(kicad_pcb
	(version 20260206)
	(generator "pcbnew")
	(generator_version "10.0")
	(general
		(thickness 1.6)
		(legacy_teardrops no)
	)
	(paper "A4")
	(layers
		(0 "F.Cu" signal "TOP")
		(4 "In1.Cu" signal "GND")
		(6 "In2.Cu" signal "IN1")
		(8 "In3.Cu" signal "GND1")
		(10 "In4.Cu" signal "IN2")
		(12 "In5.Cu" signal "GND2")
		(14 "In6.Cu" signal "IN3")
		(16 "In7.Cu" signal "GND3")
		(18 "In8.Cu" signal "VCC")
		(20 "In9.Cu" signal "VCC1")
		(22 "In10.Cu" signal "GND4")
		(24 "In11.Cu" signal "IN4")
		(26 "In12.Cu" signal "GND5")
		(28 "In13.Cu" signal "IN5")
		(30 "In14.Cu" signal "GND6")
		(32 "In15.Cu" signal "IN6")
		(34 "In16.Cu" signal "GND7")
		(2 "B.Cu" signal "BOTTOM")
		(9 "F.Adhes" user "F.Adhesive")
		(11 "B.Adhes" user "B.Adhesive")
		(13 "F.Paste" user "Package Geometry/Pastemask Top")
		(15 "B.Paste" user "Package Geometry/Pastemask Bottom")
		(5 "F.SilkS" user "Ref Des/Silkscreen Top")
		(7 "B.SilkS" user "Ref Des/Silkscreen Bottom")
		(1 "F.Mask" user "Board Geometry/Soldermask Top")
		(3 "B.Mask" user "Board Geometry/Soldermask Bottom")
		(17 "Dwgs.User" user "User.Drawings")
		(19 "Cmts.User" user "User.Comments")
		(21 "Eco1.User" user "User.Eco1")
		(23 "Eco2.User" user "User.Eco2")
		(25 "Edge.Cuts" user "Board Geometry/Outline")
		(27 "Margin" user)
		(31 "F.CrtYd" user "Package Geometry/Place Bound Top")
		(29 "B.CrtYd" user "Package Geometry/Place Bound Bottom")
		(35 "F.Fab" user "Ref Des/Assembly Top")
		(33 "B.Fab" user "Ref Des/Assembly Bottom")
	)
	(setup
		(pad_to_mask_clearance 0)
		(allow_soldermask_bridges_in_footprints no)
		(tenting
			(front yes)
			(back yes)
		)
		(covering
			(front no)
			(back no)
		)
		(plugging
			(front no)
			(back no)
		)
		(capping no)
		(filling no)
		(pcbplotparams
			(layerselection 0x00000000_00000000_55555555_5755f5ff)
			(plot_on_all_layers_selection 0x00000000_00000000_00000000_00000000)
			(disableapertmacros no)
			(usegerberextensions no)
			(usegerberattributes yes)
			(usegerberadvancedattributes yes)
			(creategerberjobfile yes)
			(dashed_line_dash_ratio 12)
			(dashed_line_gap_ratio 3)
			(svgprecision 4)
			(plotframeref no)
			(mode 1)
			(useauxorigin no)
			(pdf_front_fp_property_popups yes)
			(pdf_back_fp_property_popups yes)
			(pdf_metadata yes)
			(pdf_single_document no)
			(dxfpolygonmode yes)
			(dxfimperialunits yes)
			(dxfusepcbnewfont yes)
			(psnegative no)
			(psa4output no)
			(plot_black_and_white yes)
			(sketchpadsonfab no)
			(plotpadnumbers no)
			(hidednponfab no)
			(sketchdnponfab yes)
			(crossoutdnponfab yes)
			(subtractmaskfromsilk no)
			(outputformat 1)
			(mirror no)
			(drillshape 1)
			(scaleselection 1)
			(outputdirectory "")
		)
	)
	(gr_poly
		(pts
			(arc
				(start 408.322526 -376.75693)
				(mid 408.058874 -376.75693)
				(end 408.322526 -376.75693)
			)
		)
		(stroke
			(width 0)
			(type solid)
		)
		(fill yes)
		(layer "F.Cu")
		(net "GND")
	)
	(gr_poly
		(pts
			(arc
				(start 408.807666 -377.41733)
				(mid 408.544014 -377.41733)
				(end 408.807666 -377.41733)
			)
		)
		(stroke
			(width 0)
			(type solid)
		)
		(fill yes)
		(layer "F.Cu")
		(net "GND")
	)
	(gr_poly
		(pts
			(arc
				(start 410.026866 -382.34493)
				(mid 409.763214 -382.34493)
				(end 410.026866 -382.34493)
			)
		)
		(stroke
			(width 0)
			(type solid)
		)
		(fill yes)
		(layer "F.Cu")
		(net "GND")
	)
	(gr_poly
		(pts
			(arc
				(start 410.512006 -383.00533)
				(mid 410.248354 -383.00533)
				(end 410.512006 -383.00533)
			)
		)
		(stroke
			(width 0)
			(type solid)
		)
		(fill yes)
		(layer "F.Cu")
		(net "GND")
	)
	(gr_poly
		(pts
			(arc
				(start 410.512006 -381.68453)
				(mid 410.248354 -381.68453)
				(end 410.512006 -381.68453)
			)
		)
		(stroke
			(width 0)
			(type solid)
		)
		(fill yes)
		(layer "F.Cu")
		(net "GND")
	)
	(gr_poly
		(pts
			(arc
				(start 411.726126 -383.00533)
				(mid 411.462474 -383.00533)
				(end 411.726126 -383.00533)
			)
		)
		(stroke
			(width 0)
			(type solid)
		)
		(fill yes)
		(layer "F.Cu")
		(net "GND")
	)
	(gr_poly
		(pts
			(arc
				(start 411.726126 -381.68453)
				(mid 411.462474 -381.68453)
				(end 411.726126 -381.68453)
			)
		)
		(stroke
			(width 0)
			(type solid)
		)
		(fill yes)
		(layer "F.Cu")
		(net "GND")
	)
	(gr_poly
		(pts
			(arc
				(start 411.728666 -379.88113)
				(mid 411.465014 -379.88113)
				(end 411.728666 -379.88113)
			)
		)
		(stroke
			(width 0)
			(type solid)
		)
		(fill yes)
		(layer "F.Cu")
		(net "GND")
	)
	(gr_poly
		(pts
			(arc
				(start 412.211266 -382.34493)
				(mid 411.947614 -382.34493)
				(end 412.211266 -382.34493)
			)
		)
		(stroke
			(width 0)
			(type solid)
		)
		(fill yes)
		(layer "F.Cu")
		(net "GND")
	)
	(gr_poly
		(pts
			(arc
				(start 412.213806 -380.54153)
				(mid 411.950154 -380.54153)
				(end 412.213806 -380.54153)
			)
		)
		(stroke
			(width 0)
			(type solid)
		)
		(fill yes)
		(layer "F.Cu")
		(net "GND")
	)
	(gr_poly
		(pts
			(arc
				(start 412.213806 -379.22073)
				(mid 411.950154 -379.22073)
				(end 412.213806 -379.22073)
			)
		)
		(stroke
			(width 0)
			(type solid)
		)
		(fill yes)
		(layer "F.Cu")
		(net "GND")
	)
	(gr_poly
		(pts
			(arc
				(start 413.427926 -380.54153)
				(mid 413.164274 -380.54153)
				(end 413.427926 -380.54153)
			)
		)
		(stroke
			(width 0)
			(type solid)
		)
		(fill yes)
		(layer "F.Cu")
		(net "GND")
	)
	(gr_poly
		(pts
			(arc
				(start 413.427926 -379.22073)
				(mid 413.164274 -379.22073)
				(end 413.427926 -379.22073)
			)
		)
		(stroke
			(width 0)
			(type solid)
		)
		(fill yes)
		(layer "F.Cu")
		(net "GND")
	)
	(gr_poly
		(pts
			(arc
				(start 413.430466 -377.41733)
				(mid 413.166814 -377.41733)
				(end 413.430466 -377.41733)
			)
		)
		(stroke
			(width 0)
			(type solid)
		)
		(fill yes)
		(layer "F.Cu")
		(net "GND")
	)
	(gr_poly
		(pts
			(arc
				(start 413.913066 -379.88113)
				(mid 413.649414 -379.88113)
				(end 413.913066 -379.88113)
			)
		)
		(stroke
			(width 0)
			(type solid)
		)
		(fill yes)
		(layer "F.Cu")
		(net "GND")
	)
	(gr_poly
		(pts
			(arc
				(start 413.915606 -378.07773)
				(mid 413.651954 -378.07773)
				(end 413.915606 -378.07773)
			)
		)
		(stroke
			(width 0)
			(type solid)
		)
		(fill yes)
		(layer "F.Cu")
		(net "GND")
	)
	(gr_poly
		(pts
			(arc
				(start 413.915606 -376.75693)
				(mid 413.651954 -376.75693)
				(end 413.915606 -376.75693)
			)
		)
		(stroke
			(width 0)
			(type solid)
		)
		(fill yes)
		(layer "F.Cu")
		(net "GND")
	)
	(gr_poly
		(pts
			(arc
				(start 415.129726 -378.07773)
				(mid 414.866074 -378.07773)
				(end 415.129726 -378.07773)
			)
		)
		(stroke
			(width 0)
			(type solid)
		)
		(fill yes)
		(layer "F.Cu")
		(net "GND")
	)
	(gr_poly
		(pts
			(arc
				(start 415.129726 -376.75693)
				(mid 414.866074 -376.75693)
				(end 415.129726 -376.75693)
			)
		)
		(stroke
			(width 0)
			(type solid)
		)
		(fill yes)
		(layer "F.Cu")
		(net "GND")
	)
	(gr_poly
		(pts
			(arc
				(start 415.614866 -377.41733)
				(mid 415.351214 -377.41733)
				(end 415.614866 -377.41733)
			)
		)
		(stroke
			(width 0)
			(type solid)
		)
		(fill yes)
		(layer "F.Cu")
		(net "GND")
	)
	(gr_poly
		(pts
			(arc
				(start 416.834066 -382.34493)
				(mid 416.570414 -382.34493)
				(end 416.834066 -382.34493)
			)
		)
		(stroke
			(width 0)
			(type solid)
		)
		(fill yes)
		(layer "F.Cu")
		(net "GND")
	)
	(gr_poly
		(pts
			(arc
				(start 417.319206 -383.00533)
				(mid 417.055554 -383.00533)
				(end 417.319206 -383.00533)
			)
		)
		(stroke
			(width 0)
			(type solid)
		)
		(fill yes)
		(layer "F.Cu")
		(net "GND")
	)
	(gr_poly
		(pts
			(arc
				(start 417.319206 -381.68453)
				(mid 417.055554 -381.68453)
				(end 417.319206 -381.68453)
			)
		)
		(stroke
			(width 0)
			(type solid)
		)
		(fill yes)
		(layer "F.Cu")
		(net "GND")
	)
	(gr_poly
		(pts
			(arc
				(start 418.533326 -383.00533)
				(mid 418.269674 -383.00533)
				(end 418.533326 -383.00533)
			)
		)
		(stroke
			(width 0)
			(type solid)
		)
		(fill yes)
		(layer "F.Cu")
		(net "GND")
	)
	(gr_poly
		(pts
			(arc
				(start 418.533326 -381.68453)
				(mid 418.269674 -381.68453)
				(end 418.533326 -381.68453)
			)
		)
		(stroke
			(width 0)
			(type solid)
		)
		(fill yes)
		(layer "F.Cu")
		(net "GND")
	)
	(gr_poly
		(pts
			(arc
				(start 418.535866 -379.88113)
				(mid 418.272214 -379.88113)
				(end 418.535866 -379.88113)
			)
		)
		(stroke
			(width 0)
			(type solid)
		)
		(fill yes)
		(layer "F.Cu")
		(net "GND")
	)
	(gr_poly
		(pts
			(arc
				(start 418.724842 -439.123836)
				(mid 418.465762 -439.123836)
				(end 418.724842 -439.123836)
			)
		)
		(stroke
			(width 0)
			(type solid)
		)
		(fill yes)
		(layer "F.Cu")
		(net "GND")
	)
	(gr_poly
		(pts
			(arc
				(start 418.724842 -435.275736)
				(mid 418.465762 -435.275736)
				(end 418.724842 -435.275736)
			)
		)
		(stroke
			(width 0)
			(type solid)
		)
		(fill yes)
		(layer "F.Cu")
		(net "GND")
	)
	(gr_poly
		(pts
			(arc
				(start 419.018466 -382.34493)
				(mid 418.754814 -382.34493)
				(end 419.018466 -382.34493)
			)
		)
		(stroke
			(width 0)
			(type solid)
		)
		(fill yes)
		(layer "F.Cu")
		(net "GND")
	)
	(gr_poly
		(pts
			(arc
				(start 419.021006 -380.54153)
				(mid 418.757354 -380.54153)
				(end 419.021006 -380.54153)
			)
		)
		(stroke
			(width 0)
			(type solid)
		)
		(fill yes)
		(layer "F.Cu")
		(net "GND")
	)
	(gr_poly
		(pts
			(arc
				(start 419.021006 -379.22073)
				(mid 418.757354 -379.22073)
				(end 419.021006 -379.22073)
			)
		)
		(stroke
			(width 0)
			(type solid)
		)
		(fill yes)
		(layer "F.Cu")
		(net "GND")
	)
	(gr_poly
		(pts
			(arc
				(start 420.109396 -423.777664)
				(mid 419.850316 -423.777664)
				(end 420.109396 -423.777664)
			)
		)
		(stroke
			(width 0)
			(type solid)
		)
		(fill yes)
		(layer "F.Cu")
		(net "GND")
	)
	(gr_poly
		(pts
			(arc
				(start 420.235126 -380.54153)
				(mid 419.971474 -380.54153)
				(end 420.235126 -380.54153)
			)
		)
		(stroke
			(width 0)
			(type solid)
		)
		(fill yes)
		(layer "F.Cu")
		(net "GND")
	)
	(gr_poly
		(pts
			(arc
				(start 420.235126 -379.22073)
				(mid 419.971474 -379.22073)
				(end 420.235126 -379.22073)
			)
		)
		(stroke
			(width 0)
			(type solid)
		)
		(fill yes)
		(layer "F.Cu")
		(net "GND")
	)
	(gr_poly
		(pts
			(arc
				(start 420.237666 -377.41733)
				(mid 419.974014 -377.41733)
				(end 420.237666 -377.41733)
			)
		)
		(stroke
			(width 0)
			(type solid)
		)
		(fill yes)
		(layer "F.Cu")
		(net "GND")
	)
	(gr_poly
		(pts
			(arc
				(start 420.720266 -379.88113)
				(mid 420.456614 -379.88113)
				(end 420.720266 -379.88113)
			)
		)
		(stroke
			(width 0)
			(type solid)
		)
		(fill yes)
		(layer "F.Cu")
		(net "GND")
	)
	(gr_poly
		(pts
			(arc
				(start 420.722806 -378.07773)
				(mid 420.459154 -378.07773)
				(end 420.722806 -378.07773)
			)
		)
		(stroke
			(width 0)
			(type solid)
		)
		(fill yes)
		(layer "F.Cu")
		(net "GND")
	)
	(gr_poly
		(pts
			(arc
				(start 420.722806 -376.75693)
				(mid 420.459154 -376.75693)
				(end 420.722806 -376.75693)
			)
		)
		(stroke
			(width 0)
			(type solid)
		)
		(fill yes)
		(layer "F.Cu")
		(net "GND")
	)
	(gr_poly
		(pts
			(arc
				(start 421.936926 -378.07773)
				(mid 421.673274 -378.07773)
				(end 421.936926 -378.07773)
			)
		)
		(stroke
			(width 0)
			(type solid)
		)
		(fill yes)
		(layer "F.Cu")
		(net "GND")
	)
	(gr_poly
		(pts
			(arc
				(start 421.936926 -376.75693)
				(mid 421.673274 -376.75693)
				(end 421.936926 -376.75693)
			)
		)
		(stroke
			(width 0)
			(type solid)
		)
		(fill yes)
		(layer "F.Cu")
		(net "GND")
	)
	(gr_poly
		(pts
			(arc
				(start 422.422066 -377.41733)
				(mid 422.158414 -377.41733)
				(end 422.422066 -377.41733)
			)
		)
		(stroke
			(width 0)
			(type solid)
		)
		(fill yes)
		(layer "F.Cu")
		(net "GND")
	)
	(gr_poly
		(pts
			(arc
				(start 423.641266 -377.41733)
				(mid 423.377614 -377.41733)
				(end 423.641266 -377.41733)
			)
		)
		(stroke
			(width 0)
			(type solid)
		)
		(fill yes)
		(layer "F.Cu")
		(net "GND")
	)
	(gr_poly
		(pts
			(arc
				(start 424.126406 -378.07773)
				(mid 423.862754 -378.07773)
				(end 424.126406 -378.07773)
			)
		)
		(stroke
			(width 0)
			(type solid)
		)
		(fill yes)
		(layer "F.Cu")
		(net "GND")
	)
	(gr_poly
		(pts
			(arc
				(start 424.126406 -376.75693)
				(mid 423.862754 -376.75693)
				(end 424.126406 -376.75693)
			)
		)
		(stroke
			(width 0)
			(type solid)
		)
		(fill yes)
		(layer "F.Cu")
		(net "GND")
	)
	(gr_poly
		(pts
			(arc
				(start 425.105068 -429.448214)
				(mid 424.845988 -429.448214)
				(end 425.105068 -429.448214)
			)
		)
		(stroke
			(width 0)
			(type solid)
		)
		(fill yes)
		(layer "F.Cu")
		(net "GND")
	)
	(gr_poly
		(pts
			(arc
				(start 425.13377 -425.06265)
				(mid 424.87469 -425.06265)
				(end 425.13377 -425.06265)
			)
		)
		(stroke
			(width 0)
			(type solid)
		)
		(fill yes)
		(layer "F.Cu")
		(net "GND")
	)
	(gr_poly
		(pts
			(arc
				(start 425.340526 -378.07773)
				(mid 425.076874 -378.07773)
				(end 425.340526 -378.07773)
			)
		)
		(stroke
			(width 0)
			(type solid)
		)
		(fill yes)
		(layer "F.Cu")
		(net "GND")
	)
	(gr_poly
		(pts
			(arc
				(start 425.340526 -376.75693)
				(mid 425.076874 -376.75693)
				(end 425.340526 -376.75693)
			)
		)
		(stroke
			(width 0)
			(type solid)
		)
		(fill yes)
		(layer "F.Cu")
		(net "GND")
	)
	(gr_poly
		(pts
			(arc
				(start 425.825666 -377.41733)
				(mid 425.562014 -377.41733)
				(end 425.825666 -377.41733)
			)
		)
		(stroke
			(width 0)
			(type solid)
		)
		(fill yes)
		(layer "F.Cu")
		(net "GND")
	)
	(gr_poly
		(pts
			(arc
				(start 426.376846 -388.917688)
				(mid 426.113194 -388.917688)
				(end 426.376846 -388.917688)
			)
		)
		(stroke
			(width 0)
			(type solid)
		)
		(fill yes)
		(layer "F.Cu")
		(net "GND")
	)
	(gr_poly
		(pts
			(arc
				(start 426.376846 -387.703568)
				(mid 426.113194 -387.703568)
				(end 426.376846 -387.703568)
			)
		)
		(stroke
			(width 0)
			(type solid)
		)
		(fill yes)
		(layer "F.Cu")
		(net "GND")
	)
	(gr_poly
		(pts
			(arc
				(start 426.376846 -385.514088)
				(mid 426.113194 -385.514088)
				(end 426.376846 -385.514088)
			)
		)
		(stroke
			(width 0)
			(type solid)
		)
		(fill yes)
		(layer "F.Cu")
		(net "GND")
	)
	(gr_poly
		(pts
			(arc
				(start 426.376846 -384.299968)
				(mid 426.113194 -384.299968)
				(end 426.376846 -384.299968)
			)
		)
		(stroke
			(width 0)
			(type solid)
		)
		(fill yes)
		(layer "F.Cu")
		(net "GND")
	)
	(gr_poly
		(pts
			(xy 426.61586 -156.43225) (xy 426.61586 -132.910834) (xy 425.216066 -131.51104) (xy 421.746426 -131.51104)
			(xy 418.843206 -131.51104) (xy 414.299146 -131.51104) (xy 414.244282 -131.565904) (xy 414.244282 -142.054326)
			(xy 414.268158 -142.078456) (xy 416.715702 -142.078456) (xy 417.961572 -142.078456) (xy 418.970206 -143.08709)
			(xy 418.970206 -148.64207) (xy 418.792406 -148.81987) (xy 408.697176 -148.81987) (xy 408.459686 -149.05736)
			(xy 408.459686 -149.696678) (xy 408.459686 -151.41067) (xy 408.519122 -151.470106) (xy 422.881298 -151.470106)
			(xy 422.892982 -151.48179) (xy 422.903142 -151.49195) (xy 422.936162 -151.52497) (xy 422.936162 -156.176218)
			(xy 423.611548 -156.851604) (xy 426.196506 -156.851604)
		)
		(stroke
			(width 0)
			(type solid)
		)
		(fill yes)
		(layer "F.Cu")
		(net "GND")
	)
	(gr_poly
		(pts
			(arc
				(start 426.70222 -427.633638)
				(mid 426.44314 -427.633638)
				(end 426.70222 -427.633638)
			)
		)
		(stroke
			(width 0)
			(type solid)
		)
		(fill yes)
		(layer "F.Cu")
		(net "GND")
	)
	(gr_poly
		(pts
			(arc
				(start 426.961046 -383.844292)
				(mid 426.697394 -383.844292)
				(end 426.961046 -383.844292)
			)
		)
		(stroke
			(width 0)
			(type solid)
		)
		(fill yes)
		(layer "F.Cu")
		(net "GND")
	)
	(gr_poly
		(pts
			(arc
				(start 426.981366 -438.61355)
				(mid 426.722286 -438.61355)
				(end 426.981366 -438.61355)
			)
		)
		(stroke
			(width 0)
			(type solid)
		)
		(fill yes)
		(layer "F.Cu")
		(net "GND")
	)
	(gr_poly
		(pts
			(arc
				(start 427.037246 -389.402828)
				(mid 426.773594 -389.402828)
				(end 427.037246 -389.402828)
			)
		)
		(stroke
			(width 0)
			(type solid)
		)
		(fill yes)
		(layer "F.Cu")
		(net "GND")
	)
	(gr_poly
		(pts
			(arc
				(start 427.037246 -387.218428)
				(mid 426.773594 -387.218428)
				(end 427.037246 -387.218428)
			)
		)
		(stroke
			(width 0)
			(type solid)
		)
		(fill yes)
		(layer "F.Cu")
		(net "GND")
	)
	(gr_poly
		(pts
			(arc
				(start 427.037246 -385.999228)
				(mid 426.773594 -385.999228)
				(end 427.037246 -385.999228)
			)
		)
		(stroke
			(width 0)
			(type solid)
		)
		(fill yes)
		(layer "F.Cu")
		(net "GND")
	)
	(gr_poly
		(pts
			(arc
				(start 427.552866 -384.090926)
				(mid 427.289214 -384.090926)
				(end 427.552866 -384.090926)
			)
		)
		(stroke
			(width 0)
			(type solid)
		)
		(fill yes)
		(layer "F.Cu")
		(net "GND")
	)
	(gr_poly
		(pts
			(arc
				(start 427.614842 -435.275736)
				(mid 427.355762 -435.275736)
				(end 427.614842 -435.275736)
			)
		)
		(stroke
			(width 0)
			(type solid)
		)
		(fill yes)
		(layer "F.Cu")
		(net "GND")
	)
	(gr_poly
		(pts
			(arc
				(start 427.697646 -388.917688)
				(mid 427.433994 -388.917688)
				(end 427.697646 -388.917688)
			)
		)
		(stroke
			(width 0)
			(type solid)
		)
		(fill yes)
		(layer "F.Cu")
		(net "GND")
	)
	(gr_poly
		(pts
			(arc
				(start 427.697646 -387.703568)
				(mid 427.433994 -387.703568)
				(end 427.697646 -387.703568)
			)
		)
		(stroke
			(width 0)
			(type solid)
		)
		(fill yes)
		(layer "F.Cu")
		(net "GND")
	)
	(gr_poly
		(pts
			(arc
				(start 427.697646 -385.514088)
				(mid 427.433994 -385.514088)
				(end 427.697646 -385.514088)
			)
		)
		(stroke
			(width 0)
			(type solid)
		)
		(fill yes)
		(layer "F.Cu")
		(net "GND")
	)
	(gr_poly
		(pts
			(arc
				(start 427.889416 -18.503138)
				(mid 427.630336 -18.503138)
				(end 427.889416 -18.503138)
			)
		)
		(stroke
			(width 0)
			(type solid)
		)
		(fill yes)
		(layer "F.Cu")
		(net "GND")
	)
	(gr_poly
		(pts
			(arc
				(start 428.195232 -368.612674)
				(mid 427.936152 -368.612674)
				(end 428.195232 -368.612674)
			)
		)
		(stroke
			(width 0)
			(type solid)
		)
		(fill yes)
		(layer "F.Cu")
		(net "GND")
	)
	(gr_poly
		(pts
			(arc
				(start 428.374556 -19.13636)
				(mid 428.115476 -19.13636)
				(end 428.374556 -19.13636)
			)
		)
		(stroke
			(width 0)
			(type solid)
		)
		(fill yes)
		(layer "F.Cu")
		(net "GND")
	)
	(gr_poly
		(pts
			(arc
				(start 432.68773 -431.883312)
				(mid 432.42865 -431.883312)
				(end 432.68773 -431.883312)
			)
		)
		(stroke
			(width 0)
			(type solid)
		)
		(fill yes)
		(layer "F.Cu")
		(net "GND")
	)
	(gr_poly
		(pts
			(arc
				(start 433.154328 -430.337722)
				(mid 432.895248 -430.337722)
				(end 433.154328 -430.337722)
			)
		)
		(stroke
			(width 0)
			(type solid)
		)
		(fill yes)
		(layer "F.Cu")
		(net "GND")
	)
	(gr_poly
		(pts
			(arc
				(start 434.03901 -172.64888)
				(mid 433.77993 -172.64888)
				(end 434.03901 -172.64888)
			)
		)
		(stroke
			(width 0)
			(type solid)
		)
		(fill yes)
		(layer "F.Cu")
		(net "GND")
	)
	(gr_poly
		(pts
			(arc
				(start 436.562754 -165.63467)
				(mid 436.303674 -165.63467)
				(end 436.562754 -165.63467)
			)
		)
		(stroke
			(width 0)
			(type solid)
		)
		(fill yes)
		(layer "F.Cu")
		(net "GND")
	)
	(gr_poly
		(pts
			(arc
				(start 436.793386 -432.61026)
				(mid 436.534306 -432.61026)
				(end 436.793386 -432.61026)
			)
		)
		(stroke
			(width 0)
			(type solid)
		)
		(fill yes)
		(layer "F.Cu")
		(net "GND")
	)
	(gr_poly
		(pts
			(arc
				(start 437.047132 -5.81914)
				(mid 436.788052 -5.81914)
				(end 437.047132 -5.81914)
			)
		)
		(stroke
			(width 0)
			(type solid)
		)
		(fill yes)
		(layer "F.Cu")
		(net "GND")
	)
	(gr_poly
		(pts
			(arc
				(start 437.551322 -438.23636)
				(mid 437.292242 -438.23636)
				(end 437.551322 -438.23636)
			)
		)
		(stroke
			(width 0)
			(type solid)
		)
		(fill yes)
		(layer "F.Cu")
		(net "GND")
	)
	(gr_poly
		(pts
			(arc
				(start 440.332622 -166.124636)
				(mid 440.073542 -166.124636)
				(end 440.332622 -166.124636)
			)
		)
		(stroke
			(width 0)
			(type solid)
		)
		(fill yes)
		(layer "F.Cu")
		(net "GND")
	)
	(gr_poly
		(pts
			(arc
				(start 442.763148 -170.559476)
				(mid 442.504068 -170.559476)
				(end 442.763148 -170.559476)
			)
		)
		(stroke
			(width 0)
			(type solid)
		)
		(fill yes)
		(layer "F.Cu")
		(net "GND")
	)
	(gr_poly
		(pts
			(arc
				(start 443.487048 -167.662352)
				(mid 443.227968 -167.662352)
				(end 443.487048 -167.662352)
			)
		)
		(stroke
			(width 0)
			(type solid)
		)
		(fill yes)
		(layer "F.Cu")
		(net "GND")
	)
	(gr_poly
		(pts
			(arc
				(start 444.151004 -9.412732)
				(mid 443.891924 -9.412732)
				(end 444.151004 -9.412732)
			)
		)
		(stroke
			(width 0)
			(type solid)
		)
		(fill yes)
		(layer "F.Cu")
		(net "GND")
	)
	(gr_poly
		(pts
			(arc
				(start 445.356996 -435.961282)
				(mid 445.097916 -435.961282)
				(end 445.356996 -435.961282)
			)
		)
		(stroke
			(width 0)
			(type solid)
		)
		(fill yes)
		(layer "F.Cu")
		(net "GND")
	)
	(gr_poly
		(pts
			(arc
				(start 447.78422 -4.325874)
				(mid 447.52514 -4.325874)
				(end 447.78422 -4.325874)
			)
		)
		(stroke
			(width 0)
			(type solid)
		)
		(fill yes)
		(layer "F.Cu")
		(net "GND")
	)
	(gr_poly
		(pts
			(arc
				(start 449.56222 -4.954524)
				(mid 449.30314 -4.954524)
				(end 449.56222 -4.954524)
			)
		)
		(stroke
			(width 0)
			(type solid)
		)
		(fill yes)
		(layer "F.Cu")
		(net "GND")
	)
	(gr_poly
		(pts
			(arc
				(start 450.023484 -141.534896)
				(mid 449.764404 -141.534896)
				(end 450.023484 -141.534896)
			)
		)
		(stroke
			(width 0)
			(type solid)
		)
		(fill yes)
		(layer "F.Cu")
		(net "GND")
	)
	(gr_poly
		(pts
			(arc
				(start 451.59422 -6.224524)
				(mid 451.33514 -6.224524)
				(end 451.59422 -6.224524)
			)
		)
		(stroke
			(width 0)
			(type solid)
		)
		(fill yes)
		(layer "F.Cu")
		(net "GND")
	)
	(gr_poly
		(pts
			(arc
				(start 451.59422 -4.954524)
				(mid 451.33514 -4.954524)
				(end 451.59422 -4.954524)
			)
		)
		(stroke
			(width 0)
			(type solid)
		)
		(fill yes)
		(layer "F.Cu")
		(net "GND")
	)
	(gr_poly
		(pts
			(xy 56.54548 -401.74164) (xy 56.54548 -398.9705) (xy 56.26608 -398.6911) (xy 51.33594 -398.6911)
			(xy 49.4919 -400.53514) (xy 46.923706 -400.53514) (xy 46.67504 -400.783806) (xy 46.548802 -400.910044)
			(xy 45.329856 -400.910044) (xy 45.203618 -400.783806) (xy 44.278804 -399.858992) (xy 44.278804 -398.066768)
			(xy 44.278804 -397.236188) (xy 44.278804 -396.835884) (xy 44.097194 -396.654274) (xy 43.69689 -396.654274)
			(xy 41.154604 -396.654274) (xy 40.531542 -396.654274) (xy 40.407082 -396.778734) (xy 40.407082 -400.297904)
			(xy 40.611806 -400.502628) (xy 42.796714 -400.502628) (xy 43.062652 -400.768566) (xy 43.654726 -400.768566)
			(xy 45.048932 -402.162772) (xy 49.19853 -402.162772) (xy 56.124348 -402.162772)
		)
		(stroke
			(width 0)
			(type solid)
		)
		(fill yes)
		(layer "F.Cu")
		(net "P0V9_CPU1_RT_2D")
	)
	(gr_poly
		(pts
			(xy 82.724498 -152.870916) (xy 82.724498 -150.416514) (xy 82.568796 -150.260812) (xy 81.96834 -150.260812)
			(xy 80.469994 -150.260812) (xy 79.390494 -150.260812) (xy 75.527154 -150.260812) (xy 74.549 -150.260812)
			(xy 73.855834 -150.953978) (xy 72.86244 -150.953978) (xy 72.034654 -151.782018) (xy 67.133978 -151.782018)
			(xy 67.030092 -151.678132) (xy 66.42608 -151.678132) (xy 66.364612 -151.7396) (xy 66.364612 -152.146)
			(xy 66.424302 -152.20569) (xy 68.83527 -152.20569) (xy 69.872352 -152.20569) (xy 70.416166 -152.749504)
			(xy 70.418452 -152.749504) (xy 70.600316 -152.931368) (xy 70.602094 -152.931368) (xy 70.674738 -153.004012)
			(xy 80.533494 -153.004012) (xy 82.15122 -153.004012) (xy 82.591402 -153.004012)
		)
		(stroke
			(width 0)
			(type solid)
		)
		(fill yes)
		(layer "F.Cu")
		(net "SW_P12V_AUX_PVDD18_S5_P1_FLT")
	)
	(gr_poly
		(pts
			(arc
				(start 96.929702 -419.12413)
				(mid 96.949225 -419.120229)
				(end 96.96577 -419.109144)
			)
			(arc
				(start 97.079308 -418.995606)
				(mid 97.090419 -418.979072)
				(end 97.094294 -418.959538)
			)
			(arc
				(start 97.094294 -416.329114)
				(mid 97.090393 -416.309591)
				(end 97.079308 -416.293046)
			)
			(arc
				(start 96.958658 -416.172396)
				(mid 96.942124 -416.161285)
				(end 96.92259 -416.15741)
			)
			(arc
				(start 96.259396 -416.15741)
				(mid 96.239873 -416.161311)
				(end 96.223328 -416.172396)
			)
			(arc
				(start 96.171004 -416.22472)
				(mid 96.159893 -416.241254)
				(end 96.156018 -416.260788)
			)
			(xy 96.156018 -419.110414) (xy 96.162114 -419.11651) (xy 96.180656 -419.12413)
		)
		(stroke
			(width 0)
			(type solid)
		)
		(fill yes)
		(layer "F.Cu")
		(net "P1V8_CPU1_RT_1D")
	)
	(gr_poly
		(pts
			(xy 233.233468 -300.033436) (xy 233.243374 -300.02353) (xy 233.524044 -299.74286) (xy 233.524044 -295.391586)
			(xy 233.243374 -295.110916) (xy 232.819194 -294.686736) (xy 232.772458 -294.64) (xy 232.372662 -294.240204)
			(xy 232.372662 -294.236648) (xy 231.879648 -293.743634) (xy 231.879648 -292.053264) (xy 231.853486 -292.027102)
			(xy 231.603042 -292.027102) (xy 231.57434 -292.055804) (xy 231.57434 -295.338246) (xy 231.393492 -295.519094)
			(xy 227.862384 -295.519094) (xy 227.763578 -295.420288) (xy 227.763578 -295.238932) (xy 227.712778 -295.188132)
			(xy 226.759262 -295.188132) (xy 226.30765 -295.639744) (xy 226.30765 -299.999654) (xy 226.516692 -300.208696)
			(xy 232.17759 -300.208696) (xy 232.410762 -300.208696) (xy 233.058462 -300.208696)
		)
		(stroke
			(width 0)
			(type solid)
		)
		(fill yes)
		(layer "F.Cu")
		(net "SW_P1V8_RETIMER_CPU1_SW")
	)
	(gr_poly
		(pts
			(xy 311.99328 -410.40304) (xy 311.99328 -407.74112) (xy 311.74182 -407.48966) (xy 307.03774 -407.48966)
			(xy 305.62804 -408.89936) (xy 302.89246 -408.89936) (xy 302.8823 -408.8892) (xy 302.791622 -408.8892)
			(xy 302.515016 -409.165806) (xy 302.42764 -409.253182) (xy 301.2948 -409.253182) (xy 301.207424 -409.165806)
			(xy 301.20336 -409.165806) (xy 300.278546 -408.240992) (xy 300.278546 -406.448768) (xy 300.278546 -405.618188)
			(xy 299.696632 -405.036274) (xy 297.154346 -405.036274) (xy 296.999914 -405.190706) (xy 296.999914 -405.779478)
			(xy 296.999914 -406.496012) (xy 296.999914 -407.336752) (xy 297.322494 -407.659332) (xy 298.163234 -407.659332)
			(xy 301.048674 -410.544772) (xy 305.198272 -410.544772) (xy 311.851548 -410.544772)
		)
		(stroke
			(width 0)
			(type solid)
		)
		(fill yes)
		(layer "F.Cu")
		(net "P0V9_CPU0_RT_2D")
	)
	(gr_poly
		(pts
			(xy 337.6676 -148.4122) (xy 337.6676 -143.7132) (xy 337.555078 -143.600678) (xy 337.16214 -143.600678)
			(xy 336.611976 -143.600678) (xy 336.022442 -143.01089) (xy 336.022442 -141.177264) (xy 335.98104 -141.135862)
			(xy 335.67497 -141.135862) (xy 335.641442 -141.16939) (xy 335.641442 -142.140686) (xy 335.641442 -144.577054)
			(xy 335.378552 -144.839944) (xy 334.311752 -144.839944) (xy 333.676752 -144.839944) (xy 332.838552 -144.839944)
			(xy 331.978 -144.839944) (xy 331.851 -144.712944) (xy 331.851 -144.3228) (xy 331.7748 -144.2466)
			(xy 331.2668 -144.2466) (xy 331.2287 -144.2847) (xy 331.2287 -147.9169) (xy 331.2287 -148.3995) (xy 331.3938 -148.5646)
			(xy 331.724 -148.5646) (xy 337.5152 -148.5646)
		)
		(stroke
			(width 0)
			(type solid)
		)
		(fill yes)
		(layer "F.Cu")
		(net "SW_PVDD18_S5_P0_SW")
	)
	(gr_poly
		(pts
			(arc
				(start 59.724544 -410.664152)
				(mid 59.428888 -410.664152)
				(end 59.724544 -410.664152)
			)
		)
		(stroke
			(width 0)
			(type solid)
		)
		(fill yes)
		(layer "F.Cu")
		(net "GND")
	)
	(gr_poly
		(pts
			(xy 122.26925 -74.26833) (xy 122.26925 -73.034144) (xy 122.26671 -73.03135) (xy 122.187462 -72.952102)
			(arc
				(start 120.844056 -72.952102)
				(mid 120.824961 -72.955994)
				(end 120.80875 -72.966834)
			)
			(arc
				(start 120.758204 -73.01738)
				(mid 120.747298 -73.033563)
				(end 120.743472 -73.052686)
			)
			(arc
				(start 120.743472 -73.489058)
				(mid 120.747364 -73.508153)
				(end 120.758204 -73.524364)
			)
			(xy 121.176796 -73.942956) (xy 121.23166 -73.942956) (xy 121.489978 -74.201274)
			(arc
				(start 121.489978 -74.489564)
				(mid 121.493777 -74.520449)
				(end 121.495058 -74.55154)
			)
			(arc
				(start 121.495058 -74.55154)
				(mid 121.493488 -74.586611)
				(end 121.488708 -74.62139)
			)
			(xy 121.488708 -74.898758) (xy 121.638568 -74.898758)
		)
		(stroke
			(width 0)
			(type solid)
		)
		(fill yes)
		(layer "F.Cu")
		(net "GND")
	)
	(gr_poly
		(pts
			(xy 144.36725 -76.55433) (xy 144.36725 -75.320144) (xy 144.36471 -75.31735) (xy 144.285462 -75.238102)
			(arc
				(start 142.942056 -75.238102)
				(mid 142.922961 -75.241994)
				(end 142.90675 -75.252834)
			)
			(arc
				(start 142.856204 -75.30338)
				(mid 142.845298 -75.319563)
				(end 142.841472 -75.338686)
			)
			(arc
				(start 142.841472 -75.775058)
				(mid 142.845364 -75.794153)
				(end 142.856204 -75.810364)
			)
			(xy 143.274796 -76.228956) (xy 143.32966 -76.228956) (xy 143.587978 -76.487274)
			(arc
				(start 143.587978 -76.775564)
				(mid 143.591777 -76.806449)
				(end 143.593058 -76.83754)
			)
			(arc
				(start 143.593058 -76.83754)
				(mid 143.591488 -76.872611)
				(end 143.586708 -76.90739)
			)
			(xy 143.586708 -77.184758) (xy 143.736568 -77.184758)
		)
		(stroke
			(width 0)
			(type solid)
		)
		(fill yes)
		(layer "F.Cu")
		(net "GND")
	)
	(gr_poly
		(pts
			(xy 221.905576 -76.970128) (xy 221.905576 -76.339446) (xy 222.454216 -75.790806) (xy 222.454216 -72.734678)
			(xy 222.35668 -72.637142) (xy 222.35668 -72.101456) (xy 222.454216 -72.00392) (xy 222.454216 -70.075298)
			(xy 222.383096 -70.004178) (xy 222.268796 -70.004178) (xy 222.215456 -70.057518) (xy 222.215456 -71.711058)
			(xy 221.946216 -71.980298) (xy 221.631256 -71.980298) (xy 221.440756 -71.789798) (xy 221.440756 -70.555358)
			(xy 221.392496 -70.507098) (xy 221.235016 -70.507098) (xy 221.201996 -70.540118) (xy 221.201996 -72.912478)
			(xy 220.78188 -73.332594) (xy 220.78188 -74.920602) (xy 220.536262 -75.16622) (xy 219.11056 -75.16622)
			(xy 219.0242 -75.25258) (xy 219.0242 -77.065124) (xy 219.155772 -77.196696) (xy 221.679008 -77.196696)
		)
		(stroke
			(width 0)
			(type solid)
		)
		(fill yes)
		(layer "F.Cu")
		(net "P3V3_AUX")
	)
	(gr_poly
		(pts
			(xy 420.729918 -363.882178) (xy 420.729918 -360.910378) (xy 420.8653 -360.774996) (xy 421.6527 -360.774996)
			(xy 421.686482 -360.741214) (xy 421.686482 -360.233214) (xy 421.651684 -360.198416) (xy 420.97706 -360.198416)
			(xy 420.960296 -360.21518) (xy 417.068 -360.21518) (xy 417.051236 -360.198416) (xy 416.212274 -360.198416)
			(xy 416.181794 -360.228896) (xy 416.181794 -360.343958) (xy 416.213544 -360.375708) (xy 416.986212 -360.375708)
			(xy 417.089082 -360.478578) (xy 417.089082 -360.838242) (xy 416.928554 -360.99877) (xy 416.205162 -360.99877)
			(xy 416.174174 -361.029758) (xy 416.174174 -361.539282) (xy 416.210496 -361.575604) (xy 416.964876 -361.575604)
			(xy 417.089082 -361.69981) (xy 417.089082 -363.890814) (xy 417.114482 -363.916214) (xy 420.695882 -363.916214)
		)
		(stroke
			(width 0)
			(type solid)
		)
		(fill yes)
		(layer "F.Cu")
		(net "GND")
	)
	(gr_poly
		(pts
			(arc
				(start 467.758526 -342.568022)
				(mid 467.782821 -342.549438)
				(end 467.792054 -342.52027)
			)
			(arc
				(start 467.792054 -165.679374)
				(mid 467.782838 -165.650195)
				(end 467.758526 -165.631622)
			)
			(xy 467.653624 -165.593776) (xy 467.622636 -165.602158)
			(arc
				(start 467.612222 -165.61435)
				(mid 467.458011 -165.794474)
				(end 467.298532 -165.96995)
			)
			(arc
				(start 467.298532 -165.96995)
				(mid 467.28833 -165.986036)
				(end 467.284816 -166.004748)
			)
			(arc
				(start 467.284816 -342.194896)
				(mid 467.28838 -342.213588)
				(end 467.298532 -342.229694)
			)
			(arc
				(start 467.298532 -342.229694)
				(mid 467.458013 -342.405169)
				(end 467.612222 -342.585294)
			)
			(xy 467.622636 -342.597486) (xy 467.653624 -342.605868)
		)
		(stroke
			(width 0)
			(type solid)
		)
		(fill yes)
		(layer "F.Cu")
		(net "GND")
	)
	(gr_poly
		(pts
			(arc
				(start 42.833798 -102.26294)
				(mid 42.853321 -102.259039)
				(end 42.869866 -102.247954)
			)
			(arc
				(start 42.997374 -102.120446)
				(mid 43.008485 -102.103912)
				(end 43.01236 -102.084378)
			)
			(xy 43.01236 -101.657404) (xy 43.0149 -101.654864) (xy 43.0149 -99.9617) (xy 42.9133 -99.8601) (xy 42.1894 -99.8601)
			(arc
				(start 41.011602 -99.8601)
				(mid 40.992079 -99.864001)
				(end 40.975534 -99.875086)
			)
			(arc
				(start 40.837866 -100.012754)
				(mid 40.826755 -100.029288)
				(end 40.82288 -100.048822)
			)
			(arc
				(start 40.82288 -102.089458)
				(mid 40.826781 -102.108981)
				(end 40.837866 -102.125526)
			)
			(arc
				(start 40.960294 -102.247954)
				(mid 40.976828 -102.259065)
				(end 40.996362 -102.26294)
			)
		)
		(stroke
			(width 0)
			(type solid)
		)
		(fill yes)
		(layer "F.Cu")
		(net "P12V_AUX_DSC_VOL")
	)
	(gr_poly
		(pts
			(arc
				(start 100.054918 2.345436)
				(mid 99.734878 2.345436)
				(end 100.054918 2.345436)
			)
		)
		(stroke
			(width 0)
			(type solid)
		)
		(fill yes)
		(layer "F.Cu")
		(net "DELTA_L_GND_1")
	)
	(gr_poly
		(pts
			(arc
				(start 100.054918 4.701032)
				(mid 99.734878 4.701032)
				(end 100.054918 4.701032)
			)
		)
		(stroke
			(width 0)
			(type solid)
		)
		(fill yes)
		(layer "F.Cu")
		(net "DELTA_L_GND_1")
	)
	(gr_poly
		(pts
			(arc
				(start 100.054918 7.241032)
				(mid 99.734878 7.241032)
				(end 100.054918 7.241032)
			)
		)
		(stroke
			(width 0)
			(type solid)
		)
		(fill yes)
		(layer "F.Cu")
		(net "DELTA_L_GND_1")
	)
	(gr_poly
		(pts
			(arc
				(start 119.76989 -32.51708)
				(mid 119.44477 -32.51708)
				(end 119.76989 -32.51708)
			)
		)
		(stroke
			(width 0)
			(type solid)
		)
		(fill yes)
		(layer "F.Cu")
		(net "GND")
	)
	(gr_poly
		(pts
			(arc
				(start 121.64949 -32.51708)
				(mid 121.32437 -32.51708)
				(end 121.64949 -32.51708)
			)
		)
		(stroke
			(width 0)
			(type solid)
		)
		(fill yes)
		(layer "F.Cu")
		(net "GND")
	)
	(gr_poly
		(pts
			(arc
				(start 121.98858 -36.053268)
				(mid 121.66346 -36.053268)
				(end 121.98858 -36.053268)
			)
		)
		(stroke
			(width 0)
			(type solid)
		)
		(fill yes)
		(layer "F.Cu")
		(net "GND")
	)
	(gr_poly
		(pts
			(arc
				(start 122.65533 -34.473388)
				(mid 122.33021 -34.473388)
				(end 122.65533 -34.473388)
			)
		)
		(stroke
			(width 0)
			(type solid)
		)
		(fill yes)
		(layer "F.Cu")
		(net "GND")
	)
	(gr_poly
		(pts
			(arc
				(start 122.65533 -32.339788)
				(mid 122.33021 -32.339788)
				(end 122.65533 -32.339788)
			)
		)
		(stroke
			(width 0)
			(type solid)
		)
		(fill yes)
		(layer "F.Cu")
		(net "GND")
	)
	(gr_poly
		(pts
			(arc
				(start 124.08408 -33.386268)
				(mid 123.75896 -33.386268)
				(end 124.08408 -33.386268)
			)
		)
		(stroke
			(width 0)
			(type solid)
		)
		(fill yes)
		(layer "F.Cu")
		(net "GND")
	)
	(gr_poly
		(pts
			(arc
				(start 124.26188 -36.053268)
				(mid 123.93676 -36.053268)
				(end 124.26188 -36.053268)
			)
		)
		(stroke
			(width 0)
			(type solid)
		)
		(fill yes)
		(layer "F.Cu")
		(net "GND")
	)
	(gr_poly
		(pts
			(arc
				(start 126.21768 -33.386268)
				(mid 125.89256 -33.386268)
				(end 126.21768 -33.386268)
			)
		)
		(stroke
			(width 0)
			(type solid)
		)
		(fill yes)
		(layer "F.Cu")
		(net "GND")
	)
	(gr_poly
		(pts
			(arc
				(start 130.376676 -24.121618)
				(mid 130.051556 -24.121618)
				(end 130.376676 -24.121618)
			)
		)
		(stroke
			(width 0)
			(type solid)
		)
		(fill yes)
		(layer "F.Cu")
		(net "GND")
	)
	(gr_poly
		(pts
			(arc
				(start 131.23164 -28.38958)
				(mid 130.90652 -28.38958)
				(end 131.23164 -28.38958)
			)
		)
		(stroke
			(width 0)
			(type solid)
		)
		(fill yes)
		(layer "F.Cu")
		(net "GND")
	)
	(gr_poly
		(pts
			(arc
				(start 131.23164 -26.12898)
				(mid 130.90652 -26.12898)
				(end 131.23164 -26.12898)
			)
		)
		(stroke
			(width 0)
			(type solid)
		)
		(fill yes)
		(layer "F.Cu")
		(net "GND")
	)
	(gr_poly
		(pts
			(arc
				(start 132.04952 -24.121618)
				(mid 131.7244 -24.121618)
				(end 132.04952 -24.121618)
			)
		)
		(stroke
			(width 0)
			(type solid)
		)
		(fill yes)
		(layer "F.Cu")
		(net "GND")
	)
	(gr_poly
		(pts
			(arc
				(start 133.215634 -26.144474)
				(mid 132.890514 -26.144474)
				(end 133.215634 -26.144474)
			)
		)
		(stroke
			(width 0)
			(type solid)
		)
		(fill yes)
		(layer "F.Cu")
		(net "GND")
	)
	(gr_poly
		(pts
			(arc
				(start 133.215634 -24.24303)
				(mid 132.890514 -24.24303)
				(end 133.215634 -24.24303)
			)
		)
		(stroke
			(width 0)
			(type solid)
		)
		(fill yes)
		(layer "F.Cu")
		(net "GND")
	)
	(gr_poly
		(pts
			(arc
				(start 136.09574 -29.87802)
				(mid 135.77062 -29.87802)
				(end 136.09574 -29.87802)
			)
		)
		(stroke
			(width 0)
			(type solid)
		)
		(fill yes)
		(layer "F.Cu")
		(net "GND")
	)
	(gr_poly
		(pts
			(arc
				(start 136.09574 -27.61742)
				(mid 135.77062 -27.61742)
				(end 136.09574 -27.61742)
			)
		)
		(stroke
			(width 0)
			(type solid)
		)
		(fill yes)
		(layer "F.Cu")
		(net "GND")
	)
	(gr_poly
		(pts
			(arc
				(start 138.154918 -22.512528)
				(mid 137.829798 -22.512528)
				(end 138.154918 -22.512528)
			)
		)
		(stroke
			(width 0)
			(type solid)
		)
		(fill yes)
		(layer "F.Cu")
		(net "GND")
	)
	(gr_poly
		(pts
			(arc
				(start 139.99083 -29.053028)
				(mid 139.66571 -29.053028)
				(end 139.99083 -29.053028)
			)
		)
		(stroke
			(width 0)
			(type solid)
		)
		(fill yes)
		(layer "F.Cu")
		(net "GND")
	)
	(gr_poly
		(pts
			(arc
				(start 140.82268 -32.29356)
				(mid 140.49756 -32.29356)
				(end 140.82268 -32.29356)
			)
		)
		(stroke
			(width 0)
			(type solid)
		)
		(fill yes)
		(layer "F.Cu")
		(net "GND")
	)
	(gr_poly
		(pts
			(arc
				(start 140.82268 -30.15996)
				(mid 140.49756 -30.15996)
				(end 140.82268 -30.15996)
			)
		)
		(stroke
			(width 0)
			(type solid)
		)
		(fill yes)
		(layer "F.Cu")
		(net "GND")
	)
	(gr_poly
		(pts
			(arc
				(start 141.663674 -29.053028)
				(mid 141.338554 -29.053028)
				(end 141.663674 -29.053028)
			)
		)
		(stroke
			(width 0)
			(type solid)
		)
		(fill yes)
		(layer "F.Cu")
		(net "GND")
	)
	(gr_poly
		(pts
			(arc
				(start 142.719552 -27.17419)
				(mid 142.394432 -27.17419)
				(end 142.719552 -27.17419)
			)
		)
		(stroke
			(width 0)
			(type solid)
		)
		(fill yes)
		(layer "F.Cu")
		(net "GND")
	)
	(gr_poly
		(pts
			(arc
				(start 142.719552 -25.501346)
				(mid 142.394432 -25.501346)
				(end 142.719552 -25.501346)
			)
		)
		(stroke
			(width 0)
			(type solid)
		)
		(fill yes)
		(layer "F.Cu")
		(net "GND")
	)
	(gr_poly
		(pts
			(arc
				(start 145.1737 -32.38754)
				(mid 144.84858 -32.38754)
				(end 145.1737 -32.38754)
			)
		)
		(stroke
			(width 0)
			(type solid)
		)
		(fill yes)
		(layer "F.Cu")
		(net "GND")
	)
	(gr_poly
		(pts
			(arc
				(start 145.1737 -30.05074)
				(mid 144.84858 -30.05074)
				(end 145.1737 -30.05074)
			)
		)
		(stroke
			(width 0)
			(type solid)
		)
		(fill yes)
		(layer "F.Cu")
		(net "GND")
	)
	(gr_poly
		(pts
			(arc
				(start 183.923686 2.345436)
				(mid 183.603646 2.345436)
				(end 183.923686 2.345436)
			)
		)
		(stroke
			(width 0)
			(type solid)
		)
		(fill yes)
		(layer "F.Cu")
		(net "DELTA_L_GND_1")
	)
	(gr_poly
		(pts
			(arc
				(start 183.923686 4.885436)
				(mid 183.603646 4.885436)
				(end 183.923686 4.885436)
			)
		)
		(stroke
			(width 0)
			(type solid)
		)
		(fill yes)
		(layer "F.Cu")
		(net "DELTA_L_GND_1")
	)
	(gr_poly
		(pts
			(arc
				(start 183.923686 7.241032)
				(mid 183.603646 7.241032)
				(end 183.923686 7.241032)
			)
		)
		(stroke
			(width 0)
			(type solid)
		)
		(fill yes)
		(layer "F.Cu")
		(net "DELTA_L_GND_1")
	)
	(gr_poly
		(pts
			(arc
				(start 214.730584 -6.255004)
				(mid 214.410544 -6.255004)
				(end 214.730584 -6.255004)
			)
		)
		(stroke
			(width 0)
			(type solid)
		)
		(fill yes)
		(layer "F.Cu")
		(net "DELTA_L_GND_1")
	)
	(gr_poly
		(pts
			(arc
				(start 214.730584 -3.899408)
				(mid 214.410544 -3.899408)
				(end 214.730584 -3.899408)
			)
		)
		(stroke
			(width 0)
			(type solid)
		)
		(fill yes)
		(layer "F.Cu")
		(net "DELTA_L_GND_1")
	)
	(gr_poly
		(pts
			(arc
				(start 214.730584 -1.359408)
				(mid 214.410544 -1.359408)
				(end 214.730584 -1.359408)
			)
		)
		(stroke
			(width 0)
			(type solid)
		)
		(fill yes)
		(layer "F.Cu")
		(net "DELTA_L_GND_1")
	)
	(gr_poly
		(pts
			(arc
				(start 214.730584 1.364996)
				(mid 214.410544 1.364996)
				(end 214.730584 1.364996)
			)
		)
		(stroke
			(width 0)
			(type solid)
		)
		(fill yes)
		(layer "F.Cu")
		(net "DELTA_L_GND_1")
	)
	(gr_poly
		(pts
			(arc
				(start 214.730584 3.904996)
				(mid 214.410544 3.904996)
				(end 214.730584 3.904996)
			)
		)
		(stroke
			(width 0)
			(type solid)
		)
		(fill yes)
		(layer "F.Cu")
		(net "DELTA_L_GND_1")
	)
	(gr_poly
		(pts
			(arc
				(start 214.730584 6.260592)
				(mid 214.410544 6.260592)
				(end 214.730584 6.260592)
			)
		)
		(stroke
			(width 0)
			(type solid)
		)
		(fill yes)
		(layer "F.Cu")
		(net "DELTA_L_GND_1")
	)
	(gr_poly
		(pts
			(arc
				(start 270.309594 -364.715806)
				(mid 270.320705 -364.699272)
				(end 270.32458 -364.679738)
			)
			(arc
				(start 270.32458 -351.788222)
				(mid 270.320679 -351.768699)
				(end 270.309594 -351.752154)
			)
			(arc
				(start 270.250666 -351.693226)
				(mid 270.234132 -351.682115)
				(end 270.214598 -351.67824)
			)
			(arc
				(start 269.083282 -351.67824)
				(mid 269.063759 -351.682141)
				(end 269.047214 -351.693226)
			)
			(arc
				(start 268.416786 -352.323654)
				(mid 268.405675 -352.340188)
				(end 268.4018 -352.359722)
			)
			(arc
				(start 268.4018 -364.395258)
				(mid 268.405701 -364.414781)
				(end 268.416786 -364.431326)
			)
			(arc
				(start 268.686534 -364.701074)
				(mid 268.703068 -364.712185)
				(end 268.722602 -364.71606)
			)
			(xy 270.30934 -364.71606)
		)
		(stroke
			(width 0)
			(type solid)
		)
		(fill yes)
		(layer "F.Cu")
		(net "P5V_AUX")
	)
	(gr_poly
		(pts
			(arc
				(start 298.599352 -6.255004)
				(mid 298.279312 -6.255004)
				(end 298.599352 -6.255004)
			)
		)
		(stroke
			(width 0)
			(type solid)
		)
		(fill yes)
		(layer "F.Cu")
		(net "DELTA_L_GND_1")
	)
	(gr_poly
		(pts
			(arc
				(start 298.599352 -3.899408)
				(mid 298.279312 -3.899408)
				(end 298.599352 -3.899408)
			)
		)
		(stroke
			(width 0)
			(type solid)
		)
		(fill yes)
		(layer "F.Cu")
		(net "DELTA_L_GND_1")
	)
	(gr_poly
		(pts
			(arc
				(start 298.599352 -1.359408)
				(mid 298.279312 -1.359408)
				(end 298.599352 -1.359408)
			)
		)
		(stroke
			(width 0)
			(type solid)
		)
		(fill yes)
		(layer "F.Cu")
		(net "DELTA_L_GND_1")
	)
	(gr_poly
		(pts
			(arc
				(start 298.599352 1.364996)
				(mid 298.279312 1.364996)
				(end 298.599352 1.364996)
			)
		)
		(stroke
			(width 0)
			(type solid)
		)
		(fill yes)
		(layer "F.Cu")
		(net "DELTA_L_GND_1")
	)
	(gr_poly
		(pts
			(arc
				(start 298.599352 3.904996)
				(mid 298.279312 3.904996)
				(end 298.599352 3.904996)
			)
		)
		(stroke
			(width 0)
			(type solid)
		)
		(fill yes)
		(layer "F.Cu")
		(net "DELTA_L_GND_1")
	)
	(gr_poly
		(pts
			(arc
				(start 298.599352 6.260592)
				(mid 298.279312 6.260592)
				(end 298.599352 6.260592)
			)
		)
		(stroke
			(width 0)
			(type solid)
		)
		(fill yes)
		(layer "F.Cu")
		(net "DELTA_L_GND_1")
	)
	(gr_poly
		(pts
			(arc
				(start 317.224664 -3.715004)
				(mid 316.904624 -3.715004)
				(end 317.224664 -3.715004)
			)
		)
		(stroke
			(width 0)
			(type solid)
		)
		(fill yes)
		(layer "F.Cu")
		(net "DELTA_L_GND_1")
	)
	(gr_poly
		(pts
			(arc
				(start 317.224664 -1.359408)
				(mid 316.904624 -1.359408)
				(end 317.224664 -1.359408)
			)
		)
		(stroke
			(width 0)
			(type solid)
		)
		(fill yes)
		(layer "F.Cu")
		(net "DELTA_L_GND_1")
	)
	(gr_poly
		(pts
			(arc
				(start 317.224664 1.180592)
				(mid 316.904624 1.180592)
				(end 317.224664 1.180592)
			)
		)
		(stroke
			(width 0)
			(type solid)
		)
		(fill yes)
		(layer "F.Cu")
		(net "DELTA_L_GND_1")
	)
	(gr_poly
		(pts
			(arc
				(start 317.224664 3.904996)
				(mid 316.904624 3.904996)
				(end 317.224664 3.904996)
			)
		)
		(stroke
			(width 0)
			(type solid)
		)
		(fill yes)
		(layer "F.Cu")
		(net "DELTA_L_GND_1")
	)
	(gr_poly
		(pts
			(arc
				(start 317.224664 6.444996)
				(mid 316.904624 6.444996)
				(end 317.224664 6.444996)
			)
		)
		(stroke
			(width 0)
			(type solid)
		)
		(fill yes)
		(layer "F.Cu")
		(net "DELTA_L_GND_1")
	)
	(gr_poly
		(pts
			(arc
				(start 317.224664 8.800592)
				(mid 316.904624 8.800592)
				(end 317.224664 8.800592)
			)
		)
		(stroke
			(width 0)
			(type solid)
		)
		(fill yes)
		(layer "F.Cu")
		(net "DELTA_L_GND_1")
	)
	(gr_poly
		(pts
			(arc
				(start 364.349538 -3.715004)
				(mid 364.029498 -3.715004)
				(end 364.349538 -3.715004)
			)
		)
		(stroke
			(width 0)
			(type solid)
		)
		(fill yes)
		(layer "F.Cu")
		(net "DELTA_L_GND_1")
	)
	(gr_poly
		(pts
			(arc
				(start 364.349538 -1.359408)
				(mid 364.029498 -1.359408)
				(end 364.349538 -1.359408)
			)
		)
		(stroke
			(width 0)
			(type solid)
		)
		(fill yes)
		(layer "F.Cu")
		(net "DELTA_L_GND_1")
	)
	(gr_poly
		(pts
			(arc
				(start 364.349538 1.180592)
				(mid 364.029498 1.180592)
				(end 364.349538 1.180592)
			)
		)
		(stroke
			(width 0)
			(type solid)
		)
		(fill yes)
		(layer "F.Cu")
		(net "DELTA_L_GND_1")
	)
	(gr_poly
		(pts
			(arc
				(start 364.349538 3.904996)
				(mid 364.029498 3.904996)
				(end 364.349538 3.904996)
			)
		)
		(stroke
			(width 0)
			(type solid)
		)
		(fill yes)
		(layer "F.Cu")
		(net "DELTA_L_GND_1")
	)
	(gr_poly
		(pts
			(arc
				(start 364.349538 6.444996)
				(mid 364.029498 6.444996)
				(end 364.349538 6.444996)
			)
		)
		(stroke
			(width 0)
			(type solid)
		)
		(fill yes)
		(layer "F.Cu")
		(net "DELTA_L_GND_1")
	)
	(gr_poly
		(pts
			(arc
				(start 364.349538 8.800592)
				(mid 364.029498 8.800592)
				(end 364.349538 8.800592)
			)
		)
		(stroke
			(width 0)
			(type solid)
		)
		(fill yes)
		(layer "F.Cu")
		(net "DELTA_L_GND_1")
	)
	(gr_poly
		(pts
			(arc
				(start 391.72134 4.97205)
				(mid 391.4013 4.97205)
				(end 391.72134 4.97205)
			)
		)
		(stroke
			(width 0)
			(type solid)
		)
		(fill yes)
		(layer "F.Cu")
		(net "DELTA_L_GND_1")
	)
	(gr_poly
		(pts
			(arc
				(start 391.72134 7.327646)
				(mid 391.4013 7.327646)
				(end 391.72134 7.327646)
			)
		)
		(stroke
			(width 0)
			(type solid)
		)
		(fill yes)
		(layer "F.Cu")
		(net "DELTA_L_GND_1")
	)
	(gr_poly
		(pts
			(arc
				(start 391.72134 9.867646)
				(mid 391.4013 9.867646)
				(end 391.72134 9.867646)
			)
		)
		(stroke
			(width 0)
			(type solid)
		)
		(fill yes)
		(layer "F.Cu")
		(net "DELTA_L_GND_1")
	)
	(gr_poly
		(pts
			(xy 437.08828 -108.039408) (xy 437.08828 -107.353608) (xy 437.09082 -107.351068) (xy 437.100726 -107.36072)
			(xy 437.100726 -104.69499) (xy 434.065172 -104.69499) (xy 434.020722 -104.73944) (xy 433.493672 -104.73944)
			(xy 433.448968 -104.69499) (xy 431.033936 -104.69499) (xy 430.962816 -104.76611) (xy 430.962816 -104.88041)
			(xy 431.016156 -104.93375) (xy 432.669696 -104.93375) (xy 432.938936 -105.20299) (xy 432.938936 -105.51795)
			(xy 432.748436 -105.70845) (xy 431.513996 -105.70845) (xy 431.465736 -105.75671) (xy 431.465736 -105.91419)
			(xy 431.498756 -105.94721) (xy 433.871116 -105.94721) (xy 434.214524 -106.290364) (xy 435.872636 -106.290364)
			(xy 436.000652 -106.41838) (xy 436.09768 -106.515408) (xy 436.09768 -108.014008) (xy 436.25008 -108.166408)
			(xy 436.96128 -108.166408)
		)
		(stroke
			(width 0)
			(type solid)
		)
		(fill yes)
		(layer "F.Cu")
		(net "P3V3_AUX")
	)
	(gr_poly
		(pts
			(arc
				(start 438.846214 4.97205)
				(mid 438.526174 4.97205)
				(end 438.846214 4.97205)
			)
		)
		(stroke
			(width 0)
			(type solid)
		)
		(fill yes)
		(layer "F.Cu")
		(net "DELTA_L_GND_1")
	)
	(gr_poly
		(pts
			(arc
				(start 438.846214 7.327646)
				(mid 438.526174 7.327646)
				(end 438.846214 7.327646)
			)
		)
		(stroke
			(width 0)
			(type solid)
		)
		(fill yes)
		(layer "F.Cu")
		(net "DELTA_L_GND_1")
	)
	(gr_poly
		(pts
			(arc
				(start 438.846214 9.867646)
				(mid 438.526174 9.867646)
				(end 438.846214 9.867646)
			)
		)
		(stroke
			(width 0)
			(type solid)
		)
		(fill yes)
		(layer "F.Cu")
		(net "DELTA_L_GND_1")
	)
	(gr_poly
		(pts
			(arc
				(start 9.273032 -179.254912)
				(mid 8.939784 -179.254912)
				(end 9.273032 -179.254912)
			)
		)
		(stroke
			(width 0)
			(type solid)
		)
		(fill yes)
		(layer "F.Cu")
		(net "GND")
	)
	(gr_poly
		(pts
			(arc
				(start 9.273032 -177.119788)
				(mid 8.939784 -177.119788)
				(end 9.273032 -177.119788)
			)
		)
		(stroke
			(width 0)
			(type solid)
		)
		(fill yes)
		(layer "F.Cu")
		(net "GND")
	)
	(gr_poly
		(pts
			(arc
				(start 9.273032 -176.484788)
				(mid 8.939784 -176.484788)
				(end 9.273032 -176.484788)
			)
		)
		(stroke
			(width 0)
			(type solid)
		)
		(fill yes)
		(layer "F.Cu")
		(net "GND")
	)
	(gr_poly
		(pts
			(arc
				(start 9.273032 -174.34814)
				(mid 8.939784 -174.34814)
				(end 9.273032 -174.34814)
			)
		)
		(stroke
			(width 0)
			(type solid)
		)
		(fill yes)
		(layer "F.Cu")
		(net "GND")
	)
	(gr_poly
		(pts
			(arc
				(start 9.273032 -173.71314)
				(mid 8.939784 -173.71314)
				(end 9.273032 -173.71314)
			)
		)
		(stroke
			(width 0)
			(type solid)
		)
		(fill yes)
		(layer "F.Cu")
		(net "GND")
	)
	(gr_poly
		(pts
			(arc
				(start 9.273032 -171.57954)
				(mid 8.939784 -171.57954)
				(end 9.273032 -171.57954)
			)
		)
		(stroke
			(width 0)
			(type solid)
		)
		(fill yes)
		(layer "F.Cu")
		(net "GND")
	)
	(gr_poly
		(pts
			(arc
				(start 9.273032 -170.94454)
				(mid 8.939784 -170.94454)
				(end 9.273032 -170.94454)
			)
		)
		(stroke
			(width 0)
			(type solid)
		)
		(fill yes)
		(layer "F.Cu")
		(net "GND")
	)
	(gr_poly
		(pts
			(arc
				(start 9.273032 -168.77792)
				(mid 8.939784 -168.77792)
				(end 9.273032 -168.77792)
			)
		)
		(stroke
			(width 0)
			(type solid)
		)
		(fill yes)
		(layer "F.Cu")
		(net "GND")
	)
	(gr_poly
		(pts
			(arc
				(start 14.528292 -149.738334)
				(mid 14.195044 -149.738334)
				(end 14.528292 -149.738334)
			)
		)
		(stroke
			(width 0)
			(type solid)
		)
		(fill yes)
		(layer "F.Cu")
		(net "GND")
	)
	(gr_poly
		(pts
			(arc
				(start 16.657066 -314.210446)
				(mid 16.323818 -314.210446)
				(end 16.657066 -314.210446)
			)
		)
		(stroke
			(width 0)
			(type solid)
		)
		(fill yes)
		(layer "F.Cu")
		(net "GND")
	)
	(gr_poly
		(pts
			(arc
				(start 16.657066 -304.860452)
				(mid 16.323818 -304.860452)
				(end 16.657066 -304.860452)
			)
		)
		(stroke
			(width 0)
			(type solid)
		)
		(fill yes)
		(layer "F.Cu")
		(net "GND")
	)
	(gr_poly
		(pts
			(arc
				(start 16.657066 -295.510458)
				(mid 16.323818 -295.510458)
				(end 16.657066 -295.510458)
			)
		)
		(stroke
			(width 0)
			(type solid)
		)
		(fill yes)
		(layer "F.Cu")
		(net "GND")
	)
	(gr_poly
		(pts
			(arc
				(start 16.657066 -286.160464)
				(mid 16.323818 -286.160464)
				(end 16.657066 -286.160464)
			)
		)
		(stroke
			(width 0)
			(type solid)
		)
		(fill yes)
		(layer "F.Cu")
		(net "GND")
	)
	(gr_poly
		(pts
			(arc
				(start 16.657066 -276.81047)
				(mid 16.323818 -276.81047)
				(end 16.657066 -276.81047)
			)
		)
		(stroke
			(width 0)
			(type solid)
		)
		(fill yes)
		(layer "F.Cu")
		(net "GND")
	)
	(gr_poly
		(pts
			(arc
				(start 16.657066 -239.410494)
				(mid 16.323818 -239.410494)
				(end 16.657066 -239.410494)
			)
		)
		(stroke
			(width 0)
			(type solid)
		)
		(fill yes)
		(layer "F.Cu")
		(net "GND")
	)
	(gr_poly
		(pts
			(arc
				(start 16.657066 -230.0605)
				(mid 16.323818 -230.0605)
				(end 16.657066 -230.0605)
			)
		)
		(stroke
			(width 0)
			(type solid)
		)
		(fill yes)
		(layer "F.Cu")
		(net "GND")
	)
	(gr_poly
		(pts
			(arc
				(start 16.657066 -220.710252)
				(mid 16.323818 -220.710252)
				(end 16.657066 -220.710252)
			)
		)
		(stroke
			(width 0)
			(type solid)
		)
		(fill yes)
		(layer "F.Cu")
		(net "GND")
	)
	(gr_poly
		(pts
			(arc
				(start 16.657066 -211.360258)
				(mid 16.323818 -211.360258)
				(end 16.657066 -211.360258)
			)
		)
		(stroke
			(width 0)
			(type solid)
		)
		(fill yes)
		(layer "F.Cu")
		(net "GND")
	)
	(gr_poly
		(pts
			(arc
				(start 16.657066 -202.010264)
				(mid 16.323818 -202.010264)
				(end 16.657066 -202.010264)
			)
		)
		(stroke
			(width 0)
			(type solid)
		)
		(fill yes)
		(layer "F.Cu")
		(net "GND")
	)
	(gr_poly
		(pts
			(arc
				(start 19.910806 -138.293856)
				(mid 19.577558 -138.293856)
				(end 19.910806 -138.293856)
			)
		)
		(stroke
			(width 0)
			(type solid)
		)
		(fill yes)
		(layer "F.Cu")
		(net "GND")
	)
	(gr_poly
		(pts
			(arc
				(start 19.910806 -133.798056)
				(mid 19.577558 -133.798056)
				(end 19.910806 -133.798056)
			)
		)
		(stroke
			(width 0)
			(type solid)
		)
		(fill yes)
		(layer "F.Cu")
		(net "GND")
	)
	(gr_poly
		(pts
			(arc
				(start 19.925284 -136.603232)
				(mid 19.592036 -136.603232)
				(end 19.925284 -136.603232)
			)
		)
		(stroke
			(width 0)
			(type solid)
		)
		(fill yes)
		(layer "F.Cu")
		(net "GND")
	)
	(gr_poly
		(pts
			(arc
				(start 19.925284 -132.107432)
				(mid 19.592036 -132.107432)
				(end 19.925284 -132.107432)
			)
		)
		(stroke
			(width 0)
			(type solid)
		)
		(fill yes)
		(layer "F.Cu")
		(net "GND")
	)
	(gr_poly
		(pts
			(arc
				(start 20.757134 -313.360308)
				(mid 20.423886 -313.360308)
				(end 20.757134 -313.360308)
			)
		)
		(stroke
			(width 0)
			(type solid)
		)
		(fill yes)
		(layer "F.Cu")
		(net "GND")
	)
	(gr_poly
		(pts
			(arc
				(start 20.757134 -285.310326)
				(mid 20.423886 -285.310326)
				(end 20.757134 -285.310326)
			)
		)
		(stroke
			(width 0)
			(type solid)
		)
		(fill yes)
		(layer "F.Cu")
		(net "GND")
	)
	(gr_poly
		(pts
			(arc
				(start 20.757134 -275.960332)
				(mid 20.423886 -275.960332)
				(end 20.757134 -275.960332)
			)
		)
		(stroke
			(width 0)
			(type solid)
		)
		(fill yes)
		(layer "F.Cu")
		(net "GND")
	)
	(gr_poly
		(pts
			(arc
				(start 20.757134 -238.560356)
				(mid 20.423886 -238.560356)
				(end 20.757134 -238.560356)
			)
		)
		(stroke
			(width 0)
			(type solid)
		)
		(fill yes)
		(layer "F.Cu")
		(net "GND")
	)
	(gr_poly
		(pts
			(arc
				(start 20.757134 -229.210362)
				(mid 20.423886 -229.210362)
				(end 20.757134 -229.210362)
			)
		)
		(stroke
			(width 0)
			(type solid)
		)
		(fill yes)
		(layer "F.Cu")
		(net "GND")
	)
	(gr_poly
		(pts
			(arc
				(start 20.757134 -219.860368)
				(mid 20.423886 -219.860368)
				(end 20.757134 -219.860368)
			)
		)
		(stroke
			(width 0)
			(type solid)
		)
		(fill yes)
		(layer "F.Cu")
		(net "GND")
	)
	(gr_poly
		(pts
			(arc
				(start 20.757134 -210.510374)
				(mid 20.423886 -210.510374)
				(end 20.757134 -210.510374)
			)
		)
		(stroke
			(width 0)
			(type solid)
		)
		(fill yes)
		(layer "F.Cu")
		(net "GND")
	)
	(gr_poly
		(pts
			(arc
				(start 20.757134 -201.16038)
				(mid 20.423886 -201.16038)
				(end 20.757134 -201.16038)
			)
		)
		(stroke
			(width 0)
			(type solid)
		)
		(fill yes)
		(layer "F.Cu")
		(net "GND")
	)
	(gr_poly
		(pts
			(arc
				(start 24.20112 -314.210446)
				(mid 23.867872 -314.210446)
				(end 24.20112 -314.210446)
			)
		)
		(stroke
			(width 0)
			(type solid)
		)
		(fill yes)
		(layer "F.Cu")
		(net "GND")
	)
	(gr_poly
		(pts
			(arc
				(start 24.20112 -304.860452)
				(mid 23.867872 -304.860452)
				(end 24.20112 -304.860452)
			)
		)
		(stroke
			(width 0)
			(type solid)
		)
		(fill yes)
		(layer "F.Cu")
		(net "GND")
	)
	(gr_poly
		(pts
			(arc
				(start 24.20112 -295.510458)
				(mid 23.867872 -295.510458)
				(end 24.20112 -295.510458)
			)
		)
		(stroke
			(width 0)
			(type solid)
		)
		(fill yes)
		(layer "F.Cu")
		(net "GND")
	)
	(gr_poly
		(pts
			(arc
				(start 24.20112 -286.160464)
				(mid 23.867872 -286.160464)
				(end 24.20112 -286.160464)
			)
		)
		(stroke
			(width 0)
			(type solid)
		)
		(fill yes)
		(layer "F.Cu")
		(net "GND")
	)
	(gr_poly
		(pts
			(arc
				(start 24.20112 -276.81047)
				(mid 23.867872 -276.81047)
				(end 24.20112 -276.81047)
			)
		)
		(stroke
			(width 0)
			(type solid)
		)
		(fill yes)
		(layer "F.Cu")
		(net "GND")
	)
	(gr_poly
		(pts
			(arc
				(start 24.20112 -239.410494)
				(mid 23.867872 -239.410494)
				(end 24.20112 -239.410494)
			)
		)
		(stroke
			(width 0)
			(type solid)
		)
		(fill yes)
		(layer "F.Cu")
		(net "GND")
	)
	(gr_poly
		(pts
			(arc
				(start 24.20112 -230.0605)
				(mid 23.867872 -230.0605)
				(end 24.20112 -230.0605)
			)
		)
		(stroke
			(width 0)
			(type solid)
		)
		(fill yes)
		(layer "F.Cu")
		(net "GND")
	)
	(gr_poly
		(pts
			(arc
				(start 24.20112 -220.710252)
				(mid 23.867872 -220.710252)
				(end 24.20112 -220.710252)
			)
		)
		(stroke
			(width 0)
			(type solid)
		)
		(fill yes)
		(layer "F.Cu")
		(net "GND")
	)
	(gr_poly
		(pts
			(arc
				(start 24.20112 -211.360258)
				(mid 23.867872 -211.360258)
				(end 24.20112 -211.360258)
			)
		)
		(stroke
			(width 0)
			(type solid)
		)
		(fill yes)
		(layer "F.Cu")
		(net "GND")
	)
	(gr_poly
		(pts
			(arc
				(start 24.20112 -202.010264)
				(mid 23.867872 -202.010264)
				(end 24.20112 -202.010264)
			)
		)
		(stroke
			(width 0)
			(type solid)
		)
		(fill yes)
		(layer "F.Cu")
		(net "GND")
	)
	(gr_poly
		(pts
			(arc
				(start 28.301188 -313.360308)
				(mid 27.96794 -313.360308)
				(end 28.301188 -313.360308)
			)
		)
		(stroke
			(width 0)
			(type solid)
		)
		(fill yes)
		(layer "F.Cu")
		(net "GND")
	)
	(gr_poly
		(pts
			(arc
				(start 28.301188 -285.310326)
				(mid 27.96794 -285.310326)
				(end 28.301188 -285.310326)
			)
		)
		(stroke
			(width 0)
			(type solid)
		)
		(fill yes)
		(layer "F.Cu")
		(net "GND")
	)
	(gr_poly
		(pts
			(arc
				(start 28.301188 -275.960332)
				(mid 27.96794 -275.960332)
				(end 28.301188 -275.960332)
			)
		)
		(stroke
			(width 0)
			(type solid)
		)
		(fill yes)
		(layer "F.Cu")
		(net "GND")
	)
	(gr_poly
		(pts
			(arc
				(start 28.301188 -238.560356)
				(mid 27.96794 -238.560356)
				(end 28.301188 -238.560356)
			)
		)
		(stroke
			(width 0)
			(type solid)
		)
		(fill yes)
		(layer "F.Cu")
		(net "GND")
	)
	(gr_poly
		(pts
			(arc
				(start 28.301188 -229.210362)
				(mid 27.96794 -229.210362)
				(end 28.301188 -229.210362)
			)
		)
		(stroke
			(width 0)
			(type solid)
		)
		(fill yes)
		(layer "F.Cu")
		(net "GND")
	)
	(gr_poly
		(pts
			(arc
				(start 28.301188 -219.860368)
				(mid 27.96794 -219.860368)
				(end 28.301188 -219.860368)
			)
		)
		(stroke
			(width 0)
			(type solid)
		)
		(fill yes)
		(layer "F.Cu")
		(net "GND")
	)
	(gr_poly
		(pts
			(arc
				(start 28.301188 -210.510374)
				(mid 27.96794 -210.510374)
				(end 28.301188 -210.510374)
			)
		)
		(stroke
			(width 0)
			(type solid)
		)
		(fill yes)
		(layer "F.Cu")
		(net "GND")
	)
	(gr_poly
		(pts
			(arc
				(start 28.301188 -201.16038)
				(mid 27.96794 -201.16038)
				(end 28.301188 -201.16038)
			)
		)
		(stroke
			(width 0)
			(type solid)
		)
		(fill yes)
		(layer "F.Cu")
		(net "GND")
	)
	(gr_poly
		(pts
			(arc
				(start 31.74492 -314.210446)
				(mid 31.411672 -314.210446)
				(end 31.74492 -314.210446)
			)
		)
		(stroke
			(width 0)
			(type solid)
		)
		(fill yes)
		(layer "F.Cu")
		(net "GND")
	)
	(gr_poly
		(pts
			(arc
				(start 31.74492 -304.860452)
				(mid 31.411672 -304.860452)
				(end 31.74492 -304.860452)
			)
		)
		(stroke
			(width 0)
			(type solid)
		)
		(fill yes)
		(layer "F.Cu")
		(net "GND")
	)
	(gr_poly
		(pts
			(arc
				(start 31.74492 -295.510458)
				(mid 31.411672 -295.510458)
				(end 31.74492 -295.510458)
			)
		)
		(stroke
			(width 0)
			(type solid)
		)
		(fill yes)
		(layer "F.Cu")
		(net "GND")
	)
	(gr_poly
		(pts
			(arc
				(start 31.74492 -286.160464)
				(mid 31.411672 -286.160464)
				(end 31.74492 -286.160464)
			)
		)
		(stroke
			(width 0)
			(type solid)
		)
		(fill yes)
		(layer "F.Cu")
		(net "GND")
	)
	(gr_poly
		(pts
			(arc
				(start 31.74492 -276.81047)
				(mid 31.411672 -276.81047)
				(end 31.74492 -276.81047)
			)
		)
		(stroke
			(width 0)
			(type solid)
		)
		(fill yes)
		(layer "F.Cu")
		(net "GND")
	)
	(gr_poly
		(pts
			(arc
				(start 31.74492 -239.410494)
				(mid 31.411672 -239.410494)
				(end 31.74492 -239.410494)
			)
		)
		(stroke
			(width 0)
			(type solid)
		)
		(fill yes)
		(layer "F.Cu")
		(net "GND")
	)
	(gr_poly
		(pts
			(arc
				(start 31.74492 -230.0605)
				(mid 31.411672 -230.0605)
				(end 31.74492 -230.0605)
			)
		)
		(stroke
			(width 0)
			(type solid)
		)
		(fill yes)
		(layer "F.Cu")
		(net "GND")
	)
	(gr_poly
		(pts
			(arc
				(start 31.74492 -220.710252)
				(mid 31.411672 -220.710252)
				(end 31.74492 -220.710252)
			)
		)
		(stroke
			(width 0)
			(type solid)
		)
		(fill yes)
		(layer "F.Cu")
		(net "GND")
	)
	(gr_poly
		(pts
			(arc
				(start 31.74492 -211.360258)
				(mid 31.411672 -211.360258)
				(end 31.74492 -211.360258)
			)
		)
		(stroke
			(width 0)
			(type solid)
		)
		(fill yes)
		(layer "F.Cu")
		(net "GND")
	)
	(gr_poly
		(pts
			(arc
				(start 31.74492 -202.010264)
				(mid 31.411672 -202.010264)
				(end 31.74492 -202.010264)
			)
		)
		(stroke
			(width 0)
			(type solid)
		)
		(fill yes)
		(layer "F.Cu")
		(net "GND")
	)
	(gr_poly
		(pts
			(arc
				(start 35.844988 -313.360308)
				(mid 35.51174 -313.360308)
				(end 35.844988 -313.360308)
			)
		)
		(stroke
			(width 0)
			(type solid)
		)
		(fill yes)
		(layer "F.Cu")
		(net "GND")
	)
	(gr_poly
		(pts
			(arc
				(start 35.844988 -275.960332)
				(mid 35.51174 -275.960332)
				(end 35.844988 -275.960332)
			)
		)
		(stroke
			(width 0)
			(type solid)
		)
		(fill yes)
		(layer "F.Cu")
		(net "GND")
	)
	(gr_poly
		(pts
			(arc
				(start 35.844988 -238.560356)
				(mid 35.51174 -238.560356)
				(end 35.844988 -238.560356)
			)
		)
		(stroke
			(width 0)
			(type solid)
		)
		(fill yes)
		(layer "F.Cu")
		(net "GND")
	)
	(gr_poly
		(pts
			(arc
				(start 35.844988 -229.210362)
				(mid 35.51174 -229.210362)
				(end 35.844988 -229.210362)
			)
		)
		(stroke
			(width 0)
			(type solid)
		)
		(fill yes)
		(layer "F.Cu")
		(net "GND")
	)
	(gr_poly
		(pts
			(arc
				(start 35.844988 -219.860368)
				(mid 35.51174 -219.860368)
				(end 35.844988 -219.860368)
			)
		)
		(stroke
			(width 0)
			(type solid)
		)
		(fill yes)
		(layer "F.Cu")
		(net "GND")
	)
	(gr_poly
		(pts
			(arc
				(start 35.844988 -210.510374)
				(mid 35.51174 -210.510374)
				(end 35.844988 -210.510374)
			)
		)
		(stroke
			(width 0)
			(type solid)
		)
		(fill yes)
		(layer "F.Cu")
		(net "GND")
	)
	(gr_poly
		(pts
			(arc
				(start 35.844988 -201.16038)
				(mid 35.51174 -201.16038)
				(end 35.844988 -201.16038)
			)
		)
		(stroke
			(width 0)
			(type solid)
		)
		(fill yes)
		(layer "F.Cu")
		(net "GND")
	)
	(gr_poly
		(pts
			(arc
				(start 39.288974 -314.210446)
				(mid 38.955726 -314.210446)
				(end 39.288974 -314.210446)
			)
		)
		(stroke
			(width 0)
			(type solid)
		)
		(fill yes)
		(layer "F.Cu")
		(net "GND")
	)
	(gr_poly
		(pts
			(arc
				(start 39.288974 -304.860452)
				(mid 38.955726 -304.860452)
				(end 39.288974 -304.860452)
			)
		)
		(stroke
			(width 0)
			(type solid)
		)
		(fill yes)
		(layer "F.Cu")
		(net "GND")
	)
	(gr_poly
		(pts
			(arc
				(start 39.288974 -295.510458)
				(mid 38.955726 -295.510458)
				(end 39.288974 -295.510458)
			)
		)
		(stroke
			(width 0)
			(type solid)
		)
		(fill yes)
		(layer "F.Cu")
		(net "GND")
	)
	(gr_poly
		(pts
			(arc
				(start 39.288974 -286.160464)
				(mid 38.955726 -286.160464)
				(end 39.288974 -286.160464)
			)
		)
		(stroke
			(width 0)
			(type solid)
		)
		(fill yes)
		(layer "F.Cu")
		(net "GND")
	)
	(gr_poly
		(pts
			(arc
				(start 39.288974 -276.81047)
				(mid 38.955726 -276.81047)
				(end 39.288974 -276.81047)
			)
		)
		(stroke
			(width 0)
			(type solid)
		)
		(fill yes)
		(layer "F.Cu")
		(net "GND")
	)
	(gr_poly
		(pts
			(arc
				(start 39.288974 -239.410494)
				(mid 38.955726 -239.410494)
				(end 39.288974 -239.410494)
			)
		)
		(stroke
			(width 0)
			(type solid)
		)
		(fill yes)
		(layer "F.Cu")
		(net "GND")
	)
	(gr_poly
		(pts
			(arc
				(start 39.288974 -230.0605)
				(mid 38.955726 -230.0605)
				(end 39.288974 -230.0605)
			)
		)
		(stroke
			(width 0)
			(type solid)
		)
		(fill yes)
		(layer "F.Cu")
		(net "GND")
	)
	(gr_poly
		(pts
			(arc
				(start 39.288974 -220.710252)
				(mid 38.955726 -220.710252)
				(end 39.288974 -220.710252)
			)
		)
		(stroke
			(width 0)
			(type solid)
		)
		(fill yes)
		(layer "F.Cu")
		(net "GND")
	)
	(gr_poly
		(pts
			(arc
				(start 39.288974 -211.360258)
				(mid 38.955726 -211.360258)
				(end 39.288974 -211.360258)
			)
		)
		(stroke
			(width 0)
			(type solid)
		)
		(fill yes)
		(layer "F.Cu")
		(net "GND")
	)
	(gr_poly
		(pts
			(arc
				(start 39.288974 -202.010264)
				(mid 38.955726 -202.010264)
				(end 39.288974 -202.010264)
			)
		)
		(stroke
			(width 0)
			(type solid)
		)
		(fill yes)
		(layer "F.Cu")
		(net "GND")
	)
	(gr_poly
		(pts
			(arc
				(start 43.389042 -313.360308)
				(mid 43.055794 -313.360308)
				(end 43.389042 -313.360308)
			)
		)
		(stroke
			(width 0)
			(type solid)
		)
		(fill yes)
		(layer "F.Cu")
		(net "GND")
	)
	(gr_poly
		(pts
			(arc
				(start 43.389042 -275.960332)
				(mid 43.055794 -275.960332)
				(end 43.389042 -275.960332)
			)
		)
		(stroke
			(width 0)
			(type solid)
		)
		(fill yes)
		(layer "F.Cu")
		(net "GND")
	)
	(gr_poly
		(pts
			(arc
				(start 43.389042 -238.560356)
				(mid 43.055794 -238.560356)
				(end 43.389042 -238.560356)
			)
		)
		(stroke
			(width 0)
			(type solid)
		)
		(fill yes)
		(layer "F.Cu")
		(net "GND")
	)
	(gr_poly
		(pts
			(arc
				(start 43.389042 -229.210362)
				(mid 43.055794 -229.210362)
				(end 43.389042 -229.210362)
			)
		)
		(stroke
			(width 0)
			(type solid)
		)
		(fill yes)
		(layer "F.Cu")
		(net "GND")
	)
	(gr_poly
		(pts
			(arc
				(start 43.389042 -219.860368)
				(mid 43.055794 -219.860368)
				(end 43.389042 -219.860368)
			)
		)
		(stroke
			(width 0)
			(type solid)
		)
		(fill yes)
		(layer "F.Cu")
		(net "GND")
	)
	(gr_poly
		(pts
			(arc
				(start 43.389042 -210.510374)
				(mid 43.055794 -210.510374)
				(end 43.389042 -210.510374)
			)
		)
		(stroke
			(width 0)
			(type solid)
		)
		(fill yes)
		(layer "F.Cu")
		(net "GND")
	)
	(gr_poly
		(pts
			(arc
				(start 43.389042 -201.16038)
				(mid 43.055794 -201.16038)
				(end 43.389042 -201.16038)
			)
		)
		(stroke
			(width 0)
			(type solid)
		)
		(fill yes)
		(layer "F.Cu")
		(net "GND")
	)
	(gr_poly
		(pts
			(arc
				(start 46.833028 -314.210446)
				(mid 46.49978 -314.210446)
				(end 46.833028 -314.210446)
			)
		)
		(stroke
			(width 0)
			(type solid)
		)
		(fill yes)
		(layer "F.Cu")
		(net "GND")
	)
	(gr_poly
		(pts
			(arc
				(start 46.833028 -304.860452)
				(mid 46.49978 -304.860452)
				(end 46.833028 -304.860452)
			)
		)
		(stroke
			(width 0)
			(type solid)
		)
		(fill yes)
		(layer "F.Cu")
		(net "GND")
	)
	(gr_poly
		(pts
			(arc
				(start 46.833028 -295.510458)
				(mid 46.49978 -295.510458)
				(end 46.833028 -295.510458)
			)
		)
		(stroke
			(width 0)
			(type solid)
		)
		(fill yes)
		(layer "F.Cu")
		(net "GND")
	)
	(gr_poly
		(pts
			(arc
				(start 46.833028 -286.160464)
				(mid 46.49978 -286.160464)
				(end 46.833028 -286.160464)
			)
		)
		(stroke
			(width 0)
			(type solid)
		)
		(fill yes)
		(layer "F.Cu")
		(net "GND")
	)
	(gr_poly
		(pts
			(arc
				(start 46.833028 -276.81047)
				(mid 46.49978 -276.81047)
				(end 46.833028 -276.81047)
			)
		)
		(stroke
			(width 0)
			(type solid)
		)
		(fill yes)
		(layer "F.Cu")
		(net "GND")
	)
	(gr_poly
		(pts
			(arc
				(start 46.833028 -239.410494)
				(mid 46.49978 -239.410494)
				(end 46.833028 -239.410494)
			)
		)
		(stroke
			(width 0)
			(type solid)
		)
		(fill yes)
		(layer "F.Cu")
		(net "GND")
	)
	(gr_poly
		(pts
			(arc
				(start 46.833028 -230.0605)
				(mid 46.49978 -230.0605)
				(end 46.833028 -230.0605)
			)
		)
		(stroke
			(width 0)
			(type solid)
		)
		(fill yes)
		(layer "F.Cu")
		(net "GND")
	)
	(gr_poly
		(pts
			(arc
				(start 46.833028 -220.710252)
				(mid 46.49978 -220.710252)
				(end 46.833028 -220.710252)
			)
		)
		(stroke
			(width 0)
			(type solid)
		)
		(fill yes)
		(layer "F.Cu")
		(net "GND")
	)
	(gr_poly
		(pts
			(arc
				(start 46.833028 -211.360258)
				(mid 46.49978 -211.360258)
				(end 46.833028 -211.360258)
			)
		)
		(stroke
			(width 0)
			(type solid)
		)
		(fill yes)
		(layer "F.Cu")
		(net "GND")
	)
	(gr_poly
		(pts
			(arc
				(start 46.833028 -202.010264)
				(mid 46.49978 -202.010264)
				(end 46.833028 -202.010264)
			)
		)
		(stroke
			(width 0)
			(type solid)
		)
		(fill yes)
		(layer "F.Cu")
		(net "GND")
	)
	(gr_poly
		(pts
			(arc
				(start 50.933096 -313.360308)
				(mid 50.599848 -313.360308)
				(end 50.933096 -313.360308)
			)
		)
		(stroke
			(width 0)
			(type solid)
		)
		(fill yes)
		(layer "F.Cu")
		(net "GND")
	)
	(gr_poly
		(pts
			(arc
				(start 50.933096 -304.010314)
				(mid 50.599848 -304.010314)
				(end 50.933096 -304.010314)
			)
		)
		(stroke
			(width 0)
			(type solid)
		)
		(fill yes)
		(layer "F.Cu")
		(net "GND")
	)
	(gr_poly
		(pts
			(arc
				(start 50.933096 -294.66032)
				(mid 50.599848 -294.66032)
				(end 50.933096 -294.66032)
			)
		)
		(stroke
			(width 0)
			(type solid)
		)
		(fill yes)
		(layer "F.Cu")
		(net "GND")
	)
	(gr_poly
		(pts
			(arc
				(start 50.933096 -285.310326)
				(mid 50.599848 -285.310326)
				(end 50.933096 -285.310326)
			)
		)
		(stroke
			(width 0)
			(type solid)
		)
		(fill yes)
		(layer "F.Cu")
		(net "GND")
	)
	(gr_poly
		(pts
			(arc
				(start 50.933096 -275.960332)
				(mid 50.599848 -275.960332)
				(end 50.933096 -275.960332)
			)
		)
		(stroke
			(width 0)
			(type solid)
		)
		(fill yes)
		(layer "F.Cu")
		(net "GND")
	)
	(gr_poly
		(pts
			(arc
				(start 50.933096 -238.560356)
				(mid 50.599848 -238.560356)
				(end 50.933096 -238.560356)
			)
		)
		(stroke
			(width 0)
			(type solid)
		)
		(fill yes)
		(layer "F.Cu")
		(net "GND")
	)
	(gr_poly
		(pts
			(arc
				(start 50.933096 -229.210362)
				(mid 50.599848 -229.210362)
				(end 50.933096 -229.210362)
			)
		)
		(stroke
			(width 0)
			(type solid)
		)
		(fill yes)
		(layer "F.Cu")
		(net "GND")
	)
	(gr_poly
		(pts
			(arc
				(start 50.933096 -219.860368)
				(mid 50.599848 -219.860368)
				(end 50.933096 -219.860368)
			)
		)
		(stroke
			(width 0)
			(type solid)
		)
		(fill yes)
		(layer "F.Cu")
		(net "GND")
	)
	(gr_poly
		(pts
			(arc
				(start 50.933096 -210.510374)
				(mid 50.599848 -210.510374)
				(end 50.933096 -210.510374)
			)
		)
		(stroke
			(width 0)
			(type solid)
		)
		(fill yes)
		(layer "F.Cu")
		(net "GND")
	)
	(gr_poly
		(pts
			(arc
				(start 50.933096 -201.16038)
				(mid 50.599848 -201.16038)
				(end 50.933096 -201.16038)
			)
		)
		(stroke
			(width 0)
			(type solid)
		)
		(fill yes)
		(layer "F.Cu")
		(net "GND")
	)
	(gr_poly
		(pts
			(arc
				(start 54.377082 -314.210446)
				(mid 54.043834 -314.210446)
				(end 54.377082 -314.210446)
			)
		)
		(stroke
			(width 0)
			(type solid)
		)
		(fill yes)
		(layer "F.Cu")
		(net "GND")
	)
	(gr_poly
		(pts
			(arc
				(start 54.377082 -304.860452)
				(mid 54.043834 -304.860452)
				(end 54.377082 -304.860452)
			)
		)
		(stroke
			(width 0)
			(type solid)
		)
		(fill yes)
		(layer "F.Cu")
		(net "GND")
	)
	(gr_poly
		(pts
			(arc
				(start 54.377082 -295.510458)
				(mid 54.043834 -295.510458)
				(end 54.377082 -295.510458)
			)
		)
		(stroke
			(width 0)
			(type solid)
		)
		(fill yes)
		(layer "F.Cu")
		(net "GND")
	)
	(gr_poly
		(pts
			(arc
				(start 54.377082 -286.160464)
				(mid 54.043834 -286.160464)
				(end 54.377082 -286.160464)
			)
		)
		(stroke
			(width 0)
			(type solid)
		)
		(fill yes)
		(layer "F.Cu")
		(net "GND")
	)
	(gr_poly
		(pts
			(arc
				(start 54.377082 -276.81047)
				(mid 54.043834 -276.81047)
				(end 54.377082 -276.81047)
			)
		)
		(stroke
			(width 0)
			(type solid)
		)
		(fill yes)
		(layer "F.Cu")
		(net "GND")
	)
	(gr_poly
		(pts
			(arc
				(start 54.377082 -239.410494)
				(mid 54.043834 -239.410494)
				(end 54.377082 -239.410494)
			)
		)
		(stroke
			(width 0)
			(type solid)
		)
		(fill yes)
		(layer "F.Cu")
		(net "GND")
	)
	(gr_poly
		(pts
			(arc
				(start 54.377082 -230.0605)
				(mid 54.043834 -230.0605)
				(end 54.377082 -230.0605)
			)
		)
		(stroke
			(width 0)
			(type solid)
		)
		(fill yes)
		(layer "F.Cu")
		(net "GND")
	)
	(gr_poly
		(pts
			(arc
				(start 54.377082 -220.710252)
				(mid 54.043834 -220.710252)
				(end 54.377082 -220.710252)
			)
		)
		(stroke
			(width 0)
			(type solid)
		)
		(fill yes)
		(layer "F.Cu")
		(net "GND")
	)
	(gr_poly
		(pts
			(arc
				(start 54.377082 -211.360258)
				(mid 54.043834 -211.360258)
				(end 54.377082 -211.360258)
			)
		)
		(stroke
			(width 0)
			(type solid)
		)
		(fill yes)
		(layer "F.Cu")
		(net "GND")
	)
	(gr_poly
		(pts
			(arc
				(start 54.377082 -202.010264)
				(mid 54.043834 -202.010264)
				(end 54.377082 -202.010264)
			)
		)
		(stroke
			(width 0)
			(type solid)
		)
		(fill yes)
		(layer "F.Cu")
		(net "GND")
	)
	(gr_poly
		(pts
			(arc
				(start 58.47715 -313.360308)
				(mid 58.143902 -313.360308)
				(end 58.47715 -313.360308)
			)
		)
		(stroke
			(width 0)
			(type solid)
		)
		(fill yes)
		(layer "F.Cu")
		(net "GND")
	)
	(gr_poly
		(pts
			(arc
				(start 58.47715 -304.010314)
				(mid 58.143902 -304.010314)
				(end 58.47715 -304.010314)
			)
		)
		(stroke
			(width 0)
			(type solid)
		)
		(fill yes)
		(layer "F.Cu")
		(net "GND")
	)
	(gr_poly
		(pts
			(arc
				(start 58.47715 -294.66032)
				(mid 58.143902 -294.66032)
				(end 58.47715 -294.66032)
			)
		)
		(stroke
			(width 0)
			(type solid)
		)
		(fill yes)
		(layer "F.Cu")
		(net "GND")
	)
	(gr_poly
		(pts
			(arc
				(start 58.47715 -285.310326)
				(mid 58.143902 -285.310326)
				(end 58.47715 -285.310326)
			)
		)
		(stroke
			(width 0)
			(type solid)
		)
		(fill yes)
		(layer "F.Cu")
		(net "GND")
	)
	(gr_poly
		(pts
			(arc
				(start 58.47715 -275.960332)
				(mid 58.143902 -275.960332)
				(end 58.47715 -275.960332)
			)
		)
		(stroke
			(width 0)
			(type solid)
		)
		(fill yes)
		(layer "F.Cu")
		(net "GND")
	)
	(gr_poly
		(pts
			(arc
				(start 58.47715 -238.560356)
				(mid 58.143902 -238.560356)
				(end 58.47715 -238.560356)
			)
		)
		(stroke
			(width 0)
			(type solid)
		)
		(fill yes)
		(layer "F.Cu")
		(net "GND")
	)
	(gr_poly
		(pts
			(arc
				(start 58.47715 -229.210362)
				(mid 58.143902 -229.210362)
				(end 58.47715 -229.210362)
			)
		)
		(stroke
			(width 0)
			(type solid)
		)
		(fill yes)
		(layer "F.Cu")
		(net "GND")
	)
	(gr_poly
		(pts
			(arc
				(start 58.47715 -219.860368)
				(mid 58.143902 -219.860368)
				(end 58.47715 -219.860368)
			)
		)
		(stroke
			(width 0)
			(type solid)
		)
		(fill yes)
		(layer "F.Cu")
		(net "GND")
	)
	(gr_poly
		(pts
			(arc
				(start 58.47715 -210.510374)
				(mid 58.143902 -210.510374)
				(end 58.47715 -210.510374)
			)
		)
		(stroke
			(width 0)
			(type solid)
		)
		(fill yes)
		(layer "F.Cu")
		(net "GND")
	)
	(gr_poly
		(pts
			(arc
				(start 58.47715 -201.16038)
				(mid 58.143902 -201.16038)
				(end 58.47715 -201.16038)
			)
		)
		(stroke
			(width 0)
			(type solid)
		)
		(fill yes)
		(layer "F.Cu")
		(net "GND")
	)
	(gr_poly
		(pts
			(xy 68.295266 -151.236172) (xy 68.295266 -150.932642)
			(arc
				(start 68.295266 -150.660354)
				(mid 68.293615 -150.647349)
				(end 68.288662 -150.635208)
			)
			(xy 67.973194 -150.087838) (xy 67.96532 -150.077678) (xy 67.771264 -149.883622) (xy 66.944494 -149.883622)
			(xy 66.752724 -149.883622) (xy 66.752724 -150.388574) (xy 66.777362 -150.413212) (xy 67.178428 -150.413212)
			(xy 67.178682 -150.413212)
			(arc
				(start 67.645026 -150.413212)
				(mid 67.664258 -150.417055)
				(end 67.680586 -150.427944)
			)
			(arc
				(start 67.955922 -150.70328)
				(mid 67.966877 -150.719581)
				(end 67.970654 -150.73884)
			)
			(arc
				(start 67.970654 -151.223472)
				(mid 67.98522 -151.259019)
				(end 68.020692 -151.273764)
			)
			(xy 68.257674 -151.273764)
		)
		(stroke
			(width 0)
			(type solid)
		)
		(fill yes)
		(layer "F.Cu")
		(net "SW_PVDD18_S5_P1_BST")
	)
	(gr_poly
		(pts
			(arc
				(start 105.30967 -17.59458)
				(mid 104.976422 -17.59458)
				(end 105.30967 -17.59458)
			)
		)
		(stroke
			(width 0)
			(type solid)
		)
		(fill yes)
		(layer "F.Cu")
		(net "GND")
	)
	(gr_poly
		(pts
			(arc
				(start 150.690072 -204.720444)
				(mid 150.356824 -204.720444)
				(end 150.690072 -204.720444)
			)
		)
		(stroke
			(width 0)
			(type solid)
		)
		(fill yes)
		(layer "F.Cu")
		(net "GND")
	)
	(gr_poly
		(pts
			(arc
				(start 154.23261 -202.213464)
				(mid 153.899362 -202.213464)
				(end 154.23261 -202.213464)
			)
		)
		(stroke
			(width 0)
			(type solid)
		)
		(fill yes)
		(layer "F.Cu")
		(net "GND")
	)
	(gr_poly
		(pts
			(arc
				(start 156.674058 -198.212456)
				(mid 156.34081 -198.212456)
				(end 156.674058 -198.212456)
			)
		)
		(stroke
			(width 0)
			(type solid)
		)
		(fill yes)
		(layer "F.Cu")
		(net "GND")
	)
	(gr_poly
		(pts
			(arc
				(start 161.172652 -149.221952)
				(mid 160.839404 -149.221952)
				(end 161.172652 -149.221952)
			)
		)
		(stroke
			(width 0)
			(type solid)
		)
		(fill yes)
		(layer "F.Cu")
		(net "GND")
	)
	(gr_poly
		(pts
			(arc
				(start 162.595052 -149.221952)
				(mid 162.261804 -149.221952)
				(end 162.595052 -149.221952)
			)
		)
		(stroke
			(width 0)
			(type solid)
		)
		(fill yes)
		(layer "F.Cu")
		(net "GND")
	)
	(gr_poly
		(pts
			(arc
				(start 163.441888 -145.84299)
				(mid 163.10864 -145.84299)
				(end 163.441888 -145.84299)
			)
		)
		(stroke
			(width 0)
			(type solid)
		)
		(fill yes)
		(layer "F.Cu")
		(net "GND")
	)
	(gr_poly
		(pts
			(arc
				(start 163.65347 -171.394374)
				(mid 163.320222 -171.394374)
				(end 163.65347 -171.394374)
			)
		)
		(stroke
			(width 0)
			(type solid)
		)
		(fill yes)
		(layer "F.Cu")
		(net "GND")
	)
	(gr_poly
		(pts
			(xy 164.029644 -350.358964) (xy 164.029644 -347.387164) (xy 164.176456 -347.240352) (xy 164.922454 -347.240352)
			(xy 164.99713 -347.165676) (xy 164.99713 -346.699078) (xy 164.962332 -346.66428) (xy 164.326316 -346.66428)
			(xy 164.322506 -346.660216) (xy 164.262054 -346.720668) (xy 160.411414 -346.720668) (xy 160.355026 -346.66428)
			(xy 159.506158 -346.66428) (xy 159.492442 -346.677996) (xy 159.492442 -346.810584) (xy 159.523684 -346.841826)
			(xy 160.297114 -346.841826) (xy 160.313624 -346.858336) (xy 160.39973 -346.944442) (xy 160.39973 -347.304106)
			(xy 160.237678 -347.466158) (xy 159.510476 -347.466158) (xy 159.484822 -347.491812) (xy 159.484822 -348.019878)
			(xy 159.506158 -348.041214) (xy 160.27527 -348.041214) (xy 160.39973 -348.165674) (xy 160.39973 -350.356678)
			(xy 160.42513 -350.382078) (xy 164.00653 -350.382078)
		)
		(stroke
			(width 0)
			(type solid)
		)
		(fill yes)
		(layer "F.Cu")
		(net "GND")
	)
	(gr_poly
		(pts
			(arc
				(start 164.109908 -149.1742)
				(mid 163.77666 -149.1742)
				(end 164.109908 -149.1742)
			)
		)
		(stroke
			(width 0)
			(type solid)
		)
		(fill yes)
		(layer "F.Cu")
		(net "GND")
	)
	(gr_poly
		(pts
			(arc
				(start 165.250368 -145.84299)
				(mid 164.91712 -145.84299)
				(end 165.250368 -145.84299)
			)
		)
		(stroke
			(width 0)
			(type solid)
		)
		(fill yes)
		(layer "F.Cu")
		(net "GND")
	)
	(gr_poly
		(pts
			(arc
				(start 165.532308 -149.1742)
				(mid 165.19906 -149.1742)
				(end 165.532308 -149.1742)
			)
		)
		(stroke
			(width 0)
			(type solid)
		)
		(fill yes)
		(layer "F.Cu")
		(net "GND")
	)
	(gr_poly
		(pts
			(arc
				(start 165.71214 -314.210446)
				(mid 165.378892 -314.210446)
				(end 165.71214 -314.210446)
			)
		)
		(stroke
			(width 0)
			(type solid)
		)
		(fill yes)
		(layer "F.Cu")
		(net "GND")
	)
	(gr_poly
		(pts
			(arc
				(start 165.71214 -304.860452)
				(mid 165.378892 -304.860452)
				(end 165.71214 -304.860452)
			)
		)
		(stroke
			(width 0)
			(type solid)
		)
		(fill yes)
		(layer "F.Cu")
		(net "GND")
	)
	(gr_poly
		(pts
			(arc
				(start 165.71214 -295.510458)
				(mid 165.378892 -295.510458)
				(end 165.71214 -295.510458)
			)
		)
		(stroke
			(width 0)
			(type solid)
		)
		(fill yes)
		(layer "F.Cu")
		(net "GND")
	)
	(gr_poly
		(pts
			(arc
				(start 165.71214 -286.160464)
				(mid 165.378892 -286.160464)
				(end 165.71214 -286.160464)
			)
		)
		(stroke
			(width 0)
			(type solid)
		)
		(fill yes)
		(layer "F.Cu")
		(net "GND")
	)
	(gr_poly
		(pts
			(arc
				(start 165.71214 -276.81047)
				(mid 165.378892 -276.81047)
				(end 165.71214 -276.81047)
			)
		)
		(stroke
			(width 0)
			(type solid)
		)
		(fill yes)
		(layer "F.Cu")
		(net "GND")
	)
	(gr_poly
		(pts
			(arc
				(start 165.71214 -239.410494)
				(mid 165.378892 -239.410494)
				(end 165.71214 -239.410494)
			)
		)
		(stroke
			(width 0)
			(type solid)
		)
		(fill yes)
		(layer "F.Cu")
		(net "GND")
	)
	(gr_poly
		(pts
			(arc
				(start 165.71214 -230.0605)
				(mid 165.378892 -230.0605)
				(end 165.71214 -230.0605)
			)
		)
		(stroke
			(width 0)
			(type solid)
		)
		(fill yes)
		(layer "F.Cu")
		(net "GND")
	)
	(gr_poly
		(pts
			(arc
				(start 165.71214 -220.710252)
				(mid 165.378892 -220.710252)
				(end 165.71214 -220.710252)
			)
		)
		(stroke
			(width 0)
			(type solid)
		)
		(fill yes)
		(layer "F.Cu")
		(net "GND")
	)
	(gr_poly
		(pts
			(arc
				(start 165.71214 -211.360258)
				(mid 165.378892 -211.360258)
				(end 165.71214 -211.360258)
			)
		)
		(stroke
			(width 0)
			(type solid)
		)
		(fill yes)
		(layer "F.Cu")
		(net "GND")
	)
	(gr_poly
		(pts
			(arc
				(start 165.71214 -202.010264)
				(mid 165.378892 -202.010264)
				(end 165.71214 -202.010264)
			)
		)
		(stroke
			(width 0)
			(type solid)
		)
		(fill yes)
		(layer "F.Cu")
		(net "GND")
	)
	(gr_poly
		(pts
			(arc
				(start 166.454328 -171.400724)
				(mid 166.12108 -171.400724)
				(end 166.454328 -171.400724)
			)
		)
		(stroke
			(width 0)
			(type solid)
		)
		(fill yes)
		(layer "F.Cu")
		(net "GND")
	)
	(gr_poly
		(pts
			(arc
				(start 167.822372 -170.881294)
				(mid 167.489124 -170.881294)
				(end 167.822372 -170.881294)
			)
		)
		(stroke
			(width 0)
			(type solid)
		)
		(fill yes)
		(layer "F.Cu")
		(net "GND")
	)
	(gr_poly
		(pts
			(arc
				(start 169.812208 -313.360308)
				(mid 169.47896 -313.360308)
				(end 169.812208 -313.360308)
			)
		)
		(stroke
			(width 0)
			(type solid)
		)
		(fill yes)
		(layer "F.Cu")
		(net "GND")
	)
	(gr_poly
		(pts
			(arc
				(start 169.812208 -304.010314)
				(mid 169.47896 -304.010314)
				(end 169.812208 -304.010314)
			)
		)
		(stroke
			(width 0)
			(type solid)
		)
		(fill yes)
		(layer "F.Cu")
		(net "GND")
	)
	(gr_poly
		(pts
			(arc
				(start 169.812208 -294.66032)
				(mid 169.47896 -294.66032)
				(end 169.812208 -294.66032)
			)
		)
		(stroke
			(width 0)
			(type solid)
		)
		(fill yes)
		(layer "F.Cu")
		(net "GND")
	)
	(gr_poly
		(pts
			(arc
				(start 169.812208 -285.310326)
				(mid 169.47896 -285.310326)
				(end 169.812208 -285.310326)
			)
		)
		(stroke
			(width 0)
			(type solid)
		)
		(fill yes)
		(layer "F.Cu")
		(net "GND")
	)
	(gr_poly
		(pts
			(arc
				(start 169.812208 -275.960332)
				(mid 169.47896 -275.960332)
				(end 169.812208 -275.960332)
			)
		)
		(stroke
			(width 0)
			(type solid)
		)
		(fill yes)
		(layer "F.Cu")
		(net "GND")
	)
	(gr_poly
		(pts
			(arc
				(start 169.812208 -238.560356)
				(mid 169.47896 -238.560356)
				(end 169.812208 -238.560356)
			)
		)
		(stroke
			(width 0)
			(type solid)
		)
		(fill yes)
		(layer "F.Cu")
		(net "GND")
	)
	(gr_poly
		(pts
			(arc
				(start 169.812208 -229.210362)
				(mid 169.47896 -229.210362)
				(end 169.812208 -229.210362)
			)
		)
		(stroke
			(width 0)
			(type solid)
		)
		(fill yes)
		(layer "F.Cu")
		(net "GND")
	)
	(gr_poly
		(pts
			(arc
				(start 169.812208 -219.860368)
				(mid 169.47896 -219.860368)
				(end 169.812208 -219.860368)
			)
		)
		(stroke
			(width 0)
			(type solid)
		)
		(fill yes)
		(layer "F.Cu")
		(net "GND")
	)
	(gr_poly
		(pts
			(arc
				(start 169.812208 -210.510374)
				(mid 169.47896 -210.510374)
				(end 169.812208 -210.510374)
			)
		)
		(stroke
			(width 0)
			(type solid)
		)
		(fill yes)
		(layer "F.Cu")
		(net "GND")
	)
	(gr_poly
		(pts
			(arc
				(start 169.812208 -201.16038)
				(mid 169.47896 -201.16038)
				(end 169.812208 -201.16038)
			)
		)
		(stroke
			(width 0)
			(type solid)
		)
		(fill yes)
		(layer "F.Cu")
		(net "GND")
	)
	(gr_poly
		(pts
			(arc
				(start 173.256194 -314.210446)
				(mid 172.922946 -314.210446)
				(end 173.256194 -314.210446)
			)
		)
		(stroke
			(width 0)
			(type solid)
		)
		(fill yes)
		(layer "F.Cu")
		(net "GND")
	)
	(gr_poly
		(pts
			(arc
				(start 173.256194 -304.860452)
				(mid 172.922946 -304.860452)
				(end 173.256194 -304.860452)
			)
		)
		(stroke
			(width 0)
			(type solid)
		)
		(fill yes)
		(layer "F.Cu")
		(net "GND")
	)
	(gr_poly
		(pts
			(arc
				(start 173.256194 -295.510458)
				(mid 172.922946 -295.510458)
				(end 173.256194 -295.510458)
			)
		)
		(stroke
			(width 0)
			(type solid)
		)
		(fill yes)
		(layer "F.Cu")
		(net "GND")
	)
	(gr_poly
		(pts
			(arc
				(start 173.256194 -286.160464)
				(mid 172.922946 -286.160464)
				(end 173.256194 -286.160464)
			)
		)
		(stroke
			(width 0)
			(type solid)
		)
		(fill yes)
		(layer "F.Cu")
		(net "GND")
	)
	(gr_poly
		(pts
			(arc
				(start 173.256194 -276.81047)
				(mid 172.922946 -276.81047)
				(end 173.256194 -276.81047)
			)
		)
		(stroke
			(width 0)
			(type solid)
		)
		(fill yes)
		(layer "F.Cu")
		(net "GND")
	)
	(gr_poly
		(pts
			(arc
				(start 173.256194 -239.410494)
				(mid 172.922946 -239.410494)
				(end 173.256194 -239.410494)
			)
		)
		(stroke
			(width 0)
			(type solid)
		)
		(fill yes)
		(layer "F.Cu")
		(net "GND")
	)
	(gr_poly
		(pts
			(arc
				(start 173.256194 -230.0605)
				(mid 172.922946 -230.0605)
				(end 173.256194 -230.0605)
			)
		)
		(stroke
			(width 0)
			(type solid)
		)
		(fill yes)
		(layer "F.Cu")
		(net "GND")
	)
	(gr_poly
		(pts
			(arc
				(start 173.256194 -220.710252)
				(mid 172.922946 -220.710252)
				(end 173.256194 -220.710252)
			)
		)
		(stroke
			(width 0)
			(type solid)
		)
		(fill yes)
		(layer "F.Cu")
		(net "GND")
	)
	(gr_poly
		(pts
			(arc
				(start 173.256194 -211.360258)
				(mid 172.922946 -211.360258)
				(end 173.256194 -211.360258)
			)
		)
		(stroke
			(width 0)
			(type solid)
		)
		(fill yes)
		(layer "F.Cu")
		(net "GND")
	)
	(gr_poly
		(pts
			(arc
				(start 173.256194 -202.010264)
				(mid 172.922946 -202.010264)
				(end 173.256194 -202.010264)
			)
		)
		(stroke
			(width 0)
			(type solid)
		)
		(fill yes)
		(layer "F.Cu")
		(net "GND")
	)
	(gr_poly
		(pts
			(arc
				(start 174.938436 -171.575222)
				(mid 174.605188 -171.575222)
				(end 174.938436 -171.575222)
			)
		)
		(stroke
			(width 0)
			(type solid)
		)
		(fill yes)
		(layer "F.Cu")
		(net "GND")
	)
	(gr_poly
		(pts
			(arc
				(start 177.356262 -313.360308)
				(mid 177.023014 -313.360308)
				(end 177.356262 -313.360308)
			)
		)
		(stroke
			(width 0)
			(type solid)
		)
		(fill yes)
		(layer "F.Cu")
		(net "GND")
	)
	(gr_poly
		(pts
			(arc
				(start 177.356262 -304.010314)
				(mid 177.023014 -304.010314)
				(end 177.356262 -304.010314)
			)
		)
		(stroke
			(width 0)
			(type solid)
		)
		(fill yes)
		(layer "F.Cu")
		(net "GND")
	)
	(gr_poly
		(pts
			(arc
				(start 177.356262 -294.66032)
				(mid 177.023014 -294.66032)
				(end 177.356262 -294.66032)
			)
		)
		(stroke
			(width 0)
			(type solid)
		)
		(fill yes)
		(layer "F.Cu")
		(net "GND")
	)
	(gr_poly
		(pts
			(arc
				(start 177.356262 -285.310326)
				(mid 177.023014 -285.310326)
				(end 177.356262 -285.310326)
			)
		)
		(stroke
			(width 0)
			(type solid)
		)
		(fill yes)
		(layer "F.Cu")
		(net "GND")
	)
	(gr_poly
		(pts
			(arc
				(start 177.356262 -275.960332)
				(mid 177.023014 -275.960332)
				(end 177.356262 -275.960332)
			)
		)
		(stroke
			(width 0)
			(type solid)
		)
		(fill yes)
		(layer "F.Cu")
		(net "GND")
	)
	(gr_poly
		(pts
			(arc
				(start 177.356262 -238.560356)
				(mid 177.023014 -238.560356)
				(end 177.356262 -238.560356)
			)
		)
		(stroke
			(width 0)
			(type solid)
		)
		(fill yes)
		(layer "F.Cu")
		(net "GND")
	)
	(gr_poly
		(pts
			(arc
				(start 177.356262 -229.210362)
				(mid 177.023014 -229.210362)
				(end 177.356262 -229.210362)
			)
		)
		(stroke
			(width 0)
			(type solid)
		)
		(fill yes)
		(layer "F.Cu")
		(net "GND")
	)
	(gr_poly
		(pts
			(arc
				(start 177.356262 -219.860368)
				(mid 177.023014 -219.860368)
				(end 177.356262 -219.860368)
			)
		)
		(stroke
			(width 0)
			(type solid)
		)
		(fill yes)
		(layer "F.Cu")
		(net "GND")
	)
	(gr_poly
		(pts
			(arc
				(start 177.356262 -210.510374)
				(mid 177.023014 -210.510374)
				(end 177.356262 -210.510374)
			)
		)
		(stroke
			(width 0)
			(type solid)
		)
		(fill yes)
		(layer "F.Cu")
		(net "GND")
	)
	(gr_poly
		(pts
			(arc
				(start 177.356262 -201.16038)
				(mid 177.023014 -201.16038)
				(end 177.356262 -201.16038)
			)
		)
		(stroke
			(width 0)
			(type solid)
		)
		(fill yes)
		(layer "F.Cu")
		(net "GND")
	)
	(gr_poly
		(pts
			(arc
				(start 177.367692 -186.283854)
				(mid 177.034444 -186.283854)
				(end 177.367692 -186.283854)
			)
		)
		(stroke
			(width 0)
			(type solid)
		)
		(fill yes)
		(layer "F.Cu")
		(net "GND")
	)
	(gr_poly
		(pts
			(xy 178.559714 -38.567868) (xy 178.559714 -36.949634) (xy 177.78222 -36.17214) (xy 173.942502 -36.17214)
			(xy 173.489874 -36.624768) (xy 173.489874 -38.109398) (xy 176.257458 -38.109398) (xy 176.257458 -37.990272)
			(xy 176.308258 -37.939472) (xy 177.908458 -37.939472) (xy 177.959258 -37.990272) (xy 177.959258 -38.109398)
			(xy 177.908458 -38.160198) (xy 176.308258 -38.160198) (xy 176.257458 -38.109398) (xy 173.489874 -38.109398)
			(xy 173.489874 -38.60927) (xy 176.257458 -38.60927) (xy 176.257458 -38.490144) (xy 176.308258 -38.439344)
			(xy 177.908458 -38.439344) (xy 177.959258 -38.490144) (xy 177.959258 -38.60927) (xy 177.908458 -38.66007)
			(xy 176.308258 -38.66007) (xy 176.257458 -38.60927) (xy 173.489874 -38.60927) (xy 173.489874 -38.730428)
			(xy 173.738794 -38.979348) (xy 178.148234 -38.979348)
		)
		(stroke
			(width 0)
			(type solid)
		)
		(fill yes)
		(layer "F.Cu")
		(net "GND")
	)
	(gr_poly
		(pts
			(arc
				(start 180.800248 -314.210446)
				(mid 180.467 -314.210446)
				(end 180.800248 -314.210446)
			)
		)
		(stroke
			(width 0)
			(type solid)
		)
		(fill yes)
		(layer "F.Cu")
		(net "GND")
	)
	(gr_poly
		(pts
			(arc
				(start 180.800248 -304.860452)
				(mid 180.467 -304.860452)
				(end 180.800248 -304.860452)
			)
		)
		(stroke
			(width 0)
			(type solid)
		)
		(fill yes)
		(layer "F.Cu")
		(net "GND")
	)
	(gr_poly
		(pts
			(arc
				(start 180.800248 -295.510458)
				(mid 180.467 -295.510458)
				(end 180.800248 -295.510458)
			)
		)
		(stroke
			(width 0)
			(type solid)
		)
		(fill yes)
		(layer "F.Cu")
		(net "GND")
	)
	(gr_poly
		(pts
			(arc
				(start 180.800248 -286.160464)
				(mid 180.467 -286.160464)
				(end 180.800248 -286.160464)
			)
		)
		(stroke
			(width 0)
			(type solid)
		)
		(fill yes)
		(layer "F.Cu")
		(net "GND")
	)
	(gr_poly
		(pts
			(arc
				(start 180.800248 -276.81047)
				(mid 180.467 -276.81047)
				(end 180.800248 -276.81047)
			)
		)
		(stroke
			(width 0)
			(type solid)
		)
		(fill yes)
		(layer "F.Cu")
		(net "GND")
	)
	(gr_poly
		(pts
			(arc
				(start 180.800248 -239.410494)
				(mid 180.467 -239.410494)
				(end 180.800248 -239.410494)
			)
		)
		(stroke
			(width 0)
			(type solid)
		)
		(fill yes)
		(layer "F.Cu")
		(net "GND")
	)
	(gr_poly
		(pts
			(arc
				(start 180.800248 -230.0605)
				(mid 180.467 -230.0605)
				(end 180.800248 -230.0605)
			)
		)
		(stroke
			(width 0)
			(type solid)
		)
		(fill yes)
		(layer "F.Cu")
		(net "GND")
	)
	(gr_poly
		(pts
			(arc
				(start 180.800248 -220.710252)
				(mid 180.467 -220.710252)
				(end 180.800248 -220.710252)
			)
		)
		(stroke
			(width 0)
			(type solid)
		)
		(fill yes)
		(layer "F.Cu")
		(net "GND")
	)
	(gr_poly
		(pts
			(arc
				(start 180.800248 -211.360258)
				(mid 180.467 -211.360258)
				(end 180.800248 -211.360258)
			)
		)
		(stroke
			(width 0)
			(type solid)
		)
		(fill yes)
		(layer "F.Cu")
		(net "GND")
	)
	(gr_poly
		(pts
			(arc
				(start 181.339744 -161.771838)
				(mid 181.006496 -161.771838)
				(end 181.339744 -161.771838)
			)
		)
		(stroke
			(width 0)
			(type solid)
		)
		(fill yes)
		(layer "F.Cu")
		(net "GND")
	)
	(gr_poly
		(pts
			(arc
				(start 184.062878 -161.74466)
				(mid 183.72963 -161.74466)
				(end 184.062878 -161.74466)
			)
		)
		(stroke
			(width 0)
			(type solid)
		)
		(fill yes)
		(layer "F.Cu")
		(net "GND")
	)
	(gr_poly
		(pts
			(arc
				(start 184.900316 -313.360308)
				(mid 184.567068 -313.360308)
				(end 184.900316 -313.360308)
			)
		)
		(stroke
			(width 0)
			(type solid)
		)
		(fill yes)
		(layer "F.Cu")
		(net "GND")
	)
	(gr_poly
		(pts
			(arc
				(start 184.900316 -294.66032)
				(mid 184.567068 -294.66032)
				(end 184.900316 -294.66032)
			)
		)
		(stroke
			(width 0)
			(type solid)
		)
		(fill yes)
		(layer "F.Cu")
		(net "GND")
	)
	(gr_poly
		(pts
			(arc
				(start 184.900316 -285.310326)
				(mid 184.567068 -285.310326)
				(end 184.900316 -285.310326)
			)
		)
		(stroke
			(width 0)
			(type solid)
		)
		(fill yes)
		(layer "F.Cu")
		(net "GND")
	)
	(gr_poly
		(pts
			(arc
				(start 184.900316 -275.960332)
				(mid 184.567068 -275.960332)
				(end 184.900316 -275.960332)
			)
		)
		(stroke
			(width 0)
			(type solid)
		)
		(fill yes)
		(layer "F.Cu")
		(net "GND")
	)
	(gr_poly
		(pts
			(arc
				(start 184.900316 -238.560356)
				(mid 184.567068 -238.560356)
				(end 184.900316 -238.560356)
			)
		)
		(stroke
			(width 0)
			(type solid)
		)
		(fill yes)
		(layer "F.Cu")
		(net "GND")
	)
	(gr_poly
		(pts
			(arc
				(start 184.900316 -229.210362)
				(mid 184.567068 -229.210362)
				(end 184.900316 -229.210362)
			)
		)
		(stroke
			(width 0)
			(type solid)
		)
		(fill yes)
		(layer "F.Cu")
		(net "GND")
	)
	(gr_poly
		(pts
			(arc
				(start 184.900316 -219.860368)
				(mid 184.567068 -219.860368)
				(end 184.900316 -219.860368)
			)
		)
		(stroke
			(width 0)
			(type solid)
		)
		(fill yes)
		(layer "F.Cu")
		(net "GND")
	)
	(gr_poly
		(pts
			(arc
				(start 184.900316 -210.510374)
				(mid 184.567068 -210.510374)
				(end 184.900316 -210.510374)
			)
		)
		(stroke
			(width 0)
			(type solid)
		)
		(fill yes)
		(layer "F.Cu")
		(net "GND")
	)
	(gr_poly
		(pts
			(arc
				(start 184.900316 -201.16038)
				(mid 184.567068 -201.16038)
				(end 184.900316 -201.16038)
			)
		)
		(stroke
			(width 0)
			(type solid)
		)
		(fill yes)
		(layer "F.Cu")
		(net "GND")
	)
	(gr_poly
		(pts
			(arc
				(start 188.344302 -314.210446)
				(mid 188.011054 -314.210446)
				(end 188.344302 -314.210446)
			)
		)
		(stroke
			(width 0)
			(type solid)
		)
		(fill yes)
		(layer "F.Cu")
		(net "GND")
	)
	(gr_poly
		(pts
			(arc
				(start 188.344302 -304.860452)
				(mid 188.011054 -304.860452)
				(end 188.344302 -304.860452)
			)
		)
		(stroke
			(width 0)
			(type solid)
		)
		(fill yes)
		(layer "F.Cu")
		(net "GND")
	)
	(gr_poly
		(pts
			(arc
				(start 188.344302 -295.510458)
				(mid 188.011054 -295.510458)
				(end 188.344302 -295.510458)
			)
		)
		(stroke
			(width 0)
			(type solid)
		)
		(fill yes)
		(layer "F.Cu")
		(net "GND")
	)
	(gr_poly
		(pts
			(arc
				(start 188.344302 -286.160464)
				(mid 188.011054 -286.160464)
				(end 188.344302 -286.160464)
			)
		)
		(stroke
			(width 0)
			(type solid)
		)
		(fill yes)
		(layer "F.Cu")
		(net "GND")
	)
	(gr_poly
		(pts
			(arc
				(start 188.344302 -276.81047)
				(mid 188.011054 -276.81047)
				(end 188.344302 -276.81047)
			)
		)
		(stroke
			(width 0)
			(type solid)
		)
		(fill yes)
		(layer "F.Cu")
		(net "GND")
	)
	(gr_poly
		(pts
			(arc
				(start 188.344302 -239.410494)
				(mid 188.011054 -239.410494)
				(end 188.344302 -239.410494)
			)
		)
		(stroke
			(width 0)
			(type solid)
		)
		(fill yes)
		(layer "F.Cu")
		(net "GND")
	)
	(gr_poly
		(pts
			(arc
				(start 188.344302 -230.0605)
				(mid 188.011054 -230.0605)
				(end 188.344302 -230.0605)
			)
		)
		(stroke
			(width 0)
			(type solid)
		)
		(fill yes)
		(layer "F.Cu")
		(net "GND")
	)
	(gr_poly
		(pts
			(arc
				(start 188.344302 -220.710252)
				(mid 188.011054 -220.710252)
				(end 188.344302 -220.710252)
			)
		)
		(stroke
			(width 0)
			(type solid)
		)
		(fill yes)
		(layer "F.Cu")
		(net "GND")
	)
	(gr_poly
		(pts
			(arc
				(start 188.344302 -211.360258)
				(mid 188.011054 -211.360258)
				(end 188.344302 -211.360258)
			)
		)
		(stroke
			(width 0)
			(type solid)
		)
		(fill yes)
		(layer "F.Cu")
		(net "GND")
	)
	(gr_poly
		(pts
			(arc
				(start 188.344302 -202.010264)
				(mid 188.011054 -202.010264)
				(end 188.344302 -202.010264)
			)
		)
		(stroke
			(width 0)
			(type solid)
		)
		(fill yes)
		(layer "F.Cu")
		(net "GND")
	)
	(gr_poly
		(pts
			(arc
				(start 192.44437 -313.360308)
				(mid 192.111122 -313.360308)
				(end 192.44437 -313.360308)
			)
		)
		(stroke
			(width 0)
			(type solid)
		)
		(fill yes)
		(layer "F.Cu")
		(net "GND")
	)
	(gr_poly
		(pts
			(arc
				(start 192.44437 -304.010314)
				(mid 192.111122 -304.010314)
				(end 192.44437 -304.010314)
			)
		)
		(stroke
			(width 0)
			(type solid)
		)
		(fill yes)
		(layer "F.Cu")
		(net "GND")
	)
	(gr_poly
		(pts
			(arc
				(start 192.44437 -294.66032)
				(mid 192.111122 -294.66032)
				(end 192.44437 -294.66032)
			)
		)
		(stroke
			(width 0)
			(type solid)
		)
		(fill yes)
		(layer "F.Cu")
		(net "GND")
	)
	(gr_poly
		(pts
			(arc
				(start 192.44437 -285.310326)
				(mid 192.111122 -285.310326)
				(end 192.44437 -285.310326)
			)
		)
		(stroke
			(width 0)
			(type solid)
		)
		(fill yes)
		(layer "F.Cu")
		(net "GND")
	)
	(gr_poly
		(pts
			(arc
				(start 192.44437 -275.960332)
				(mid 192.111122 -275.960332)
				(end 192.44437 -275.960332)
			)
		)
		(stroke
			(width 0)
			(type solid)
		)
		(fill yes)
		(layer "F.Cu")
		(net "GND")
	)
	(gr_poly
		(pts
			(arc
				(start 192.44437 -238.560356)
				(mid 192.111122 -238.560356)
				(end 192.44437 -238.560356)
			)
		)
		(stroke
			(width 0)
			(type solid)
		)
		(fill yes)
		(layer "F.Cu")
		(net "GND")
	)
	(gr_poly
		(pts
			(arc
				(start 192.44437 -229.210362)
				(mid 192.111122 -229.210362)
				(end 192.44437 -229.210362)
			)
		)
		(stroke
			(width 0)
			(type solid)
		)
		(fill yes)
		(layer "F.Cu")
		(net "GND")
	)
	(gr_poly
		(pts
			(arc
				(start 192.44437 -219.860368)
				(mid 192.111122 -219.860368)
				(end 192.44437 -219.860368)
			)
		)
		(stroke
			(width 0)
			(type solid)
		)
		(fill yes)
		(layer "F.Cu")
		(net "GND")
	)
	(gr_poly
		(pts
			(arc
				(start 192.44437 -201.16038)
				(mid 192.111122 -201.16038)
				(end 192.44437 -201.16038)
			)
		)
		(stroke
			(width 0)
			(type solid)
		)
		(fill yes)
		(layer "F.Cu")
		(net "GND")
	)
	(gr_poly
		(pts
			(arc
				(start 195.888356 -314.210446)
				(mid 195.555108 -314.210446)
				(end 195.888356 -314.210446)
			)
		)
		(stroke
			(width 0)
			(type solid)
		)
		(fill yes)
		(layer "F.Cu")
		(net "GND")
	)
	(gr_poly
		(pts
			(arc
				(start 195.888356 -304.860452)
				(mid 195.555108 -304.860452)
				(end 195.888356 -304.860452)
			)
		)
		(stroke
			(width 0)
			(type solid)
		)
		(fill yes)
		(layer "F.Cu")
		(net "GND")
	)
	(gr_poly
		(pts
			(arc
				(start 195.888356 -295.510458)
				(mid 195.555108 -295.510458)
				(end 195.888356 -295.510458)
			)
		)
		(stroke
			(width 0)
			(type solid)
		)
		(fill yes)
		(layer "F.Cu")
		(net "GND")
	)
	(gr_poly
		(pts
			(arc
				(start 195.888356 -286.160464)
				(mid 195.555108 -286.160464)
				(end 195.888356 -286.160464)
			)
		)
		(stroke
			(width 0)
			(type solid)
		)
		(fill yes)
		(layer "F.Cu")
		(net "GND")
	)
	(gr_poly
		(pts
			(arc
				(start 195.888356 -276.81047)
				(mid 195.555108 -276.81047)
				(end 195.888356 -276.81047)
			)
		)
		(stroke
			(width 0)
			(type solid)
		)
		(fill yes)
		(layer "F.Cu")
		(net "GND")
	)
	(gr_poly
		(pts
			(arc
				(start 195.888356 -239.410494)
				(mid 195.555108 -239.410494)
				(end 195.888356 -239.410494)
			)
		)
		(stroke
			(width 0)
			(type solid)
		)
		(fill yes)
		(layer "F.Cu")
		(net "GND")
	)
	(gr_poly
		(pts
			(arc
				(start 195.888356 -230.0605)
				(mid 195.555108 -230.0605)
				(end 195.888356 -230.0605)
			)
		)
		(stroke
			(width 0)
			(type solid)
		)
		(fill yes)
		(layer "F.Cu")
		(net "GND")
	)
	(gr_poly
		(pts
			(arc
				(start 195.888356 -220.710252)
				(mid 195.555108 -220.710252)
				(end 195.888356 -220.710252)
			)
		)
		(stroke
			(width 0)
			(type solid)
		)
		(fill yes)
		(layer "F.Cu")
		(net "GND")
	)
	(gr_poly
		(pts
			(arc
				(start 195.888356 -211.360258)
				(mid 195.555108 -211.360258)
				(end 195.888356 -211.360258)
			)
		)
		(stroke
			(width 0)
			(type solid)
		)
		(fill yes)
		(layer "F.Cu")
		(net "GND")
	)
	(gr_poly
		(pts
			(arc
				(start 195.888356 -202.010264)
				(mid 195.555108 -202.010264)
				(end 195.888356 -202.010264)
			)
		)
		(stroke
			(width 0)
			(type solid)
		)
		(fill yes)
		(layer "F.Cu")
		(net "GND")
	)
	(gr_poly
		(pts
			(arc
				(start 199.988424 -313.360308)
				(mid 199.655176 -313.360308)
				(end 199.988424 -313.360308)
			)
		)
		(stroke
			(width 0)
			(type solid)
		)
		(fill yes)
		(layer "F.Cu")
		(net "GND")
	)
	(gr_poly
		(pts
			(arc
				(start 199.988424 -304.010314)
				(mid 199.655176 -304.010314)
				(end 199.988424 -304.010314)
			)
		)
		(stroke
			(width 0)
			(type solid)
		)
		(fill yes)
		(layer "F.Cu")
		(net "GND")
	)
	(gr_poly
		(pts
			(arc
				(start 199.988424 -294.66032)
				(mid 199.655176 -294.66032)
				(end 199.988424 -294.66032)
			)
		)
		(stroke
			(width 0)
			(type solid)
		)
		(fill yes)
		(layer "F.Cu")
		(net "GND")
	)
	(gr_poly
		(pts
			(arc
				(start 199.988424 -275.960332)
				(mid 199.655176 -275.960332)
				(end 199.988424 -275.960332)
			)
		)
		(stroke
			(width 0)
			(type solid)
		)
		(fill yes)
		(layer "F.Cu")
		(net "GND")
	)
	(gr_poly
		(pts
			(arc
				(start 199.988424 -238.560356)
				(mid 199.655176 -238.560356)
				(end 199.988424 -238.560356)
			)
		)
		(stroke
			(width 0)
			(type solid)
		)
		(fill yes)
		(layer "F.Cu")
		(net "GND")
	)
	(gr_poly
		(pts
			(arc
				(start 199.988424 -229.210362)
				(mid 199.655176 -229.210362)
				(end 199.988424 -229.210362)
			)
		)
		(stroke
			(width 0)
			(type solid)
		)
		(fill yes)
		(layer "F.Cu")
		(net "GND")
	)
	(gr_poly
		(pts
			(arc
				(start 199.988424 -219.860368)
				(mid 199.655176 -219.860368)
				(end 199.988424 -219.860368)
			)
		)
		(stroke
			(width 0)
			(type solid)
		)
		(fill yes)
		(layer "F.Cu")
		(net "GND")
	)
	(gr_poly
		(pts
			(arc
				(start 199.988424 -201.16038)
				(mid 199.655176 -201.16038)
				(end 199.988424 -201.16038)
			)
		)
		(stroke
			(width 0)
			(type solid)
		)
		(fill yes)
		(layer "F.Cu")
		(net "GND")
	)
	(gr_poly
		(pts
			(arc
				(start 203.432156 -314.210446)
				(mid 203.098908 -314.210446)
				(end 203.432156 -314.210446)
			)
		)
		(stroke
			(width 0)
			(type solid)
		)
		(fill yes)
		(layer "F.Cu")
		(net "GND")
	)
	(gr_poly
		(pts
			(arc
				(start 203.432156 -304.860452)
				(mid 203.098908 -304.860452)
				(end 203.432156 -304.860452)
			)
		)
		(stroke
			(width 0)
			(type solid)
		)
		(fill yes)
		(layer "F.Cu")
		(net "GND")
	)
	(gr_poly
		(pts
			(arc
				(start 203.432156 -295.510458)
				(mid 203.098908 -295.510458)
				(end 203.432156 -295.510458)
			)
		)
		(stroke
			(width 0)
			(type solid)
		)
		(fill yes)
		(layer "F.Cu")
		(net "GND")
	)
	(gr_poly
		(pts
			(arc
				(start 203.432156 -286.160464)
				(mid 203.098908 -286.160464)
				(end 203.432156 -286.160464)
			)
		)
		(stroke
			(width 0)
			(type solid)
		)
		(fill yes)
		(layer "F.Cu")
		(net "GND")
	)
	(gr_poly
		(pts
			(arc
				(start 203.432156 -239.410494)
				(mid 203.098908 -239.410494)
				(end 203.432156 -239.410494)
			)
		)
		(stroke
			(width 0)
			(type solid)
		)
		(fill yes)
		(layer "F.Cu")
		(net "GND")
	)
	(gr_poly
		(pts
			(arc
				(start 203.432156 -230.0605)
				(mid 203.098908 -230.0605)
				(end 203.432156 -230.0605)
			)
		)
		(stroke
			(width 0)
			(type solid)
		)
		(fill yes)
		(layer "F.Cu")
		(net "GND")
	)
	(gr_poly
		(pts
			(arc
				(start 203.432156 -220.710252)
				(mid 203.098908 -220.710252)
				(end 203.432156 -220.710252)
			)
		)
		(stroke
			(width 0)
			(type solid)
		)
		(fill yes)
		(layer "F.Cu")
		(net "GND")
	)
	(gr_poly
		(pts
			(arc
				(start 203.432156 -211.360258)
				(mid 203.098908 -211.360258)
				(end 203.432156 -211.360258)
			)
		)
		(stroke
			(width 0)
			(type solid)
		)
		(fill yes)
		(layer "F.Cu")
		(net "GND")
	)
	(gr_poly
		(pts
			(arc
				(start 203.432156 -202.010264)
				(mid 203.098908 -202.010264)
				(end 203.432156 -202.010264)
			)
		)
		(stroke
			(width 0)
			(type solid)
		)
		(fill yes)
		(layer "F.Cu")
		(net "GND")
	)
	(gr_poly
		(pts
			(arc
				(start 207.532224 -313.360308)
				(mid 207.198976 -313.360308)
				(end 207.532224 -313.360308)
			)
		)
		(stroke
			(width 0)
			(type solid)
		)
		(fill yes)
		(layer "F.Cu")
		(net "GND")
	)
	(gr_poly
		(pts
			(arc
				(start 207.532224 -304.010314)
				(mid 207.198976 -304.010314)
				(end 207.532224 -304.010314)
			)
		)
		(stroke
			(width 0)
			(type solid)
		)
		(fill yes)
		(layer "F.Cu")
		(net "GND")
	)
	(gr_poly
		(pts
			(arc
				(start 207.532224 -294.66032)
				(mid 207.198976 -294.66032)
				(end 207.532224 -294.66032)
			)
		)
		(stroke
			(width 0)
			(type solid)
		)
		(fill yes)
		(layer "F.Cu")
		(net "GND")
	)
	(gr_poly
		(pts
			(arc
				(start 207.532224 -285.310326)
				(mid 207.198976 -285.310326)
				(end 207.532224 -285.310326)
			)
		)
		(stroke
			(width 0)
			(type solid)
		)
		(fill yes)
		(layer "F.Cu")
		(net "GND")
	)
	(gr_poly
		(pts
			(arc
				(start 207.532224 -275.960332)
				(mid 207.198976 -275.960332)
				(end 207.532224 -275.960332)
			)
		)
		(stroke
			(width 0)
			(type solid)
		)
		(fill yes)
		(layer "F.Cu")
		(net "GND")
	)
	(gr_poly
		(pts
			(arc
				(start 207.532224 -238.560356)
				(mid 207.198976 -238.560356)
				(end 207.532224 -238.560356)
			)
		)
		(stroke
			(width 0)
			(type solid)
		)
		(fill yes)
		(layer "F.Cu")
		(net "GND")
	)
	(gr_poly
		(pts
			(arc
				(start 207.532224 -229.210362)
				(mid 207.198976 -229.210362)
				(end 207.532224 -229.210362)
			)
		)
		(stroke
			(width 0)
			(type solid)
		)
		(fill yes)
		(layer "F.Cu")
		(net "GND")
	)
	(gr_poly
		(pts
			(arc
				(start 207.532224 -219.860368)
				(mid 207.198976 -219.860368)
				(end 207.532224 -219.860368)
			)
		)
		(stroke
			(width 0)
			(type solid)
		)
		(fill yes)
		(layer "F.Cu")
		(net "GND")
	)
	(gr_poly
		(pts
			(arc
				(start 207.532224 -210.510374)
				(mid 207.198976 -210.510374)
				(end 207.532224 -210.510374)
			)
		)
		(stroke
			(width 0)
			(type solid)
		)
		(fill yes)
		(layer "F.Cu")
		(net "GND")
	)
	(gr_poly
		(pts
			(arc
				(start 211.432648 -228.934772)
				(mid 211.0994 -228.934772)
				(end 211.432648 -228.934772)
			)
		)
		(stroke
			(width 0)
			(type solid)
		)
		(fill yes)
		(layer "F.Cu")
		(net "GND")
	)
	(gr_poly
		(pts
			(arc
				(start 228.21392 -230.909622)
				(mid 227.880672 -230.909622)
				(end 228.21392 -230.909622)
			)
		)
		(stroke
			(width 0)
			(type solid)
		)
		(fill yes)
		(layer "F.Cu")
		(net "GND")
	)
	(gr_poly
		(pts
			(arc
				(start 228.684836 -152.664922)
				(mid 228.351588 -152.664922)
				(end 228.684836 -152.664922)
			)
		)
		(stroke
			(width 0)
			(type solid)
		)
		(fill yes)
		(layer "F.Cu")
		(net "GND")
	)
	(gr_poly
		(pts
			(arc
				(start 229.96525 -234.135168)
				(mid 229.632002 -234.135168)
				(end 229.96525 -234.135168)
			)
		)
		(stroke
			(width 0)
			(type solid)
		)
		(fill yes)
		(layer "F.Cu")
		(net "GND")
	)
	(gr_poly
		(pts
			(arc
				(start 230.47706 -157.320742)
				(mid 230.143812 -157.320742)
				(end 230.47706 -157.320742)
			)
		)
		(stroke
			(width 0)
			(type solid)
		)
		(fill yes)
		(layer "F.Cu")
		(net "GND")
	)
	(gr_poly
		(pts
			(arc
				(start 230.553514 -149.903688)
				(mid 230.220266 -149.903688)
				(end 230.553514 -149.903688)
			)
		)
		(stroke
			(width 0)
			(type solid)
		)
		(fill yes)
		(layer "F.Cu")
		(net "GND")
	)
	(gr_poly
		(pts
			(arc
				(start 231.00157 -250.263914)
				(mid 230.668322 -250.263914)
				(end 231.00157 -250.263914)
			)
		)
		(stroke
			(width 0)
			(type solid)
		)
		(fill yes)
		(layer "F.Cu")
		(net "GND")
	)
	(gr_poly
		(pts
			(arc
				(start 231.104186 -246.560086)
				(mid 230.770938 -246.560086)
				(end 231.104186 -246.560086)
			)
		)
		(stroke
			(width 0)
			(type solid)
		)
		(fill yes)
		(layer "F.Cu")
		(net "GND")
	)
	(gr_poly
		(pts
			(arc
				(start 231.278684 -241.355118)
				(mid 230.945436 -241.355118)
				(end 231.278684 -241.355118)
			)
		)
		(stroke
			(width 0)
			(type solid)
		)
		(fill yes)
		(layer "F.Cu")
		(net "GND")
	)
	(gr_poly
		(pts
			(arc
				(start 231.323388 -243.924328)
				(mid 230.99014 -243.924328)
				(end 231.323388 -243.924328)
			)
		)
		(stroke
			(width 0)
			(type solid)
		)
		(fill yes)
		(layer "F.Cu")
		(net "GND")
	)
	(gr_poly
		(pts
			(arc
				(start 233.825288 -230.864664)
				(mid 233.49204 -230.864664)
				(end 233.825288 -230.864664)
			)
		)
		(stroke
			(width 0)
			(type solid)
		)
		(fill yes)
		(layer "F.Cu")
		(net "GND")
	)
	(gr_poly
		(pts
			(arc
				(start 233.916728 -228.740716)
				(mid 233.58348 -228.740716)
				(end 233.916728 -228.740716)
			)
		)
		(stroke
			(width 0)
			(type solid)
		)
		(fill yes)
		(layer "F.Cu")
		(net "GND")
	)
	(gr_poly
		(pts
			(arc
				(start 233.95051 -233.241596)
				(mid 233.617262 -233.241596)
				(end 233.95051 -233.241596)
			)
		)
		(stroke
			(width 0)
			(type solid)
		)
		(fill yes)
		(layer "F.Cu")
		(net "GND")
	)
	(gr_poly
		(pts
			(arc
				(start 234.841288 -214.37346)
				(mid 234.50804 -214.37346)
				(end 234.841288 -214.37346)
			)
		)
		(stroke
			(width 0)
			(type solid)
		)
		(fill yes)
		(layer "F.Cu")
		(net "GND")
	)
	(gr_poly
		(pts
			(arc
				(start 235.37164 -241.989864)
				(mid 235.038392 -241.989864)
				(end 235.37164 -241.989864)
			)
		)
		(stroke
			(width 0)
			(type solid)
		)
		(fill yes)
		(layer "F.Cu")
		(net "GND")
	)
	(gr_poly
		(pts
			(arc
				(start 235.386372 -238.436658)
				(mid 235.053124 -238.436658)
				(end 235.386372 -238.436658)
			)
		)
		(stroke
			(width 0)
			(type solid)
		)
		(fill yes)
		(layer "F.Cu")
		(net "GND")
	)
	(gr_poly
		(pts
			(arc
				(start 236.014514 -232.017316)
				(mid 235.681266 -232.017316)
				(end 236.014514 -232.017316)
			)
		)
		(stroke
			(width 0)
			(type solid)
		)
		(fill yes)
		(layer "F.Cu")
		(net "GND")
	)
	(gr_poly
		(pts
			(arc
				(start 236.863382 -233.214672)
				(mid 236.530134 -233.214672)
				(end 236.863382 -233.214672)
			)
		)
		(stroke
			(width 0)
			(type solid)
		)
		(fill yes)
		(layer "F.Cu")
		(net "GND")
	)
	(gr_poly
		(pts
			(arc
				(start 236.881416 -226.414838)
				(mid 236.548168 -226.414838)
				(end 236.881416 -226.414838)
			)
		)
		(stroke
			(width 0)
			(type solid)
		)
		(fill yes)
		(layer "F.Cu")
		(net "GND")
	)
	(gr_poly
		(pts
			(arc
				(start 237.479332 -146.892772)
				(mid 237.146084 -146.892772)
				(end 237.479332 -146.892772)
			)
		)
		(stroke
			(width 0)
			(type solid)
		)
		(fill yes)
		(layer "F.Cu")
		(net "GND")
	)
	(gr_poly
		(pts
			(arc
				(start 238.771938 -152.545034)
				(mid 238.43869 -152.545034)
				(end 238.771938 -152.545034)
			)
		)
		(stroke
			(width 0)
			(type solid)
		)
		(fill yes)
		(layer "F.Cu")
		(net "GND")
	)
	(gr_poly
		(pts
			(arc
				(start 238.842804 -240.072926)
				(mid 238.509556 -240.072926)
				(end 238.842804 -240.072926)
			)
		)
		(stroke
			(width 0)
			(type solid)
		)
		(fill yes)
		(layer "F.Cu")
		(net "GND")
	)
	(gr_poly
		(pts
			(arc
				(start 239.025938 -218.426538)
				(mid 238.69269 -218.426538)
				(end 239.025938 -218.426538)
			)
		)
		(stroke
			(width 0)
			(type solid)
		)
		(fill yes)
		(layer "F.Cu")
		(net "GND")
	)
	(gr_poly
		(pts
			(arc
				(start 239.05718 -233.206036)
				(mid 238.723932 -233.206036)
				(end 239.05718 -233.206036)
			)
		)
		(stroke
			(width 0)
			(type solid)
		)
		(fill yes)
		(layer "F.Cu")
		(net "GND")
	)
	(gr_poly
		(pts
			(arc
				(start 239.66932 -249.566938)
				(mid 239.336072 -249.566938)
				(end 239.66932 -249.566938)
			)
		)
		(stroke
			(width 0)
			(type solid)
		)
		(fill yes)
		(layer "F.Cu")
		(net "GND")
	)
	(gr_poly
		(pts
			(arc
				(start 239.722914 -248.190766)
				(mid 239.389666 -248.190766)
				(end 239.722914 -248.190766)
			)
		)
		(stroke
			(width 0)
			(type solid)
		)
		(fill yes)
		(layer "F.Cu")
		(net "GND")
	)
	(gr_poly
		(pts
			(arc
				(start 240.973864 -226.432872)
				(mid 240.640616 -226.432872)
				(end 240.973864 -226.432872)
			)
		)
		(stroke
			(width 0)
			(type solid)
		)
		(fill yes)
		(layer "F.Cu")
		(net "GND")
	)
	(gr_poly
		(pts
			(arc
				(start 241.74577 -160.580324)
				(mid 241.412522 -160.580324)
				(end 241.74577 -160.580324)
			)
		)
		(stroke
			(width 0)
			(type solid)
		)
		(fill yes)
		(layer "F.Cu")
		(net "GND")
	)
	(gr_poly
		(pts
			(arc
				(start 241.813842 -232.066592)
				(mid 241.480594 -232.066592)
				(end 241.813842 -232.066592)
			)
		)
		(stroke
			(width 0)
			(type solid)
		)
		(fill yes)
		(layer "F.Cu")
		(net "GND")
	)
	(gr_poly
		(pts
			(arc
				(start 242.87099 -155.960318)
				(mid 242.537742 -155.960318)
				(end 242.87099 -155.960318)
			)
		)
		(stroke
			(width 0)
			(type solid)
		)
		(fill yes)
		(layer "F.Cu")
		(net "GND")
	)
	(gr_poly
		(pts
			(arc
				(start 243.511578 -218.283536)
				(mid 243.17833 -218.283536)
				(end 243.511578 -218.283536)
			)
		)
		(stroke
			(width 0)
			(type solid)
		)
		(fill yes)
		(layer "F.Cu")
		(net "GND")
	)
	(gr_poly
		(pts
			(arc
				(start 263.220454 -196.489828)
				(mid 262.887206 -196.489828)
				(end 263.220454 -196.489828)
			)
		)
		(stroke
			(width 0)
			(type solid)
		)
		(fill yes)
		(layer "F.Cu")
		(net "GND")
	)
	(gr_poly
		(pts
			(arc
				(start 264.597134 -314.210192)
				(mid 264.263886 -314.210192)
				(end 264.597134 -314.210192)
			)
		)
		(stroke
			(width 0)
			(type solid)
		)
		(fill yes)
		(layer "F.Cu")
		(net "GND")
	)
	(gr_poly
		(pts
			(arc
				(start 264.597134 -304.860198)
				(mid 264.263886 -304.860198)
				(end 264.597134 -304.860198)
			)
		)
		(stroke
			(width 0)
			(type solid)
		)
		(fill yes)
		(layer "F.Cu")
		(net "GND")
	)
	(gr_poly
		(pts
			(arc
				(start 264.597134 -295.510204)
				(mid 264.263886 -295.510204)
				(end 264.597134 -295.510204)
			)
		)
		(stroke
			(width 0)
			(type solid)
		)
		(fill yes)
		(layer "F.Cu")
		(net "GND")
	)
	(gr_poly
		(pts
			(arc
				(start 264.597134 -286.16021)
				(mid 264.263886 -286.16021)
				(end 264.597134 -286.16021)
			)
		)
		(stroke
			(width 0)
			(type solid)
		)
		(fill yes)
		(layer "F.Cu")
		(net "GND")
	)
	(gr_poly
		(pts
			(arc
				(start 264.597134 -276.810216)
				(mid 264.263886 -276.810216)
				(end 264.597134 -276.810216)
			)
		)
		(stroke
			(width 0)
			(type solid)
		)
		(fill yes)
		(layer "F.Cu")
		(net "GND")
	)
	(gr_poly
		(pts
			(arc
				(start 264.597134 -239.41024)
				(mid 264.263886 -239.41024)
				(end 264.597134 -239.41024)
			)
		)
		(stroke
			(width 0)
			(type solid)
		)
		(fill yes)
		(layer "F.Cu")
		(net "GND")
	)
	(gr_poly
		(pts
			(arc
				(start 264.597134 -230.060246)
				(mid 264.263886 -230.060246)
				(end 264.597134 -230.060246)
			)
		)
		(stroke
			(width 0)
			(type solid)
		)
		(fill yes)
		(layer "F.Cu")
		(net "GND")
	)
	(gr_poly
		(pts
			(arc
				(start 264.597134 -220.709998)
				(mid 264.263886 -220.709998)
				(end 264.597134 -220.709998)
			)
		)
		(stroke
			(width 0)
			(type solid)
		)
		(fill yes)
		(layer "F.Cu")
		(net "GND")
	)
	(gr_poly
		(pts
			(arc
				(start 264.597134 -211.360004)
				(mid 264.263886 -211.360004)
				(end 264.597134 -211.360004)
			)
		)
		(stroke
			(width 0)
			(type solid)
		)
		(fill yes)
		(layer "F.Cu")
		(net "GND")
	)
	(gr_poly
		(pts
			(arc
				(start 268.697202 -313.360054)
				(mid 268.363954 -313.360054)
				(end 268.697202 -313.360054)
			)
		)
		(stroke
			(width 0)
			(type solid)
		)
		(fill yes)
		(layer "F.Cu")
		(net "GND")
	)
	(gr_poly
		(pts
			(arc
				(start 268.697202 -285.310072)
				(mid 268.363954 -285.310072)
				(end 268.697202 -285.310072)
			)
		)
		(stroke
			(width 0)
			(type solid)
		)
		(fill yes)
		(layer "F.Cu")
		(net "GND")
	)
	(gr_poly
		(pts
			(arc
				(start 268.697202 -275.960078)
				(mid 268.363954 -275.960078)
				(end 268.697202 -275.960078)
			)
		)
		(stroke
			(width 0)
			(type solid)
		)
		(fill yes)
		(layer "F.Cu")
		(net "GND")
	)
	(gr_poly
		(pts
			(arc
				(start 268.697202 -238.560102)
				(mid 268.363954 -238.560102)
				(end 268.697202 -238.560102)
			)
		)
		(stroke
			(width 0)
			(type solid)
		)
		(fill yes)
		(layer "F.Cu")
		(net "GND")
	)
	(gr_poly
		(pts
			(arc
				(start 268.697202 -229.210108)
				(mid 268.363954 -229.210108)
				(end 268.697202 -229.210108)
			)
		)
		(stroke
			(width 0)
			(type solid)
		)
		(fill yes)
		(layer "F.Cu")
		(net "GND")
	)
	(gr_poly
		(pts
			(arc
				(start 268.697202 -219.860114)
				(mid 268.363954 -219.860114)
				(end 268.697202 -219.860114)
			)
		)
		(stroke
			(width 0)
			(type solid)
		)
		(fill yes)
		(layer "F.Cu")
		(net "GND")
	)
	(gr_poly
		(pts
			(arc
				(start 268.697202 -210.51012)
				(mid 268.363954 -210.51012)
				(end 268.697202 -210.51012)
			)
		)
		(stroke
			(width 0)
			(type solid)
		)
		(fill yes)
		(layer "F.Cu")
		(net "GND")
	)
	(gr_poly
		(pts
			(arc
				(start 268.697202 -201.160126)
				(mid 268.363954 -201.160126)
				(end 268.697202 -201.160126)
			)
		)
		(stroke
			(width 0)
			(type solid)
		)
		(fill yes)
		(layer "F.Cu")
		(net "GND")
	)
	(gr_poly
		(pts
			(arc
				(start 271.648682 -98.992436)
				(mid 271.315434 -98.992436)
				(end 271.648682 -98.992436)
			)
		)
		(stroke
			(width 0)
			(type solid)
		)
		(fill yes)
		(layer "F.Cu")
		(net "GND")
	)
	(gr_poly
		(pts
			(arc
				(start 272.141188 -314.210192)
				(mid 271.80794 -314.210192)
				(end 272.141188 -314.210192)
			)
		)
		(stroke
			(width 0)
			(type solid)
		)
		(fill yes)
		(layer "F.Cu")
		(net "GND")
	)
	(gr_poly
		(pts
			(arc
				(start 272.141188 -304.860198)
				(mid 271.80794 -304.860198)
				(end 272.141188 -304.860198)
			)
		)
		(stroke
			(width 0)
			(type solid)
		)
		(fill yes)
		(layer "F.Cu")
		(net "GND")
	)
	(gr_poly
		(pts
			(arc
				(start 272.141188 -295.510204)
				(mid 271.80794 -295.510204)
				(end 272.141188 -295.510204)
			)
		)
		(stroke
			(width 0)
			(type solid)
		)
		(fill yes)
		(layer "F.Cu")
		(net "GND")
	)
	(gr_poly
		(pts
			(arc
				(start 272.141188 -286.16021)
				(mid 271.80794 -286.16021)
				(end 272.141188 -286.16021)
			)
		)
		(stroke
			(width 0)
			(type solid)
		)
		(fill yes)
		(layer "F.Cu")
		(net "GND")
	)
	(gr_poly
		(pts
			(arc
				(start 272.141188 -276.810216)
				(mid 271.80794 -276.810216)
				(end 272.141188 -276.810216)
			)
		)
		(stroke
			(width 0)
			(type solid)
		)
		(fill yes)
		(layer "F.Cu")
		(net "GND")
	)
	(gr_poly
		(pts
			(arc
				(start 272.141188 -239.41024)
				(mid 271.80794 -239.41024)
				(end 272.141188 -239.41024)
			)
		)
		(stroke
			(width 0)
			(type solid)
		)
		(fill yes)
		(layer "F.Cu")
		(net "GND")
	)
	(gr_poly
		(pts
			(arc
				(start 272.141188 -230.060246)
				(mid 271.80794 -230.060246)
				(end 272.141188 -230.060246)
			)
		)
		(stroke
			(width 0)
			(type solid)
		)
		(fill yes)
		(layer "F.Cu")
		(net "GND")
	)
	(gr_poly
		(pts
			(arc
				(start 272.141188 -220.709998)
				(mid 271.80794 -220.709998)
				(end 272.141188 -220.709998)
			)
		)
		(stroke
			(width 0)
			(type solid)
		)
		(fill yes)
		(layer "F.Cu")
		(net "GND")
	)
	(gr_poly
		(pts
			(arc
				(start 272.141188 -211.360004)
				(mid 271.80794 -211.360004)
				(end 272.141188 -211.360004)
			)
		)
		(stroke
			(width 0)
			(type solid)
		)
		(fill yes)
		(layer "F.Cu")
		(net "GND")
	)
	(gr_poly
		(pts
			(arc
				(start 272.141188 -202.01001)
				(mid 271.80794 -202.01001)
				(end 272.141188 -202.01001)
			)
		)
		(stroke
			(width 0)
			(type solid)
		)
		(fill yes)
		(layer "F.Cu")
		(net "GND")
	)
	(gr_poly
		(pts
			(arc
				(start 273.165824 -99.380548)
				(mid 272.832576 -99.380548)
				(end 273.165824 -99.380548)
			)
		)
		(stroke
			(width 0)
			(type solid)
		)
		(fill yes)
		(layer "F.Cu")
		(net "GND")
	)
	(gr_poly
		(pts
			(xy 273.292316 -101.821488) (xy 273.292316 -101.176582) (xy 273.292316 -100.720398) (xy 273.129756 -100.557838)
			(xy 272.751804 -100.557838) (xy 271.383506 -100.557838) (xy 271.142206 -100.316538) (xy 271.142206 -99.56673)
			(xy 270.81226 -99.236784) (xy 269.034514 -99.236784) (xy 268.310868 -99.96043) (xy 267.750036 -99.96043)
			(xy 267.687044 -99.897438) (xy 267.687044 -96.793304) (xy 268.180058 -96.30029) (xy 270.392906 -96.30029)
			(xy 270.52905 -96.164146) (xy 270.52905 -95.388176) (xy 270.41348 -95.272606) (xy 263.534652 -95.272606)
			(xy 263.345676 -95.461582) (xy 263.345676 -96.206056) (xy 263.460992 -96.321372) (xy 265.809984 -96.321372)
			(xy 267.0683 -97.579688) (xy 267.0683 -100.823776) (xy 267.309346 -101.064822) (xy 270.39824 -101.064822)
			(xy 271.47393 -102.140512) (xy 272.973292 -102.140512)
		)
		(stroke
			(width 0)
			(type solid)
		)
		(fill yes)
		(layer "F.Cu")
		(net "PVDD18_S5_P0")
	)
	(gr_poly
		(pts
			(arc
				(start 273.830796 -107.168188)
				(mid 273.497548 -107.168188)
				(end 273.830796 -107.168188)
			)
		)
		(stroke
			(width 0)
			(type solid)
		)
		(fill yes)
		(layer "F.Cu")
		(net "GND")
	)
	(gr_poly
		(pts
			(arc
				(start 273.830796 -105.857802)
				(mid 273.497548 -105.857802)
				(end 273.830796 -105.857802)
			)
		)
		(stroke
			(width 0)
			(type solid)
		)
		(fill yes)
		(layer "F.Cu")
		(net "GND")
	)
	(gr_poly
		(pts
			(arc
				(start 273.830796 -104.475788)
				(mid 273.497548 -104.475788)
				(end 273.830796 -104.475788)
			)
		)
		(stroke
			(width 0)
			(type solid)
		)
		(fill yes)
		(layer "F.Cu")
		(net "GND")
	)
	(gr_poly
		(pts
			(arc
				(start 276.241256 -313.360054)
				(mid 275.908008 -313.360054)
				(end 276.241256 -313.360054)
			)
		)
		(stroke
			(width 0)
			(type solid)
		)
		(fill yes)
		(layer "F.Cu")
		(net "GND")
	)
	(gr_poly
		(pts
			(arc
				(start 276.241256 -285.310072)
				(mid 275.908008 -285.310072)
				(end 276.241256 -285.310072)
			)
		)
		(stroke
			(width 0)
			(type solid)
		)
		(fill yes)
		(layer "F.Cu")
		(net "GND")
	)
	(gr_poly
		(pts
			(arc
				(start 276.241256 -275.960078)
				(mid 275.908008 -275.960078)
				(end 276.241256 -275.960078)
			)
		)
		(stroke
			(width 0)
			(type solid)
		)
		(fill yes)
		(layer "F.Cu")
		(net "GND")
	)
	(gr_poly
		(pts
			(arc
				(start 276.241256 -238.560102)
				(mid 275.908008 -238.560102)
				(end 276.241256 -238.560102)
			)
		)
		(stroke
			(width 0)
			(type solid)
		)
		(fill yes)
		(layer "F.Cu")
		(net "GND")
	)
	(gr_poly
		(pts
			(arc
				(start 276.241256 -229.210108)
				(mid 275.908008 -229.210108)
				(end 276.241256 -229.210108)
			)
		)
		(stroke
			(width 0)
			(type solid)
		)
		(fill yes)
		(layer "F.Cu")
		(net "GND")
	)
	(gr_poly
		(pts
			(arc
				(start 276.241256 -219.860114)
				(mid 275.908008 -219.860114)
				(end 276.241256 -219.860114)
			)
		)
		(stroke
			(width 0)
			(type solid)
		)
		(fill yes)
		(layer "F.Cu")
		(net "GND")
	)
	(gr_poly
		(pts
			(arc
				(start 276.241256 -210.51012)
				(mid 275.908008 -210.51012)
				(end 276.241256 -210.51012)
			)
		)
		(stroke
			(width 0)
			(type solid)
		)
		(fill yes)
		(layer "F.Cu")
		(net "GND")
	)
	(gr_poly
		(pts
			(arc
				(start 276.241256 -201.160126)
				(mid 275.908008 -201.160126)
				(end 276.241256 -201.160126)
			)
		)
		(stroke
			(width 0)
			(type solid)
		)
		(fill yes)
		(layer "F.Cu")
		(net "GND")
	)
	(gr_poly
		(pts
			(arc
				(start 277.972012 -108.70184)
				(mid 277.638764 -108.70184)
				(end 277.972012 -108.70184)
			)
		)
		(stroke
			(width 0)
			(type solid)
		)
		(fill yes)
		(layer "F.Cu")
		(net "GND")
	)
	(gr_poly
		(pts
			(arc
				(start 279.684988 -314.210192)
				(mid 279.35174 -314.210192)
				(end 279.684988 -314.210192)
			)
		)
		(stroke
			(width 0)
			(type solid)
		)
		(fill yes)
		(layer "F.Cu")
		(net "GND")
	)
	(gr_poly
		(pts
			(arc
				(start 279.684988 -304.860198)
				(mid 279.35174 -304.860198)
				(end 279.684988 -304.860198)
			)
		)
		(stroke
			(width 0)
			(type solid)
		)
		(fill yes)
		(layer "F.Cu")
		(net "GND")
	)
	(gr_poly
		(pts
			(arc
				(start 279.684988 -295.510204)
				(mid 279.35174 -295.510204)
				(end 279.684988 -295.510204)
			)
		)
		(stroke
			(width 0)
			(type solid)
		)
		(fill yes)
		(layer "F.Cu")
		(net "GND")
	)
	(gr_poly
		(pts
			(arc
				(start 279.684988 -286.16021)
				(mid 279.35174 -286.16021)
				(end 279.684988 -286.16021)
			)
		)
		(stroke
			(width 0)
			(type solid)
		)
		(fill yes)
		(layer "F.Cu")
		(net "GND")
	)
	(gr_poly
		(pts
			(arc
				(start 279.684988 -276.810216)
				(mid 279.35174 -276.810216)
				(end 279.684988 -276.810216)
			)
		)
		(stroke
			(width 0)
			(type solid)
		)
		(fill yes)
		(layer "F.Cu")
		(net "GND")
	)
	(gr_poly
		(pts
			(arc
				(start 279.684988 -239.41024)
				(mid 279.35174 -239.41024)
				(end 279.684988 -239.41024)
			)
		)
		(stroke
			(width 0)
			(type solid)
		)
		(fill yes)
		(layer "F.Cu")
		(net "GND")
	)
	(gr_poly
		(pts
			(arc
				(start 279.684988 -230.060246)
				(mid 279.35174 -230.060246)
				(end 279.684988 -230.060246)
			)
		)
		(stroke
			(width 0)
			(type solid)
		)
		(fill yes)
		(layer "F.Cu")
		(net "GND")
	)
	(gr_poly
		(pts
			(arc
				(start 279.684988 -220.709998)
				(mid 279.35174 -220.709998)
				(end 279.684988 -220.709998)
			)
		)
		(stroke
			(width 0)
			(type solid)
		)
		(fill yes)
		(layer "F.Cu")
		(net "GND")
	)
	(gr_poly
		(pts
			(arc
				(start 279.684988 -211.360004)
				(mid 279.35174 -211.360004)
				(end 279.684988 -211.360004)
			)
		)
		(stroke
			(width 0)
			(type solid)
		)
		(fill yes)
		(layer "F.Cu")
		(net "GND")
	)
	(gr_poly
		(pts
			(arc
				(start 279.684988 -202.01001)
				(mid 279.35174 -202.01001)
				(end 279.684988 -202.01001)
			)
		)
		(stroke
			(width 0)
			(type solid)
		)
		(fill yes)
		(layer "F.Cu")
		(net "GND")
	)
	(gr_poly
		(pts
			(arc
				(start 283.785056 -313.360054)
				(mid 283.451808 -313.360054)
				(end 283.785056 -313.360054)
			)
		)
		(stroke
			(width 0)
			(type solid)
		)
		(fill yes)
		(layer "F.Cu")
		(net "GND")
	)
	(gr_poly
		(pts
			(arc
				(start 283.785056 -275.960078)
				(mid 283.451808 -275.960078)
				(end 283.785056 -275.960078)
			)
		)
		(stroke
			(width 0)
			(type solid)
		)
		(fill yes)
		(layer "F.Cu")
		(net "GND")
	)
	(gr_poly
		(pts
			(arc
				(start 283.785056 -238.560102)
				(mid 283.451808 -238.560102)
				(end 283.785056 -238.560102)
			)
		)
		(stroke
			(width 0)
			(type solid)
		)
		(fill yes)
		(layer "F.Cu")
		(net "GND")
	)
	(gr_poly
		(pts
			(arc
				(start 283.785056 -229.210108)
				(mid 283.451808 -229.210108)
				(end 283.785056 -229.210108)
			)
		)
		(stroke
			(width 0)
			(type solid)
		)
		(fill yes)
		(layer "F.Cu")
		(net "GND")
	)
	(gr_poly
		(pts
			(arc
				(start 283.785056 -219.860114)
				(mid 283.451808 -219.860114)
				(end 283.785056 -219.860114)
			)
		)
		(stroke
			(width 0)
			(type solid)
		)
		(fill yes)
		(layer "F.Cu")
		(net "GND")
	)
	(gr_poly
		(pts
			(arc
				(start 283.785056 -210.51012)
				(mid 283.451808 -210.51012)
				(end 283.785056 -210.51012)
			)
		)
		(stroke
			(width 0)
			(type solid)
		)
		(fill yes)
		(layer "F.Cu")
		(net "GND")
	)
	(gr_poly
		(pts
			(arc
				(start 283.785056 -201.160126)
				(mid 283.451808 -201.160126)
				(end 283.785056 -201.160126)
			)
		)
		(stroke
			(width 0)
			(type solid)
		)
		(fill yes)
		(layer "F.Cu")
		(net "GND")
	)
	(gr_poly
		(pts
			(xy 285.884112 -102.899464) (xy 285.884112 -102.12324) (xy 285.884112 -99.323398) (xy 285.632398 -99.071684)
			(xy 283.36748 -99.071684) (xy 283.36748 -99.061524) (xy 283.133546 -98.82759) (xy 283.133546 -96.52762)
			(xy 283.420566 -96.2406) (xy 285.0134 -96.2406) (xy 285.084012 -96.169988) (xy 285.084012 -96.080326)
			(xy 285.084012 -95.167958) (xy 285.02483 -95.108776) (xy 284.931104 -95.108776) (xy 284.929834 -95.10776)
			(xy 277.86203 -95.10776) (xy 277.80742 -95.16237) (xy 277.80742 -95.520764) (xy 277.83409 -95.547434)
			(xy 281.800554 -95.547434) (xy 282.105862 -95.852742) (xy 282.105862 -96.478598) (xy 282.105862 -100.368862)
			(xy 282.26639 -100.52939) (xy 283.157676 -100.52939) (xy 283.870908 -101.242622) (xy 283.870908 -102.700074)
			(xy 284.174946 -103.004112) (xy 285.779464 -103.004112)
		)
		(stroke
			(width 0)
			(type solid)
		)
		(fill yes)
		(layer "F.Cu")
		(net "PVDD18_S5_P0")
	)
	(gr_poly
		(pts
			(arc
				(start 287.229042 -314.210192)
				(mid 286.895794 -314.210192)
				(end 287.229042 -314.210192)
			)
		)
		(stroke
			(width 0)
			(type solid)
		)
		(fill yes)
		(layer "F.Cu")
		(net "GND")
	)
	(gr_poly
		(pts
			(arc
				(start 287.229042 -304.860198)
				(mid 286.895794 -304.860198)
				(end 287.229042 -304.860198)
			)
		)
		(stroke
			(width 0)
			(type solid)
		)
		(fill yes)
		(layer "F.Cu")
		(net "GND")
	)
	(gr_poly
		(pts
			(arc
				(start 287.229042 -295.510204)
				(mid 286.895794 -295.510204)
				(end 287.229042 -295.510204)
			)
		)
		(stroke
			(width 0)
			(type solid)
		)
		(fill yes)
		(layer "F.Cu")
		(net "GND")
	)
	(gr_poly
		(pts
			(arc
				(start 287.229042 -286.16021)
				(mid 286.895794 -286.16021)
				(end 287.229042 -286.16021)
			)
		)
		(stroke
			(width 0)
			(type solid)
		)
		(fill yes)
		(layer "F.Cu")
		(net "GND")
	)
	(gr_poly
		(pts
			(arc
				(start 287.229042 -276.810216)
				(mid 286.895794 -276.810216)
				(end 287.229042 -276.810216)
			)
		)
		(stroke
			(width 0)
			(type solid)
		)
		(fill yes)
		(layer "F.Cu")
		(net "GND")
	)
	(gr_poly
		(pts
			(arc
				(start 287.229042 -239.41024)
				(mid 286.895794 -239.41024)
				(end 287.229042 -239.41024)
			)
		)
		(stroke
			(width 0)
			(type solid)
		)
		(fill yes)
		(layer "F.Cu")
		(net "GND")
	)
	(gr_poly
		(pts
			(arc
				(start 287.229042 -230.060246)
				(mid 286.895794 -230.060246)
				(end 287.229042 -230.060246)
			)
		)
		(stroke
			(width 0)
			(type solid)
		)
		(fill yes)
		(layer "F.Cu")
		(net "GND")
	)
	(gr_poly
		(pts
			(arc
				(start 287.229042 -220.709998)
				(mid 286.895794 -220.709998)
				(end 287.229042 -220.709998)
			)
		)
		(stroke
			(width 0)
			(type solid)
		)
		(fill yes)
		(layer "F.Cu")
		(net "GND")
	)
	(gr_poly
		(pts
			(arc
				(start 287.229042 -211.360004)
				(mid 286.895794 -211.360004)
				(end 287.229042 -211.360004)
			)
		)
		(stroke
			(width 0)
			(type solid)
		)
		(fill yes)
		(layer "F.Cu")
		(net "GND")
	)
	(gr_poly
		(pts
			(arc
				(start 287.229042 -202.01001)
				(mid 286.895794 -202.01001)
				(end 287.229042 -202.01001)
			)
		)
		(stroke
			(width 0)
			(type solid)
		)
		(fill yes)
		(layer "F.Cu")
		(net "GND")
	)
	(gr_poly
		(pts
			(arc
				(start 291.32911 -313.360054)
				(mid 290.995862 -313.360054)
				(end 291.32911 -313.360054)
			)
		)
		(stroke
			(width 0)
			(type solid)
		)
		(fill yes)
		(layer "F.Cu")
		(net "GND")
	)
	(gr_poly
		(pts
			(arc
				(start 291.32911 -275.960078)
				(mid 290.995862 -275.960078)
				(end 291.32911 -275.960078)
			)
		)
		(stroke
			(width 0)
			(type solid)
		)
		(fill yes)
		(layer "F.Cu")
		(net "GND")
	)
	(gr_poly
		(pts
			(arc
				(start 291.32911 -238.560102)
				(mid 290.995862 -238.560102)
				(end 291.32911 -238.560102)
			)
		)
		(stroke
			(width 0)
			(type solid)
		)
		(fill yes)
		(layer "F.Cu")
		(net "GND")
	)
	(gr_poly
		(pts
			(arc
				(start 291.32911 -229.210108)
				(mid 290.995862 -229.210108)
				(end 291.32911 -229.210108)
			)
		)
		(stroke
			(width 0)
			(type solid)
		)
		(fill yes)
		(layer "F.Cu")
		(net "GND")
	)
	(gr_poly
		(pts
			(arc
				(start 291.32911 -219.860114)
				(mid 290.995862 -219.860114)
				(end 291.32911 -219.860114)
			)
		)
		(stroke
			(width 0)
			(type solid)
		)
		(fill yes)
		(layer "F.Cu")
		(net "GND")
	)
	(gr_poly
		(pts
			(arc
				(start 291.32911 -210.51012)
				(mid 290.995862 -210.51012)
				(end 291.32911 -210.51012)
			)
		)
		(stroke
			(width 0)
			(type solid)
		)
		(fill yes)
		(layer "F.Cu")
		(net "GND")
	)
	(gr_poly
		(pts
			(arc
				(start 291.32911 -201.160126)
				(mid 290.995862 -201.160126)
				(end 291.32911 -201.160126)
			)
		)
		(stroke
			(width 0)
			(type solid)
		)
		(fill yes)
		(layer "F.Cu")
		(net "GND")
	)
	(gr_poly
		(pts
			(arc
				(start 294.773096 -314.210192)
				(mid 294.439848 -314.210192)
				(end 294.773096 -314.210192)
			)
		)
		(stroke
			(width 0)
			(type solid)
		)
		(fill yes)
		(layer "F.Cu")
		(net "GND")
	)
	(gr_poly
		(pts
			(arc
				(start 294.773096 -304.860198)
				(mid 294.439848 -304.860198)
				(end 294.773096 -304.860198)
			)
		)
		(stroke
			(width 0)
			(type solid)
		)
		(fill yes)
		(layer "F.Cu")
		(net "GND")
	)
	(gr_poly
		(pts
			(arc
				(start 294.773096 -295.510204)
				(mid 294.439848 -295.510204)
				(end 294.773096 -295.510204)
			)
		)
		(stroke
			(width 0)
			(type solid)
		)
		(fill yes)
		(layer "F.Cu")
		(net "GND")
	)
	(gr_poly
		(pts
			(arc
				(start 294.773096 -286.16021)
				(mid 294.439848 -286.16021)
				(end 294.773096 -286.16021)
			)
		)
		(stroke
			(width 0)
			(type solid)
		)
		(fill yes)
		(layer "F.Cu")
		(net "GND")
	)
	(gr_poly
		(pts
			(arc
				(start 294.773096 -276.810216)
				(mid 294.439848 -276.810216)
				(end 294.773096 -276.810216)
			)
		)
		(stroke
			(width 0)
			(type solid)
		)
		(fill yes)
		(layer "F.Cu")
		(net "GND")
	)
	(gr_poly
		(pts
			(arc
				(start 294.773096 -239.41024)
				(mid 294.439848 -239.41024)
				(end 294.773096 -239.41024)
			)
		)
		(stroke
			(width 0)
			(type solid)
		)
		(fill yes)
		(layer "F.Cu")
		(net "GND")
	)
	(gr_poly
		(pts
			(arc
				(start 294.773096 -230.060246)
				(mid 294.439848 -230.060246)
				(end 294.773096 -230.060246)
			)
		)
		(stroke
			(width 0)
			(type solid)
		)
		(fill yes)
		(layer "F.Cu")
		(net "GND")
	)
	(gr_poly
		(pts
			(arc
				(start 294.773096 -220.709998)
				(mid 294.439848 -220.709998)
				(end 294.773096 -220.709998)
			)
		)
		(stroke
			(width 0)
			(type solid)
		)
		(fill yes)
		(layer "F.Cu")
		(net "GND")
	)
	(gr_poly
		(pts
			(arc
				(start 294.773096 -211.360004)
				(mid 294.439848 -211.360004)
				(end 294.773096 -211.360004)
			)
		)
		(stroke
			(width 0)
			(type solid)
		)
		(fill yes)
		(layer "F.Cu")
		(net "GND")
	)
	(gr_poly
		(pts
			(arc
				(start 294.773096 -202.01001)
				(mid 294.439848 -202.01001)
				(end 294.773096 -202.01001)
			)
		)
		(stroke
			(width 0)
			(type solid)
		)
		(fill yes)
		(layer "F.Cu")
		(net "GND")
	)
	(gr_poly
		(pts
			(arc
				(start 298.873164 -313.360054)
				(mid 298.539916 -313.360054)
				(end 298.873164 -313.360054)
			)
		)
		(stroke
			(width 0)
			(type solid)
		)
		(fill yes)
		(layer "F.Cu")
		(net "GND")
	)
	(gr_poly
		(pts
			(arc
				(start 298.873164 -304.01006)
				(mid 298.539916 -304.01006)
				(end 298.873164 -304.01006)
			)
		)
		(stroke
			(width 0)
			(type solid)
		)
		(fill yes)
		(layer "F.Cu")
		(net "GND")
	)
	(gr_poly
		(pts
			(arc
				(start 298.873164 -294.660066)
				(mid 298.539916 -294.660066)
				(end 298.873164 -294.660066)
			)
		)
		(stroke
			(width 0)
			(type solid)
		)
		(fill yes)
		(layer "F.Cu")
		(net "GND")
	)
	(gr_poly
		(pts
			(arc
				(start 298.873164 -285.310072)
				(mid 298.539916 -285.310072)
				(end 298.873164 -285.310072)
			)
		)
		(stroke
			(width 0)
			(type solid)
		)
		(fill yes)
		(layer "F.Cu")
		(net "GND")
	)
	(gr_poly
		(pts
			(arc
				(start 298.873164 -275.960078)
				(mid 298.539916 -275.960078)
				(end 298.873164 -275.960078)
			)
		)
		(stroke
			(width 0)
			(type solid)
		)
		(fill yes)
		(layer "F.Cu")
		(net "GND")
	)
	(gr_poly
		(pts
			(arc
				(start 298.873164 -238.560102)
				(mid 298.539916 -238.560102)
				(end 298.873164 -238.560102)
			)
		)
		(stroke
			(width 0)
			(type solid)
		)
		(fill yes)
		(layer "F.Cu")
		(net "GND")
	)
	(gr_poly
		(pts
			(arc
				(start 298.873164 -229.210108)
				(mid 298.539916 -229.210108)
				(end 298.873164 -229.210108)
			)
		)
		(stroke
			(width 0)
			(type solid)
		)
		(fill yes)
		(layer "F.Cu")
		(net "GND")
	)
	(gr_poly
		(pts
			(arc
				(start 298.873164 -219.860114)
				(mid 298.539916 -219.860114)
				(end 298.873164 -219.860114)
			)
		)
		(stroke
			(width 0)
			(type solid)
		)
		(fill yes)
		(layer "F.Cu")
		(net "GND")
	)
	(gr_poly
		(pts
			(arc
				(start 298.873164 -210.51012)
				(mid 298.539916 -210.51012)
				(end 298.873164 -210.51012)
			)
		)
		(stroke
			(width 0)
			(type solid)
		)
		(fill yes)
		(layer "F.Cu")
		(net "GND")
	)
	(gr_poly
		(pts
			(arc
				(start 298.873164 -201.160126)
				(mid 298.539916 -201.160126)
				(end 298.873164 -201.160126)
			)
		)
		(stroke
			(width 0)
			(type solid)
		)
		(fill yes)
		(layer "F.Cu")
		(net "GND")
	)
	(gr_poly
		(pts
			(arc
				(start 302.31715 -314.210192)
				(mid 301.983902 -314.210192)
				(end 302.31715 -314.210192)
			)
		)
		(stroke
			(width 0)
			(type solid)
		)
		(fill yes)
		(layer "F.Cu")
		(net "GND")
	)
	(gr_poly
		(pts
			(arc
				(start 302.31715 -304.860198)
				(mid 301.983902 -304.860198)
				(end 302.31715 -304.860198)
			)
		)
		(stroke
			(width 0)
			(type solid)
		)
		(fill yes)
		(layer "F.Cu")
		(net "GND")
	)
	(gr_poly
		(pts
			(arc
				(start 302.31715 -295.510204)
				(mid 301.983902 -295.510204)
				(end 302.31715 -295.510204)
			)
		)
		(stroke
			(width 0)
			(type solid)
		)
		(fill yes)
		(layer "F.Cu")
		(net "GND")
	)
	(gr_poly
		(pts
			(arc
				(start 302.31715 -286.16021)
				(mid 301.983902 -286.16021)
				(end 302.31715 -286.16021)
			)
		)
		(stroke
			(width 0)
			(type solid)
		)
		(fill yes)
		(layer "F.Cu")
		(net "GND")
	)
	(gr_poly
		(pts
			(arc
				(start 302.31715 -276.810216)
				(mid 301.983902 -276.810216)
				(end 302.31715 -276.810216)
			)
		)
		(stroke
			(width 0)
			(type solid)
		)
		(fill yes)
		(layer "F.Cu")
		(net "GND")
	)
	(gr_poly
		(pts
			(arc
				(start 302.31715 -239.41024)
				(mid 301.983902 -239.41024)
				(end 302.31715 -239.41024)
			)
		)
		(stroke
			(width 0)
			(type solid)
		)
		(fill yes)
		(layer "F.Cu")
		(net "GND")
	)
	(gr_poly
		(pts
			(arc
				(start 302.31715 -230.060246)
				(mid 301.983902 -230.060246)
				(end 302.31715 -230.060246)
			)
		)
		(stroke
			(width 0)
			(type solid)
		)
		(fill yes)
		(layer "F.Cu")
		(net "GND")
	)
	(gr_poly
		(pts
			(arc
				(start 302.31715 -220.709998)
				(mid 301.983902 -220.709998)
				(end 302.31715 -220.709998)
			)
		)
		(stroke
			(width 0)
			(type solid)
		)
		(fill yes)
		(layer "F.Cu")
		(net "GND")
	)
	(gr_poly
		(pts
			(arc
				(start 302.31715 -211.360004)
				(mid 301.983902 -211.360004)
				(end 302.31715 -211.360004)
			)
		)
		(stroke
			(width 0)
			(type solid)
		)
		(fill yes)
		(layer "F.Cu")
		(net "GND")
	)
	(gr_poly
		(pts
			(arc
				(start 302.31715 -202.01001)
				(mid 301.983902 -202.01001)
				(end 302.31715 -202.01001)
			)
		)
		(stroke
			(width 0)
			(type solid)
		)
		(fill yes)
		(layer "F.Cu")
		(net "GND")
	)
	(gr_poly
		(pts
			(arc
				(start 306.417218 -313.360054)
				(mid 306.08397 -313.360054)
				(end 306.417218 -313.360054)
			)
		)
		(stroke
			(width 0)
			(type solid)
		)
		(fill yes)
		(layer "F.Cu")
		(net "GND")
	)
	(gr_poly
		(pts
			(arc
				(start 306.417218 -304.01006)
				(mid 306.08397 -304.01006)
				(end 306.417218 -304.01006)
			)
		)
		(stroke
			(width 0)
			(type solid)
		)
		(fill yes)
		(layer "F.Cu")
		(net "GND")
	)
	(gr_poly
		(pts
			(arc
				(start 306.417218 -294.660066)
				(mid 306.08397 -294.660066)
				(end 306.417218 -294.660066)
			)
		)
		(stroke
			(width 0)
			(type solid)
		)
		(fill yes)
		(layer "F.Cu")
		(net "GND")
	)
	(gr_poly
		(pts
			(arc
				(start 306.417218 -285.310072)
				(mid 306.08397 -285.310072)
				(end 306.417218 -285.310072)
			)
		)
		(stroke
			(width 0)
			(type solid)
		)
		(fill yes)
		(layer "F.Cu")
		(net "GND")
	)
	(gr_poly
		(pts
			(arc
				(start 306.417218 -275.960078)
				(mid 306.08397 -275.960078)
				(end 306.417218 -275.960078)
			)
		)
		(stroke
			(width 0)
			(type solid)
		)
		(fill yes)
		(layer "F.Cu")
		(net "GND")
	)
	(gr_poly
		(pts
			(arc
				(start 306.417218 -238.560102)
				(mid 306.08397 -238.560102)
				(end 306.417218 -238.560102)
			)
		)
		(stroke
			(width 0)
			(type solid)
		)
		(fill yes)
		(layer "F.Cu")
		(net "GND")
	)
	(gr_poly
		(pts
			(arc
				(start 306.417218 -229.210108)
				(mid 306.08397 -229.210108)
				(end 306.417218 -229.210108)
			)
		)
		(stroke
			(width 0)
			(type solid)
		)
		(fill yes)
		(layer "F.Cu")
		(net "GND")
	)
	(gr_poly
		(pts
			(arc
				(start 306.417218 -219.860114)
				(mid 306.08397 -219.860114)
				(end 306.417218 -219.860114)
			)
		)
		(stroke
			(width 0)
			(type solid)
		)
		(fill yes)
		(layer "F.Cu")
		(net "GND")
	)
	(gr_poly
		(pts
			(arc
				(start 306.417218 -210.51012)
				(mid 306.08397 -210.51012)
				(end 306.417218 -210.51012)
			)
		)
		(stroke
			(width 0)
			(type solid)
		)
		(fill yes)
		(layer "F.Cu")
		(net "GND")
	)
	(gr_poly
		(pts
			(arc
				(start 306.417218 -201.160126)
				(mid 306.08397 -201.160126)
				(end 306.417218 -201.160126)
			)
		)
		(stroke
			(width 0)
			(type solid)
		)
		(fill yes)
		(layer "F.Cu")
		(net "GND")
	)
	(gr_poly
		(pts
			(arc
				(start 338.056982 -217.776552)
				(mid 337.723734 -217.776552)
				(end 338.056982 -217.776552)
			)
		)
		(stroke
			(width 0)
			(type solid)
		)
		(fill yes)
		(layer "F.Cu")
		(net "GND")
	)
	(gr_poly
		(pts
			(arc
				(start 340.360762 -217.776552)
				(mid 340.027514 -217.776552)
				(end 340.360762 -217.776552)
			)
		)
		(stroke
			(width 0)
			(type solid)
		)
		(fill yes)
		(layer "F.Cu")
		(net "GND")
	)
	(gr_poly
		(pts
			(arc
				(start 379.305566 -210.442302)
				(mid 378.972318 -210.442302)
				(end 379.305566 -210.442302)
			)
		)
		(stroke
			(width 0)
			(type solid)
		)
		(fill yes)
		(layer "F.Cu")
		(net "GND")
	)
	(gr_poly
		(pts
			(arc
				(start 381.506476 -209.587338)
				(mid 381.173228 -209.587338)
				(end 381.506476 -209.587338)
			)
		)
		(stroke
			(width 0)
			(type solid)
		)
		(fill yes)
		(layer "F.Cu")
		(net "GND")
	)
	(gr_poly
		(pts
			(arc
				(start 413.652208 -314.210192)
				(mid 413.31896 -314.210192)
				(end 413.652208 -314.210192)
			)
		)
		(stroke
			(width 0)
			(type solid)
		)
		(fill yes)
		(layer "F.Cu")
		(net "GND")
	)
	(gr_poly
		(pts
			(arc
				(start 413.652208 -304.860198)
				(mid 413.31896 -304.860198)
				(end 413.652208 -304.860198)
			)
		)
		(stroke
			(width 0)
			(type solid)
		)
		(fill yes)
		(layer "F.Cu")
		(net "GND")
	)
	(gr_poly
		(pts
			(arc
				(start 413.652208 -295.510204)
				(mid 413.31896 -295.510204)
				(end 413.652208 -295.510204)
			)
		)
		(stroke
			(width 0)
			(type solid)
		)
		(fill yes)
		(layer "F.Cu")
		(net "GND")
	)
	(gr_poly
		(pts
			(arc
				(start 413.652208 -286.16021)
				(mid 413.31896 -286.16021)
				(end 413.652208 -286.16021)
			)
		)
		(stroke
			(width 0)
			(type solid)
		)
		(fill yes)
		(layer "F.Cu")
		(net "GND")
	)
	(gr_poly
		(pts
			(arc
				(start 413.652208 -276.810216)
				(mid 413.31896 -276.810216)
				(end 413.652208 -276.810216)
			)
		)
		(stroke
			(width 0)
			(type solid)
		)
		(fill yes)
		(layer "F.Cu")
		(net "GND")
	)
	(gr_poly
		(pts
			(arc
				(start 413.652208 -239.41024)
				(mid 413.31896 -239.41024)
				(end 413.652208 -239.41024)
			)
		)
		(stroke
			(width 0)
			(type solid)
		)
		(fill yes)
		(layer "F.Cu")
		(net "GND")
	)
	(gr_poly
		(pts
			(arc
				(start 413.652208 -230.060246)
				(mid 413.31896 -230.060246)
				(end 413.652208 -230.060246)
			)
		)
		(stroke
			(width 0)
			(type solid)
		)
		(fill yes)
		(layer "F.Cu")
		(net "GND")
	)
	(gr_poly
		(pts
			(arc
				(start 413.652208 -220.709998)
				(mid 413.31896 -220.709998)
				(end 413.652208 -220.709998)
			)
		)
		(stroke
			(width 0)
			(type solid)
		)
		(fill yes)
		(layer "F.Cu")
		(net "GND")
	)
	(gr_poly
		(pts
			(arc
				(start 413.652208 -211.360004)
				(mid 413.31896 -211.360004)
				(end 413.652208 -211.360004)
			)
		)
		(stroke
			(width 0)
			(type solid)
		)
		(fill yes)
		(layer "F.Cu")
		(net "GND")
	)
	(gr_poly
		(pts
			(arc
				(start 413.652208 -202.01001)
				(mid 413.31896 -202.01001)
				(end 413.652208 -202.01001)
			)
		)
		(stroke
			(width 0)
			(type solid)
		)
		(fill yes)
		(layer "F.Cu")
		(net "GND")
	)
	(gr_poly
		(pts
			(arc
				(start 417.752276 -313.360054)
				(mid 417.419028 -313.360054)
				(end 417.752276 -313.360054)
			)
		)
		(stroke
			(width 0)
			(type solid)
		)
		(fill yes)
		(layer "F.Cu")
		(net "GND")
	)
	(gr_poly
		(pts
			(arc
				(start 417.752276 -304.01006)
				(mid 417.419028 -304.01006)
				(end 417.752276 -304.01006)
			)
		)
		(stroke
			(width 0)
			(type solid)
		)
		(fill yes)
		(layer "F.Cu")
		(net "GND")
	)
	(gr_poly
		(pts
			(arc
				(start 417.752276 -294.660066)
				(mid 417.419028 -294.660066)
				(end 417.752276 -294.660066)
			)
		)
		(stroke
			(width 0)
			(type solid)
		)
		(fill yes)
		(layer "F.Cu")
		(net "GND")
	)
	(gr_poly
		(pts
			(arc
				(start 417.752276 -285.310072)
				(mid 417.419028 -285.310072)
				(end 417.752276 -285.310072)
			)
		)
		(stroke
			(width 0)
			(type solid)
		)
		(fill yes)
		(layer "F.Cu")
		(net "GND")
	)
	(gr_poly
		(pts
			(arc
				(start 417.752276 -275.960078)
				(mid 417.419028 -275.960078)
				(end 417.752276 -275.960078)
			)
		)
		(stroke
			(width 0)
			(type solid)
		)
		(fill yes)
		(layer "F.Cu")
		(net "GND")
	)
	(gr_poly
		(pts
			(arc
				(start 417.752276 -238.560102)
				(mid 417.419028 -238.560102)
				(end 417.752276 -238.560102)
			)
		)
		(stroke
			(width 0)
			(type solid)
		)
		(fill yes)
		(layer "F.Cu")
		(net "GND")
	)
	(gr_poly
		(pts
			(arc
				(start 417.752276 -229.210108)
				(mid 417.419028 -229.210108)
				(end 417.752276 -229.210108)
			)
		)
		(stroke
			(width 0)
			(type solid)
		)
		(fill yes)
		(layer "F.Cu")
		(net "GND")
	)
	(gr_poly
		(pts
			(arc
				(start 417.752276 -219.860114)
				(mid 417.419028 -219.860114)
				(end 417.752276 -219.860114)
			)
		)
		(stroke
			(width 0)
			(type solid)
		)
		(fill yes)
		(layer "F.Cu")
		(net "GND")
	)
	(gr_poly
		(pts
			(arc
				(start 417.752276 -210.51012)
				(mid 417.419028 -210.51012)
				(end 417.752276 -210.51012)
			)
		)
		(stroke
			(width 0)
			(type solid)
		)
		(fill yes)
		(layer "F.Cu")
		(net "GND")
	)
	(gr_poly
		(pts
			(arc
				(start 417.752276 -201.160126)
				(mid 417.419028 -201.160126)
				(end 417.752276 -201.160126)
			)
		)
		(stroke
			(width 0)
			(type solid)
		)
		(fill yes)
		(layer "F.Cu")
		(net "GND")
	)
	(gr_poly
		(pts
			(arc
				(start 421.196262 -314.210192)
				(mid 420.863014 -314.210192)
				(end 421.196262 -314.210192)
			)
		)
		(stroke
			(width 0)
			(type solid)
		)
		(fill yes)
		(layer "F.Cu")
		(net "GND")
	)
	(gr_poly
		(pts
			(arc
				(start 421.196262 -304.860198)
				(mid 420.863014 -304.860198)
				(end 421.196262 -304.860198)
			)
		)
		(stroke
			(width 0)
			(type solid)
		)
		(fill yes)
		(layer "F.Cu")
		(net "GND")
	)
	(gr_poly
		(pts
			(arc
				(start 421.196262 -295.510204)
				(mid 420.863014 -295.510204)
				(end 421.196262 -295.510204)
			)
		)
		(stroke
			(width 0)
			(type solid)
		)
		(fill yes)
		(layer "F.Cu")
		(net "GND")
	)
	(gr_poly
		(pts
			(arc
				(start 421.196262 -286.16021)
				(mid 420.863014 -286.16021)
				(end 421.196262 -286.16021)
			)
		)
		(stroke
			(width 0)
			(type solid)
		)
		(fill yes)
		(layer "F.Cu")
		(net "GND")
	)
	(gr_poly
		(pts
			(arc
				(start 421.196262 -276.810216)
				(mid 420.863014 -276.810216)
				(end 421.196262 -276.810216)
			)
		)
		(stroke
			(width 0)
			(type solid)
		)
		(fill yes)
		(layer "F.Cu")
		(net "GND")
	)
	(gr_poly
		(pts
			(arc
				(start 421.196262 -239.41024)
				(mid 420.863014 -239.41024)
				(end 421.196262 -239.41024)
			)
		)
		(stroke
			(width 0)
			(type solid)
		)
		(fill yes)
		(layer "F.Cu")
		(net "GND")
	)
	(gr_poly
		(pts
			(arc
				(start 421.196262 -230.060246)
				(mid 420.863014 -230.060246)
				(end 421.196262 -230.060246)
			)
		)
		(stroke
			(width 0)
			(type solid)
		)
		(fill yes)
		(layer "F.Cu")
		(net "GND")
	)
	(gr_poly
		(pts
			(arc
				(start 421.196262 -220.709998)
				(mid 420.863014 -220.709998)
				(end 421.196262 -220.709998)
			)
		)
		(stroke
			(width 0)
			(type solid)
		)
		(fill yes)
		(layer "F.Cu")
		(net "GND")
	)
	(gr_poly
		(pts
			(arc
				(start 421.196262 -211.360004)
				(mid 420.863014 -211.360004)
				(end 421.196262 -211.360004)
			)
		)
		(stroke
			(width 0)
			(type solid)
		)
		(fill yes)
		(layer "F.Cu")
		(net "GND")
	)
	(gr_poly
		(pts
			(arc
				(start 421.196262 -202.01001)
				(mid 420.863014 -202.01001)
				(end 421.196262 -202.01001)
			)
		)
		(stroke
			(width 0)
			(type solid)
		)
		(fill yes)
		(layer "F.Cu")
		(net "GND")
	)
	(gr_poly
		(pts
			(arc
				(start 425.29633 -313.360054)
				(mid 424.963082 -313.360054)
				(end 425.29633 -313.360054)
			)
		)
		(stroke
			(width 0)
			(type solid)
		)
		(fill yes)
		(layer "F.Cu")
		(net "GND")
	)
	(gr_poly
		(pts
			(arc
				(start 425.29633 -304.01006)
				(mid 424.963082 -304.01006)
				(end 425.29633 -304.01006)
			)
		)
		(stroke
			(width 0)
			(type solid)
		)
		(fill yes)
		(layer "F.Cu")
		(net "GND")
	)
	(gr_poly
		(pts
			(arc
				(start 425.29633 -294.660066)
				(mid 424.963082 -294.660066)
				(end 425.29633 -294.660066)
			)
		)
		(stroke
			(width 0)
			(type solid)
		)
		(fill yes)
		(layer "F.Cu")
		(net "GND")
	)
	(gr_poly
		(pts
			(arc
				(start 425.29633 -285.310072)
				(mid 424.963082 -285.310072)
				(end 425.29633 -285.310072)
			)
		)
		(stroke
			(width 0)
			(type solid)
		)
		(fill yes)
		(layer "F.Cu")
		(net "GND")
	)
	(gr_poly
		(pts
			(arc
				(start 425.29633 -275.960078)
				(mid 424.963082 -275.960078)
				(end 425.29633 -275.960078)
			)
		)
		(stroke
			(width 0)
			(type solid)
		)
		(fill yes)
		(layer "F.Cu")
		(net "GND")
	)
	(gr_poly
		(pts
			(arc
				(start 425.29633 -238.560102)
				(mid 424.963082 -238.560102)
				(end 425.29633 -238.560102)
			)
		)
		(stroke
			(width 0)
			(type solid)
		)
		(fill yes)
		(layer "F.Cu")
		(net "GND")
	)
	(gr_poly
		(pts
			(arc
				(start 425.29633 -229.210108)
				(mid 424.963082 -229.210108)
				(end 425.29633 -229.210108)
			)
		)
		(stroke
			(width 0)
			(type solid)
		)
		(fill yes)
		(layer "F.Cu")
		(net "GND")
	)
	(gr_poly
		(pts
			(arc
				(start 425.29633 -219.860114)
				(mid 424.963082 -219.860114)
				(end 425.29633 -219.860114)
			)
		)
		(stroke
			(width 0)
			(type solid)
		)
		(fill yes)
		(layer "F.Cu")
		(net "GND")
	)
	(gr_poly
		(pts
			(arc
				(start 425.29633 -210.51012)
				(mid 424.963082 -210.51012)
				(end 425.29633 -210.51012)
			)
		)
		(stroke
			(width 0)
			(type solid)
		)
		(fill yes)
		(layer "F.Cu")
		(net "GND")
	)
	(gr_poly
		(pts
			(arc
				(start 425.29633 -201.160126)
				(mid 424.963082 -201.160126)
				(end 425.29633 -201.160126)
			)
		)
		(stroke
			(width 0)
			(type solid)
		)
		(fill yes)
		(layer "F.Cu")
		(net "GND")
	)
	(gr_poly
		(pts
			(arc
				(start 428.740316 -314.210192)
				(mid 428.407068 -314.210192)
				(end 428.740316 -314.210192)
			)
		)
		(stroke
			(width 0)
			(type solid)
		)
		(fill yes)
		(layer "F.Cu")
		(net "GND")
	)
	(gr_poly
		(pts
			(arc
				(start 428.740316 -304.860198)
				(mid 428.407068 -304.860198)
				(end 428.740316 -304.860198)
			)
		)
		(stroke
			(width 0)
			(type solid)
		)
		(fill yes)
		(layer "F.Cu")
		(net "GND")
	)
	(gr_poly
		(pts
			(arc
				(start 428.740316 -295.510204)
				(mid 428.407068 -295.510204)
				(end 428.740316 -295.510204)
			)
		)
		(stroke
			(width 0)
			(type solid)
		)
		(fill yes)
		(layer "F.Cu")
		(net "GND")
	)
	(gr_poly
		(pts
			(arc
				(start 428.740316 -286.16021)
				(mid 428.407068 -286.16021)
				(end 428.740316 -286.16021)
			)
		)
		(stroke
			(width 0)
			(type solid)
		)
		(fill yes)
		(layer "F.Cu")
		(net "GND")
	)
	(gr_poly
		(pts
			(arc
				(start 428.740316 -276.810216)
				(mid 428.407068 -276.810216)
				(end 428.740316 -276.810216)
			)
		)
		(stroke
			(width 0)
			(type solid)
		)
		(fill yes)
		(layer "F.Cu")
		(net "GND")
	)
	(gr_poly
		(pts
			(arc
				(start 428.740316 -239.41024)
				(mid 428.407068 -239.41024)
				(end 428.740316 -239.41024)
			)
		)
		(stroke
			(width 0)
			(type solid)
		)
		(fill yes)
		(layer "F.Cu")
		(net "GND")
	)
	(gr_poly
		(pts
			(arc
				(start 428.740316 -230.060246)
				(mid 428.407068 -230.060246)
				(end 428.740316 -230.060246)
			)
		)
		(stroke
			(width 0)
			(type solid)
		)
		(fill yes)
		(layer "F.Cu")
		(net "GND")
	)
	(gr_poly
		(pts
			(arc
				(start 428.740316 -220.709998)
				(mid 428.407068 -220.709998)
				(end 428.740316 -220.709998)
			)
		)
		(stroke
			(width 0)
			(type solid)
		)
		(fill yes)
		(layer "F.Cu")
		(net "GND")
	)
	(gr_poly
		(pts
			(arc
				(start 428.740316 -211.360004)
				(mid 428.407068 -211.360004)
				(end 428.740316 -211.360004)
			)
		)
		(stroke
			(width 0)
			(type solid)
		)
		(fill yes)
		(layer "F.Cu")
		(net "GND")
	)
	(gr_poly
		(pts
			(arc
				(start 432.840384 -313.360054)
				(mid 432.507136 -313.360054)
				(end 432.840384 -313.360054)
			)
		)
		(stroke
			(width 0)
			(type solid)
		)
		(fill yes)
		(layer "F.Cu")
		(net "GND")
	)
	(gr_poly
		(pts
			(arc
				(start 432.840384 -294.660066)
				(mid 432.507136 -294.660066)
				(end 432.840384 -294.660066)
			)
		)
		(stroke
			(width 0)
			(type solid)
		)
		(fill yes)
		(layer "F.Cu")
		(net "GND")
	)
	(gr_poly
		(pts
			(arc
				(start 432.840384 -285.310072)
				(mid 432.507136 -285.310072)
				(end 432.840384 -285.310072)
			)
		)
		(stroke
			(width 0)
			(type solid)
		)
		(fill yes)
		(layer "F.Cu")
		(net "GND")
	)
	(gr_poly
		(pts
			(arc
				(start 432.840384 -275.960078)
				(mid 432.507136 -275.960078)
				(end 432.840384 -275.960078)
			)
		)
		(stroke
			(width 0)
			(type solid)
		)
		(fill yes)
		(layer "F.Cu")
		(net "GND")
	)
	(gr_poly
		(pts
			(arc
				(start 432.840384 -238.560102)
				(mid 432.507136 -238.560102)
				(end 432.840384 -238.560102)
			)
		)
		(stroke
			(width 0)
			(type solid)
		)
		(fill yes)
		(layer "F.Cu")
		(net "GND")
	)
	(gr_poly
		(pts
			(arc
				(start 432.840384 -229.210108)
				(mid 432.507136 -229.210108)
				(end 432.840384 -229.210108)
			)
		)
		(stroke
			(width 0)
			(type solid)
		)
		(fill yes)
		(layer "F.Cu")
		(net "GND")
	)
	(gr_poly
		(pts
			(arc
				(start 432.840384 -219.860114)
				(mid 432.507136 -219.860114)
				(end 432.840384 -219.860114)
			)
		)
		(stroke
			(width 0)
			(type solid)
		)
		(fill yes)
		(layer "F.Cu")
		(net "GND")
	)
	(gr_poly
		(pts
			(arc
				(start 432.840384 -210.51012)
				(mid 432.507136 -210.51012)
				(end 432.840384 -210.51012)
			)
		)
		(stroke
			(width 0)
			(type solid)
		)
		(fill yes)
		(layer "F.Cu")
		(net "GND")
	)
	(gr_poly
		(pts
			(arc
				(start 432.840384 -201.160126)
				(mid 432.507136 -201.160126)
				(end 432.840384 -201.160126)
			)
		)
		(stroke
			(width 0)
			(type solid)
		)
		(fill yes)
		(layer "F.Cu")
		(net "GND")
	)
	(gr_poly
		(pts
			(arc
				(start 436.28437 -314.210192)
				(mid 435.951122 -314.210192)
				(end 436.28437 -314.210192)
			)
		)
		(stroke
			(width 0)
			(type solid)
		)
		(fill yes)
		(layer "F.Cu")
		(net "GND")
	)
	(gr_poly
		(pts
			(arc
				(start 436.28437 -304.860198)
				(mid 435.951122 -304.860198)
				(end 436.28437 -304.860198)
			)
		)
		(stroke
			(width 0)
			(type solid)
		)
		(fill yes)
		(layer "F.Cu")
		(net "GND")
	)
	(gr_poly
		(pts
			(arc
				(start 436.28437 -295.510204)
				(mid 435.951122 -295.510204)
				(end 436.28437 -295.510204)
			)
		)
		(stroke
			(width 0)
			(type solid)
		)
		(fill yes)
		(layer "F.Cu")
		(net "GND")
	)
	(gr_poly
		(pts
			(arc
				(start 436.28437 -286.16021)
				(mid 435.951122 -286.16021)
				(end 436.28437 -286.16021)
			)
		)
		(stroke
			(width 0)
			(type solid)
		)
		(fill yes)
		(layer "F.Cu")
		(net "GND")
	)
	(gr_poly
		(pts
			(arc
				(start 436.28437 -276.810216)
				(mid 435.951122 -276.810216)
				(end 436.28437 -276.810216)
			)
		)
		(stroke
			(width 0)
			(type solid)
		)
		(fill yes)
		(layer "F.Cu")
		(net "GND")
	)
	(gr_poly
		(pts
			(arc
				(start 436.28437 -239.41024)
				(mid 435.951122 -239.41024)
				(end 436.28437 -239.41024)
			)
		)
		(stroke
			(width 0)
			(type solid)
		)
		(fill yes)
		(layer "F.Cu")
		(net "GND")
	)
	(gr_poly
		(pts
			(arc
				(start 436.28437 -230.060246)
				(mid 435.951122 -230.060246)
				(end 436.28437 -230.060246)
			)
		)
		(stroke
			(width 0)
			(type solid)
		)
		(fill yes)
		(layer "F.Cu")
		(net "GND")
	)
	(gr_poly
		(pts
			(arc
				(start 436.28437 -220.709998)
				(mid 435.951122 -220.709998)
				(end 436.28437 -220.709998)
			)
		)
		(stroke
			(width 0)
			(type solid)
		)
		(fill yes)
		(layer "F.Cu")
		(net "GND")
	)
	(gr_poly
		(pts
			(arc
				(start 436.28437 -211.360004)
				(mid 435.951122 -211.360004)
				(end 436.28437 -211.360004)
			)
		)
		(stroke
			(width 0)
			(type solid)
		)
		(fill yes)
		(layer "F.Cu")
		(net "GND")
	)
	(gr_poly
		(pts
			(arc
				(start 436.28437 -202.01001)
				(mid 435.951122 -202.01001)
				(end 436.28437 -202.01001)
			)
		)
		(stroke
			(width 0)
			(type solid)
		)
		(fill yes)
		(layer "F.Cu")
		(net "GND")
	)
	(gr_poly
		(pts
			(xy 438.42178 -362.78058) (xy 438.42178 -351.487994) (xy 438.293256 -351.35947) (xy 432.381152 -351.35947)
			(xy 432.343814 -351.396808) (xy 432.343814 -353.408742) (xy 432.42611 -353.491038) (xy 433.783994 -353.491038)
			(xy 433.921916 -353.62896) (xy 433.921916 -354.406454) (xy 434.222906 -354.707444) (xy 434.222906 -356.549452)
			(xy 433.714398 -357.05796) (xy 428.384462 -357.05796) (xy 427.642782 -356.31628) (xy 427.642782 -351.43567)
			(xy 427.541182 -351.33407) (xy 424.054524 -351.33407) (xy 424.032934 -351.35566) (xy 424.032934 -353.39909)
			(xy 424.048428 -353.414584) (xy 425.406312 -353.414584) (xy 425.593764 -353.602036) (xy 425.593764 -354.37953)
			(xy 425.955206 -354.740972) (xy 425.955206 -358.9147) (xy 426.151548 -359.111042) (xy 426.151548 -362.603542)
			(xy 426.510958 -362.962952) (xy 438.239408 -362.962952)
		)
		(stroke
			(width 0)
			(type solid)
		)
		(fill yes)
		(layer "F.Cu")
		(net "SW_P12V_AUX_PVDD11_S3_P0_FLT")
	)
	(gr_poly
		(pts
			(arc
				(start 440.384438 -313.360054)
				(mid 440.05119 -313.360054)
				(end 440.384438 -313.360054)
			)
		)
		(stroke
			(width 0)
			(type solid)
		)
		(fill yes)
		(layer "F.Cu")
		(net "GND")
	)
	(gr_poly
		(pts
			(arc
				(start 440.384438 -304.01006)
				(mid 440.05119 -304.01006)
				(end 440.384438 -304.01006)
			)
		)
		(stroke
			(width 0)
			(type solid)
		)
		(fill yes)
		(layer "F.Cu")
		(net "GND")
	)
	(gr_poly
		(pts
			(arc
				(start 440.384438 -294.660066)
				(mid 440.05119 -294.660066)
				(end 440.384438 -294.660066)
			)
		)
		(stroke
			(width 0)
			(type solid)
		)
		(fill yes)
		(layer "F.Cu")
		(net "GND")
	)
	(gr_poly
		(pts
			(arc
				(start 440.384438 -285.310072)
				(mid 440.05119 -285.310072)
				(end 440.384438 -285.310072)
			)
		)
		(stroke
			(width 0)
			(type solid)
		)
		(fill yes)
		(layer "F.Cu")
		(net "GND")
	)
	(gr_poly
		(pts
			(arc
				(start 440.384438 -275.960078)
				(mid 440.05119 -275.960078)
				(end 440.384438 -275.960078)
			)
		)
		(stroke
			(width 0)
			(type solid)
		)
		(fill yes)
		(layer "F.Cu")
		(net "GND")
	)
	(gr_poly
		(pts
			(arc
				(start 440.384438 -238.560102)
				(mid 440.05119 -238.560102)
				(end 440.384438 -238.560102)
			)
		)
		(stroke
			(width 0)
			(type solid)
		)
		(fill yes)
		(layer "F.Cu")
		(net "GND")
	)
	(gr_poly
		(pts
			(arc
				(start 440.384438 -229.210108)
				(mid 440.05119 -229.210108)
				(end 440.384438 -229.210108)
			)
		)
		(stroke
			(width 0)
			(type solid)
		)
		(fill yes)
		(layer "F.Cu")
		(net "GND")
	)
	(gr_poly
		(pts
			(arc
				(start 440.384438 -219.860114)
				(mid 440.05119 -219.860114)
				(end 440.384438 -219.860114)
			)
		)
		(stroke
			(width 0)
			(type solid)
		)
		(fill yes)
		(layer "F.Cu")
		(net "GND")
	)
	(gr_poly
		(pts
			(arc
				(start 440.384438 -201.160126)
				(mid 440.05119 -201.160126)
				(end 440.384438 -201.160126)
			)
		)
		(stroke
			(width 0)
			(type solid)
		)
		(fill yes)
		(layer "F.Cu")
		(net "GND")
	)
	(gr_poly
		(pts
			(arc
				(start 443.828424 -314.210192)
				(mid 443.495176 -314.210192)
				(end 443.828424 -314.210192)
			)
		)
		(stroke
			(width 0)
			(type solid)
		)
		(fill yes)
		(layer "F.Cu")
		(net "GND")
	)
	(gr_poly
		(pts
			(arc
				(start 443.828424 -304.860198)
				(mid 443.495176 -304.860198)
				(end 443.828424 -304.860198)
			)
		)
		(stroke
			(width 0)
			(type solid)
		)
		(fill yes)
		(layer "F.Cu")
		(net "GND")
	)
	(gr_poly
		(pts
			(arc
				(start 443.828424 -295.510204)
				(mid 443.495176 -295.510204)
				(end 443.828424 -295.510204)
			)
		)
		(stroke
			(width 0)
			(type solid)
		)
		(fill yes)
		(layer "F.Cu")
		(net "GND")
	)
	(gr_poly
		(pts
			(arc
				(start 443.828424 -286.16021)
				(mid 443.495176 -286.16021)
				(end 443.828424 -286.16021)
			)
		)
		(stroke
			(width 0)
			(type solid)
		)
		(fill yes)
		(layer "F.Cu")
		(net "GND")
	)
	(gr_poly
		(pts
			(arc
				(start 443.828424 -276.810216)
				(mid 443.495176 -276.810216)
				(end 443.828424 -276.810216)
			)
		)
		(stroke
			(width 0)
			(type solid)
		)
		(fill yes)
		(layer "F.Cu")
		(net "GND")
	)
	(gr_poly
		(pts
			(arc
				(start 443.828424 -239.41024)
				(mid 443.495176 -239.41024)
				(end 443.828424 -239.41024)
			)
		)
		(stroke
			(width 0)
			(type solid)
		)
		(fill yes)
		(layer "F.Cu")
		(net "GND")
	)
	(gr_poly
		(pts
			(arc
				(start 443.828424 -230.060246)
				(mid 443.495176 -230.060246)
				(end 443.828424 -230.060246)
			)
		)
		(stroke
			(width 0)
			(type solid)
		)
		(fill yes)
		(layer "F.Cu")
		(net "GND")
	)
	(gr_poly
		(pts
			(arc
				(start 443.828424 -220.709998)
				(mid 443.495176 -220.709998)
				(end 443.828424 -220.709998)
			)
		)
		(stroke
			(width 0)
			(type solid)
		)
		(fill yes)
		(layer "F.Cu")
		(net "GND")
	)
	(gr_poly
		(pts
			(arc
				(start 443.828424 -211.360004)
				(mid 443.495176 -211.360004)
				(end 443.828424 -211.360004)
			)
		)
		(stroke
			(width 0)
			(type solid)
		)
		(fill yes)
		(layer "F.Cu")
		(net "GND")
	)
	(gr_poly
		(pts
			(arc
				(start 443.828424 -202.01001)
				(mid 443.495176 -202.01001)
				(end 443.828424 -202.01001)
			)
		)
		(stroke
			(width 0)
			(type solid)
		)
		(fill yes)
		(layer "F.Cu")
		(net "GND")
	)
	(gr_poly
		(pts
			(arc
				(start 447.928492 -313.360054)
				(mid 447.595244 -313.360054)
				(end 447.928492 -313.360054)
			)
		)
		(stroke
			(width 0)
			(type solid)
		)
		(fill yes)
		(layer "F.Cu")
		(net "GND")
	)
	(gr_poly
		(pts
			(arc
				(start 447.928492 -304.01006)
				(mid 447.595244 -304.01006)
				(end 447.928492 -304.01006)
			)
		)
		(stroke
			(width 0)
			(type solid)
		)
		(fill yes)
		(layer "F.Cu")
		(net "GND")
	)
	(gr_poly
		(pts
			(arc
				(start 447.928492 -294.660066)
				(mid 447.595244 -294.660066)
				(end 447.928492 -294.660066)
			)
		)
		(stroke
			(width 0)
			(type solid)
		)
		(fill yes)
		(layer "F.Cu")
		(net "GND")
	)
	(gr_poly
		(pts
			(arc
				(start 447.928492 -275.960078)
				(mid 447.595244 -275.960078)
				(end 447.928492 -275.960078)
			)
		)
		(stroke
			(width 0)
			(type solid)
		)
		(fill yes)
		(layer "F.Cu")
		(net "GND")
	)
	(gr_poly
		(pts
			(arc
				(start 447.928492 -238.560102)
				(mid 447.595244 -238.560102)
				(end 447.928492 -238.560102)
			)
		)
		(stroke
			(width 0)
			(type solid)
		)
		(fill yes)
		(layer "F.Cu")
		(net "GND")
	)
	(gr_poly
		(pts
			(arc
				(start 447.928492 -229.210108)
				(mid 447.595244 -229.210108)
				(end 447.928492 -229.210108)
			)
		)
		(stroke
			(width 0)
			(type solid)
		)
		(fill yes)
		(layer "F.Cu")
		(net "GND")
	)
	(gr_poly
		(pts
			(arc
				(start 447.928492 -219.860114)
				(mid 447.595244 -219.860114)
				(end 447.928492 -219.860114)
			)
		)
		(stroke
			(width 0)
			(type solid)
		)
		(fill yes)
		(layer "F.Cu")
		(net "GND")
	)
	(gr_poly
		(pts
			(arc
				(start 447.928492 -201.160126)
				(mid 447.595244 -201.160126)
				(end 447.928492 -201.160126)
			)
		)
		(stroke
			(width 0)
			(type solid)
		)
		(fill yes)
		(layer "F.Cu")
		(net "GND")
	)
	(gr_poly
		(pts
			(arc
				(start 451.372224 -314.210192)
				(mid 451.038976 -314.210192)
				(end 451.372224 -314.210192)
			)
		)
		(stroke
			(width 0)
			(type solid)
		)
		(fill yes)
		(layer "F.Cu")
		(net "GND")
	)
	(gr_poly
		(pts
			(arc
				(start 451.372224 -304.860198)
				(mid 451.038976 -304.860198)
				(end 451.372224 -304.860198)
			)
		)
		(stroke
			(width 0)
			(type solid)
		)
		(fill yes)
		(layer "F.Cu")
		(net "GND")
	)
	(gr_poly
		(pts
			(arc
				(start 451.372224 -295.510204)
				(mid 451.038976 -295.510204)
				(end 451.372224 -295.510204)
			)
		)
		(stroke
			(width 0)
			(type solid)
		)
		(fill yes)
		(layer "F.Cu")
		(net "GND")
	)
	(gr_poly
		(pts
			(arc
				(start 451.372224 -286.16021)
				(mid 451.038976 -286.16021)
				(end 451.372224 -286.16021)
			)
		)
		(stroke
			(width 0)
			(type solid)
		)
		(fill yes)
		(layer "F.Cu")
		(net "GND")
	)
	(gr_poly
		(pts
			(arc
				(start 451.372224 -239.41024)
				(mid 451.038976 -239.41024)
				(end 451.372224 -239.41024)
			)
		)
		(stroke
			(width 0)
			(type solid)
		)
		(fill yes)
		(layer "F.Cu")
		(net "GND")
	)
	(gr_poly
		(pts
			(arc
				(start 451.372224 -230.060246)
				(mid 451.038976 -230.060246)
				(end 451.372224 -230.060246)
			)
		)
		(stroke
			(width 0)
			(type solid)
		)
		(fill yes)
		(layer "F.Cu")
		(net "GND")
	)
	(gr_poly
		(pts
			(arc
				(start 451.372224 -220.709998)
				(mid 451.038976 -220.709998)
				(end 451.372224 -220.709998)
			)
		)
		(stroke
			(width 0)
			(type solid)
		)
		(fill yes)
		(layer "F.Cu")
		(net "GND")
	)
	(gr_poly
		(pts
			(arc
				(start 451.372224 -211.360004)
				(mid 451.038976 -211.360004)
				(end 451.372224 -211.360004)
			)
		)
		(stroke
			(width 0)
			(type solid)
		)
		(fill yes)
		(layer "F.Cu")
		(net "GND")
	)
	(gr_poly
		(pts
			(arc
				(start 451.372224 -202.01001)
				(mid 451.038976 -202.01001)
				(end 451.372224 -202.01001)
			)
		)
		(stroke
			(width 0)
			(type solid)
		)
		(fill yes)
		(layer "F.Cu")
		(net "GND")
	)
	(gr_poly
		(pts
			(arc
				(start 455.472292 -313.360054)
				(mid 455.139044 -313.360054)
				(end 455.472292 -313.360054)
			)
		)
		(stroke
			(width 0)
			(type solid)
		)
		(fill yes)
		(layer "F.Cu")
		(net "GND")
	)
	(gr_poly
		(pts
			(arc
				(start 455.472292 -304.01006)
				(mid 455.139044 -304.01006)
				(end 455.472292 -304.01006)
			)
		)
		(stroke
			(width 0)
			(type solid)
		)
		(fill yes)
		(layer "F.Cu")
		(net "GND")
	)
	(gr_poly
		(pts
			(arc
				(start 455.472292 -294.660066)
				(mid 455.139044 -294.660066)
				(end 455.472292 -294.660066)
			)
		)
		(stroke
			(width 0)
			(type solid)
		)
		(fill yes)
		(layer "F.Cu")
		(net "GND")
	)
	(gr_poly
		(pts
			(arc
				(start 455.472292 -285.310072)
				(mid 455.139044 -285.310072)
				(end 455.472292 -285.310072)
			)
		)
		(stroke
			(width 0)
			(type solid)
		)
		(fill yes)
		(layer "F.Cu")
		(net "GND")
	)
	(gr_poly
		(pts
			(arc
				(start 455.472292 -275.960078)
				(mid 455.139044 -275.960078)
				(end 455.472292 -275.960078)
			)
		)
		(stroke
			(width 0)
			(type solid)
		)
		(fill yes)
		(layer "F.Cu")
		(net "GND")
	)
	(gr_poly
		(pts
			(arc
				(start 455.472292 -238.560102)
				(mid 455.139044 -238.560102)
				(end 455.472292 -238.560102)
			)
		)
		(stroke
			(width 0)
			(type solid)
		)
		(fill yes)
		(layer "F.Cu")
		(net "GND")
	)
	(gr_poly
		(pts
			(arc
				(start 455.472292 -229.210108)
				(mid 455.139044 -229.210108)
				(end 455.472292 -229.210108)
			)
		)
		(stroke
			(width 0)
			(type solid)
		)
		(fill yes)
		(layer "F.Cu")
		(net "GND")
	)
	(gr_poly
		(pts
			(arc
				(start 455.472292 -219.860114)
				(mid 455.139044 -219.860114)
				(end 455.472292 -219.860114)
			)
		)
		(stroke
			(width 0)
			(type solid)
		)
		(fill yes)
		(layer "F.Cu")
		(net "GND")
	)
	(gr_poly
		(pts
			(arc
				(start 455.472292 -210.51012)
				(mid 455.139044 -210.51012)
				(end 455.472292 -210.51012)
			)
		)
		(stroke
			(width 0)
			(type solid)
		)
		(fill yes)
		(layer "F.Cu")
		(net "GND")
	)
	(gr_poly
		(pts
			(arc
				(start 11.618468 -114.072924)
				(mid 11.252708 -114.072924)
				(end 11.618468 -114.072924)
			)
		)
		(stroke
			(width 0)
			(type solid)
		)
		(fill yes)
		(layer "F.Cu")
		(net "GND")
	)
	(gr_poly
		(pts
			(arc
				(start 11.659108 -108.15574)
				(mid 11.293348 -108.15574)
				(end 11.659108 -108.15574)
			)
		)
		(stroke
			(width 0)
			(type solid)
		)
		(fill yes)
		(layer "F.Cu")
		(net "GND")
	)
	(gr_poly
		(pts
			(arc
				(start 12.277852 -104.803702)
				(mid 11.912092 -104.803702)
				(end 12.277852 -104.803702)
			)
		)
		(stroke
			(width 0)
			(type solid)
		)
		(fill yes)
		(layer "F.Cu")
		(net "GND")
	)
	(gr_poly
		(pts
			(arc
				(start 12.278106 -107.10037)
				(mid 11.912346 -107.10037)
				(end 12.278106 -107.10037)
			)
		)
		(stroke
			(width 0)
			(type solid)
		)
		(fill yes)
		(layer "F.Cu")
		(net "GND")
	)
	(gr_poly
		(pts
			(arc
				(start 12.883388 -114.072924)
				(mid 12.517628 -114.072924)
				(end 12.883388 -114.072924)
			)
		)
		(stroke
			(width 0)
			(type solid)
		)
		(fill yes)
		(layer "F.Cu")
		(net "GND")
	)
	(gr_poly
		(pts
			(arc
				(start 12.917932 -108.15574)
				(mid 12.552172 -108.15574)
				(end 12.917932 -108.15574)
			)
		)
		(stroke
			(width 0)
			(type solid)
		)
		(fill yes)
		(layer "F.Cu")
		(net "GND")
	)
	(gr_poly
		(pts
			(arc
				(start 15.522702 -108.66374)
				(mid 15.156942 -108.66374)
				(end 15.522702 -108.66374)
			)
		)
		(stroke
			(width 0)
			(type solid)
		)
		(fill yes)
		(layer "F.Cu")
		(net "GND")
	)
	(gr_poly
		(pts
			(arc
				(start 16.136112 -106.34345)
				(mid 15.770352 -106.34345)
				(end 16.136112 -106.34345)
			)
		)
		(stroke
			(width 0)
			(type solid)
		)
		(fill yes)
		(layer "F.Cu")
		(net "GND")
	)
	(gr_poly
		(pts
			(arc
				(start 16.142462 -104.037638)
				(mid 15.776702 -104.037638)
				(end 16.142462 -104.037638)
			)
		)
		(stroke
			(width 0)
			(type solid)
		)
		(fill yes)
		(layer "F.Cu")
		(net "GND")
	)
	(gr_poly
		(pts
			(arc
				(start 16.7894 -108.66374)
				(mid 16.42364 -108.66374)
				(end 16.7894 -108.66374)
			)
		)
		(stroke
			(width 0)
			(type solid)
		)
		(fill yes)
		(layer "F.Cu")
		(net "GND")
	)
	(gr_poly
		(pts
			(arc
				(start 62.028324 -5.84327)
				(mid 61.662564 -5.84327)
				(end 62.028324 -5.84327)
			)
		)
		(stroke
			(width 0)
			(type solid)
		)
		(fill yes)
		(layer "F.Cu")
		(net "GND")
	)
	(gr_poly
		(pts
			(xy 67.071494 -153.583132) (xy 67.81419 -152.84069) (xy 67.94627 -152.84069) (xy 69.544692 -152.84069)
			(xy 69.586094 -152.799288) (xy 69.586094 -152.493218) (xy 69.552566 -152.45969) (xy 68.58127 -152.45969)
			(xy 66.144902 -152.45969) (xy 65.882012 -152.1968) (xy 65.882012 -151.13) (xy 65.882012 -150.495)
			(xy 65.882012 -149.6568) (xy 65.882012 -148.825966) (xy 65.902332 -148.805646) (xy 66.072512 -148.635466)
			(xy 66.372232 -148.635466) (xy 66.46545 -148.635466) (xy 66.490342 -148.635466) (xy 66.500756 -148.625052)
			(xy 66.500756 -147.724368) (xy 66.486024 -147.709636) (xy 66.429636 -147.709636) (xy 66.203576 -147.709636)
			(xy 62.198504 -147.709636) (xy 61.952886 -147.955254) (xy 61.952886 -153.399998) (xy 62.1411 -153.588212)
			(xy 63.566294 -153.588212) (xy 63.673736 -153.588212) (xy 67.066414 -153.588212)
		)
		(stroke
			(width 0)
			(type solid)
		)
		(fill yes)
		(layer "F.Cu")
		(net "SW_PVDD18_S5_P1_SW")
	)
	(gr_poly
		(pts
			(arc
				(start 69.168264 -10.20191)
				(mid 68.802504 -10.20191)
				(end 69.168264 -10.20191)
			)
		)
		(stroke
			(width 0)
			(type solid)
		)
		(fill yes)
		(layer "F.Cu")
		(net "GND")
	)
	(gr_poly
		(pts
			(arc
				(start 69.422264 -6.90499)
				(mid 69.056504 -6.90499)
				(end 69.422264 -6.90499)
			)
		)
		(stroke
			(width 0)
			(type solid)
		)
		(fill yes)
		(layer "F.Cu")
		(net "GND")
	)
	(gr_poly
		(pts
			(arc
				(start 72.699626 -13.510514)
				(mid 72.333866 -13.510514)
				(end 72.699626 -13.510514)
			)
		)
		(stroke
			(width 0)
			(type solid)
		)
		(fill yes)
		(layer "F.Cu")
		(net "GND")
	)
	(gr_poly
		(pts
			(arc
				(start 72.800464 -6.08711)
				(mid 72.434704 -6.08711)
				(end 72.800464 -6.08711)
			)
		)
		(stroke
			(width 0)
			(type solid)
		)
		(fill yes)
		(layer "F.Cu")
		(net "GND")
	)
	(gr_poly
		(pts
			(arc
				(start 74.136504 -5.43433)
				(mid 73.770744 -5.43433)
				(end 74.136504 -5.43433)
			)
		)
		(stroke
			(width 0)
			(type solid)
		)
		(fill yes)
		(layer "F.Cu")
		(net "GND")
	)
	(gr_poly
		(pts
			(xy 79.981044 -28.357068) (xy 79.981044 -19.901916) (xy 79.91094 -19.831812) (xy 79.824072 -19.831812)
			(xy 79.751682 -19.904202) (xy 79.751682 -21.591524) (xy 79.751682 -21.674836) (xy 79.59471 -21.831808)
			(xy 79.112618 -21.831808) (xy 78.973172 -21.692362) (xy 78.973172 -21.591524) (xy 78.973172 -20.386548)
			(xy 78.912974 -20.32635) (xy 78.752954 -20.32635) (xy 78.72984 -20.349464) (xy 78.72984 -24.43988)
			(xy 78.724506 -24.699468) (xy 78.579218 -24.844756) (xy 78.321916 -24.844756) (xy 78.321408 -24.845264)
			(xy 76.276454 -24.845264) (xy 74.928476 -26.193242) (xy 71.206868 -26.193242) (xy 70.132956 -27.267154)
			(xy 66.113914 -27.267154) (xy 65.94856 -27.432508) (xy 65.94856 -28.460954) (xy 66.018664 -28.531058)
			(xy 70.512686 -28.531058) (xy 71.699628 -29.718) (xy 78.620112 -29.718)
		)
		(stroke
			(width 0)
			(type solid)
		)
		(fill yes)
		(layer "F.Cu")
		(net "P12V_AUX")
	)
	(gr_poly
		(pts
			(arc
				(start 106.936032 -62.022736)
				(mid 106.570272 -62.022736)
				(end 106.936032 -62.022736)
			)
		)
		(stroke
			(width 0)
			(type solid)
		)
		(fill yes)
		(layer "F.Cu")
		(net "GND")
	)
	(gr_poly
		(pts
			(arc
				(start 107.608624 -59.129422)
				(mid 107.242864 -59.129422)
				(end 107.608624 -59.129422)
			)
		)
		(stroke
			(width 0)
			(type solid)
		)
		(fill yes)
		(layer "F.Cu")
		(net "GND")
	)
	(gr_poly
		(pts
			(arc
				(start 107.608624 -57.949338)
				(mid 107.242864 -57.949338)
				(end 107.608624 -57.949338)
			)
		)
		(stroke
			(width 0)
			(type solid)
		)
		(fill yes)
		(layer "F.Cu")
		(net "GND")
	)
	(gr_poly
		(pts
			(arc
				(start 111.950246 -61.056774)
				(mid 111.584486 -61.056774)
				(end 111.950246 -61.056774)
			)
		)
		(stroke
			(width 0)
			(type solid)
		)
		(fill yes)
		(layer "F.Cu")
		(net "GND")
	)
	(gr_poly
		(pts
			(arc
				(start 112.80648 -62.96152)
				(mid 112.44072 -62.96152)
				(end 112.80648 -62.96152)
			)
		)
		(stroke
			(width 0)
			(type solid)
		)
		(fill yes)
		(layer "F.Cu")
		(net "GND")
	)
	(gr_poly
		(pts
			(arc
				(start 116.446554 -60.347352)
				(mid 116.080794 -60.347352)
				(end 116.446554 -60.347352)
			)
		)
		(stroke
			(width 0)
			(type solid)
		)
		(fill yes)
		(layer "F.Cu")
		(net "GND")
	)
	(gr_poly
		(pts
			(arc
				(start 117.886988 -58.41238)
				(mid 117.521228 -58.41238)
				(end 117.886988 -58.41238)
			)
		)
		(stroke
			(width 0)
			(type solid)
		)
		(fill yes)
		(layer "F.Cu")
		(net "GND")
	)
	(gr_poly
		(pts
			(arc
				(start 117.950742 -60.29706)
				(mid 117.584982 -60.29706)
				(end 117.950742 -60.29706)
			)
		)
		(stroke
			(width 0)
			(type solid)
		)
		(fill yes)
		(layer "F.Cu")
		(net "GND")
	)
	(gr_poly
		(pts
			(arc
				(start 118.964456 -89.767918)
				(mid 118.598696 -89.767918)
				(end 118.964456 -89.767918)
			)
		)
		(stroke
			(width 0)
			(type solid)
		)
		(fill yes)
		(layer "F.Cu")
		(net "GND")
	)
	(gr_poly
		(pts
			(arc
				(start 123.06808 -68.69176)
				(mid 122.70232 -68.69176)
				(end 123.06808 -68.69176)
			)
		)
		(stroke
			(width 0)
			(type solid)
		)
		(fill yes)
		(layer "F.Cu")
		(net "GND")
	)
	(gr_poly
		(pts
			(arc
				(start 124.154184 -89.00668)
				(mid 123.788424 -89.00668)
				(end 124.154184 -89.00668)
			)
		)
		(stroke
			(width 0)
			(type solid)
		)
		(fill yes)
		(layer "F.Cu")
		(net "GND")
	)
	(gr_poly
		(pts
			(arc
				(start 124.365512 -61.659516)
				(mid 123.999752 -61.659516)
				(end 124.365512 -61.659516)
			)
		)
		(stroke
			(width 0)
			(type solid)
		)
		(fill yes)
		(layer "F.Cu")
		(net "GND")
	)
	(gr_poly
		(pts
			(arc
				(start 127.251206 -57.168034)
				(mid 126.885446 -57.168034)
				(end 127.251206 -57.168034)
			)
		)
		(stroke
			(width 0)
			(type solid)
		)
		(fill yes)
		(layer "F.Cu")
		(net "GND")
	)
	(gr_poly
		(pts
			(arc
				(start 127.619252 -61.101732)
				(mid 127.253492 -61.101732)
				(end 127.619252 -61.101732)
			)
		)
		(stroke
			(width 0)
			(type solid)
		)
		(fill yes)
		(layer "F.Cu")
		(net "GND")
	)
	(gr_poly
		(pts
			(arc
				(start 130.172714 -50.692304)
				(mid 129.806954 -50.692304)
				(end 130.172714 -50.692304)
			)
		)
		(stroke
			(width 0)
			(type solid)
		)
		(fill yes)
		(layer "F.Cu")
		(net "GND")
	)
	(gr_poly
		(pts
			(arc
				(start 140.18768 -95.9231)
				(mid 139.82192 -95.9231)
				(end 140.18768 -95.9231)
			)
		)
		(stroke
			(width 0)
			(type solid)
		)
		(fill yes)
		(layer "F.Cu")
		(net "GND")
	)
	(gr_poly
		(pts
			(arc
				(start 140.67028 -57.8358)
				(mid 140.30452 -57.8358)
				(end 140.67028 -57.8358)
			)
		)
		(stroke
			(width 0)
			(type solid)
		)
		(fill yes)
		(layer "F.Cu")
		(net "GND")
	)
	(gr_poly
		(pts
			(arc
				(start 143.05153 -61.651134)
				(mid 142.68577 -61.651134)
				(end 143.05153 -61.651134)
			)
		)
		(stroke
			(width 0)
			(type solid)
		)
		(fill yes)
		(layer "F.Cu")
		(net "GND")
	)
	(gr_poly
		(pts
			(arc
				(start 143.548354 -11.463528)
				(mid 143.182594 -11.463528)
				(end 143.548354 -11.463528)
			)
		)
		(stroke
			(width 0)
			(type solid)
		)
		(fill yes)
		(layer "F.Cu")
		(net "GND")
	)
	(gr_poly
		(pts
			(arc
				(start 147.152614 -11.458448)
				(mid 146.786854 -11.458448)
				(end 147.152614 -11.458448)
			)
		)
		(stroke
			(width 0)
			(type solid)
		)
		(fill yes)
		(layer "F.Cu")
		(net "GND")
	)
	(gr_poly
		(pts
			(arc
				(start 148.848064 -56.630316)
				(mid 148.482304 -56.630316)
				(end 148.848064 -56.630316)
			)
		)
		(stroke
			(width 0)
			(type solid)
		)
		(fill yes)
		(layer "F.Cu")
		(net "GND")
	)
	(gr_poly
		(pts
			(arc
				(start 150.11908 -48.42764)
				(mid 149.75332 -48.42764)
				(end 150.11908 -48.42764)
			)
		)
		(stroke
			(width 0)
			(type solid)
		)
		(fill yes)
		(layer "F.Cu")
		(net "GND")
	)
	(gr_poly
		(pts
			(arc
				(start 151.455882 -60.738512)
				(mid 151.090122 -60.738512)
				(end 151.455882 -60.738512)
			)
		)
		(stroke
			(width 0)
			(type solid)
		)
		(fill yes)
		(layer "F.Cu")
		(net "GND")
	)
	(gr_poly
		(pts
			(arc
				(start 151.486108 -11.389868)
				(mid 151.120348 -11.389868)
				(end 151.486108 -11.389868)
			)
		)
		(stroke
			(width 0)
			(type solid)
		)
		(fill yes)
		(layer "F.Cu")
		(net "GND")
	)
	(gr_poly
		(pts
			(arc
				(start 152.401016 -8.347964)
				(mid 152.035256 -8.347964)
				(end 152.401016 -8.347964)
			)
		)
		(stroke
			(width 0)
			(type solid)
		)
		(fill yes)
		(layer "F.Cu")
		(net "GND")
	)
	(gr_poly
		(pts
			(arc
				(start 153.361136 -11.308842)
				(mid 152.995376 -11.308842)
				(end 153.361136 -11.308842)
			)
		)
		(stroke
			(width 0)
			(type solid)
		)
		(fill yes)
		(layer "F.Cu")
		(net "GND")
	)
	(gr_poly
		(pts
			(arc
				(start 153.416762 -106.614976)
				(mid 153.051002 -106.614976)
				(end 153.416762 -106.614976)
			)
		)
		(stroke
			(width 0)
			(type solid)
		)
		(fill yes)
		(layer "F.Cu")
		(net "GND")
	)
	(gr_poly
		(pts
			(arc
				(start 154.582114 -91.252548)
				(mid 154.216354 -91.252548)
				(end 154.582114 -91.252548)
			)
		)
		(stroke
			(width 0)
			(type solid)
		)
		(fill yes)
		(layer "F.Cu")
		(net "GND")
	)
	(gr_poly
		(pts
			(arc
				(start 157.263338 -11.031728)
				(mid 156.897578 -11.031728)
				(end 157.263338 -11.031728)
			)
		)
		(stroke
			(width 0)
			(type solid)
		)
		(fill yes)
		(layer "F.Cu")
		(net "GND")
	)
	(gr_poly
		(pts
			(arc
				(start 157.30728 -40.8305)
				(mid 156.94152 -40.8305)
				(end 157.30728 -40.8305)
			)
		)
		(stroke
			(width 0)
			(type solid)
		)
		(fill yes)
		(layer "F.Cu")
		(net "GND")
	)
	(gr_poly
		(pts
			(arc
				(start 157.76194 -9.345676)
				(mid 157.39618 -9.345676)
				(end 157.76194 -9.345676)
			)
		)
		(stroke
			(width 0)
			(type solid)
		)
		(fill yes)
		(layer "F.Cu")
		(net "GND")
	)
	(gr_poly
		(pts
			(arc
				(start 160.43148 -30.20568)
				(mid 160.06572 -30.20568)
				(end 160.43148 -30.20568)
			)
		)
		(stroke
			(width 0)
			(type solid)
		)
		(fill yes)
		(layer "F.Cu")
		(net "GND")
	)
	(gr_poly
		(pts
			(arc
				(start 165.17747 -7.441692)
				(mid 164.81171 -7.441692)
				(end 165.17747 -7.441692)
			)
		)
		(stroke
			(width 0)
			(type solid)
		)
		(fill yes)
		(layer "F.Cu")
		(net "GND")
	)
	(gr_poly
		(pts
			(arc
				(start 166.18966 -14.824202)
				(mid 165.8239 -14.824202)
				(end 166.18966 -14.824202)
			)
		)
		(stroke
			(width 0)
			(type solid)
		)
		(fill yes)
		(layer "F.Cu")
		(net "GND")
	)
	(gr_poly
		(pts
			(arc
				(start 168.01973 -19.89582)
				(mid 167.65397 -19.89582)
				(end 168.01973 -19.89582)
			)
		)
		(stroke
			(width 0)
			(type solid)
		)
		(fill yes)
		(layer "F.Cu")
		(net "GND")
	)
	(gr_poly
		(pts
			(arc
				(start 168.763442 -8.273796)
				(mid 168.397682 -8.273796)
				(end 168.763442 -8.273796)
			)
		)
		(stroke
			(width 0)
			(type solid)
		)
		(fill yes)
		(layer "F.Cu")
		(net "GND")
	)
	(gr_poly
		(pts
			(arc
				(start 170.042586 -11.496548)
				(mid 169.676826 -11.496548)
				(end 170.042586 -11.496548)
			)
		)
		(stroke
			(width 0)
			(type solid)
		)
		(fill yes)
		(layer "F.Cu")
		(net "GND")
	)
	(gr_poly
		(pts
			(arc
				(start 171.315634 -19.835368)
				(mid 170.949874 -19.835368)
				(end 171.315634 -19.835368)
			)
		)
		(stroke
			(width 0)
			(type solid)
		)
		(fill yes)
		(layer "F.Cu")
		(net "GND")
	)
	(gr_poly
		(pts
			(arc
				(start 171.858178 -11.496548)
				(mid 171.492418 -11.496548)
				(end 171.858178 -11.496548)
			)
		)
		(stroke
			(width 0)
			(type solid)
		)
		(fill yes)
		(layer "F.Cu")
		(net "GND")
	)
	(gr_poly
		(pts
			(arc
				(start 172.291756 -9.19607)
				(mid 171.925996 -9.19607)
				(end 172.291756 -9.19607)
			)
		)
		(stroke
			(width 0)
			(type solid)
		)
		(fill yes)
		(layer "F.Cu")
		(net "GND")
	)
	(gr_poly
		(pts
			(arc
				(start 173.637194 -18.451068)
				(mid 173.271434 -18.451068)
				(end 173.637194 -18.451068)
			)
		)
		(stroke
			(width 0)
			(type solid)
		)
		(fill yes)
		(layer "F.Cu")
		(net "GND")
	)
	(gr_poly
		(pts
			(arc
				(start 175.835818 -98.255836)
				(mid 175.470058 -98.255836)
				(end 175.835818 -98.255836)
			)
		)
		(stroke
			(width 0)
			(type solid)
		)
		(fill yes)
		(layer "F.Cu")
		(net "GND")
	)
	(gr_poly
		(pts
			(arc
				(start 176.375568 -8.301736)
				(mid 176.009808 -8.301736)
				(end 176.375568 -8.301736)
			)
		)
		(stroke
			(width 0)
			(type solid)
		)
		(fill yes)
		(layer "F.Cu")
		(net "GND")
	)
	(gr_poly
		(pts
			(arc
				(start 177.32248 -87.823294)
				(mid 176.95672 -87.823294)
				(end 177.32248 -87.823294)
			)
		)
		(stroke
			(width 0)
			(type solid)
		)
		(fill yes)
		(layer "F.Cu")
		(net "GND")
	)
	(gr_poly
		(pts
			(arc
				(start 178.449986 -11.458448)
				(mid 178.084226 -11.458448)
				(end 178.449986 -11.458448)
			)
		)
		(stroke
			(width 0)
			(type solid)
		)
		(fill yes)
		(layer "F.Cu")
		(net "GND")
	)
	(gr_poly
		(pts
			(arc
				(start 179.915312 -17.708372)
				(mid 179.549552 -17.708372)
				(end 179.915312 -17.708372)
			)
		)
		(stroke
			(width 0)
			(type solid)
		)
		(fill yes)
		(layer "F.Cu")
		(net "GND")
	)
	(gr_poly
		(pts
			(arc
				(start 183.146192 -87.585296)
				(mid 182.780432 -87.585296)
				(end 183.146192 -87.585296)
			)
		)
		(stroke
			(width 0)
			(type solid)
		)
		(fill yes)
		(layer "F.Cu")
		(net "GND")
	)
	(gr_poly
		(pts
			(arc
				(start 185.22188 -135.600948)
				(mid 184.85612 -135.600948)
				(end 185.22188 -135.600948)
			)
		)
		(stroke
			(width 0)
			(type solid)
		)
		(fill yes)
		(layer "F.Cu")
		(net "GND")
	)
	(gr_poly
		(pts
			(arc
				(start 185.344054 -10.127488)
				(mid 184.978294 -10.127488)
				(end 185.344054 -10.127488)
			)
		)
		(stroke
			(width 0)
			(type solid)
		)
		(fill yes)
		(layer "F.Cu")
		(net "GND")
	)
	(gr_poly
		(pts
			(arc
				(start 185.636154 -15.432278)
				(mid 185.270394 -15.432278)
				(end 185.636154 -15.432278)
			)
		)
		(stroke
			(width 0)
			(type solid)
		)
		(fill yes)
		(layer "F.Cu")
		(net "GND")
	)
	(gr_poly
		(pts
			(arc
				(start 186.23788 -135.600948)
				(mid 185.87212 -135.600948)
				(end 186.23788 -135.600948)
			)
		)
		(stroke
			(width 0)
			(type solid)
		)
		(fill yes)
		(layer "F.Cu")
		(net "GND")
	)
	(gr_poly
		(pts
			(arc
				(start 187.25388 -135.600948)
				(mid 186.88812 -135.600948)
				(end 187.25388 -135.600948)
			)
		)
		(stroke
			(width 0)
			(type solid)
		)
		(fill yes)
		(layer "F.Cu")
		(net "GND")
	)
	(gr_poly
		(pts
			(arc
				(start 187.259976 -14.749526)
				(mid 186.894216 -14.749526)
				(end 187.259976 -14.749526)
			)
		)
		(stroke
			(width 0)
			(type solid)
		)
		(fill yes)
		(layer "F.Cu")
		(net "GND")
	)
	(gr_poly
		(pts
			(arc
				(start 187.327794 -10.117328)
				(mid 186.962034 -10.117328)
				(end 187.327794 -10.117328)
			)
		)
		(stroke
			(width 0)
			(type solid)
		)
		(fill yes)
		(layer "F.Cu")
		(net "GND")
	)
	(gr_poly
		(pts
			(arc
				(start 187.70092 -140.62075)
				(mid 187.33516 -140.62075)
				(end 187.70092 -140.62075)
			)
		)
		(stroke
			(width 0)
			(type solid)
		)
		(fill yes)
		(layer "F.Cu")
		(net "GND")
	)
	(gr_poly
		(pts
			(arc
				(start 188.304932 -139.6746)
				(mid 187.939172 -139.6746)
				(end 188.304932 -139.6746)
			)
		)
		(stroke
			(width 0)
			(type solid)
		)
		(fill yes)
		(layer "F.Cu")
		(net "GND")
	)
	(gr_poly
		(pts
			(arc
				(start 188.864494 -10.117328)
				(mid 188.498734 -10.117328)
				(end 188.864494 -10.117328)
			)
		)
		(stroke
			(width 0)
			(type solid)
		)
		(fill yes)
		(layer "F.Cu")
		(net "GND")
	)
	(gr_poly
		(pts
			(arc
				(start 189.280038 -14.826742)
				(mid 188.914278 -14.826742)
				(end 189.280038 -14.826742)
			)
		)
		(stroke
			(width 0)
			(type solid)
		)
		(fill yes)
		(layer "F.Cu")
		(net "GND")
	)
	(gr_poly
		(pts
			(arc
				(start 189.390274 -42.389298)
				(mid 189.024514 -42.389298)
				(end 189.390274 -42.389298)
			)
		)
		(stroke
			(width 0)
			(type solid)
		)
		(fill yes)
		(layer "F.Cu")
		(net "GND")
	)
	(gr_poly
		(pts
			(arc
				(start 189.84595 -80.174338)
				(mid 189.48019 -80.174338)
				(end 189.84595 -80.174338)
			)
		)
		(stroke
			(width 0)
			(type solid)
		)
		(fill yes)
		(layer "F.Cu")
		(net "GND")
	)
	(gr_poly
		(pts
			(arc
				(start 190.082678 -135.857996)
				(mid 189.716918 -135.857996)
				(end 190.082678 -135.857996)
			)
		)
		(stroke
			(width 0)
			(type solid)
		)
		(fill yes)
		(layer "F.Cu")
		(net "GND")
	)
	(gr_poly
		(pts
			(arc
				(start 191.257174 -15.184628)
				(mid 190.891414 -15.184628)
				(end 191.257174 -15.184628)
			)
		)
		(stroke
			(width 0)
			(type solid)
		)
		(fill yes)
		(layer "F.Cu")
		(net "GND")
	)
	(gr_poly
		(pts
			(arc
				(start 191.568578 -171.6532)
				(mid 191.209422 -171.6532)
				(end 191.568578 -171.6532)
			)
		)
		(stroke
			(width 0)
			(type solid)
		)
		(fill yes)
		(layer "F.Cu")
		(net "GND")
	)
	(gr_poly
		(pts
			(arc
				(start 191.688466 -87.32266)
				(mid 191.322706 -87.32266)
				(end 191.688466 -87.32266)
			)
		)
		(stroke
			(width 0)
			(type solid)
		)
		(fill yes)
		(layer "F.Cu")
		(net "GND")
	)
	(gr_poly
		(pts
			(arc
				(start 192.03797 -75.079606)
				(mid 191.67221 -75.079606)
				(end 192.03797 -75.079606)
			)
		)
		(stroke
			(width 0)
			(type solid)
		)
		(fill yes)
		(layer "F.Cu")
		(net "GND")
	)
	(gr_poly
		(pts
			(arc
				(start 193.34988 -135.725408)
				(mid 192.98412 -135.725408)
				(end 193.34988 -135.725408)
			)
		)
		(stroke
			(width 0)
			(type solid)
		)
		(fill yes)
		(layer "F.Cu")
		(net "GND")
	)
	(gr_poly
		(pts
			(arc
				(start 193.80708 -47.98314)
				(mid 193.44132 -47.98314)
				(end 193.80708 -47.98314)
			)
		)
		(stroke
			(width 0)
			(type solid)
		)
		(fill yes)
		(layer "F.Cu")
		(net "GND")
	)
	(gr_poly
		(pts
			(arc
				(start 194.36588 -135.743696)
				(mid 194.00012 -135.743696)
				(end 194.36588 -135.743696)
			)
		)
		(stroke
			(width 0)
			(type solid)
		)
		(fill yes)
		(layer "F.Cu")
		(net "GND")
	)
	(gr_poly
		(pts
			(arc
				(start 196.581014 -75.250548)
				(mid 196.215254 -75.250548)
				(end 196.581014 -75.250548)
			)
		)
		(stroke
			(width 0)
			(type solid)
		)
		(fill yes)
		(layer "F.Cu")
		(net "GND")
	)
	(gr_poly
		(pts
			(arc
				(start 198.079614 -77.76337)
				(mid 197.713854 -77.76337)
				(end 198.079614 -77.76337)
			)
		)
		(stroke
			(width 0)
			(type solid)
		)
		(fill yes)
		(layer "F.Cu")
		(net "GND")
	)
	(gr_poly
		(pts
			(arc
				(start 202.282552 -75.895454)
				(mid 201.916792 -75.895454)
				(end 202.282552 -75.895454)
			)
		)
		(stroke
			(width 0)
			(type solid)
		)
		(fill yes)
		(layer "F.Cu")
		(net "GND")
	)
	(gr_poly
		(pts
			(arc
				(start 202.771756 -71.687182)
				(mid 202.405996 -71.687182)
				(end 202.771756 -71.687182)
			)
		)
		(stroke
			(width 0)
			(type solid)
		)
		(fill yes)
		(layer "F.Cu")
		(net "GND")
	)
	(gr_poly
		(pts
			(arc
				(start 204.211936 -83.845908)
				(mid 203.846176 -83.845908)
				(end 204.211936 -83.845908)
			)
		)
		(stroke
			(width 0)
			(type solid)
		)
		(fill yes)
		(layer "F.Cu")
		(net "GND")
	)
	(gr_poly
		(pts
			(arc
				(start 205.156816 -67.475862)
				(mid 204.791056 -67.475862)
				(end 205.156816 -67.475862)
			)
		)
		(stroke
			(width 0)
			(type solid)
		)
		(fill yes)
		(layer "F.Cu")
		(net "GND")
	)
	(gr_poly
		(pts
			(arc
				(start 205.516734 -86.78418)
				(mid 205.150974 -86.78418)
				(end 205.516734 -86.78418)
			)
		)
		(stroke
			(width 0)
			(type solid)
		)
		(fill yes)
		(layer "F.Cu")
		(net "GND")
	)
	(gr_poly
		(pts
			(arc
				(start 207.528668 -72.229726)
				(mid 207.162908 -72.229726)
				(end 207.528668 -72.229726)
			)
		)
		(stroke
			(width 0)
			(type solid)
		)
		(fill yes)
		(layer "F.Cu")
		(net "GND")
	)
	(gr_poly
		(pts
			(arc
				(start 211.64423 -68.219066)
				(mid 211.27847 -68.219066)
				(end 211.64423 -68.219066)
			)
		)
		(stroke
			(width 0)
			(type solid)
		)
		(fill yes)
		(layer "F.Cu")
		(net "GND")
	)
	(gr_poly
		(pts
			(arc
				(start 211.685124 -84.081112)
				(mid 211.319364 -84.081112)
				(end 211.685124 -84.081112)
			)
		)
		(stroke
			(width 0)
			(type solid)
		)
		(fill yes)
		(layer "F.Cu")
		(net "GND")
	)
	(gr_poly
		(pts
			(arc
				(start 212.568282 -70.95617)
				(mid 212.202522 -70.95617)
				(end 212.568282 -70.95617)
			)
		)
		(stroke
			(width 0)
			(type solid)
		)
		(fill yes)
		(layer "F.Cu")
		(net "GND")
	)
	(gr_poly
		(pts
			(arc
				(start 212.74024 -97.028762)
				(mid 212.37448 -97.028762)
				(end 212.74024 -97.028762)
			)
		)
		(stroke
			(width 0)
			(type solid)
		)
		(fill yes)
		(layer "F.Cu")
		(net "GND")
	)
	(gr_poly
		(pts
			(arc
				(start 213.616032 -73.048622)
				(mid 213.250272 -73.048622)
				(end 213.616032 -73.048622)
			)
		)
		(stroke
			(width 0)
			(type solid)
		)
		(fill yes)
		(layer "F.Cu")
		(net "GND")
	)
	(gr_poly
		(pts
			(arc
				(start 215.13673 -85.23605)
				(mid 214.77097 -85.23605)
				(end 215.13673 -85.23605)
			)
		)
		(stroke
			(width 0)
			(type solid)
		)
		(fill yes)
		(layer "F.Cu")
		(net "GND")
	)
	(gr_poly
		(pts
			(arc
				(start 216.895934 -75.555348)
				(mid 216.530174 -75.555348)
				(end 216.895934 -75.555348)
			)
		)
		(stroke
			(width 0)
			(type solid)
		)
		(fill yes)
		(layer "F.Cu")
		(net "GND")
	)
	(gr_poly
		(pts
			(arc
				(start 217.784934 -77.434948)
				(mid 217.419174 -77.434948)
				(end 217.784934 -77.434948)
			)
		)
		(stroke
			(width 0)
			(type solid)
		)
		(fill yes)
		(layer "F.Cu")
		(net "GND")
	)
	(gr_poly
		(pts
			(arc
				(start 218.966034 -15.664688)
				(mid 218.600274 -15.664688)
				(end 218.966034 -15.664688)
			)
		)
		(stroke
			(width 0)
			(type solid)
		)
		(fill yes)
		(layer "F.Cu")
		(net "GND")
	)
	(gr_poly
		(pts
			(arc
				(start 219.813378 -212.3694)
				(mid 219.454222 -212.3694)
				(end 219.813378 -212.3694)
			)
		)
		(stroke
			(width 0)
			(type solid)
		)
		(fill yes)
		(layer "F.Cu")
		(net "GND")
	)
	(gr_poly
		(pts
			(arc
				(start 222.149416 -115.159282)
				(mid 221.783656 -115.159282)
				(end 222.149416 -115.159282)
			)
		)
		(stroke
			(width 0)
			(type solid)
		)
		(fill yes)
		(layer "F.Cu")
		(net "GND")
	)
	(gr_poly
		(pts
			(arc
				(start 225.87712 -119.259858)
				(mid 225.51136 -119.259858)
				(end 225.87712 -119.259858)
			)
		)
		(stroke
			(width 0)
			(type solid)
		)
		(fill yes)
		(layer "F.Cu")
		(net "GND")
	)
	(gr_poly
		(pts
			(xy 231.30002 -295.188894) (xy 231.30002 -292.777926) (xy 231.30002 -291.740844) (xy 231.843834 -291.19703)
			(xy 231.843834 -291.194744) (xy 232.025698 -291.01288) (xy 232.025698 -289.24123) (xy 233.254042 -288.012886)
			(xy 233.254042 -277.40102) (xy 231.265984 -275.412708) (xy 231.265984 -270.758412) (xy 231.265984 -270.357092)
			(xy 230.918766 -270.009874) (xy 229.887018 -270.009874) (xy 226.64801 -270.009874) (xy 226.13493 -270.522954)
			(xy 226.13493 -280.151078) (xy 226.530662 -280.54681) (xy 226.689158 -280.54681) (xy 228.9429 -280.54681)
			(xy 229.898702 -281.502612) (xy 229.898702 -288.431224) (xy 230.186992 -288.719514) (xy 230.186992 -289.186112)
			(xy 230.492046 -289.49142) (xy 230.968042 -289.967416) (xy 230.968042 -294.387524) (xy 230.772462 -294.583104)
			(xy 230.772462 -295.187116) (xy 230.83393 -295.248584) (xy 231.24033 -295.248584)
		)
		(stroke
			(width 0)
			(type solid)
		)
		(fill yes)
		(layer "F.Cu")
		(net "SW_P12V_AUX_P1V8_RETIMER_CPU1_FLT")
	)
	(gr_poly
		(pts
			(xy 243.24437 -295.188894) (xy 243.24437 -292.777926) (xy 243.24437 -291.740844) (xy 243.788184 -291.19703)
			(xy 243.788184 -291.194744) (xy 243.970048 -291.01288) (xy 243.970048 -288.638996) (xy 244.413278 -288.195766)
			(xy 244.413278 -281.080972) (xy 246.407432 -279.086818) (xy 247.259602 -279.086818) (xy 247.606312 -278.740108)
			(xy 247.606312 -269.865602) (xy 247.352058 -269.611348) (xy 247.165622 -269.611348) (xy 243.307362 -269.611348)
			(xy 242.77955 -269.611348) (xy 242.618768 -269.611348) (xy 242.194588 -270.035528) (xy 242.194588 -274.685506)
			(xy 240.859818 -276.020276) (xy 240.859818 -276.15642) (xy 240.859818 -287.580324) (xy 241.121946 -287.842452)
			(xy 242.912392 -289.632898) (xy 242.912392 -289.967416) (xy 242.912392 -294.387524) (xy 242.716812 -294.583104)
			(xy 242.716812 -295.187116) (xy 242.77828 -295.248584) (xy 243.18468 -295.248584)
		)
		(stroke
			(width 0)
			(type solid)
		)
		(fill yes)
		(layer "F.Cu")
		(net "SW_P12V_AUX_P1V8_RETIMER_CPU0_FLT")
	)
	(gr_poly
		(pts
			(arc
				(start 252.160278 -123.283726)
				(mid 251.794518 -123.283726)
				(end 252.160278 -123.283726)
			)
		)
		(stroke
			(width 0)
			(type solid)
		)
		(fill yes)
		(layer "F.Cu")
		(net "GND")
	)
	(gr_poly
		(pts
			(xy 256.748534 -45.313346) (xy 256.748534 -44.126658) (xy 256.676398 -44.054522) (xy 255.837944 -44.054522)
			(xy 255.177544 -44.054522) (xy 255.126744 -44.105322) (xy 255.126744 -45.741336) (xy 254.843534 -46.024546)
			(xy 254.368808 -46.024546) (xy 254.230124 -45.885862) (xy 252.833124 -45.885862) (xy 252.703584 -45.756322)
			(xy 252.703584 -43.602402) (xy 252.703584 -43.282362) (xy 252.812804 -43.173142) (xy 253.132844 -43.173142)
			(xy 253.206504 -43.099482) (xy 253.206504 -43.015662) (xy 253.130304 -42.939462) (xy 252.510544 -42.939462)
			(xy 252.469904 -42.980102) (xy 252.469904 -43.620182) (xy 252.469904 -43.701462) (xy 251.791724 -44.379642)
			(xy 251.791724 -45.925994) (xy 251.654056 -46.063662) (xy 251.029724 -46.063662) (xy 250.978924 -46.114462)
			(xy 250.978924 -46.909736) (xy 251.389134 -47.319946) (xy 254.741934 -47.319946)
		)
		(stroke
			(width 0)
			(type solid)
		)
		(fill yes)
		(layer "F.Cu")
		(net "GND")
	)
	(gr_poly
		(pts
			(arc
				(start 302.860964 -149.750018)
				(mid 302.495204 -149.750018)
				(end 302.860964 -149.750018)
			)
		)
		(stroke
			(width 0)
			(type solid)
		)
		(fill yes)
		(layer "F.Cu")
		(net "GND")
	)
	(gr_poly
		(pts
			(arc
				(start 305.34864 -169.707052)
				(mid 304.98288 -169.707052)
				(end 305.34864 -169.707052)
			)
		)
		(stroke
			(width 0)
			(type solid)
		)
		(fill yes)
		(layer "F.Cu")
		(net "GND")
	)
	(gr_poly
		(pts
			(xy 305.7398 -48.360838) (xy 305.7398 -48.284384) (xy 305.7398 -47.820834) (xy 305.63693 -47.717964)
			(xy 304.46345 -47.717964) (xy 304.252122 -47.506636) (xy 304.252122 -46.477428) (xy 304.183034 -46.40834)
			(xy 304.183034 -44.40301) (xy 304.252122 -44.333922) (xy 304.252122 -44.321222) (xy 304.491644 -44.0817)
			(xy 307.799232 -44.0817) (xy 308.586378 -43.294554) (xy 310.669178 -43.294554) (xy 310.694578 -43.269154)
			(xy 310.694578 -43.015154) (xy 310.669178 -42.989754) (xy 309.119778 -42.989754) (xy 308.967378 -42.837354)
			(xy 307.392578 -42.837354) (xy 307.163978 -42.608754) (xy 305.995578 -42.608754) (xy 303.488852 -42.608754)
			(xy 303.303178 -42.794428) (xy 303.303178 -43.700954) (xy 303.303178 -46.774354) (xy 303.303178 -47.883318)
			(xy 303.303178 -48.338994) (xy 303.436782 -48.472598) (xy 305.62804 -48.472598)
		)
		(stroke
			(width 0)
			(type solid)
		)
		(fill yes)
		(layer "F.Cu")
		(net "P3V3_ADC128_VCC")
	)
	(gr_poly
		(pts
			(arc
				(start 306.805838 -169.70121)
				(mid 306.440078 -169.70121)
				(end 306.805838 -169.70121)
			)
		)
		(stroke
			(width 0)
			(type solid)
		)
		(fill yes)
		(layer "F.Cu")
		(net "GND")
	)
	(gr_poly
		(pts
			(arc
				(start 307.11648 -150.274274)
				(mid 306.75072 -150.274274)
				(end 307.11648 -150.274274)
			)
		)
		(stroke
			(width 0)
			(type solid)
		)
		(fill yes)
		(layer "F.Cu")
		(net "GND")
	)
	(gr_poly
		(pts
			(arc
				(start 337.096862 -308.440836)
				(mid 336.731102 -308.440836)
				(end 337.096862 -308.440836)
			)
		)
		(stroke
			(width 0)
			(type solid)
		)
		(fill yes)
		(layer "F.Cu")
		(net "GND")
	)
	(gr_poly
		(pts
			(arc
				(start 380.990602 -204.092302)
				(mid 380.624842 -204.092302)
				(end 380.990602 -204.092302)
			)
		)
		(stroke
			(width 0)
			(type solid)
		)
		(fill yes)
		(layer "F.Cu")
		(net "GND")
	)
	(gr_poly
		(pts
			(arc
				(start 413.544004 -43.690032)
				(mid 413.178244 -43.690032)
				(end 413.544004 -43.690032)
			)
		)
		(stroke
			(width 0)
			(type solid)
		)
		(fill yes)
		(layer "F.Cu")
		(net "GND")
	)
	(gr_poly
		(pts
			(arc
				(start 418.2618 -18.247106)
				(mid 417.89604 -18.247106)
				(end 418.2618 -18.247106)
			)
		)
		(stroke
			(width 0)
			(type solid)
		)
		(fill yes)
		(layer "F.Cu")
		(net "GND")
	)
	(gr_poly
		(pts
			(arc
				(start 419.52672 -18.247106)
				(mid 419.16096 -18.247106)
				(end 419.52672 -18.247106)
			)
		)
		(stroke
			(width 0)
			(type solid)
		)
		(fill yes)
		(layer "F.Cu")
		(net "GND")
	)
	(gr_poly
		(pts
			(arc
				(start 420.01186 -17.61236)
				(mid 419.6461 -17.61236)
				(end 420.01186 -17.61236)
			)
		)
		(stroke
			(width 0)
			(type solid)
		)
		(fill yes)
		(layer "F.Cu")
		(net "GND")
	)
	(gr_poly
		(pts
			(arc
				(start 420.569644 -19.137122)
				(mid 420.203884 -19.137122)
				(end 420.569644 -19.137122)
			)
		)
		(stroke
			(width 0)
			(type solid)
		)
		(fill yes)
		(layer "F.Cu")
		(net "GND")
	)
	(gr_poly
		(pts
			(arc
				(start 421.0558 -18.5039)
				(mid 420.69004 -18.5039)
				(end 421.0558 -18.5039)
			)
		)
		(stroke
			(width 0)
			(type solid)
		)
		(fill yes)
		(layer "F.Cu")
		(net "GND")
	)
	(gr_poly
		(pts
			(arc
				(start 422.34739 -18.5039)
				(mid 421.98163 -18.5039)
				(end 422.34739 -18.5039)
			)
		)
		(stroke
			(width 0)
			(type solid)
		)
		(fill yes)
		(layer "F.Cu")
		(net "GND")
	)
	(gr_poly
		(pts
			(arc
				(start 422.804844 -19.137122)
				(mid 422.439084 -19.137122)
				(end 422.804844 -19.137122)
			)
		)
		(stroke
			(width 0)
			(type solid)
		)
		(fill yes)
		(layer "F.Cu")
		(net "GND")
	)
	(gr_poly
		(pts
			(arc
				(start 423.36466 -17.61236)
				(mid 422.9989 -17.61236)
				(end 423.36466 -17.61236)
			)
		)
		(stroke
			(width 0)
			(type solid)
		)
		(fill yes)
		(layer "F.Cu")
		(net "GND")
	)
	(gr_poly
		(pts
			(arc
				(start 423.8498 -18.247106)
				(mid 423.48404 -18.247106)
				(end 423.8498 -18.247106)
			)
		)
		(stroke
			(width 0)
			(type solid)
		)
		(fill yes)
		(layer "F.Cu")
		(net "GND")
	)
	(gr_poly
		(pts
			(arc
				(start 428.98568 -17.613122)
				(mid 428.61992 -17.613122)
				(end 428.98568 -17.613122)
			)
		)
		(stroke
			(width 0)
			(type solid)
		)
		(fill yes)
		(layer "F.Cu")
		(net "GND")
	)
	(gr_poly
		(pts
			(arc
				(start 429.471836 -18.247868)
				(mid 429.106076 -18.247868)
				(end 429.471836 -18.247868)
			)
		)
		(stroke
			(width 0)
			(type solid)
		)
		(fill yes)
		(layer "F.Cu")
		(net "GND")
	)
	(gr_poly
		(pts
			(arc
				(start 433.530756 -19.771106)
				(mid 433.164996 -19.771106)
				(end 433.530756 -19.771106)
			)
		)
		(stroke
			(width 0)
			(type solid)
		)
		(fill yes)
		(layer "F.Cu")
		(net "GND")
	)
	(gr_poly
		(pts
			(arc
				(start 434.015896 -19.13636)
				(mid 433.650136 -19.13636)
				(end 434.015896 -19.13636)
			)
		)
		(stroke
			(width 0)
			(type solid)
		)
		(fill yes)
		(layer "F.Cu")
		(net "GND")
	)
	(gr_poly
		(pts
			(arc
				(start 445.192912 -6.387084)
				(mid 444.827152 -6.387084)
				(end 445.192912 -6.387084)
			)
		)
		(stroke
			(width 0)
			(type solid)
		)
		(fill yes)
		(layer "F.Cu")
		(net "GND")
	)
	(gr_poly
		(pts
			(arc
				(start 447.138044 -14.657832)
				(mid 446.772284 -14.657832)
				(end 447.138044 -14.657832)
			)
		)
		(stroke
			(width 0)
			(type solid)
		)
		(fill yes)
		(layer "F.Cu")
		(net "GND")
	)
	(gr_poly
		(pts
			(arc
				(start 448.331844 -14.607032)
				(mid 447.966084 -14.607032)
				(end 448.331844 -14.607032)
			)
		)
		(stroke
			(width 0)
			(type solid)
		)
		(fill yes)
		(layer "F.Cu")
		(net "GND")
	)
	(gr_poly
		(pts
			(arc
				(start 39.022782 -129.642616)
				(mid 39.042139 -129.638783)
				(end 39.058596 -129.627884)
			)
			(arc
				(start 39.182294 -129.504186)
				(mid 39.193405 -129.487652)
				(end 39.19728 -129.468118)
			)
			(arc
				(start 39.19728 -127.343662)
				(mid 39.193379 -127.324139)
				(end 39.182294 -127.307594)
			)
			(arc
				(start 39.087806 -127.213106)
				(mid 39.071272 -127.201995)
				(end 39.051738 -127.19812)
			)
			(arc
				(start 35.692842 -127.19812)
				(mid 35.673319 -127.202021)
				(end 35.656774 -127.213106)
			)
			(arc
				(start 35.214306 -127.655574)
				(mid 35.203195 -127.672108)
				(end 35.19932 -127.691642)
			)
			(arc
				(start 35.19932 -129.181098)
				(mid 35.203221 -129.200621)
				(end 35.214306 -129.217166)
			)
			(arc
				(start 35.625024 -129.627884)
				(mid 35.64147 -129.63881)
				(end 35.660838 -129.642616)
			)
		)
		(stroke
			(width 0)
			(type solid)
		)
		(fill yes)
		(layer "F.Cu")
		(net "P12V_AUX")
	)
	(gr_poly
		(pts
			(arc
				(start 40.636698 -108.2548)
				(mid 40.656221 -108.250899)
				(end 40.672766 -108.239814)
			)
			(arc
				(start 40.985694 -107.926886)
				(mid 40.996805 -107.910352)
				(end 41.00068 -107.890818)
			)
			(arc
				(start 41.00068 -102.972362)
				(mid 40.996779 -102.952839)
				(end 40.985694 -102.936294)
			)
			(arc
				(start 40.947086 -102.897686)
				(mid 40.930552 -102.886575)
				(end 40.911018 -102.8827)
			)
			(arc
				(start 39.911782 -102.8827)
				(mid 39.892259 -102.886601)
				(end 39.875714 -102.897686)
			)
			(arc
				(start 39.699946 -103.073454)
				(mid 39.688835 -103.089988)
				(end 39.68496 -103.109522)
			)
			(arc
				(start 39.68496 -108.114338)
				(mid 39.688861 -108.133861)
				(end 39.699946 -108.150406)
			)
			(arc
				(start 39.789354 -108.239814)
				(mid 39.805888 -108.250925)
				(end 39.825422 -108.2548)
			)
		)
		(stroke
			(width 0)
			(type solid)
		)
		(fill yes)
		(layer "F.Cu")
		(net "P12V_AUX_DSC_S1")
	)
	(gr_poly
		(pts
			(arc
				(start 43.067478 -106.28376)
				(mid 43.087001 -106.279859)
				(end 43.103546 -106.268774)
			)
			(arc
				(start 43.246294 -106.126026)
				(mid 43.257405 -106.109492)
				(end 43.26128 -106.089958)
			)
			(arc
				(start 43.26128 -104.432862)
				(mid 43.257379 -104.413339)
				(end 43.246294 -104.396794)
			)
			(arc
				(start 43.090846 -104.241346)
				(mid 43.074312 -104.230235)
				(end 43.054778 -104.22636)
			)
			(arc
				(start 41.707562 -104.22636)
				(mid 41.688039 -104.230261)
				(end 41.671494 -104.241346)
			)
			(arc
				(start 41.470326 -104.442514)
				(mid 41.459215 -104.459048)
				(end 41.45534 -104.478582)
			)
			(arc
				(start 41.45534 -106.102658)
				(mid 41.459241 -106.122181)
				(end 41.470326 -106.138726)
			)
			(arc
				(start 41.600374 -106.268774)
				(mid 41.616908 -106.279885)
				(end 41.636442 -106.28376)
			)
		)
		(stroke
			(width 0)
			(type solid)
		)
		(fill yes)
		(layer "F.Cu")
		(net "GND")
	)
	(gr_poly
		(pts
			(arc
				(start 44.274232 -365.79556)
				(mid 44.293755 -365.791659)
				(end 44.3103 -365.780574)
			)
			(arc
				(start 44.433744 -365.65713)
				(mid 44.444855 -365.640596)
				(end 44.44873 -365.621062)
			)
			(arc
				(start 44.44873 -361.792774)
				(mid 44.444829 -361.773251)
				(end 44.433744 -361.756706)
			)
			(arc
				(start 44.376594 -361.699556)
				(mid 44.36006 -361.688445)
				(end 44.340526 -361.68457)
			)
			(arc
				(start 41.46042 -361.68457)
				(mid 41.440897 -361.688471)
				(end 41.424352 -361.699556)
			)
			(arc
				(start 41.29786 -361.826048)
				(mid 41.286749 -361.842582)
				(end 41.282874 -361.862116)
			)
			(arc
				(start 41.282874 -365.179356)
				(mid 41.286775 -365.198879)
				(end 41.29786 -365.215424)
			)
			(arc
				(start 41.86301 -365.780574)
				(mid 41.879544 -365.791685)
				(end 41.899078 -365.79556)
			)
		)
		(stroke
			(width 0)
			(type solid)
		)
		(fill yes)
		(layer "F.Cu")
		(net "GND")
	)
	(gr_poly
		(pts
			(arc
				(start 45.746162 -421.550846)
				(mid 45.765685 -421.546945)
				(end 45.78223 -421.53586)
			)
			(arc
				(start 45.796708 -421.521382)
				(mid 45.807819 -421.504848)
				(end 45.811694 -421.485314)
			)
			(arc
				(start 45.811694 -418.75329)
				(mid 45.807793 -418.733767)
				(end 45.796708 -418.717222)
			)
			(arc
				(start 45.734478 -418.654992)
				(mid 45.717944 -418.643881)
				(end 45.69841 -418.640006)
			)
			(arc
				(start 44.904914 -418.640006)
				(mid 44.885391 -418.643907)
				(end 44.868846 -418.654992)
			)
			(arc
				(start 44.809918 -418.71392)
				(mid 44.798807 -418.730454)
				(end 44.794932 -418.749988)
			)
			(arc
				(start 44.794932 -421.283384)
				(mid 44.798833 -421.302907)
				(end 44.809918 -421.319452)
			)
			(arc
				(start 45.026326 -421.53586)
				(mid 45.04286 -421.546971)
				(end 45.062394 -421.550846)
			)
		)
		(stroke
			(width 0)
			(type solid)
		)
		(fill yes)
		(layer "F.Cu")
		(net "P1V8_CPU1_RT_1D")
	)
	(gr_poly
		(pts
			(arc
				(start 45.818298 -129.51206)
				(mid 45.837821 -129.508159)
				(end 45.854366 -129.497074)
			)
			(arc
				(start 45.984414 -129.367026)
				(mid 45.995525 -129.350492)
				(end 45.9994 -129.330958)
			)
			(arc
				(start 45.9994 -127.206502)
				(mid 45.995499 -127.186979)
				(end 45.984414 -127.170434)
			)
			(arc
				(start 45.889926 -127.075946)
				(mid 45.873392 -127.064835)
				(end 45.853858 -127.06096)
			)
			(arc
				(start 42.494962 -127.06096)
				(mid 42.475439 -127.064861)
				(end 42.458894 -127.075946)
			)
			(arc
				(start 42.016426 -127.518414)
				(mid 42.005315 -127.534948)
				(end 42.00144 -127.554482)
			)
			(arc
				(start 42.00144 -129.043938)
				(mid 42.005341 -129.063461)
				(end 42.016426 -129.080006)
			)
			(arc
				(start 42.433494 -129.497074)
				(mid 42.450028 -129.508185)
				(end 42.469562 -129.51206)
			)
		)
		(stroke
			(width 0)
			(type solid)
		)
		(fill yes)
		(layer "F.Cu")
		(net "P3V3_AUX")
	)
	(gr_poly
		(pts
			(arc
				(start 47.438818 -108.11764)
				(mid 47.458341 -108.113739)
				(end 47.474886 -108.102654)
			)
			(arc
				(start 47.787814 -107.789726)
				(mid 47.798925 -107.773192)
				(end 47.8028 -107.753658)
			)
			(arc
				(start 47.8028 -102.835202)
				(mid 47.798899 -102.815679)
				(end 47.787814 -102.799134)
			)
			(arc
				(start 47.749206 -102.760526)
				(mid 47.732672 -102.749415)
				(end 47.713138 -102.74554)
			)
			(arc
				(start 46.713902 -102.74554)
				(mid 46.694379 -102.749441)
				(end 46.677834 -102.760526)
			)
			(arc
				(start 46.502066 -102.936294)
				(mid 46.490955 -102.952828)
				(end 46.48708 -102.972362)
			)
			(arc
				(start 46.48708 -107.977178)
				(mid 46.490981 -107.996701)
				(end 46.502066 -108.013246)
			)
			(arc
				(start 46.591474 -108.102654)
				(mid 46.608008 -108.113765)
				(end 46.627542 -108.11764)
			)
		)
		(stroke
			(width 0)
			(type solid)
		)
		(fill yes)
		(layer "F.Cu")
		(net "P3V3_AUX_DSC_S1")
	)
	(gr_poly
		(pts
			(arc
				(start 49.12614 -400.166586)
				(mid 49.145663 -400.162685)
				(end 49.162208 -400.1516)
			)
			(arc
				(start 54.287674 -395.026134)
				(mid 54.298785 -395.0096)
				(end 54.30266 -394.990066)
			)
			(arc
				(start 54.30266 -394.589762)
				(mid 54.298759 -394.570239)
				(end 54.287674 -394.553694)
			)
			(arc
				(start 54.081426 -394.347446)
				(mid 54.064892 -394.336335)
				(end 54.045358 -394.33246)
			)
			(arc
				(start 47.996602 -394.33246)
				(mid 47.977079 -394.336361)
				(end 47.960534 -394.347446)
			)
			(arc
				(start 47.817024 -394.490956)
				(mid 47.805913 -394.50749)
				(end 47.802038 -394.527024)
			)
			(arc
				(start 47.802038 -400.078194)
				(mid 47.805939 -400.097717)
				(end 47.817024 -400.114262)
			)
			(arc
				(start 47.854362 -400.1516)
				(mid 47.870896 -400.162711)
				(end 47.89043 -400.166586)
			)
		)
		(stroke
			(width 0)
			(type solid)
		)
		(fill yes)
		(layer "F.Cu")
		(net "GND")
	)
	(gr_poly
		(pts
			(arc
				(start 49.869598 -106.1466)
				(mid 49.889121 -106.142699)
				(end 49.905666 -106.131614)
			)
			(arc
				(start 50.048414 -105.988866)
				(mid 50.059525 -105.972332)
				(end 50.0634 -105.952798)
			)
			(arc
				(start 50.0634 -104.295702)
				(mid 50.059499 -104.276179)
				(end 50.048414 -104.259634)
			)
			(arc
				(start 49.892966 -104.104186)
				(mid 49.876432 -104.093075)
				(end 49.856898 -104.0892)
			)
			(arc
				(start 48.509682 -104.0892)
				(mid 48.490159 -104.093101)
				(end 48.473614 -104.104186)
			)
			(arc
				(start 48.272446 -104.305354)
				(mid 48.261335 -104.321888)
				(end 48.25746 -104.341422)
			)
			(arc
				(start 48.25746 -105.965498)
				(mid 48.261361 -105.985021)
				(end 48.272446 -106.001566)
			)
			(arc
				(start 48.402494 -106.131614)
				(mid 48.419028 -106.142725)
				(end 48.438562 -106.1466)
			)
		)
		(stroke
			(width 0)
			(type solid)
		)
		(fill yes)
		(layer "F.Cu")
		(net "GND")
	)
	(gr_poly
		(pts
			(arc
				(start 67.892676 -403.38248)
				(mid 67.912199 -403.378579)
				(end 67.928744 -403.367494)
			)
			(arc
				(start 67.997832 -403.298406)
				(mid 68.008943 -403.281872)
				(end 68.012818 -403.262338)
			)
			(arc
				(start 68.012818 -399.159222)
				(mid 68.008917 -399.139699)
				(end 67.997832 -399.123154)
			)
			(arc
				(start 67.809364 -398.934686)
				(mid 67.79283 -398.923575)
				(end 67.773296 -398.9197)
			)
			(arc
				(start 59.91098 -398.9197)
				(mid 59.891457 -398.923601)
				(end 59.874912 -398.934686)
			)
			(arc
				(start 59.394344 -399.415254)
				(mid 59.383233 -399.431788)
				(end 59.379358 -399.451322)
			)
			(arc
				(start 59.379358 -403.142958)
				(mid 59.383259 -403.162481)
				(end 59.394344 -403.179026)
			)
			(arc
				(start 59.582812 -403.367494)
				(mid 59.599346 -403.378605)
				(end 59.61888 -403.38248)
			)
		)
		(stroke
			(width 0)
			(type solid)
		)
		(fill yes)
		(layer "F.Cu")
		(net "GND")
	)
	(gr_poly
		(pts
			(arc
				(start 101.869494 -411.358588)
				(mid 101.889017 -411.354687)
				(end 101.905562 -411.343602)
			)
			(arc
				(start 101.958648 -411.290516)
				(mid 101.969759 -411.273982)
				(end 101.973634 -411.254448)
			)
			(arc
				(start 101.973634 -407.984198)
				(mid 101.969733 -407.964675)
				(end 101.958648 -407.94813)
			)
			(arc
				(start 101.609398 -407.59888)
				(mid 101.592864 -407.587769)
				(end 101.57333 -407.583894)
			)
			(arc
				(start 100.77196 -407.583894)
				(mid 100.752437 -407.587795)
				(end 100.735892 -407.59888)
			)
			(arc
				(start 100.610162 -407.72461)
				(mid 100.599051 -407.741144)
				(end 100.595176 -407.760678)
			)
			(arc
				(start 100.595176 -411.19298)
				(mid 100.599077 -411.212503)
				(end 100.610162 -411.229048)
			)
			(arc
				(start 100.724716 -411.343602)
				(mid 100.74125 -411.354713)
				(end 100.760784 -411.358588)
			)
		)
		(stroke
			(width 0)
			(type solid)
		)
		(fill yes)
		(layer "F.Cu")
		(net "P3V3_9ZXL045_P1_VDD")
	)
	(gr_poly
		(pts
			(arc
				(start 134.992618 -403.38248)
				(mid 135.012141 -403.378579)
				(end 135.028686 -403.367494)
			)
			(arc
				(start 135.097774 -403.298406)
				(mid 135.108885 -403.281872)
				(end 135.11276 -403.262338)
			)
			(arc
				(start 135.11276 -399.159222)
				(mid 135.108859 -399.139699)
				(end 135.097774 -399.123154)
			)
			(arc
				(start 134.909306 -398.934686)
				(mid 134.892772 -398.923575)
				(end 134.873238 -398.9197)
			)
			(arc
				(start 127.010922 -398.9197)
				(mid 126.991399 -398.923601)
				(end 126.974854 -398.934686)
			)
			(arc
				(start 126.494286 -399.415254)
				(mid 126.483175 -399.431788)
				(end 126.4793 -399.451322)
			)
			(arc
				(start 126.4793 -403.142958)
				(mid 126.483201 -403.162481)
				(end 126.494286 -403.179026)
			)
			(arc
				(start 126.682754 -403.367494)
				(mid 126.699288 -403.378605)
				(end 126.718822 -403.38248)
			)
		)
		(stroke
			(width 0)
			(type solid)
		)
		(fill yes)
		(layer "F.Cu")
		(net "GND")
	)
	(gr_poly
		(pts
			(xy 142.399004 -195.651882) (xy 142.399004 -169.939462) (xy 141.958314 -169.498772) (xy 138.717274 -169.498772)
			(xy 138.490452 -169.27195) (xy 138.490452 -168.336976) (xy 138.232388 -168.078912) (xy 136.13765 -168.078912)
			(xy 135.963152 -168.25341) (xy 130.494278 -168.25341) (xy 130.340354 -168.407334) (xy 130.340354 -173.284134)
			(xy 128.974596 -174.649892) (xy 128.958594 -174.649892) (xy 128.817624 -174.790862) (xy 127.479044 -174.790862)
			(xy 127.319278 -174.950628) (xy 127.319278 -176.48301) (xy 126.871476 -176.930812) (xy 121.588276 -176.930812)
			(xy 121.401078 -177.11801) (xy 121.401078 -180.52161) (xy 120.402604 -181.520084) (xy 118.802404 -181.520084)
			(xy 118.657878 -181.66461) (xy 118.657878 -183.21401) (xy 118.464076 -183.407812) (xy 113.08715 -183.407812)
			(xy 112.738154 -183.756808) (xy 112.738154 -201.769472) (xy 112.812068 -201.843132) (xy 136.207754 -201.843132)
		)
		(stroke
			(width 0)
			(type solid)
		)
		(fill yes)
		(layer "F.Cu")
		(net "PVDDCR_SOC_P1")
	)
	(gr_poly
		(pts
			(xy 171.0436 -39.0398) (xy 171.0436 -38.2016) (xy 170.378374 -37.536374) (xy 170.378374 -37.015928)
			(xy 169.923714 -36.561268) (xy 168.183814 -36.561268) (xy 167.85844 -36.886642) (xy 167.85844 -38.359334)
			(xy 168.707308 -38.359334) (xy 168.707308 -38.240208) (xy 168.758108 -38.189408) (xy 170.358308 -38.189408)
			(xy 170.409108 -38.240208) (xy 170.409108 -38.359334) (xy 170.358308 -38.410134) (xy 168.758108 -38.410134)
			(xy 168.707308 -38.359334) (xy 167.85844 -38.359334) (xy 167.85844 -38.36924) (xy 168.348406 -38.859206)
			(xy 168.707308 -38.859206) (xy 168.707308 -38.74008) (xy 168.758108 -38.68928) (xy 170.358308 -38.68928)
			(xy 170.409108 -38.74008) (xy 170.409108 -38.859206) (xy 170.358308 -38.910006) (xy 168.758108 -38.910006)
			(xy 168.707308 -38.859206) (xy 168.348406 -38.859206) (xy 168.689528 -39.200328) (xy 170.883072 -39.200328)
		)
		(stroke
			(width 0)
			(type solid)
		)
		(fill yes)
		(layer "F.Cu")
		(net "P3V3_M2_0")
	)
	(gr_poly
		(pts
			(arc
				(start 283.08935 -431.924714)
				(mid 283.108873 -431.920813)
				(end 283.125418 -431.909728)
			)
			(arc
				(start 283.407358 -431.627788)
				(mid 283.418469 -431.611254)
				(end 283.422344 -431.59172)
			)
			(arc
				(start 283.422344 -430.682908)
				(mid 283.418443 -430.663385)
				(end 283.407358 -430.64684)
			)
			(arc
				(start 283.106114 -430.345596)
				(mid 283.08958 -430.334485)
				(end 283.070046 -430.33061)
			)
			(arc
				(start 281.34056 -430.33061)
				(mid 281.321037 -430.334511)
				(end 281.304492 -430.345596)
			)
			(arc
				(start 281.257502 -430.392586)
				(mid 281.246391 -430.40912)
				(end 281.242516 -430.428654)
			)
			(arc
				(start 281.242516 -431.72126)
				(mid 281.246417 -431.740783)
				(end 281.257502 -431.757328)
			)
			(arc
				(start 281.409902 -431.909728)
				(mid 281.426436 -431.920839)
				(end 281.44597 -431.924714)
			)
		)
		(stroke
			(width 0)
			(type solid)
		)
		(fill yes)
		(layer "F.Cu")
		(net "P3V3_AUX")
	)
	(gr_poly
		(pts
			(arc
				(start 302.501554 -422.872154)
				(mid 302.521077 -422.868253)
				(end 302.537622 -422.857168)
			)
			(arc
				(start 302.58131 -422.81348)
				(mid 302.592421 -422.796946)
				(end 302.596296 -422.777412)
			)
			(arc
				(start 302.596296 -421.649652)
				(mid 302.592395 -421.630129)
				(end 302.58131 -421.613584)
			)
			(arc
				(start 302.455834 -421.488108)
				(mid 302.4393 -421.476997)
				(end 302.419766 -421.473122)
			)
			(arc
				(start 300.400212 -421.473122)
				(mid 300.380689 -421.477023)
				(end 300.364144 -421.488108)
			)
			(arc
				(start 300.345094 -421.507158)
				(mid 300.333983 -421.523692)
				(end 300.330108 -421.543226)
			)
			(arc
				(start 300.330108 -422.801796)
				(mid 300.334009 -422.821319)
				(end 300.345094 -422.837864)
			)
			(arc
				(start 300.364398 -422.857168)
				(mid 300.380932 -422.868279)
				(end 300.400466 -422.872154)
			)
		)
		(stroke
			(width 0)
			(type solid)
		)
		(fill yes)
		(layer "F.Cu")
		(net "P1V8_CPU0_RT_1D")
	)
	(gr_poly
		(pts
			(arc
				(start 305.162712 -408.548586)
				(mid 305.182235 -408.544685)
				(end 305.19878 -408.5336)
			)
			(arc
				(start 310.101234 -403.631146)
				(mid 310.112345 -403.614612)
				(end 310.11622 -403.595078)
			)
			(arc
				(start 310.11622 -403.022562)
				(mid 310.112319 -403.003039)
				(end 310.101234 -402.986494)
			)
			(arc
				(start 309.958486 -402.843746)
				(mid 309.941952 -402.832635)
				(end 309.922418 -402.82876)
			)
			(arc
				(start 304.120042 -402.82876)
				(mid 304.100519 -402.832661)
				(end 304.083974 -402.843746)
			)
			(arc
				(start 303.816766 -403.110954)
				(mid 303.805655 -403.127488)
				(end 303.80178 -403.147022)
			)
			(arc
				(start 303.80178 -408.460194)
				(mid 303.805681 -408.479717)
				(end 303.816766 -408.496262)
			)
			(arc
				(start 303.854104 -408.5336)
				(mid 303.870638 -408.544711)
				(end 303.890172 -408.548586)
			)
		)
		(stroke
			(width 0)
			(type solid)
		)
		(fill yes)
		(layer "F.Cu")
		(net "GND")
	)
	(gr_poly
		(pts
			(xy 313.19724 -339.283548) (xy 313.367928 -339.283548) (xy 313.79668 -338.854796) (xy 313.79668 -333.289402)
			(xy 313.401964 -332.894686) (xy 313.401964 -331.504544) (xy 313.81573 -331.090778) (xy 313.81573 -328.819764)
			(xy 313.87288 -328.819764) (xy 315.472572 -327.220072) (xy 315.472572 -327.14438) (xy 315.472572 -326.115934)
			(xy 315.72962 -325.858886) (xy 316.0395 -325.549006) (xy 320.76136 -325.549006) (xy 320.93916 -325.371206)
			(xy 320.93916 -323.882766) (xy 320.873374 -323.81698) (xy 316.060582 -323.81698) (xy 314.934092 -323.81698)
			(xy 313.363102 -325.38797) (xy 312.73877 -326.012302) (xy 312.73877 -326.023478) (xy 311.582562 -327.179686)
			(xy 311.582562 -337.276694) (xy 311.352946 -337.50631) (xy 306.526946 -337.50631) (xy 306.326286 -337.70697)
			(xy 306.326286 -339.03031) (xy 306.580286 -339.28431) (xy 312.554366 -339.28431) (xy 313.196224 -339.28431)
		)
		(stroke
			(width 0)
			(type solid)
		)
		(fill yes)
		(layer "F.Cu")
		(net "IND_CPU1_P0_CPL3")
	)
	(gr_poly
		(pts
			(arc
				(start 323.892418 -411.76448)
				(mid 323.911941 -411.760579)
				(end 323.928486 -411.749494)
			)
			(arc
				(start 323.997574 -411.680406)
				(mid 324.008685 -411.663872)
				(end 324.01256 -411.644338)
			)
			(arc
				(start 324.01256 -407.541222)
				(mid 324.008659 -407.521699)
				(end 323.997574 -407.505154)
			)
			(arc
				(start 323.809106 -407.316686)
				(mid 323.792572 -407.305575)
				(end 323.773038 -407.3017)
			)
			(arc
				(start 315.910722 -407.3017)
				(mid 315.891199 -407.305601)
				(end 315.874654 -407.316686)
			)
			(arc
				(start 315.394086 -407.797254)
				(mid 315.382975 -407.813788)
				(end 315.3791 -407.833322)
			)
			(arc
				(start 315.3791 -411.524958)
				(mid 315.383001 -411.544481)
				(end 315.394086 -411.561026)
			)
			(arc
				(start 315.582554 -411.749494)
				(mid 315.599088 -411.760605)
				(end 315.618622 -411.76448)
			)
		)
		(stroke
			(width 0)
			(type solid)
		)
		(fill yes)
		(layer "F.Cu")
		(net "GND")
	)
	(gr_poly
		(pts
			(arc
				(start 390.992614 -411.76448)
				(mid 391.012137 -411.760579)
				(end 391.028682 -411.749494)
			)
			(arc
				(start 391.09777 -411.680406)
				(mid 391.108881 -411.663872)
				(end 391.112756 -411.644338)
			)
			(arc
				(start 391.112756 -407.541222)
				(mid 391.108855 -407.521699)
				(end 391.09777 -407.505154)
			)
			(arc
				(start 390.909302 -407.316686)
				(mid 390.892768 -407.305575)
				(end 390.873234 -407.3017)
			)
			(arc
				(start 383.010918 -407.3017)
				(mid 382.991395 -407.305601)
				(end 382.97485 -407.316686)
			)
			(arc
				(start 382.494282 -407.797254)
				(mid 382.483171 -407.813788)
				(end 382.479296 -407.833322)
			)
			(arc
				(start 382.479296 -411.524958)
				(mid 382.483197 -411.544481)
				(end 382.494282 -411.561026)
			)
			(arc
				(start 382.68275 -411.749494)
				(mid 382.699284 -411.760605)
				(end 382.718818 -411.76448)
			)
		)
		(stroke
			(width 0)
			(type solid)
		)
		(fill yes)
		(layer "F.Cu")
		(net "GND")
	)
	(gr_poly
		(pts
			(arc
				(start 427.21911 -421.540432)
				(mid 427.238633 -421.536531)
				(end 427.255178 -421.525446)
			)
			(arc
				(start 427.30039 -421.480234)
				(mid 427.311501 -421.4637)
				(end 427.315376 -421.444166)
			)
			(arc
				(start 427.315376 -420.592758)
				(mid 427.311475 -420.573235)
				(end 427.30039 -420.55669)
			)
			(arc
				(start 427.149514 -420.405814)
				(mid 427.13298 -420.394703)
				(end 427.113446 -420.390828)
			)
			(arc
				(start 424.303698 -420.390828)
				(mid 424.284175 -420.394729)
				(end 424.26763 -420.405814)
			)
			(arc
				(start 424.166284 -420.50716)
				(mid 424.155173 -420.523694)
				(end 424.151298 -420.543228)
			)
			(arc
				(start 424.151298 -421.375586)
				(mid 424.155199 -421.395109)
				(end 424.166284 -421.411654)
			)
			(arc
				(start 424.280076 -421.525446)
				(mid 424.29661 -421.536557)
				(end 424.316144 -421.540432)
			)
		)
		(stroke
			(width 0)
			(type solid)
		)
		(fill yes)
		(layer "F.Cu")
		(net "P1V8_CPU0_RT_1D")
	)
	(gr_poly
		(pts
			(xy 193.081148 -18.098008) (xy 193.915792 -18.098008) (xy 194.2338 -17.78) (xy 194.2338 -14.038834)
			(xy 193.469514 -13.274548) (xy 193.058034 -12.863068) (xy 190.858394 -12.863068) (xy 190.871348 -12.876022)
			(xy 190.871348 -14.323822) (xy 190.820548 -14.374622) (xy 190.7032 -14.374622) (xy 190.6524 -14.323822)
			(xy 190.6524 -12.876022) (xy 190.665354 -12.863068) (xy 190.322454 -12.863068) (xy 190.276734 -12.908788)
			(xy 190.276734 -14.414754) (xy 190.409068 -14.547088) (xy 191.467994 -14.547088) (xy 191.650874 -14.729968)
			(xy 191.650874 -15.588488) (xy 191.412114 -15.827248) (xy 190.871348 -15.827248) (xy 190.871348 -17.273778)
			(xy 190.820548 -17.324578) (xy 190.7032 -17.324578) (xy 190.6524 -17.273778) (xy 190.6524 -15.827248)
			(xy 190.297054 -15.827248) (xy 190.281814 -15.842488) (xy 190.281814 -17.772888) (xy 190.622174 -18.113248)
			(xy 193.065654 -18.113248)
		)
		(stroke
			(width 0)
			(type solid)
		)
		(fill yes)
		(layer "F.Cu")
		(net "P12V_SCM")
	)
	(gr_poly
		(pts
			(xy 91.06916 -59.135518) (xy 91.06916 -57.32653) (xy 91.187524 -57.208166) (xy 91.710764 -57.208166)
			(xy 91.833192 -57.330594) (xy 91.833192 -58.648346) (xy 91.881452 -58.696606) (xy 92.038932 -58.696606)
			(xy 92.071952 -58.663586) (xy 92.071952 -56.291226) (xy 92.51061 -55.852568) (xy 92.51061 -55.311294)
			(xy 92.612464 -55.20944) (xy 92.85732 -55.20944) (xy 93.295978 -54.770782) (xy 93.295978 -53.346096)
			(xy 93.011498 -53.061616) (xy 90.991436 -53.061616) (xy 90.827352 -53.2257)
			(arc
				(start 90.827352 -56.580278)
				(mid 90.888442 -56.71276)
				(end 90.909394 -56.857138)
			)
			(arc
				(start 90.909394 -56.857138)
				(mid 90.888455 -57.00152)
				(end 90.827352 -57.133998)
			)
			(xy 90.827352 -59.136026) (xy 90.890852 -59.199526) (xy 91.005152 -59.199526)
		)
		(stroke
			(width 0)
			(type solid)
		)
		(fill yes)
		(layer "F.Cu")
		(net "P3V3_AUX")
	)
	(gr_poly
		(pts
			(xy 366.551464 -402.216366)
			(arc
				(start 366.558322 -402.204682)
				(mid 366.57983 -402.173259)
				(end 366.605058 -402.144738)
			)
			(arc
				(start 366.640364 -402.109686)
				(mid 366.651338 -402.093123)
				(end 366.655096 -402.073618)
			)
			(arc
				(start 366.655096 -399.818352)
				(mid 366.651263 -399.798995)
				(end 366.640364 -399.782538)
			)
			(arc
				(start 366.58423 -399.726404)
				(mid 366.567696 -399.715293)
				(end 366.548162 -399.711418)
			)
			(arc
				(start 364.453932 -399.711418)
				(mid 364.434409 -399.715319)
				(end 364.417864 -399.726404)
			)
			(arc
				(start 364.313724 -399.830544)
				(mid 364.302613 -399.847078)
				(end 364.298738 -399.866612)
			)
			(arc
				(start 364.298738 -401.961858)
				(mid 364.302639 -401.981381)
				(end 364.313724 -401.997926)
			)
			(xy 364.518194 -402.202396) (xy 364.526068 -402.206206)
			(arc
				(start 364.556548 -402.222462)
				(mid 364.569024 -402.227758)
				(end 364.582456 -402.229574)
			)
			(xy 366.52835 -402.229574)
		)
		(stroke
			(width 0)
			(type solid)
		)
		(fill yes)
		(layer "F.Cu")
		(net "P0V9_CPU0_RT3_2A")
	)
	(gr_poly
		(pts
			(arc
				(start 153.325576 -387.860794)
				(mid 153.333951 -387.860099)
				(end 153.342086 -387.858)
			)
			(arc
				(start 153.574242 -387.778244)
				(mid 153.629601 -387.763721)
				(end 153.68651 -387.75767)
			)
			(xy 153.696416 -387.757416) (xy 153.71445 -387.749542)
			(arc
				(start 153.770584 -387.69163)
				(mid 153.781192 -387.675245)
				(end 153.784808 -387.65607)
			)
			(arc
				(start 153.784808 -387.121654)
				(mid 153.781159 -387.102493)
				(end 153.770584 -387.086094)
			)
			(xy 153.71445 -387.028182) (xy 153.696416 -387.020308)
			(arc
				(start 153.68651 -387.020054)
				(mid 153.641533 -387.015971)
				(end 153.597356 -387.006592)
			)
			(xy 153.287222 -386.921502) (xy 153.27376 -386.919724) (xy 152.930352 -386.919724) (xy 152.91181 -386.927344)
			(xy 152.909016 -386.929884)
			(arc
				(start 152.909016 -387.754876)
				(mid 152.912966 -387.774263)
				(end 152.924002 -387.79069)
			)
			(arc
				(start 152.97912 -387.845808)
				(mid 152.995654 -387.856919)
				(end 153.015188 -387.860794)
			)
		)
		(stroke
			(width 0)
			(type solid)
		)
		(fill yes)
		(layer "F.Cu")
		(net "P0V9_CPU1_RT_2D")
	)
	(gr_poly
		(pts
			(arc
				(start 282.209494 -412.097474)
				(mid 282.229017 -412.093573)
				(end 282.245562 -412.082488)
			)
			(arc
				(start 282.502102 -411.825948)
				(mid 282.513213 -411.809414)
				(end 282.517088 -411.78988)
			)
			(arc
				(start 282.517088 -410.269436)
				(mid 282.513187 -410.249913)
				(end 282.502102 -410.233368)
			)
			(arc
				(start 282.30322 -410.034486)
				(mid 282.286686 -410.023375)
				(end 282.267152 -410.0195)
			)
			(arc
				(start 281.106372 -410.0195)
				(mid 281.086849 -410.023401)
				(end 281.070304 -410.034486)
			)
			(xy 281.066748 -410.038296)
			(arc
				(start 281.066748 -410.14777)
				(mid 281.062798 -410.167157)
				(end 281.051762 -410.183584)
			)
			(arc
				(start 280.895806 -410.33954)
				(mid 280.884695 -410.356074)
				(end 280.88082 -410.375608)
			)
			(arc
				(start 280.88082 -411.986476)
				(mid 280.884721 -412.005999)
				(end 280.895806 -412.022544)
			)
			(arc
				(start 280.95575 -412.082488)
				(mid 280.972284 -412.093599)
				(end 280.991818 -412.097474)
			)
		)
		(stroke
			(width 0)
			(type solid)
		)
		(fill yes)
		(layer "F.Cu")
		(net "P3V3_AUX")
	)
	(gr_poly
		(pts
			(arc
				(start 342.225376 -396.242794)
				(mid 342.233751 -396.242099)
				(end 342.241886 -396.24)
			)
			(arc
				(start 342.474042 -396.160244)
				(mid 342.529401 -396.145721)
				(end 342.58631 -396.13967)
			)
			(xy 342.596216 -396.139416) (xy 342.61425 -396.131542)
			(arc
				(start 342.670384 -396.07363)
				(mid 342.680992 -396.057245)
				(end 342.684608 -396.03807)
			)
			(arc
				(start 342.684608 -395.503654)
				(mid 342.680959 -395.484493)
				(end 342.670384 -395.468094)
			)
			(xy 342.61425 -395.410182) (xy 342.596216 -395.402308)
			(arc
				(start 342.58631 -395.402054)
				(mid 342.541333 -395.397971)
				(end 342.497156 -395.388592)
			)
			(xy 342.187022 -395.303502) (xy 342.17356 -395.301724) (xy 341.830152 -395.301724) (xy 341.81161 -395.309344)
			(xy 341.808816 -395.311884)
			(arc
				(start 341.808816 -396.136876)
				(mid 341.812766 -396.156263)
				(end 341.823802 -396.17269)
			)
			(arc
				(start 341.87892 -396.227808)
				(mid 341.895454 -396.238919)
				(end 341.914988 -396.242794)
			)
		)
		(stroke
			(width 0)
			(type solid)
		)
		(fill yes)
		(layer "F.Cu")
		(net "P0V9_CPU0_RT_2D")
	)
	(gr_poly
		(pts
			(arc
				(start 376.797824 -396.242794)
				(mid 376.806199 -396.242099)
				(end 376.814334 -396.24)
			)
			(arc
				(start 377.04649 -396.160244)
				(mid 377.101849 -396.145721)
				(end 377.158758 -396.13967)
			)
			(xy 377.168664 -396.139416) (xy 377.186698 -396.131542)
			(arc
				(start 377.242832 -396.07363)
				(mid 377.25344 -396.057245)
				(end 377.257056 -396.03807)
			)
			(arc
				(start 377.257056 -395.503654)
				(mid 377.253407 -395.484493)
				(end 377.242832 -395.468094)
			)
			(xy 377.186698 -395.410182) (xy 377.168664 -395.402308)
			(arc
				(start 377.158758 -395.402054)
				(mid 377.113781 -395.397971)
				(end 377.069604 -395.388592)
			)
			(xy 376.75947 -395.303502) (xy 376.746008 -395.301724) (xy 376.4026 -395.301724) (xy 376.384058 -395.309344)
			(xy 376.381264 -395.311884)
			(arc
				(start 376.381264 -396.136876)
				(mid 376.385214 -396.156263)
				(end 376.39625 -396.17269)
			)
			(arc
				(start 376.451368 -396.227808)
				(mid 376.467902 -396.238919)
				(end 376.487436 -396.242794)
			)
		)
		(stroke
			(width 0)
			(type solid)
		)
		(fill yes)
		(layer "F.Cu")
		(net "P0V9_CPU0_RT_2D")
	)
	(gr_poly
		(pts
			(arc
				(start 409.325572 -396.242794)
				(mid 409.333947 -396.242099)
				(end 409.342082 -396.24)
			)
			(arc
				(start 409.574238 -396.160244)
				(mid 409.629597 -396.145721)
				(end 409.686506 -396.13967)
			)
			(xy 409.696412 -396.139416) (xy 409.714446 -396.131542)
			(arc
				(start 409.77058 -396.07363)
				(mid 409.781188 -396.057245)
				(end 409.784804 -396.03807)
			)
			(arc
				(start 409.784804 -395.503654)
				(mid 409.781155 -395.484493)
				(end 409.77058 -395.468094)
			)
			(xy 409.714446 -395.410182) (xy 409.696412 -395.402308)
			(arc
				(start 409.686506 -395.402054)
				(mid 409.641529 -395.397971)
				(end 409.597352 -395.388592)
			)
			(xy 409.287218 -395.303502) (xy 409.273756 -395.301724) (xy 408.930348 -395.301724) (xy 408.911806 -395.309344)
			(xy 408.909012 -395.311884)
			(arc
				(start 408.909012 -396.136876)
				(mid 408.912962 -396.156263)
				(end 408.923998 -396.17269)
			)
			(arc
				(start 408.979116 -396.227808)
				(mid 408.99565 -396.238919)
				(end 409.015184 -396.242794)
			)
		)
		(stroke
			(width 0)
			(type solid)
		)
		(fill yes)
		(layer "F.Cu")
		(net "P0V9_CPU0_RT_2D")
	)
	(gr_poly
		(pts
			(arc
				(start 75.974956 -393.767056)
				(mid 75.994479 -393.763155)
				(end 76.011024 -393.75207)
			)
			(arc
				(start 76.068174 -393.69492)
				(mid 76.079236 -393.678503)
				(end 76.08316 -393.659106)
			)
			(arc
				(start 76.08316 -391.420604)
				(mid 76.07921 -391.401217)
				(end 76.068174 -391.38479)
			)
			(arc
				(start 75.959208 -391.275824)
				(mid 75.942674 -391.264713)
				(end 75.92314 -391.260838)
			)
			(arc
				(start 74.458576 -391.260838)
				(mid 74.439189 -391.264788)
				(end 74.422762 -391.275824)
			)
			(arc
				(start 74.307446 -391.390886)
				(mid 74.291029 -391.401948)
				(end 74.271632 -391.405872)
			)
			(arc
				(start 73.825354 -391.405872)
				(mid 73.789433 -391.420751)
				(end 73.774554 -391.456672)
			)
			(arc
				(start 73.774554 -393.610084)
				(mid 73.778455 -393.629607)
				(end 73.78954 -393.646152)
			)
			(arc
				(start 73.895458 -393.75207)
				(mid 73.911992 -393.763181)
				(end 73.931526 -393.767056)
			)
		)
		(stroke
			(width 0)
			(type solid)
		)
		(fill yes)
		(layer "F.Cu")
		(net "P0V9_CPU1_RT1_2A")
	)
	(gr_poly
		(pts
			(xy 418.449252 -156.233368) (xy 418.739574 -155.943046) (xy 421.991536 -155.943046) (xy 422.28389 -155.650692)
			(xy 422.28389 -152.019) (xy 422.021508 -151.756364) (xy 408.118564 -151.756364) (xy 407.856944 -151.756364)
			(xy 406.853136 -150.752556)
			(arc
				(start 406.853136 -150.490936)
				(mid 406.842025 -150.474402)
				(end 406.83815 -150.454868)
			)
			(arc
				(start 406.83815 -143.49349)
				(mid 406.834249 -143.473967)
				(end 406.823164 -143.457422)
			)
			(arc
				(start 406.61463 -143.248888)
				(mid 406.598096 -143.237777)
				(end 406.578562 -143.233902)
			)
			(arc
				(start 402.222462 -143.233902)
				(mid 402.202939 -143.237803)
				(end 402.186394 -143.248888)
			)
			(arc
				(start 402.11375 -143.321532)
				(mid 402.102639 -143.338066)
				(end 402.098764 -143.3576)
			)
			(arc
				(start 402.098764 -156.335222)
				(mid 402.102665 -156.354745)
				(end 402.11375 -156.37129)
			)
			(arc
				(start 402.76526 -157.0228)
				(mid 402.781794 -157.033911)
				(end 402.801328 -157.037786)
			)
			(xy 417.644834 -157.037786)
		)
		(stroke
			(width 0)
			(type solid)
		)
		(fill yes)
		(layer "F.Cu")
		(net "P5V_AUX")
	)
	(gr_poly
		(pts
			(xy 76.169774 -24.5872) (xy 76.931774 -24.5872) (xy 77.093064 -24.42591) (xy 77.093064 -23.05431)
			(xy 77.027278 -22.988524) (xy 74.968862 -22.988524) (xy 74.714862 -22.734524) (xy 74.714862 -22.404324)
			(xy 74.918062 -22.201124) (xy 75.415902 -22.201124) (xy 75.525122 -22.091904) (xy 75.525122 -20.694904)
			(xy 75.654662 -20.565364) (xy 77.808582 -20.565364) (xy 78.128622 -20.565364) (xy 78.237842 -20.674584)
			(xy 78.237842 -20.994624) (xy 78.311502 -21.068284) (xy 78.395322 -21.068284) (xy 78.471522 -20.992084)
			(xy 78.471522 -20.372324) (xy 78.430882 -20.331684) (xy 77.790802 -20.331684) (xy 77.709522 -20.331684)
			(xy 77.031342 -19.653504) (xy 75.48499 -19.653504) (xy 75.347322 -19.515836) (xy 75.347322 -19.095466)
			(xy 75.221846 -18.96999) (xy 74.020172 -18.96999) (xy 73.800462 -19.1897) (xy 73.800462 -21.185124)
			(xy 73.800462 -23.826724) (xy 73.114662 -24.512524) (xy 70.473062 -24.512524) (xy 70.066662 -24.918924)
			(xy 70.066662 -25.401524) (xy 70.549262 -25.884124) (xy 74.87285 -25.884124)
		)
		(stroke
			(width 0)
			(type solid)
		)
		(fill yes)
		(layer "F.Cu")
		(net "GND")
	)
	(gr_poly
		(pts
			(xy 331.979016 -402.216366)
			(arc
				(start 331.985874 -402.204682)
				(mid 332.007382 -402.173259)
				(end 332.03261 -402.144738)
			)
			(arc
				(start 332.067916 -402.109686)
				(mid 332.07889 -402.093123)
				(end 332.082648 -402.073618)
			)
			(arc
				(start 332.082648 -399.818352)
				(mid 332.078815 -399.798995)
				(end 332.067916 -399.782538)
			)
			(arc
				(start 332.011782 -399.726404)
				(mid 331.995248 -399.715293)
				(end 331.975714 -399.711418)
			)
			(arc
				(start 330.496164 -399.711418)
				(mid 330.476777 -399.715368)
				(end 330.46035 -399.726404)
			)
			(arc
				(start 330.369926 -399.816574)
				(mid 330.353509 -399.827636)
				(end 330.334112 -399.83156)
			)
			(xy 329.751436 -399.83156) (xy 329.73264 -399.83918) (xy 329.72629 -399.84553)
			(arc
				(start 329.72629 -401.961858)
				(mid 329.730191 -401.981381)
				(end 329.741276 -401.997926)
			)
			(xy 329.945746 -402.202396) (xy 329.95362 -402.206206)
			(arc
				(start 329.9841 -402.222462)
				(mid 329.996576 -402.227758)
				(end 330.010008 -402.229574)
			)
			(xy 331.955902 -402.229574)
		)
		(stroke
			(width 0)
			(type solid)
		)
		(fill yes)
		(layer "F.Cu")
		(net "P0V9_CPU0_RT1_2A")
	)
	(gr_poly
		(pts
			(xy 399.079212 -402.216366)
			(arc
				(start 399.08607 -402.204682)
				(mid 399.107578 -402.173259)
				(end 399.132806 -402.144738)
			)
			(arc
				(start 399.168112 -402.109686)
				(mid 399.179086 -402.093123)
				(end 399.182844 -402.073618)
			)
			(arc
				(start 399.182844 -399.818352)
				(mid 399.179011 -399.798995)
				(end 399.168112 -399.782538)
			)
			(arc
				(start 399.111978 -399.726404)
				(mid 399.095444 -399.715293)
				(end 399.07591 -399.711418)
			)
			(arc
				(start 397.596106 -399.711418)
				(mid 397.576719 -399.715368)
				(end 397.560292 -399.726404)
			)
			(arc
				(start 397.469868 -399.816574)
				(mid 397.453451 -399.827636)
				(end 397.434054 -399.83156)
			)
			(xy 396.851632 -399.83156) (xy 396.832836 -399.83918) (xy 396.826486 -399.84553)
			(arc
				(start 396.826486 -401.961858)
				(mid 396.830387 -401.981381)
				(end 396.841472 -401.997926)
			)
			(xy 397.045942 -402.202396) (xy 397.053816 -402.206206)
			(arc
				(start 397.084296 -402.222462)
				(mid 397.096772 -402.227758)
				(end 397.110204 -402.229574)
			)
			(xy 399.056098 -402.229574)
		)
		(stroke
			(width 0)
			(type solid)
		)
		(fill yes)
		(layer "F.Cu")
		(net "P0V9_CPU0_RT2_2A")
	)
	(gr_poly
		(pts
			(arc
				(start 38.355778 -113.8555)
				(mid 38.375301 -113.851599)
				(end 38.391846 -113.840514)
			)
			(arc
				(start 38.430454 -113.801906)
				(mid 38.441565 -113.785372)
				(end 38.44544 -113.765838)
			)
			(arc
				(start 38.44544 -112.035082)
				(mid 38.449341 -112.015559)
				(end 38.460426 -111.999014)
			)
			(arc
				(start 38.763194 -111.696246)
				(mid 38.774305 -111.679712)
				(end 38.77818 -111.660178)
			)
			(arc
				(start 38.77818 -111.130842)
				(mid 38.774279 -111.111319)
				(end 38.763194 -111.094774)
			)
			(arc
				(start 38.470586 -110.802166)
				(mid 38.454052 -110.791055)
				(end 38.434518 -110.78718)
			)
			(arc
				(start 34.905442 -110.78718)
				(mid 34.885919 -110.791081)
				(end 34.869374 -110.802166)
			)
			(arc
				(start 34.726626 -110.944914)
				(mid 34.715515 -110.961448)
				(end 34.71164 -110.980982)
			)
			(arc
				(start 34.71164 -113.628678)
				(mid 34.715541 -113.648201)
				(end 34.726626 -113.664746)
			)
			(arc
				(start 34.902394 -113.840514)
				(mid 34.918928 -113.851625)
				(end 34.938462 -113.8555)
			)
		)
		(stroke
			(width 0)
			(type solid)
		)
		(fill yes)
		(layer "F.Cu")
		(net "GND")
	)
	(gr_poly
		(pts
			(arc
				(start 45.157898 -113.71834)
				(mid 45.177421 -113.714439)
				(end 45.193966 -113.703354)
			)
			(arc
				(start 45.232574 -113.664746)
				(mid 45.243685 -113.648212)
				(end 45.24756 -113.628678)
			)
			(arc
				(start 45.24756 -111.897922)
				(mid 45.251461 -111.878399)
				(end 45.262546 -111.861854)
			)
			(arc
				(start 45.565314 -111.559086)
				(mid 45.576425 -111.542552)
				(end 45.5803 -111.523018)
			)
			(arc
				(start 45.5803 -110.993682)
				(mid 45.576399 -110.974159)
				(end 45.565314 -110.957614)
			)
			(arc
				(start 45.272706 -110.665006)
				(mid 45.256172 -110.653895)
				(end 45.236638 -110.65002)
			)
			(arc
				(start 41.707562 -110.65002)
				(mid 41.688039 -110.653921)
				(end 41.671494 -110.665006)
			)
			(arc
				(start 41.528746 -110.807754)
				(mid 41.517635 -110.824288)
				(end 41.51376 -110.843822)
			)
			(arc
				(start 41.51376 -113.491518)
				(mid 41.517661 -113.511041)
				(end 41.528746 -113.527586)
			)
			(arc
				(start 41.704514 -113.703354)
				(mid 41.721048 -113.714465)
				(end 41.740582 -113.71834)
			)
		)
		(stroke
			(width 0)
			(type solid)
		)
		(fill yes)
		(layer "F.Cu")
		(net "GND")
	)
	(gr_poly
		(pts
			(arc
				(start 45.610018 -108.11002)
				(mid 45.629541 -108.106119)
				(end 45.646086 -108.095034)
			)
			(arc
				(start 45.788834 -107.952286)
				(mid 45.799945 -107.935752)
				(end 45.80382 -107.916218)
			)
			(arc
				(start 45.80382 -104.488742)
				(mid 45.799919 -104.469219)
				(end 45.788834 -104.452674)
			)
			(arc
				(start 45.727366 -104.391206)
				(mid 45.710832 -104.380095)
				(end 45.691298 -104.37622)
			)
			(arc
				(start 44.953682 -104.37622)
				(mid 44.934159 -104.380121)
				(end 44.917614 -104.391206)
			)
			(arc
				(start 44.863766 -104.445054)
				(mid 44.852655 -104.461588)
				(end 44.84878 -104.481122)
			)
			(arc
				(start 44.84878 -106.171238)
				(mid 44.844879 -106.190761)
				(end 44.833794 -106.207306)
			)
			(arc
				(start 44.691046 -106.350054)
				(mid 44.679935 -106.366588)
				(end 44.67606 -106.386122)
			)
			(arc
				(start 44.67606 -108.033058)
				(mid 44.679961 -108.052581)
				(end 44.691046 -108.069126)
			)
			(arc
				(start 44.716954 -108.095034)
				(mid 44.733488 -108.106145)
				(end 44.753022 -108.11002)
			)
		)
		(stroke
			(width 0)
			(type solid)
		)
		(fill yes)
		(layer "F.Cu")
		(net "P3V3_AUX_DSC_G1")
	)
	(gr_poly
		(pts
			(arc
				(start 84.939632 -359.911396)
				(mid 84.959155 -359.907495)
				(end 84.9757 -359.89641)
			)
			(arc
				(start 85.877146 -358.994964)
				(mid 85.888257 -358.97843)
				(end 85.892132 -358.958896)
			)
			(arc
				(start 85.892132 -352.24974)
				(mid 85.888231 -352.230217)
				(end 85.877146 -352.213672)
			)
			(arc
				(start 85.73262 -352.069146)
				(mid 85.716086 -352.058035)
				(end 85.696552 -352.05416)
			)
			(arc
				(start 81.908904 -352.05416)
				(mid 81.889381 -352.058061)
				(end 81.872836 -352.069146)
			)
			(arc
				(start 79.27213 -354.669852)
				(mid 79.255596 -354.680963)
				(end 79.236062 -354.684838)
			)
			(arc
				(start 72.992488 -354.684838)
				(mid 72.972965 -354.688739)
				(end 72.95642 -354.699824)
			)
			(arc
				(start 72.776588 -354.879656)
				(mid 72.765477 -354.89619)
				(end 72.761602 -354.915724)
			)
			(arc
				(start 72.761602 -359.657396)
				(mid 72.765503 -359.676919)
				(end 72.776588 -359.693464)
			)
			(arc
				(start 72.979534 -359.89641)
				(mid 72.996068 -359.907521)
				(end 73.015602 -359.911396)
			)
		)
		(stroke
			(width 0)
			(type solid)
		)
		(fill yes)
		(layer "F.Cu")
		(net "GND")
	)
	(gr_poly
		(pts
			(arc
				(start 182.339996 -394.597128)
				(mid 182.359519 -394.593227)
				(end 182.376064 -394.582142)
			)
			(arc
				(start 182.45836 -394.499846)
				(mid 182.469471 -394.483312)
				(end 182.473346 -394.463778)
			)
			(arc
				(start 182.473346 -388.994396)
				(mid 182.469445 -388.974873)
				(end 182.45836 -388.958328)
			)
			(arc
				(start 182.324502 -388.82447)
				(mid 182.307968 -388.813359)
				(end 182.288434 -388.809484)
			)
			(arc
				(start 180.579776 -388.809484)
				(mid 180.560253 -388.813385)
				(end 180.543708 -388.82447)
			)
			(arc
				(start 180.495956 -388.872222)
				(mid 180.484845 -388.888756)
				(end 180.48097 -388.90829)
			)
			(xy 180.48097 -390.072372)
			(arc
				(start 180.483764 -390.0805)
				(mid 180.500089 -390.143071)
				(end 180.505608 -390.2075)
			)
			(arc
				(start 180.505608 -390.2075)
				(mid 180.500085 -390.271928)
				(end 180.483764 -390.3345)
			)
			(xy 180.48097 -390.342628)
			(arc
				(start 180.48097 -394.498322)
				(mid 180.484871 -394.517845)
				(end 180.495956 -394.53439)
			)
			(arc
				(start 180.543708 -394.582142)
				(mid 180.560242 -394.593253)
				(end 180.579776 -394.597128)
			)
		)
		(stroke
			(width 0)
			(type solid)
		)
		(fill yes)
		(layer "F.Cu")
		(net "GND")
	)
	(gr_poly
		(pts
			(arc
				(start 437.212232 -410.152088)
				(mid 437.231755 -410.148187)
				(end 437.2483 -410.137102)
			)
			(arc
				(start 437.33339 -410.052012)
				(mid 437.344501 -410.035478)
				(end 437.348376 -410.015944)
			)
			(arc
				(start 437.348376 -405.020526)
				(mid 437.344475 -405.001003)
				(end 437.33339 -404.984458)
			)
			(arc
				(start 437.21782 -404.868888)
				(mid 437.201286 -404.857777)
				(end 437.181752 -404.853902)
			)
			(arc
				(start 436.25008 -404.853902)
				(mid 436.230557 -404.857803)
				(end 436.214012 -404.868888)
			)
			(arc
				(start 436.157878 -404.925022)
				(mid 436.146767 -404.941556)
				(end 436.142892 -404.96109)
			)
			(xy 436.142892 -405.551132)
			(arc
				(start 436.145686 -405.55926)
				(mid 436.162011 -405.621831)
				(end 436.16753 -405.68626)
			)
			(arc
				(start 436.16753 -405.68626)
				(mid 436.162007 -405.750688)
				(end 436.145686 -405.81326)
			)
			(xy 436.142892 -405.821388)
			(arc
				(start 436.142892 -410.053282)
				(mid 436.146793 -410.072805)
				(end 436.157878 -410.08935)
			)
			(arc
				(start 436.20563 -410.137102)
				(mid 436.222164 -410.148213)
				(end 436.241698 -410.152088)
			)
		)
		(stroke
			(width 0)
			(type solid)
		)
		(fill yes)
		(layer "F.Cu")
		(net "GND")
	)
	(gr_poly
		(pts
			(xy 446.556384 -24.944832) (xy 449.398644 -24.944832) (xy 449.489576 -24.8539) (xy 449.489576 -23.996142)
			(xy 449.489576 -23.335742) (xy 449.438776 -23.284942) (xy 447.101976 -23.284942) (xy 446.847976 -23.030942)
			(xy 446.847976 -22.700742) (xy 447.105278 -22.44344) (xy 447.603118 -22.44344) (xy 447.658236 -22.388322)
			(xy 447.658236 -20.991322) (xy 447.658236 -20.870164) (xy 447.75882 -20.76958) (xy 448.420998 -20.76958)
			(xy 448.5132 -20.861782) (xy 449.941696 -20.861782) (xy 450.261736 -20.861782) (xy 450.370956 -20.971002)
			(xy 450.370956 -21.291042) (xy 450.444616 -21.364702) (xy 450.528436 -21.364702) (xy 450.604636 -21.288502)
			(xy 450.604636 -20.668742) (xy 450.563996 -20.628102) (xy 449.923916 -20.628102) (xy 449.842636 -20.628102)
			(xy 449.164456 -19.949922) (xy 447.618104 -19.949922) (xy 447.480436 -19.812254) (xy 447.480436 -19.187922)
			(xy 447.429636 -19.137122) (xy 446.464436 -19.137122) (xy 446.017396 -19.137122) (xy 445.933576 -19.220942)
			(xy 445.933576 -24.070564) (xy 444.73368 -25.27046) (xy 444.73368 -25.70734) (xy 444.783972 -25.757632)
			(xy 445.743584 -25.757632)
		)
		(stroke
			(width 0)
			(type solid)
		)
		(fill yes)
		(layer "F.Cu")
		(net "GND")
	)
	(gr_poly
		(pts
			(arc
				(start 52.49799 -387.860794)
				(mid 52.506365 -387.860099)
				(end 52.5145 -387.858)
			)
			(arc
				(start 52.746656 -387.778244)
				(mid 52.803143 -387.763554)
				(end 52.86121 -387.75767)
			)
			(xy 52.871116 -387.757416) (xy 52.88915 -387.749542)
			(arc
				(start 52.945792 -387.69163)
				(mid 52.9564 -387.675245)
				(end 52.960016 -387.65607)
			)
			(arc
				(start 52.960016 -387.121654)
				(mid 52.956367 -387.102493)
				(end 52.945792 -387.086094)
			)
			(xy 52.88915 -387.028182) (xy 52.871116 -387.020308)
			(arc
				(start 52.86121 -387.020054)
				(mid 52.81508 -387.016106)
				(end 52.76977 -387.006592)
			)
			(xy 52.459382 -386.921502) (xy 52.44592 -386.919724)
			(arc
				(start 52.093114 -386.919724)
				(mid 52.073591 -386.923625)
				(end 52.057046 -386.93471)
			)
			(arc
				(start 52.01539 -386.976366)
				(mid 52.004279 -386.9929)
				(end 52.000404 -387.012434)
			)
			(arc
				(start 52.000404 -387.756908)
				(mid 52.004305 -387.776431)
				(end 52.01539 -387.792976)
			)
			(arc
				(start 52.068222 -387.845808)
				(mid 52.084756 -387.856919)
				(end 52.10429 -387.860794)
			)
		)
		(stroke
			(width 0)
			(type solid)
		)
		(fill yes)
		(layer "F.Cu")
		(net "P0V9_CPU1_RT0_2A_2D")
	)
	(gr_poly
		(pts
			(arc
				(start 53.697886 -387.860794)
				(mid 53.706261 -387.860099)
				(end 53.714396 -387.858)
			)
			(arc
				(start 53.946552 -387.778244)
				(mid 54.001911 -387.763721)
				(end 54.05882 -387.75767)
			)
			(xy 54.068726 -387.757416) (xy 54.08676 -387.749542)
			(arc
				(start 54.142894 -387.69163)
				(mid 54.153636 -387.675273)
				(end 54.157372 -387.65607)
			)
			(arc
				(start 54.157372 -387.121654)
				(mid 54.153607 -387.102463)
				(end 54.142894 -387.086094)
			)
			(xy 54.08676 -387.028182) (xy 54.068726 -387.020308)
			(arc
				(start 54.05882 -387.020054)
				(mid 54.013843 -387.015971)
				(end 53.969666 -387.006592)
			)
			(xy 53.659532 -386.921502) (xy 53.64607 -386.919724)
			(arc
				(start 53.312822 -386.919724)
				(mid 53.293299 -386.923625)
				(end 53.276754 -386.93471)
			)
			(arc
				(start 53.22951 -386.981954)
				(mid 53.218399 -386.998488)
				(end 53.214524 -387.018022)
			)
			(arc
				(start 53.214524 -387.68782)
				(mid 53.218425 -387.707343)
				(end 53.22951 -387.723888)
			)
			(arc
				(start 53.35143 -387.845808)
				(mid 53.367964 -387.856919)
				(end 53.387498 -387.860794)
			)
		)
		(stroke
			(width 0)
			(type solid)
		)
		(fill yes)
		(layer "F.Cu")
		(net "P0V9_CPU1_RT_2D")
	)
	(gr_poly
		(pts
			(arc
				(start 85.025738 -387.860794)
				(mid 85.034113 -387.860099)
				(end 85.042248 -387.858)
			)
			(arc
				(start 85.274404 -387.778244)
				(mid 85.330891 -387.763554)
				(end 85.388958 -387.75767)
			)
			(xy 85.398864 -387.757416) (xy 85.416898 -387.749542)
			(arc
				(start 85.47354 -387.69163)
				(mid 85.484148 -387.675245)
				(end 85.487764 -387.65607)
			)
			(arc
				(start 85.487764 -387.121654)
				(mid 85.484115 -387.102493)
				(end 85.47354 -387.086094)
			)
			(xy 85.416898 -387.028182) (xy 85.398864 -387.020308)
			(arc
				(start 85.388958 -387.020054)
				(mid 85.342828 -387.016106)
				(end 85.297518 -387.006592)
			)
			(xy 84.98713 -386.921502) (xy 84.973668 -386.919724)
			(arc
				(start 84.620862 -386.919724)
				(mid 84.601339 -386.923625)
				(end 84.584794 -386.93471)
			)
			(arc
				(start 84.543138 -386.976366)
				(mid 84.532027 -386.9929)
				(end 84.528152 -387.012434)
			)
			(arc
				(start 84.528152 -387.756908)
				(mid 84.532053 -387.776431)
				(end 84.543138 -387.792976)
			)
			(arc
				(start 84.59597 -387.845808)
				(mid 84.612504 -387.856919)
				(end 84.632038 -387.860794)
			)
		)
		(stroke
			(width 0)
			(type solid)
		)
		(fill yes)
		(layer "F.Cu")
		(net "P0V9_CPU1_RT1_2A_2D")
	)
	(gr_poly
		(pts
			(arc
				(start 86.225634 -387.860794)
				(mid 86.234009 -387.860099)
				(end 86.242144 -387.858)
			)
			(arc
				(start 86.4743 -387.778244)
				(mid 86.529659 -387.763721)
				(end 86.586568 -387.75767)
			)
			(xy 86.596474 -387.757416) (xy 86.614508 -387.749542)
			(arc
				(start 86.670642 -387.69163)
				(mid 86.681384 -387.675273)
				(end 86.68512 -387.65607)
			)
			(arc
				(start 86.68512 -387.121654)
				(mid 86.681355 -387.102463)
				(end 86.670642 -387.086094)
			)
			(xy 86.614508 -387.028182) (xy 86.596474 -387.020308)
			(arc
				(start 86.586568 -387.020054)
				(mid 86.541591 -387.015971)
				(end 86.497414 -387.006592)
			)
			(xy 86.18728 -386.921502) (xy 86.173818 -386.919724)
			(arc
				(start 85.84057 -386.919724)
				(mid 85.821047 -386.923625)
				(end 85.804502 -386.93471)
			)
			(arc
				(start 85.757258 -386.981954)
				(mid 85.746147 -386.998488)
				(end 85.742272 -387.018022)
			)
			(arc
				(start 85.742272 -387.68782)
				(mid 85.746173 -387.707343)
				(end 85.757258 -387.723888)
			)
			(arc
				(start 85.879178 -387.845808)
				(mid 85.895712 -387.856919)
				(end 85.915246 -387.860794)
			)
		)
		(stroke
			(width 0)
			(type solid)
		)
		(fill yes)
		(layer "F.Cu")
		(net "P0V9_CPU1_RT_2D")
	)
	(gr_poly
		(pts
			(arc
				(start 119.597932 -387.860794)
				(mid 119.606307 -387.860099)
				(end 119.614442 -387.858)
			)
			(arc
				(start 119.846598 -387.778244)
				(mid 119.903085 -387.763554)
				(end 119.961152 -387.75767)
			)
			(xy 119.971058 -387.757416) (xy 119.989092 -387.749542)
			(arc
				(start 120.045734 -387.69163)
				(mid 120.056476 -387.675273)
				(end 120.060212 -387.65607)
			)
			(arc
				(start 120.060212 -387.121654)
				(mid 120.056447 -387.102463)
				(end 120.045734 -387.086094)
			)
			(xy 119.989092 -387.028182) (xy 119.971058 -387.020308)
			(arc
				(start 119.961152 -387.020054)
				(mid 119.915022 -387.016106)
				(end 119.869712 -387.006592)
			)
			(xy 119.559324 -386.921502) (xy 119.545862 -386.919724)
			(arc
				(start 119.193056 -386.919724)
				(mid 119.173533 -386.923625)
				(end 119.156988 -386.93471)
			)
			(arc
				(start 119.115332 -386.976366)
				(mid 119.104221 -386.9929)
				(end 119.100346 -387.012434)
			)
			(arc
				(start 119.100346 -387.756908)
				(mid 119.104247 -387.776431)
				(end 119.115332 -387.792976)
			)
			(arc
				(start 119.168164 -387.845808)
				(mid 119.184698 -387.856919)
				(end 119.204232 -387.860794)
			)
		)
		(stroke
			(width 0)
			(type solid)
		)
		(fill yes)
		(layer "F.Cu")
		(net "P0V9_CPU1_RT3_2A_2D")
	)
	(gr_poly
		(pts
			(arc
				(start 120.797828 -387.860794)
				(mid 120.806203 -387.860099)
				(end 120.814338 -387.858)
			)
			(arc
				(start 121.046494 -387.778244)
				(mid 121.101853 -387.763721)
				(end 121.158762 -387.75767)
			)
			(xy 121.168668 -387.757416) (xy 121.186702 -387.749542)
			(arc
				(start 121.242836 -387.69163)
				(mid 121.253444 -387.675245)
				(end 121.25706 -387.65607)
			)
			(arc
				(start 121.25706 -387.121654)
				(mid 121.253411 -387.102493)
				(end 121.242836 -387.086094)
			)
			(xy 121.186702 -387.028182) (xy 121.168668 -387.020308)
			(arc
				(start 121.158762 -387.020054)
				(mid 121.113785 -387.015971)
				(end 121.069608 -387.006592)
			)
			(xy 120.759474 -386.921502) (xy 120.746012 -386.919724)
			(arc
				(start 120.412764 -386.919724)
				(mid 120.393241 -386.923625)
				(end 120.376696 -386.93471)
			)
			(arc
				(start 120.329452 -386.981954)
				(mid 120.318341 -386.998488)
				(end 120.314466 -387.018022)
			)
			(arc
				(start 120.314466 -387.68782)
				(mid 120.318367 -387.707343)
				(end 120.329452 -387.723888)
			)
			(arc
				(start 120.451372 -387.845808)
				(mid 120.467906 -387.856919)
				(end 120.48744 -387.860794)
			)
		)
		(stroke
			(width 0)
			(type solid)
		)
		(fill yes)
		(layer "F.Cu")
		(net "P0V9_CPU1_RT_2D")
	)
	(gr_poly
		(pts
			(arc
				(start 284.021276 -414.483042)
				(mid 284.040799 -414.479141)
				(end 284.057344 -414.468056)
			)
			(arc
				(start 284.088332 -414.437068)
				(mid 284.099443 -414.420534)
				(end 284.103318 -414.401)
			)
			(arc
				(start 284.103318 -412.927546)
				(mid 284.099417 -412.908023)
				(end 284.088332 -412.891478)
			)
			(arc
				(start 283.973524 -412.77667)
				(mid 283.95699 -412.765559)
				(end 283.937456 -412.761684)
			)
			(arc
				(start 280.923492 -412.761684)
				(mid 280.887571 -412.776563)
				(end 280.872692 -412.812484)
			)
			(arc
				(start 280.872692 -414.022286)
				(mid 280.875963 -414.040221)
				(end 280.885392 -414.055814)
			)
			(arc
				(start 280.885392 -414.055814)
				(mid 280.905637 -414.079777)
				(end 280.924508 -414.104836)
			)
			(xy 280.930096 -414.111694)
			(arc
				(start 281.091386 -414.272984)
				(mid 281.10792 -414.284095)
				(end 281.127454 -414.28797)
			)
			(arc
				(start 282.7401 -414.28797)
				(mid 282.759623 -414.291871)
				(end 282.776168 -414.302956)
			)
			(arc
				(start 282.941268 -414.468056)
				(mid 282.957802 -414.479167)
				(end 282.977336 -414.483042)
			)
		)
		(stroke
			(width 0)
			(type solid)
		)
		(fill yes)
		(layer "F.Cu")
		(net "P3V3_9ZXL045_P0_VDD")
	)
	(gr_poly
		(pts
			(arc
				(start 308.497732 -396.242794)
				(mid 308.506107 -396.242099)
				(end 308.514242 -396.24)
			)
			(arc
				(start 308.746398 -396.160244)
				(mid 308.802885 -396.145554)
				(end 308.860952 -396.13967)
			)
			(xy 308.870858 -396.139416) (xy 308.888892 -396.131542)
			(arc
				(start 308.945534 -396.07363)
				(mid 308.956276 -396.057273)
				(end 308.960012 -396.03807)
			)
			(arc
				(start 308.960012 -395.503654)
				(mid 308.956247 -395.484463)
				(end 308.945534 -395.468094)
			)
			(xy 308.888892 -395.410182) (xy 308.870858 -395.402308)
			(arc
				(start 308.860952 -395.402054)
				(mid 308.814822 -395.398106)
				(end 308.769512 -395.388592)
			)
			(xy 308.459124 -395.303502) (xy 308.445662 -395.301724)
			(arc
				(start 308.092856 -395.301724)
				(mid 308.073333 -395.305625)
				(end 308.056788 -395.31671)
			)
			(arc
				(start 308.015132 -395.358366)
				(mid 308.004021 -395.3749)
				(end 308.000146 -395.394434)
			)
			(arc
				(start 308.000146 -396.138908)
				(mid 308.004047 -396.158431)
				(end 308.015132 -396.174976)
			)
			(arc
				(start 308.067964 -396.227808)
				(mid 308.084498 -396.238919)
				(end 308.104032 -396.242794)
			)
		)
		(stroke
			(width 0)
			(type solid)
		)
		(fill yes)
		(layer "F.Cu")
		(net "P0V9_CPU0_RT0_2A_2D")
	)
	(gr_poly
		(pts
			(arc
				(start 309.697628 -396.242794)
				(mid 309.706003 -396.242099)
				(end 309.714138 -396.24)
			)
			(arc
				(start 309.946294 -396.160244)
				(mid 310.001653 -396.145721)
				(end 310.058562 -396.13967)
			)
			(xy 310.068468 -396.139416) (xy 310.086502 -396.131542)
			(arc
				(start 310.142636 -396.07363)
				(mid 310.153244 -396.057245)
				(end 310.15686 -396.03807)
			)
			(arc
				(start 310.15686 -395.503654)
				(mid 310.153211 -395.484493)
				(end 310.142636 -395.468094)
			)
			(xy 310.086502 -395.410182) (xy 310.068468 -395.402308)
			(arc
				(start 310.058562 -395.402054)
				(mid 310.013585 -395.397971)
				(end 309.969408 -395.388592)
			)
			(xy 309.659274 -395.303502) (xy 309.645812 -395.301724)
			(arc
				(start 309.312564 -395.301724)
				(mid 309.293041 -395.305625)
				(end 309.276496 -395.31671)
			)
			(arc
				(start 309.229252 -395.363954)
				(mid 309.218141 -395.380488)
				(end 309.214266 -395.400022)
			)
			(arc
				(start 309.214266 -396.06982)
				(mid 309.218167 -396.089343)
				(end 309.229252 -396.105888)
			)
			(arc
				(start 309.351172 -396.227808)
				(mid 309.367706 -396.238919)
				(end 309.38724 -396.242794)
			)
		)
		(stroke
			(width 0)
			(type solid)
		)
		(fill yes)
		(layer "F.Cu")
		(net "P0V9_CPU0_RT_2D")
	)
	(gr_poly
		(pts
			(arc
				(start 93.330776 -387.860794)
				(mid 93.366697 -387.845915)
				(end 93.381576 -387.809994)
			)
			(xy 93.381576 -386.939028) (xy 93.373702 -386.920486) (xy 93.37294 -386.919724)
			(arc
				(start 92.945204 -386.919724)
				(mid 92.936167 -386.92058)
				(end 92.927424 -386.923026)
			)
			(arc
				(start 92.73159 -386.996178)
				(mid 92.665996 -387.014225)
				(end 92.59824 -387.020308)
			)
			(arc
				(start 92.59824 -387.020308)
				(mid 92.562907 -387.018645)
				(end 92.527882 -387.013704)
			)
			(xy 92.515436 -387.011164) (xy 92.491306 -387.018784)
			(arc
				(start 92.459302 -387.050788)
				(mid 92.44824 -387.067205)
				(end 92.444316 -387.086602)
			)
			(arc
				(start 92.444316 -387.658864)
				(mid 92.448753 -387.679626)
				(end 92.461334 -387.69671)
			)
			(xy 92.52585 -387.754368) (xy 92.54617 -387.760972)
			(arc
				(start 92.557092 -387.759702)
				(mid 92.577635 -387.758006)
				(end 92.59824 -387.757416)
			)
			(arc
				(start 92.59824 -387.757416)
				(mid 92.652384 -387.761351)
				(end 92.705428 -387.77291)
			)
			(arc
				(start 92.998544 -387.858762)
				(mid 93.005584 -387.860283)
				(end 93.012768 -387.860794)
			)
		)
		(stroke
			(width 0)
			(type solid)
		)
		(fill yes)
		(layer "F.Cu")
		(net "P0V9_CPU1_RT1_2A_2D")
	)
	(gr_poly
		(pts
			(xy 187.740036 -29.486606) (xy 187.740036 -28.648152) (xy 187.740036 -27.987752) (xy 187.689236 -27.936952)
			(xy 185.352436 -27.936952) (xy 185.098436 -27.682952) (xy 185.098436 -27.352752) (xy 185.301636 -27.149552)
			(xy 185.799476 -27.149552) (xy 185.908696 -27.040332) (xy 185.908696 -25.643332) (xy 186.038236 -25.513792)
			(xy 188.192156 -25.513792) (xy 188.512196 -25.513792) (xy 188.621416 -25.623012) (xy 188.621416 -25.943052)
			(xy 188.695076 -26.016712) (xy 188.778896 -26.016712) (xy 188.855096 -25.940512) (xy 188.855096 -25.320752)
			(xy 188.814456 -25.280112) (xy 188.174376 -25.280112) (xy 188.093096 -25.280112) (xy 187.414916 -24.601932)
			(xy 185.868564 -24.601932) (xy 185.730896 -24.464264) (xy 185.730896 -23.839932) (xy 185.680096 -23.789132)
			(xy 185.21172 -23.789132) (xy 185.07964 -23.921212) (xy 185.07964 -24.372316) (xy 185.075068 -24.376888)
			(xy 185.075068 -24.652732) (xy 184.184036 -25.543764) (xy 184.184036 -26.133552) (xy 184.184036 -28.618688)
			(xy 184.190894 -28.618688) (xy 184.383934 -28.811728) (xy 186.400694 -28.811728) (xy 186.624214 -29.035248)
			(xy 186.624214 -29.383228) (xy 186.911234 -29.670248) (xy 187.556394 -29.670248)
		)
		(stroke
			(width 0)
			(type solid)
		)
		(fill yes)
		(layer "F.Cu")
		(net "GND")
	)
	(gr_poly
		(pts
			(arc
				(start 316.802516 -396.242794)
				(mid 316.838437 -396.227915)
				(end 316.853316 -396.191994)
			)
			(xy 316.853316 -395.321028) (xy 316.845696 -395.302486) (xy 316.844934 -395.301724)
			(arc
				(start 316.417198 -395.301724)
				(mid 316.408161 -395.30258)
				(end 316.399418 -395.305026)
			)
			(arc
				(start 316.203584 -395.378178)
				(mid 316.13799 -395.396225)
				(end 316.070234 -395.402308)
			)
			(arc
				(start 316.070234 -395.402308)
				(mid 316.034901 -395.400645)
				(end 315.999876 -395.395704)
			)
			(xy 315.98743 -395.393164) (xy 315.9633 -395.400784)
			(arc
				(start 315.925708 -395.438376)
				(mid 315.914597 -395.45491)
				(end 315.910722 -395.474444)
			)
			(arc
				(start 315.910722 -396.041372)
				(mid 315.915106 -396.062273)
				(end 315.92774 -396.079472)
			)
			(xy 315.992764 -396.13713) (xy 316.013592 -396.14348)
			(arc
				(start 316.024514 -396.14221)
				(mid 316.047332 -396.140133)
				(end 316.070234 -396.139416)
			)
			(arc
				(start 316.070234 -396.139416)
				(mid 316.124378 -396.143351)
				(end 316.177422 -396.15491)
			)
			(arc
				(start 316.470538 -396.240762)
				(mid 316.477578 -396.242283)
				(end 316.484762 -396.242794)
			)
		)
		(stroke
			(width 0)
			(type solid)
		)
		(fill yes)
		(layer "F.Cu")
		(net "P0V9_CPU0_RT0_2A_2D")
	)
	(gr_poly
		(pts
			(arc
				(start 383.902712 -396.242794)
				(mid 383.938633 -396.227915)
				(end 383.953512 -396.191994)
			)
			(xy 383.953512 -395.321028) (xy 383.945892 -395.302486) (xy 383.94513 -395.301724)
			(arc
				(start 383.517394 -395.301724)
				(mid 383.508357 -395.30258)
				(end 383.499614 -395.305026)
			)
			(arc
				(start 383.30378 -395.378178)
				(mid 383.238186 -395.396225)
				(end 383.17043 -395.402308)
			)
			(arc
				(start 383.17043 -395.402308)
				(mid 383.135097 -395.400645)
				(end 383.100072 -395.395704)
			)
			(xy 383.087626 -395.393164) (xy 383.063496 -395.400784)
			(arc
				(start 383.025904 -395.438376)
				(mid 383.014793 -395.45491)
				(end 383.010918 -395.474444)
			)
			(arc
				(start 383.010918 -396.041372)
				(mid 383.015302 -396.062273)
				(end 383.027936 -396.079472)
			)
			(xy 383.09296 -396.13713) (xy 383.113788 -396.14348)
			(arc
				(start 383.12471 -396.14221)
				(mid 383.147528 -396.140133)
				(end 383.17043 -396.139416)
			)
			(arc
				(start 383.17043 -396.139416)
				(mid 383.224574 -396.143351)
				(end 383.277618 -396.15491)
			)
			(arc
				(start 383.570734 -396.240762)
				(mid 383.577774 -396.242283)
				(end 383.584958 -396.242794)
			)
		)
		(stroke
			(width 0)
			(type solid)
		)
		(fill yes)
		(layer "F.Cu")
		(net "P0V9_CPU0_RT3_2A_2D")
	)
	(gr_poly
		(pts
			(arc
				(start 81.154778 -2.750312)
				(mid 81.182917 -2.732466)
				(end 81.193894 -2.701036)
			)
			(arc
				(start 81.193894 -0.5588)
				(mid 81.179015 -0.522879)
				(end 81.143094 -0.508)
			)
			(arc
				(start 13.660882 -0.508)
				(mid 13.624961 -0.522879)
				(end 13.610082 -0.5588)
			)
			(arc
				(start 13.610082 -2.701036)
				(mid 13.621129 -2.732411)
				(end 13.649198 -2.750312)
			)
			(xy 13.762482 -2.77749) (xy 13.794486 -2.762504)
			(arc
				(start 13.80236 -2.746756)
				(mid 13.928356 -2.557713)
				(end 14.095984 -2.404364)
			)
			(xy 14.11732 -2.363216) (xy 14.11732 -1.014984) (xy 80.686656 -1.014984) (xy 80.686656 -2.363216)
			(arc
				(start 80.707992 -2.404364)
				(mid 80.875659 -2.55768)
				(end 81.001616 -2.746756)
			)
			(xy 81.00949 -2.762504) (xy 81.041494 -2.77749)
		)
		(stroke
			(width 0)
			(type solid)
		)
		(fill yes)
		(layer "F.Cu")
		(net "GND")
	)
	(gr_poly
		(pts
			(arc
				(start 143.002508 -393.84478)
				(mid 143.022031 -393.840879)
				(end 143.038576 -393.829794)
			)
			(arc
				(start 143.168116 -393.700254)
				(mid 143.179042 -393.683808)
				(end 143.182848 -393.66444)
			)
			(arc
				(start 143.182848 -391.408666)
				(mid 143.179015 -391.389309)
				(end 143.168116 -391.372852)
			)
			(arc
				(start 143.1163 -391.321036)
				(mid 143.099766 -391.309925)
				(end 143.080232 -391.30605)
			)
			(arc
				(start 141.584426 -391.30605)
				(mid 141.565039 -391.31)
				(end 141.548612 -391.321036)
			)
			(arc
				(start 141.461744 -391.40765)
				(mid 141.445327 -391.418712)
				(end 141.42593 -391.422636)
			)
			(arc
				(start 140.92428 -391.422636)
				(mid 140.888359 -391.437515)
				(end 140.87348 -391.473436)
			)
			(arc
				(start 140.87348 -393.720066)
				(mid 140.877381 -393.739589)
				(end 140.888466 -393.756134)
			)
			(xy 140.913866 -393.781534) (xy 140.928852 -393.7889)
			(arc
				(start 140.937234 -393.789916)
				(mid 141.011007 -393.806791)
				(end 141.079982 -393.837922)
			)
			(arc
				(start 141.079982 -393.837922)
				(mid 141.092233 -393.843002)
				(end 141.105382 -393.84478)
			)
		)
		(stroke
			(width 0)
			(type solid)
		)
		(fill yes)
		(layer "F.Cu")
		(net "P0V9_CPU1_RT2_2A")
	)
	(gr_poly
		(pts
			(arc
				(start 194.154806 -8.03021)
				(mid 194.182945 -8.012364)
				(end 194.193922 -7.980934)
			)
			(arc
				(start 194.193922 -5.838698)
				(mid 194.179043 -5.802777)
				(end 194.143122 -5.787898)
			)
			(arc
				(start 126.66091 -5.787898)
				(mid 126.624989 -5.802777)
				(end 126.61011 -5.838698)
			)
			(arc
				(start 126.61011 -7.980934)
				(mid 126.621157 -8.012309)
				(end 126.649226 -8.03021)
			)
			(xy 126.76251 -8.057388) (xy 126.794514 -8.042402)
			(arc
				(start 126.802388 -8.026654)
				(mid 126.928384 -7.837611)
				(end 127.096012 -7.684262)
			)
			(xy 127.117348 -7.643114) (xy 127.117348 -6.295136) (xy 193.686684 -6.295136) (xy 193.686684 -7.643114)
			(arc
				(start 193.70802 -7.684262)
				(mid 193.875687 -7.837578)
				(end 194.001644 -8.026654)
			)
			(xy 194.009518 -8.042402) (xy 194.041522 -8.057388)
		)
		(stroke
			(width 0)
			(type solid)
		)
		(fill yes)
		(layer "F.Cu")
		(net "GND")
	)
	(gr_poly
		(pts
			(xy 262.643366 -135.382254) (xy 262.643366 -135.128254) (xy 262.592566 -135.077454) (xy 260.043168 -135.077454)
			(xy 259.970524 -135.00481) (xy 259.970524 -134.847838) (xy 260.035294 -134.783068) (xy 262.592566 -134.783068)
			(xy 262.643366 -134.732268) (xy 262.643366 -134.478268) (xy 262.592566 -134.427468) (xy 259.27177 -134.427468)
			(xy 259.17017 -134.325868) (xy 259.17017 -131.65582) (xy 259.293106 -131.532884) (xy 262.592566 -131.532884)
			(xy 262.643366 -131.482084) (xy 262.643366 -131.228084) (xy 262.592566 -131.177284) (xy 260.043168 -131.177284)
			(xy 259.982716 -131.116832) (xy 259.982716 -130.935476) (xy 260.035294 -130.882898) (xy 262.592566 -130.882898)
			(xy 262.643366 -130.832098) (xy 262.643366 -130.578098) (xy 262.592566 -130.527298) (xy 256.774696 -130.527298)
			(xy 256.465324 -130.217926) (xy 256.465324 -129.272538) (xy 256.426716 -129.23393) (xy 255.361186 -129.23393)
			(xy 255.322324 -129.272792) (xy 255.322324 -130.813048) (xy 255.392174 -130.882898) (xy 258.64312 -130.882898)
			(xy 258.81457 -131.054348)
			(arc
				(start 258.81457 -134.843012)
				(mid 258.828104 -134.911053)
				(end 258.86664 -134.968742)
			)
			(xy 259.330952 -135.433054) (xy 262.592566 -135.433054)
		)
		(stroke
			(width 0)
			(type solid)
		)
		(fill yes)
		(layer "F.Cu")
		(net "PVDD18_S5_P0")
	)
	(gr_poly
		(pts
			(xy 166.894256 -57.814464) (xy 166.894256 -56.540908) (xy 167.248078 -56.187086) (xy 170.341798 -56.187086)
			(xy 170.35653 -56.172354) (xy 170.35653 -55.927498) (xy 170.339258 -55.910226) (xy 168.75252 -55.910226)
			(xy 168.707308 -55.865014) (xy 168.707308 -55.733696) (xy 168.752012 -55.688992) (xy 170.295824 -55.688992)
			(xy 170.346624 -55.638192) (xy 170.346624 -55.466742) (xy 170.298364 -55.418482) (xy 168.056814 -55.418482)
			(xy 167.625776 -54.987444) (xy 167.625776 -54.585362) (xy 168.511728 -53.69941) (xy 170.257978 -53.69941)
			(xy 170.357546 -53.599842) (xy 170.357546 -53.410104) (xy 168.758108 -53.410104) (xy 168.707308 -53.359304)
			(xy 168.707308 -53.240178) (xy 168.758108 -53.189378) (xy 170.357546 -53.189378) (xy 170.357546 -52.910232)
			(xy 168.758108 -52.910232) (xy 168.707308 -52.859432) (xy 168.707308 -52.740306) (xy 168.758108 -52.689506)
			(xy 170.357546 -52.689506) (xy 170.357546 -52.410106) (xy 168.758108 -52.410106) (xy 168.707308 -52.359306)
			(xy 168.707308 -52.24018) (xy 168.758108 -52.18938) (xy 170.357546 -52.18938) (xy 170.357546 -51.98491)
			(xy 170.276266 -51.90363) (xy 161.96437 -51.90363) (xy 161.677096 -52.190904) (xy 161.677096 -57.904888)
			(xy 161.715704 -57.943496) (xy 166.765224 -57.943496)
		)
		(stroke
			(width 0)
			(type solid)
		)
		(fill yes)
		(layer "F.Cu")
		(net "P3V3_M2_0")
	)
	(gr_poly
		(pts
			(xy 243.786152 -392.744452) (xy 244.44452 -392.744452) (xy 244.978428 -393.27836) (xy 251.285756 -393.27836)
			(xy 251.8156 -392.748516) (xy 252.473968 -392.748516) (xy 253.003812 -393.27836) (xy 259.312156 -393.27836)
			(xy 259.842 -392.748516) (xy 260.500368 -392.748516) (xy 261.030212 -393.27836) (xy 267.338556 -393.27836)
			(xy 267.8684 -392.748516) (xy 268.526768 -392.748516) (xy 269.056612 -393.27836)
			(arc
				(start 273.15541 -393.27836)
				(mid 273.174933 -393.274459)
				(end 273.191478 -393.263374)
			)
			(arc
				(start 273.669506 -392.785346)
				(mid 273.680617 -392.768812)
				(end 273.684492 -392.749278)
			)
			(arc
				(start 273.684492 -384.155442)
				(mid 273.680591 -384.135919)
				(end 273.669506 -384.119374)
			)
			(xy 273.445478 -383.895346) (xy 273.438366 -383.88798) (xy 273.41957 -383.88036)
			(arc
				(start 239.542574 -383.88036)
				(mid 239.523051 -383.884261)
				(end 239.506506 -383.895346)
			)
			(xy 239.028478 -384.373374) (xy 239.021112 -384.380486) (xy 239.013492 -384.399282)
			(arc
				(start 239.013492 -393.003278)
				(mid 239.017393 -393.022801)
				(end 239.028478 -393.039346)
			)
			(arc
				(start 239.252506 -393.263374)
				(mid 239.26904 -393.274485)
				(end 239.288574 -393.27836)
			)
			(xy 243.252244 -393.27836)
		)
		(stroke
			(width 0)
			(type solid)
		)
		(fill yes)
		(layer "F.Cu")
		(net "P12V_MAIN_R")
	)
	(gr_poly
		(pts
			(arc
				(start 455.654918 -2.75082)
				(mid 455.683057 -2.732974)
				(end 455.694034 -2.701544)
			)
			(arc
				(start 455.694034 -0.5588)
				(mid 455.679155 -0.522879)
				(end 455.643234 -0.508)
			)
			(arc
				(start 388.160768 -0.508)
				(mid 388.124847 -0.522879)
				(end 388.109968 -0.5588)
			)
			(arc
				(start 388.109968 -2.701036)
				(mid 388.121015 -2.732411)
				(end 388.149084 -2.750312)
			)
			(xy 388.262368 -2.77749) (xy 388.294372 -2.762504)
			(arc
				(start 388.302246 -2.746756)
				(mid 388.428345 -2.557672)
				(end 388.596124 -2.404364)
			)
			(arc
				(start 388.596124 -2.404364)
				(mid 388.610195 -2.388884)
				(end 388.616952 -2.369058)
			)
			(xy 388.616952 -1.014984) (xy 455.186796 -1.014984) (xy 455.186796 -2.36347)
			(arc
				(start 455.208132 -2.404618)
				(mid 455.3758 -2.558068)
				(end 455.501756 -2.747264)
			)
			(xy 455.50963 -2.763012) (xy 455.54138 -2.777744)
		)
		(stroke
			(width 0)
			(type solid)
		)
		(fill yes)
		(layer "F.Cu")
		(net "GND")
	)
	(gr_poly
		(pts
			(arc
				(start 46.410118 -123.45162)
				(mid 46.429641 -123.447719)
				(end 46.446186 -123.436634)
			)
			(arc
				(start 46.853094 -123.029726)
				(mid 46.864205 -123.013192)
				(end 46.86808 -122.993658)
			)
			(arc
				(start 46.86808 -118.488968)
				(mid 46.855281 -118.455352)
				(end 46.823376 -118.438676)
			)
			(xy 46.620684 -118.438676)
			(arc
				(start 46.620684 -117.797072)
				(mid 46.606136 -117.767478)
				(end 46.576488 -117.752876)
			)
			(xy 46.366684 -117.752876)
			(arc
				(start 46.366684 -114.698272)
				(mid 46.352136 -114.668678)
				(end 46.322488 -114.654076)
			)
			(arc
				(start 42.094912 -114.654076)
				(mid 42.06524 -114.6686)
				(end 42.050716 -114.698272)
			)
			(xy 42.050716 -117.752876)
			(arc
				(start 41.840912 -117.752876)
				(mid 41.81124 -117.7674)
				(end 41.796716 -117.797072)
			)
			(xy 41.796716 -118.438676) (xy 41.726104 -118.438676) (xy 41.69664 -118.46814)
			(arc
				(start 41.69664 -123.133358)
				(mid 41.700541 -123.152881)
				(end 41.711626 -123.169426)
			)
			(arc
				(start 41.978834 -123.436634)
				(mid 41.995368 -123.447745)
				(end 42.014902 -123.45162)
			)
		)
		(stroke
			(width 0)
			(type solid)
		)
		(fill yes)
		(layer "F.Cu")
		(net "P3V3_AUX_DSC")
	)
	(gr_poly
		(pts
			(arc
				(start 100.183188 -409.499308)
				(mid 100.202711 -409.495407)
				(end 100.219256 -409.484322)
			)
			(arc
				(start 100.316284 -409.387294)
				(mid 100.327395 -409.37076)
				(end 100.33127 -409.351226)
			)
			(arc
				(start 100.33127 -405.961342)
				(mid 100.327369 -405.941819)
				(end 100.316284 -405.925274)
			)
			(arc
				(start 100.25126 -405.86025)
				(mid 100.234726 -405.849139)
				(end 100.215192 -405.845264)
			)
			(arc
				(start 99.496118 -405.845264)
				(mid 99.476595 -405.849165)
				(end 99.46005 -405.86025)
			)
			(arc
				(start 99.393756 -405.926544)
				(mid 99.382645 -405.943078)
				(end 99.37877 -405.962612)
			)
			(arc
				(start 99.37877 -407.084276)
				(mid 99.374869 -407.103799)
				(end 99.363784 -407.120344)
			)
			(arc
				(start 99.209606 -407.274522)
				(mid 99.193072 -407.285633)
				(end 99.173538 -407.289508)
			)
			(arc
				(start 98.320352 -407.289508)
				(mid 98.300829 -407.293409)
				(end 98.284284 -407.304494)
			)
			(arc
				(start 98.161856 -407.426922)
				(mid 98.150745 -407.443456)
				(end 98.14687 -407.46299)
			)
			(arc
				(start 98.14687 -409.325826)
				(mid 98.150771 -409.345349)
				(end 98.161856 -409.361894)
			)
			(arc
				(start 98.284284 -409.484322)
				(mid 98.300818 -409.495433)
				(end 98.320352 -409.499308)
			)
		)
		(stroke
			(width 0)
			(type solid)
		)
		(fill yes)
		(layer "F.Cu")
		(net "GND")
	)
	(gr_poly
		(pts
			(arc
				(start 152.12568 -387.860794)
				(mid 152.134055 -387.860099)
				(end 152.14219 -387.858)
			)
			(arc
				(start 152.374346 -387.778244)
				(mid 152.43546 -387.762711)
				(end 152.498298 -387.757416)
			)
			(arc
				(start 152.498298 -387.757416)
				(mid 152.520051 -387.758066)
				(end 152.541732 -387.759956)
			)
			(xy 152.552654 -387.761226) (xy 152.572974 -387.754876)
			(arc
				(start 152.637744 -387.696964)
				(mid 152.650262 -387.679852)
				(end 152.654762 -387.659118)
			)
			(arc
				(start 152.654762 -387.118606)
				(mid 152.650325 -387.097844)
				(end 152.637744 -387.08076)
			)
			(xy 152.572974 -387.022848) (xy 152.552654 -387.016498)
			(arc
				(start 152.541732 -387.017768)
				(mid 152.520051 -387.019657)
				(end 152.498298 -387.020308)
			)
			(arc
				(start 152.498298 -387.020308)
				(mid 152.447419 -387.016832)
				(end 152.39746 -387.006592)
			)
			(xy 152.087072 -386.921502) (xy 152.07361 -386.919724)
			(arc
				(start 151.720804 -386.919724)
				(mid 151.701281 -386.923625)
				(end 151.684736 -386.93471)
			)
			(arc
				(start 151.64308 -386.976366)
				(mid 151.631969 -386.9929)
				(end 151.628094 -387.012434)
			)
			(arc
				(start 151.628094 -387.756908)
				(mid 151.631995 -387.776431)
				(end 151.64308 -387.792976)
			)
			(arc
				(start 151.695912 -387.845808)
				(mid 151.712446 -387.856919)
				(end 151.73198 -387.860794)
			)
		)
		(stroke
			(width 0)
			(type solid)
		)
		(fill yes)
		(layer "F.Cu")
		(net "P0V9_CPU1_RT2_2A_2D")
	)
	(gr_poly
		(pts
			(arc
				(start 283.70276 -429.751744)
				(mid 283.722283 -429.747843)
				(end 283.738828 -429.736758)
			)
			(arc
				(start 283.82595 -429.649636)
				(mid 283.837061 -429.633102)
				(end 283.840936 -429.613568)
			)
			(arc
				(start 283.840936 -427.72584)
				(mid 283.837035 -427.706317)
				(end 283.82595 -427.689772)
			)
			(arc
				(start 283.739844 -427.603666)
				(mid 283.728733 -427.587132)
				(end 283.724858 -427.567598)
			)
			(arc
				(start 283.724858 -426.57522)
				(mid 283.720957 -426.555697)
				(end 283.709872 -426.539152)
			)
			(arc
				(start 283.672534 -426.501814)
				(mid 283.656 -426.490703)
				(end 283.636466 -426.486828)
			)
			(arc
				(start 281.565858 -426.486828)
				(mid 281.546335 -426.490729)
				(end 281.52979 -426.501814)
			)
			(arc
				(start 281.425396 -426.606208)
				(mid 281.414285 -426.622742)
				(end 281.41041 -426.642276)
			)
			(arc
				(start 281.41041 -428.213266)
				(mid 281.406509 -428.232789)
				(end 281.395424 -428.249334)
			)
			(arc
				(start 281.146758 -428.498)
				(mid 281.135647 -428.514534)
				(end 281.131772 -428.534068)
			)
			(arc
				(start 281.131772 -429.557688)
				(mid 281.135673 -429.577211)
				(end 281.146758 -429.593756)
			)
			(arc
				(start 281.28976 -429.736758)
				(mid 281.306294 -429.747869)
				(end 281.325828 -429.751744)
			)
		)
		(stroke
			(width 0)
			(type solid)
		)
		(fill yes)
		(layer "F.Cu")
		(net "P3V3_9ZXL045_P0")
	)
	(gr_poly
		(pts
			(arc
				(start 303.225708 -408.16657)
				(mid 303.245231 -408.162669)
				(end 303.261776 -408.151584)
			)
			(arc
				(start 303.421542 -407.991818)
				(mid 303.432653 -407.975284)
				(end 303.436528 -407.95575)
			)
			(arc
				(start 303.436528 -403.960838)
				(mid 303.432627 -403.941315)
				(end 303.421542 -403.92477)
			)
			(arc
				(start 301.55007 -402.053298)
				(mid 301.533536 -402.042187)
				(end 301.514002 -402.038312)
			)
			(arc
				(start 296.579036 -402.038312)
				(mid 296.559513 -402.042213)
				(end 296.542968 -402.053298)
			)
			(arc
				(start 296.426382 -402.169884)
				(mid 296.415271 -402.186418)
				(end 296.411396 -402.205952)
			)
			(arc
				(start 296.411396 -403.780498)
				(mid 296.415297 -403.800021)
				(end 296.426382 -403.816566)
			)
			(arc
				(start 296.569892 -403.960076)
				(mid 296.586426 -403.971187)
				(end 296.60596 -403.975062)
			)
			(arc
				(start 301.135034 -403.975062)
				(mid 301.154557 -403.978963)
				(end 301.171102 -403.990048)
			)
			(arc
				(start 302.36541 -405.184356)
				(mid 302.376521 -405.20089)
				(end 302.380396 -405.220424)
			)
			(arc
				(start 302.380396 -408.043126)
				(mid 302.384297 -408.062649)
				(end 302.395382 -408.079194)
			)
			(arc
				(start 302.467772 -408.151584)
				(mid 302.484306 -408.162695)
				(end 302.50384 -408.16657)
			)
		)
		(stroke
			(width 0)
			(type solid)
		)
		(fill yes)
		(layer "F.Cu")
		(net "P0V9_CPU0_RT0_2A")
	)
	(gr_poly
		(pts
			(arc
				(start 341.02548 -396.242794)
				(mid 341.033855 -396.242099)
				(end 341.04199 -396.24)
			)
			(arc
				(start 341.274146 -396.160244)
				(mid 341.33526 -396.144711)
				(end 341.398098 -396.139416)
			)
			(arc
				(start 341.398098 -396.139416)
				(mid 341.419851 -396.140066)
				(end 341.441532 -396.141956)
			)
			(xy 341.452454 -396.143226) (xy 341.472774 -396.136876)
			(arc
				(start 341.537544 -396.078964)
				(mid 341.550062 -396.061852)
				(end 341.554562 -396.041118)
			)
			(arc
				(start 341.554562 -395.500606)
				(mid 341.550125 -395.479844)
				(end 341.537544 -395.46276)
			)
			(xy 341.472774 -395.404848) (xy 341.452454 -395.398498)
			(arc
				(start 341.441532 -395.399768)
				(mid 341.419851 -395.401657)
				(end 341.398098 -395.402308)
			)
			(arc
				(start 341.398098 -395.402308)
				(mid 341.347219 -395.398832)
				(end 341.29726 -395.388592)
			)
			(xy 340.986872 -395.303502) (xy 340.97341 -395.301724)
			(arc
				(start 340.620604 -395.301724)
				(mid 340.601081 -395.305625)
				(end 340.584536 -395.31671)
			)
			(arc
				(start 340.54288 -395.358366)
				(mid 340.531769 -395.3749)
				(end 340.527894 -395.394434)
			)
			(arc
				(start 340.527894 -396.138908)
				(mid 340.531795 -396.158431)
				(end 340.54288 -396.174976)
			)
			(arc
				(start 340.595712 -396.227808)
				(mid 340.612246 -396.238919)
				(end 340.63178 -396.242794)
			)
		)
		(stroke
			(width 0)
			(type solid)
		)
		(fill yes)
		(layer "F.Cu")
		(net "P0V9_CPU0_RT1_2A_2D")
	)
	(gr_poly
		(pts
			(arc
				(start 375.597928 -396.242794)
				(mid 375.606303 -396.242099)
				(end 375.614438 -396.24)
			)
			(arc
				(start 375.846594 -396.160244)
				(mid 375.907708 -396.144711)
				(end 375.970546 -396.139416)
			)
			(arc
				(start 375.970546 -396.139416)
				(mid 375.992299 -396.140066)
				(end 376.01398 -396.141956)
			)
			(xy 376.024902 -396.143226) (xy 376.045222 -396.136876)
			(arc
				(start 376.109992 -396.078964)
				(mid 376.12251 -396.061852)
				(end 376.12701 -396.041118)
			)
			(arc
				(start 376.12701 -395.500606)
				(mid 376.122573 -395.479844)
				(end 376.109992 -395.46276)
			)
			(xy 376.045222 -395.404848) (xy 376.024902 -395.398498)
			(arc
				(start 376.01398 -395.399768)
				(mid 375.992299 -395.401657)
				(end 375.970546 -395.402308)
			)
			(arc
				(start 375.970546 -395.402308)
				(mid 375.919667 -395.398832)
				(end 375.869708 -395.388592)
			)
			(xy 375.55932 -395.303502) (xy 375.545858 -395.301724)
			(arc
				(start 375.193052 -395.301724)
				(mid 375.173529 -395.305625)
				(end 375.156984 -395.31671)
			)
			(arc
				(start 375.115328 -395.358366)
				(mid 375.104217 -395.3749)
				(end 375.100342 -395.394434)
			)
			(arc
				(start 375.100342 -396.138908)
				(mid 375.104243 -396.158431)
				(end 375.115328 -396.174976)
			)
			(arc
				(start 375.16816 -396.227808)
				(mid 375.184694 -396.238919)
				(end 375.204228 -396.242794)
			)
		)
		(stroke
			(width 0)
			(type solid)
		)
		(fill yes)
		(layer "F.Cu")
		(net "P0V9_CPU0_RT3_2A_2D")
	)
	(gr_poly
		(pts
			(arc
				(start 408.125676 -396.242794)
				(mid 408.134051 -396.242099)
				(end 408.142186 -396.24)
			)
			(arc
				(start 408.374342 -396.160244)
				(mid 408.435456 -396.144711)
				(end 408.498294 -396.139416)
			)
			(arc
				(start 408.498294 -396.139416)
				(mid 408.520047 -396.140066)
				(end 408.541728 -396.141956)
			)
			(xy 408.55265 -396.143226) (xy 408.57297 -396.136876)
			(arc
				(start 408.63774 -396.078964)
				(mid 408.650258 -396.061852)
				(end 408.654758 -396.041118)
			)
			(arc
				(start 408.654758 -395.500606)
				(mid 408.650321 -395.479844)
				(end 408.63774 -395.46276)
			)
			(xy 408.57297 -395.404848) (xy 408.55265 -395.398498)
			(arc
				(start 408.541728 -395.399768)
				(mid 408.520047 -395.401657)
				(end 408.498294 -395.402308)
			)
			(arc
				(start 408.498294 -395.402308)
				(mid 408.447415 -395.398832)
				(end 408.397456 -395.388592)
			)
			(xy 408.087068 -395.303502) (xy 408.073606 -395.301724)
			(arc
				(start 407.7208 -395.301724)
				(mid 407.701277 -395.305625)
				(end 407.684732 -395.31671)
			)
			(arc
				(start 407.643076 -395.358366)
				(mid 407.631965 -395.3749)
				(end 407.62809 -395.394434)
			)
			(arc
				(start 407.62809 -396.138908)
				(mid 407.631991 -396.158431)
				(end 407.643076 -396.174976)
			)
			(arc
				(start 407.695908 -396.227808)
				(mid 407.712442 -396.238919)
				(end 407.731976 -396.242794)
			)
		)
		(stroke
			(width 0)
			(type solid)
		)
		(fill yes)
		(layer "F.Cu")
		(net "P0V9_CPU0_RT2_2A_2D")
	)
	(gr_poly
		(pts
			(arc
				(start 59.52617 -387.860794)
				(mid 59.545693 -387.856893)
				(end 59.562238 -387.845808)
			)
			(arc
				(start 59.647328 -387.760718)
				(mid 59.658439 -387.744184)
				(end 59.662314 -387.72465)
			)
			(arc
				(start 59.662314 -387.053328)
				(mid 59.658413 -387.033805)
				(end 59.647328 -387.01726)
			)
			(arc
				(start 59.564778 -386.93471)
				(mid 59.548244 -386.923599)
				(end 59.52871 -386.919724)
			)
			(arc
				(start 59.21756 -386.919724)
				(mid 59.208523 -386.92058)
				(end 59.19978 -386.923026)
			)
			(arc
				(start 59.003946 -386.996178)
				(mid 58.938352 -387.014225)
				(end 58.870596 -387.020308)
			)
			(arc
				(start 58.870596 -387.020308)
				(mid 58.837321 -387.018844)
				(end 58.804302 -387.014466)
			)
			(xy 58.79211 -387.01218) (xy 58.768488 -387.019546)
			(arc
				(start 58.737754 -387.05028)
				(mid 58.726643 -387.066814)
				(end 58.722768 -387.086348)
			)
			(arc
				(start 58.722768 -387.689852)
				(mid 58.726669 -387.709375)
				(end 58.737754 -387.72592)
			)
			(xy 58.769758 -387.757924) (xy 58.792872 -387.76529)
			(arc
				(start 58.805572 -387.763258)
				(mid 58.837959 -387.758939)
				(end 58.870596 -387.757416)
			)
			(arc
				(start 58.870596 -387.757416)
				(mid 58.92474 -387.761351)
				(end 58.977784 -387.77291)
			)
			(arc
				(start 59.2709 -387.858762)
				(mid 59.27794 -387.860283)
				(end 59.285124 -387.860794)
			)
		)
		(stroke
			(width 0)
			(type solid)
		)
		(fill yes)
		(layer "F.Cu")
		(net "P0V9_CPU1_RT_2D")
	)
	(gr_poly
		(pts
			(arc
				(start 60.795916 -387.860794)
				(mid 60.815439 -387.856893)
				(end 60.831984 -387.845808)
			)
			(arc
				(start 60.883546 -387.794246)
				(mid 60.894657 -387.777712)
				(end 60.898532 -387.758178)
			)
			(arc
				(start 60.898532 -387.09092)
				(mid 60.894631 -387.071397)
				(end 60.883546 -387.054852)
			)
			(arc
				(start 60.763404 -386.93471)
				(mid 60.74687 -386.923599)
				(end 60.727336 -386.919724)
			)
			(arc
				(start 60.417456 -386.919724)
				(mid 60.408419 -386.92058)
				(end 60.399676 -386.923026)
			)
			(arc
				(start 60.203842 -386.996178)
				(mid 60.138248 -387.014225)
				(end 60.070492 -387.020308)
			)
			(arc
				(start 60.070492 -387.020308)
				(mid 60.035159 -387.018645)
				(end 60.000134 -387.013704)
			)
			(xy 59.987688 -387.011164) (xy 59.963558 -387.018784)
			(arc
				(start 59.931554 -387.050788)
				(mid 59.920492 -387.067205)
				(end 59.916568 -387.086602)
			)
			(arc
				(start 59.916568 -387.658864)
				(mid 59.921005 -387.679626)
				(end 59.933586 -387.69671)
			)
			(xy 59.998102 -387.754368) (xy 60.018422 -387.760972)
			(arc
				(start 60.029344 -387.759702)
				(mid 60.049887 -387.758006)
				(end 60.070492 -387.757416)
			)
			(arc
				(start 60.070492 -387.757416)
				(mid 60.124636 -387.761351)
				(end 60.17768 -387.77291)
			)
			(arc
				(start 60.470796 -387.858762)
				(mid 60.477836 -387.860283)
				(end 60.48502 -387.860794)
			)
		)
		(stroke
			(width 0)
			(type solid)
		)
		(fill yes)
		(layer "F.Cu")
		(net "P0V9_CPU1_RT0_2A_2D")
	)
	(gr_poly
		(pts
			(arc
				(start 92.053918 -387.860794)
				(mid 92.073441 -387.856893)
				(end 92.089986 -387.845808)
			)
			(arc
				(start 92.175076 -387.760718)
				(mid 92.186187 -387.744184)
				(end 92.190062 -387.72465)
			)
			(arc
				(start 92.190062 -387.053328)
				(mid 92.186161 -387.033805)
				(end 92.175076 -387.01726)
			)
			(arc
				(start 92.092526 -386.93471)
				(mid 92.075992 -386.923599)
				(end 92.056458 -386.919724)
			)
			(arc
				(start 91.745308 -386.919724)
				(mid 91.736271 -386.92058)
				(end 91.727528 -386.923026)
			)
			(arc
				(start 91.531694 -386.996178)
				(mid 91.4661 -387.014225)
				(end 91.398344 -387.020308)
			)
			(arc
				(start 91.398344 -387.020308)
				(mid 91.365069 -387.018844)
				(end 91.33205 -387.014466)
			)
			(xy 91.319858 -387.01218) (xy 91.296236 -387.019546)
			(arc
				(start 91.276424 -387.039358)
				(mid 91.265498 -387.055804)
				(end 91.261692 -387.075172)
			)
			(arc
				(start 91.261692 -387.701028)
				(mid 91.265525 -387.720385)
				(end 91.276424 -387.736842)
			)
			(xy 91.297506 -387.757924) (xy 91.32062 -387.76529)
			(arc
				(start 91.33332 -387.763258)
				(mid 91.365707 -387.758939)
				(end 91.398344 -387.757416)
			)
			(arc
				(start 91.398344 -387.757416)
				(mid 91.452488 -387.761351)
				(end 91.505532 -387.77291)
			)
			(arc
				(start 91.798648 -387.858762)
				(mid 91.805688 -387.860283)
				(end 91.812872 -387.860794)
			)
		)
		(stroke
			(width 0)
			(type solid)
		)
		(fill yes)
		(layer "F.Cu")
		(net "P0V9_CPU1_RT_2D")
	)
	(gr_poly
		(pts
			(arc
				(start 126.626112 -387.860794)
				(mid 126.645635 -387.856893)
				(end 126.66218 -387.845808)
			)
			(arc
				(start 126.741682 -387.766306)
				(mid 126.752744 -387.749889)
				(end 126.756668 -387.730492)
			)
			(arc
				(start 126.756668 -387.047486)
				(mid 126.752718 -387.028099)
				(end 126.741682 -387.011672)
			)
			(arc
				(start 126.66472 -386.93471)
				(mid 126.648186 -386.923599)
				(end 126.628652 -386.919724)
			)
			(arc
				(start 126.317502 -386.919724)
				(mid 126.308465 -386.92058)
				(end 126.299722 -386.923026)
			)
			(arc
				(start 126.103888 -386.996178)
				(mid 126.038294 -387.014225)
				(end 125.970538 -387.020308)
			)
			(arc
				(start 125.970538 -387.020308)
				(mid 125.937263 -387.018844)
				(end 125.904244 -387.014466)
			)
			(xy 125.892052 -387.01218) (xy 125.86843 -387.019546)
			(arc
				(start 125.848618 -387.039358)
				(mid 125.837556 -387.055775)
				(end 125.833632 -387.075172)
			)
			(arc
				(start 125.833632 -387.701028)
				(mid 125.837582 -387.720415)
				(end 125.848618 -387.736842)
			)
			(xy 125.8697 -387.757924) (xy 125.892814 -387.76529)
			(arc
				(start 125.905514 -387.763258)
				(mid 125.937901 -387.758939)
				(end 125.970538 -387.757416)
			)
			(arc
				(start 125.970538 -387.757416)
				(mid 126.024682 -387.761351)
				(end 126.077726 -387.77291)
			)
			(arc
				(start 126.370842 -387.858762)
				(mid 126.377882 -387.860283)
				(end 126.385066 -387.860794)
			)
		)
		(stroke
			(width 0)
			(type solid)
		)
		(fill yes)
		(layer "F.Cu")
		(net "P0V9_CPU1_RT_2D")
	)
	(gr_poly
		(pts
			(arc
				(start 127.962152 -387.860794)
				(mid 127.981675 -387.856893)
				(end 127.99822 -387.845808)
			)
			(arc
				(start 128.028446 -387.815582)
				(mid 128.039557 -387.799048)
				(end 128.043432 -387.779514)
			)
			(arc
				(start 128.043432 -387.039104)
				(mid 128.039531 -387.019581)
				(end 128.028446 -387.003036)
			)
			(arc
				(start 127.96012 -386.93471)
				(mid 127.943586 -386.923599)
				(end 127.924052 -386.919724)
			)
			(arc
				(start 127.517398 -386.919724)
				(mid 127.508361 -386.92058)
				(end 127.499618 -386.923026)
			)
			(arc
				(start 127.303784 -386.996178)
				(mid 127.23819 -387.014225)
				(end 127.170434 -387.020308)
			)
			(arc
				(start 127.170434 -387.020308)
				(mid 127.135101 -387.018645)
				(end 127.100076 -387.013704)
			)
			(xy 127.08763 -387.011164) (xy 127.0635 -387.018784)
			(arc
				(start 127.025908 -387.056376)
				(mid 127.014797 -387.07291)
				(end 127.010922 -387.092444)
			)
			(arc
				(start 127.010922 -387.659372)
				(mid 127.015306 -387.680273)
				(end 127.02794 -387.697472)
			)
			(xy 127.092964 -387.75513) (xy 127.113792 -387.76148)
			(arc
				(start 127.124714 -387.76021)
				(mid 127.147532 -387.758133)
				(end 127.170434 -387.757416)
			)
			(arc
				(start 127.170434 -387.757416)
				(mid 127.224578 -387.761351)
				(end 127.277622 -387.77291)
			)
			(arc
				(start 127.570738 -387.858762)
				(mid 127.577778 -387.860283)
				(end 127.584962 -387.860794)
			)
		)
		(stroke
			(width 0)
			(type solid)
		)
		(fill yes)
		(layer "F.Cu")
		(net "P0V9_CPU1_RT3_2A_2D")
	)
	(gr_poly
		(pts
			(arc
				(start 159.15386 -387.860794)
				(mid 159.173383 -387.856893)
				(end 159.189928 -387.845808)
			)
			(arc
				(start 159.26943 -387.766306)
				(mid 159.280492 -387.749889)
				(end 159.284416 -387.730492)
			)
			(arc
				(start 159.284416 -387.047486)
				(mid 159.280466 -387.028099)
				(end 159.26943 -387.011672)
			)
			(arc
				(start 159.192468 -386.93471)
				(mid 159.175934 -386.923599)
				(end 159.1564 -386.919724)
			)
			(arc
				(start 158.84525 -386.919724)
				(mid 158.836213 -386.92058)
				(end 158.82747 -386.923026)
			)
			(arc
				(start 158.631636 -386.996178)
				(mid 158.566042 -387.014225)
				(end 158.498286 -387.020308)
			)
			(arc
				(start 158.498286 -387.020308)
				(mid 158.465011 -387.018844)
				(end 158.431992 -387.014466)
			)
			(xy 158.4198 -387.01218) (xy 158.396178 -387.019546)
			(arc
				(start 158.376366 -387.039358)
				(mid 158.365304 -387.055775)
				(end 158.36138 -387.075172)
			)
			(arc
				(start 158.36138 -387.701028)
				(mid 158.36533 -387.720415)
				(end 158.376366 -387.736842)
			)
			(xy 158.397448 -387.757924) (xy 158.420562 -387.76529)
			(arc
				(start 158.433262 -387.763258)
				(mid 158.465649 -387.758939)
				(end 158.498286 -387.757416)
			)
			(arc
				(start 158.498286 -387.757416)
				(mid 158.55243 -387.761351)
				(end 158.605474 -387.77291)
			)
			(arc
				(start 158.89859 -387.858762)
				(mid 158.90563 -387.860283)
				(end 158.912814 -387.860794)
			)
		)
		(stroke
			(width 0)
			(type solid)
		)
		(fill yes)
		(layer "F.Cu")
		(net "P0V9_CPU1_RT_2D")
	)
	(gr_poly
		(pts
			(arc
				(start 160.4899 -387.860794)
				(mid 160.509423 -387.856893)
				(end 160.525968 -387.845808)
			)
			(arc
				(start 160.556194 -387.815582)
				(mid 160.567305 -387.799048)
				(end 160.57118 -387.779514)
			)
			(arc
				(start 160.57118 -387.039104)
				(mid 160.567279 -387.019581)
				(end 160.556194 -387.003036)
			)
			(arc
				(start 160.487868 -386.93471)
				(mid 160.471334 -386.923599)
				(end 160.4518 -386.919724)
			)
			(arc
				(start 160.045146 -386.919724)
				(mid 160.036109 -386.92058)
				(end 160.027366 -386.923026)
			)
			(arc
				(start 159.831532 -386.996178)
				(mid 159.765938 -387.014225)
				(end 159.698182 -387.020308)
			)
			(arc
				(start 159.698182 -387.020308)
				(mid 159.662849 -387.018645)
				(end 159.627824 -387.013704)
			)
			(xy 159.615378 -387.011164) (xy 159.591248 -387.018784)
			(arc
				(start 159.553656 -387.056376)
				(mid 159.542545 -387.07291)
				(end 159.53867 -387.092444)
			)
			(arc
				(start 159.53867 -387.659372)
				(mid 159.543054 -387.680273)
				(end 159.555688 -387.697472)
			)
			(xy 159.620712 -387.75513) (xy 159.64154 -387.76148)
			(arc
				(start 159.652462 -387.76021)
				(mid 159.67528 -387.758133)
				(end 159.698182 -387.757416)
			)
			(arc
				(start 159.698182 -387.757416)
				(mid 159.752326 -387.761351)
				(end 159.80537 -387.77291)
			)
			(arc
				(start 160.098486 -387.858762)
				(mid 160.105526 -387.860283)
				(end 160.11271 -387.860794)
			)
		)
		(stroke
			(width 0)
			(type solid)
		)
		(fill yes)
		(layer "F.Cu")
		(net "P0V9_CPU1_RT2_2A_2D")
	)
	(gr_poly
		(pts
			(arc
				(start 315.525912 -396.242794)
				(mid 315.545435 -396.238893)
				(end 315.56198 -396.227808)
			)
			(arc
				(start 315.641482 -396.148306)
				(mid 315.652544 -396.131889)
				(end 315.656468 -396.112492)
			)
			(arc
				(start 315.656468 -395.429486)
				(mid 315.652518 -395.410099)
				(end 315.641482 -395.393672)
			)
			(arc
				(start 315.56452 -395.31671)
				(mid 315.547986 -395.305599)
				(end 315.528452 -395.301724)
			)
			(arc
				(start 315.217302 -395.301724)
				(mid 315.208265 -395.30258)
				(end 315.199522 -395.305026)
			)
			(arc
				(start 315.003688 -395.378178)
				(mid 314.938094 -395.396225)
				(end 314.870338 -395.402308)
			)
			(arc
				(start 314.870338 -395.402308)
				(mid 314.837063 -395.400844)
				(end 314.804044 -395.396466)
			)
			(xy 314.791852 -395.39418) (xy 314.76823 -395.401546)
			(arc
				(start 314.748418 -395.421358)
				(mid 314.737356 -395.437775)
				(end 314.733432 -395.457172)
			)
			(arc
				(start 314.733432 -396.083028)
				(mid 314.737382 -396.102415)
				(end 314.748418 -396.118842)
			)
			(xy 314.7695 -396.139924) (xy 314.792614 -396.14729)
			(arc
				(start 314.805314 -396.145258)
				(mid 314.837701 -396.140939)
				(end 314.870338 -396.139416)
			)
			(arc
				(start 314.870338 -396.139416)
				(mid 314.924482 -396.143351)
				(end 314.977526 -396.15491)
			)
			(arc
				(start 315.270642 -396.240762)
				(mid 315.277682 -396.242283)
				(end 315.284866 -396.242794)
			)
		)
		(stroke
			(width 0)
			(type solid)
		)
		(fill yes)
		(layer "F.Cu")
		(net "P0V9_CPU0_RT_2D")
	)
	(gr_poly
		(pts
			(arc
				(start 348.05366 -396.242794)
				(mid 348.073183 -396.238893)
				(end 348.089728 -396.227808)
			)
			(arc
				(start 348.16923 -396.148306)
				(mid 348.180292 -396.131889)
				(end 348.184216 -396.112492)
			)
			(arc
				(start 348.184216 -395.429486)
				(mid 348.180266 -395.410099)
				(end 348.16923 -395.393672)
			)
			(arc
				(start 348.092268 -395.31671)
				(mid 348.075734 -395.305599)
				(end 348.0562 -395.301724)
			)
			(arc
				(start 347.74505 -395.301724)
				(mid 347.736013 -395.30258)
				(end 347.72727 -395.305026)
			)
			(arc
				(start 347.531436 -395.378178)
				(mid 347.465842 -395.396225)
				(end 347.398086 -395.402308)
			)
			(arc
				(start 347.398086 -395.402308)
				(mid 347.364811 -395.400844)
				(end 347.331792 -395.396466)
			)
			(xy 347.3196 -395.39418) (xy 347.295978 -395.401546)
			(arc
				(start 347.265244 -395.43228)
				(mid 347.254133 -395.448814)
				(end 347.250258 -395.468348)
			)
			(arc
				(start 347.250258 -396.071852)
				(mid 347.254159 -396.091375)
				(end 347.265244 -396.10792)
			)
			(xy 347.297248 -396.139924) (xy 347.320362 -396.14729)
			(arc
				(start 347.333062 -396.145258)
				(mid 347.365449 -396.140939)
				(end 347.398086 -396.139416)
			)
			(arc
				(start 347.398086 -396.139416)
				(mid 347.45223 -396.143351)
				(end 347.505274 -396.15491)
			)
			(arc
				(start 347.79839 -396.240762)
				(mid 347.80543 -396.242283)
				(end 347.812614 -396.242794)
			)
		)
		(stroke
			(width 0)
			(type solid)
		)
		(fill yes)
		(layer "F.Cu")
		(net "P0V9_CPU0_RT_2D")
	)
	(gr_poly
		(pts
			(arc
				(start 349.3897 -396.242794)
				(mid 349.409223 -396.238893)
				(end 349.425768 -396.227808)
			)
			(arc
				(start 349.455994 -396.197582)
				(mid 349.467105 -396.181048)
				(end 349.47098 -396.161514)
			)
			(arc
				(start 349.47098 -395.421104)
				(mid 349.467079 -395.401581)
				(end 349.455994 -395.385036)
			)
			(arc
				(start 349.387668 -395.31671)
				(mid 349.371134 -395.305599)
				(end 349.3516 -395.301724)
			)
			(arc
				(start 348.944946 -395.301724)
				(mid 348.935909 -395.30258)
				(end 348.927166 -395.305026)
			)
			(arc
				(start 348.731332 -395.378178)
				(mid 348.665738 -395.396225)
				(end 348.597982 -395.402308)
			)
			(arc
				(start 348.597982 -395.402308)
				(mid 348.562649 -395.400645)
				(end 348.527624 -395.395704)
			)
			(xy 348.515178 -395.393164) (xy 348.491048 -395.400784)
			(arc
				(start 348.453456 -395.438376)
				(mid 348.442345 -395.45491)
				(end 348.43847 -395.474444)
			)
			(arc
				(start 348.43847 -396.041372)
				(mid 348.442854 -396.062273)
				(end 348.455488 -396.079472)
			)
			(xy 348.520512 -396.13713) (xy 348.54134 -396.14348)
			(arc
				(start 348.552262 -396.14221)
				(mid 348.57508 -396.140133)
				(end 348.597982 -396.139416)
			)
			(arc
				(start 348.597982 -396.139416)
				(mid 348.652126 -396.143351)
				(end 348.70517 -396.15491)
			)
			(arc
				(start 348.998286 -396.240762)
				(mid 349.005326 -396.242283)
				(end 349.01251 -396.242794)
			)
		)
		(stroke
			(width 0)
			(type solid)
		)
		(fill yes)
		(layer "F.Cu")
		(net "P0V9_CPU0_RT1_2A_2D")
	)
	(gr_poly
		(pts
			(arc
				(start 382.626108 -396.242794)
				(mid 382.645631 -396.238893)
				(end 382.662176 -396.227808)
			)
			(arc
				(start 382.741678 -396.148306)
				(mid 382.75274 -396.131889)
				(end 382.756664 -396.112492)
			)
			(arc
				(start 382.756664 -395.429486)
				(mid 382.752714 -395.410099)
				(end 382.741678 -395.393672)
			)
			(arc
				(start 382.664716 -395.31671)
				(mid 382.648182 -395.305599)
				(end 382.628648 -395.301724)
			)
			(arc
				(start 382.317498 -395.301724)
				(mid 382.308461 -395.30258)
				(end 382.299718 -395.305026)
			)
			(arc
				(start 382.103884 -395.378178)
				(mid 382.03829 -395.396225)
				(end 381.970534 -395.402308)
			)
			(arc
				(start 381.970534 -395.402308)
				(mid 381.937259 -395.400844)
				(end 381.90424 -395.396466)
			)
			(xy 381.892048 -395.39418) (xy 381.868426 -395.401546)
			(arc
				(start 381.848614 -395.421358)
				(mid 381.837552 -395.437775)
				(end 381.833628 -395.457172)
			)
			(arc
				(start 381.833628 -396.083028)
				(mid 381.837578 -396.102415)
				(end 381.848614 -396.118842)
			)
			(xy 381.869696 -396.139924) (xy 381.89281 -396.14729)
			(arc
				(start 381.90551 -396.145258)
				(mid 381.937897 -396.140939)
				(end 381.970534 -396.139416)
			)
			(arc
				(start 381.970534 -396.139416)
				(mid 382.024678 -396.143351)
				(end 382.077722 -396.15491)
			)
			(arc
				(start 382.370838 -396.240762)
				(mid 382.377878 -396.242283)
				(end 382.385062 -396.242794)
			)
		)
		(stroke
			(width 0)
			(type solid)
		)
		(fill yes)
		(layer "F.Cu")
		(net "P0V9_CPU0_RT_2D")
	)
	(gr_poly
		(pts
			(arc
				(start 415.153856 -396.242794)
				(mid 415.173379 -396.238893)
				(end 415.189924 -396.227808)
			)
			(arc
				(start 415.269426 -396.148306)
				(mid 415.280488 -396.131889)
				(end 415.284412 -396.112492)
			)
			(arc
				(start 415.284412 -395.429486)
				(mid 415.280462 -395.410099)
				(end 415.269426 -395.393672)
			)
			(arc
				(start 415.192464 -395.31671)
				(mid 415.17593 -395.305599)
				(end 415.156396 -395.301724)
			)
			(arc
				(start 414.845246 -395.301724)
				(mid 414.836209 -395.30258)
				(end 414.827466 -395.305026)
			)
			(arc
				(start 414.631632 -395.378178)
				(mid 414.566038 -395.396225)
				(end 414.498282 -395.402308)
			)
			(arc
				(start 414.498282 -395.402308)
				(mid 414.465007 -395.400844)
				(end 414.431988 -395.396466)
			)
			(xy 414.419796 -395.39418) (xy 414.396174 -395.401546)
			(arc
				(start 414.376362 -395.421358)
				(mid 414.3653 -395.437775)
				(end 414.361376 -395.457172)
			)
			(arc
				(start 414.361376 -396.083028)
				(mid 414.365326 -396.102415)
				(end 414.376362 -396.118842)
			)
			(xy 414.397444 -396.139924) (xy 414.420558 -396.14729)
			(arc
				(start 414.433258 -396.145258)
				(mid 414.465645 -396.140939)
				(end 414.498282 -396.139416)
			)
			(arc
				(start 414.498282 -396.139416)
				(mid 414.552426 -396.143351)
				(end 414.60547 -396.15491)
			)
			(arc
				(start 414.898586 -396.240762)
				(mid 414.905626 -396.242283)
				(end 414.91281 -396.242794)
			)
		)
		(stroke
			(width 0)
			(type solid)
		)
		(fill yes)
		(layer "F.Cu")
		(net "P0V9_CPU0_RT_2D")
	)
	(gr_poly
		(pts
			(arc
				(start 416.489896 -396.242794)
				(mid 416.509419 -396.238893)
				(end 416.525964 -396.227808)
			)
			(arc
				(start 416.55619 -396.197582)
				(mid 416.567301 -396.181048)
				(end 416.571176 -396.161514)
			)
			(arc
				(start 416.571176 -395.421104)
				(mid 416.567275 -395.401581)
				(end 416.55619 -395.385036)
			)
			(arc
				(start 416.487864 -395.31671)
				(mid 416.47133 -395.305599)
				(end 416.451796 -395.301724)
			)
			(arc
				(start 416.045142 -395.301724)
				(mid 416.036105 -395.30258)
				(end 416.027362 -395.305026)
			)
			(arc
				(start 415.831528 -395.378178)
				(mid 415.765934 -395.396225)
				(end 415.698178 -395.402308)
			)
			(arc
				(start 415.698178 -395.402308)
				(mid 415.662845 -395.400645)
				(end 415.62782 -395.395704)
			)
			(xy 415.615374 -395.393164) (xy 415.591244 -395.400784)
			(arc
				(start 415.553652 -395.438376)
				(mid 415.542541 -395.45491)
				(end 415.538666 -395.474444)
			)
			(arc
				(start 415.538666 -396.041372)
				(mid 415.54305 -396.062273)
				(end 415.555684 -396.079472)
			)
			(xy 415.620708 -396.13713) (xy 415.641536 -396.14348)
			(arc
				(start 415.652458 -396.14221)
				(mid 415.675276 -396.140133)
				(end 415.698178 -396.139416)
			)
			(arc
				(start 415.698178 -396.139416)
				(mid 415.752322 -396.143351)
				(end 415.805366 -396.15491)
			)
			(arc
				(start 416.098482 -396.240762)
				(mid 416.105522 -396.242283)
				(end 416.112706 -396.242794)
			)
		)
		(stroke
			(width 0)
			(type solid)
		)
		(fill yes)
		(layer "F.Cu")
		(net "P0V9_CPU0_RT2_2A_2D")
	)
	(gr_poly
		(pts
			(xy 243.634006 -50.583592) (xy 243.634006 -49.756314) (xy 243.714016 -49.676304) (xy 243.714016 -49.475136)
			(xy 243.714016 -46.337982) (xy 243.714016 -46.223174) (xy 243.714016 -46.027594) (xy 242.708684 -45.022262)
			(xy 242.708684 -43.999658) (xy 242.990116 -43.718226) (xy 244.391942 -43.718226) (xy 244.860572 -43.718226)
			(xy 245.032784 -43.890438) (xy 245.403116 -43.890438) (xy 245.644416 -43.649138) (xy 245.644416 -42.672508)
			(xy 245.389654 -42.417746) (xy 241.683286 -42.417746)
			(arc
				(start 237.587536 -42.417746)
				(mid 237.568013 -42.413845)
				(end 237.551468 -42.40276)
			)
			(arc
				(start 237.24108 -42.092372)
				(mid 237.224546 -42.081261)
				(end 237.205012 -42.077386)
			)
			(arc
				(start 235.809536 -42.077386)
				(mid 235.790013 -42.081287)
				(end 235.773468 -42.092372)
			)
			(arc
				(start 235.68406 -42.18178)
				(mid 235.672949 -42.198314)
				(end 235.669074 -42.217848)
			)
			(arc
				(start 235.669074 -45.642784)
				(mid 235.672975 -45.662307)
				(end 235.68406 -45.678852)
			)
			(arc
				(start 235.793788 -45.78858)
				(mid 235.810322 -45.799691)
				(end 235.829856 -45.803566)
			)
			(xy 238.435134 -45.803566) (xy 238.440214 -45.798486) (xy 240.359438 -45.798486) (xy 240.554256 -45.993304)
			(xy 240.554256 -49.33696) (xy 240.898934 -49.681638) (xy 242.13439 -49.681638) (xy 243.08816 -50.635408)
			(xy 243.58219 -50.635408)
		)
		(stroke
			(width 0)
			(type solid)
		)
		(fill yes)
		(layer "F.Cu")
		(net "P12V_E1S_0_R")
	)
	(gr_poly
		(pts
			(xy 427.583346 -108.94695) (xy 427.583346 -106.995468) (xy 429.137064 -105.44175) (xy 432.618896 -105.44175)
			(xy 432.689 -105.371646) (xy 432.689 -105.27411) (xy 432.630326 -105.215436) (xy 430.663096 -105.215436)
			(xy 430.56556 -105.1179) (xy 430.56556 -104.541574) (xy 430.66462 -104.442514) (xy 432.124358 -104.442514)
			(xy 432.190906 -104.375966) (xy 432.190906 -104.278684) (xy 432.128422 -104.2162) (xy 430.652936 -104.2162)
			(xy 430.55921 -104.122474) (xy 430.554892 -104.122474) (xy 430.285652 -103.853234) (xy 428.771304 -103.853234)
			(xy 428.748952 -103.830628) (xy 427.629828 -103.830628) (xy 427.4566 -103.6574) (xy 427.4566 -100.87356)
			(xy 428.201074 -100.129086) (xy 429.240188 -100.129086) (xy 429.7553 -100.129086) (xy 430.004982 -99.879404)
			(xy 430.004982 -95.361252) (xy 431.142902 -94.223332) (xy 432.267106 -94.223332) (xy 432.423062 -94.067376)
			(xy 432.423062 -93.739208) (xy 432.110896 -93.427042) (xy 423.944796 -93.427042) (xy 423.3672 -94.004638)
			(xy 423.3672 -103.482394) (xy 422.024556 -104.825038) (xy 420.845742 -104.825038) (xy 420.720774 -104.950006)
			(xy 420.720774 -105.480866) (xy 420.829994 -105.590086) (xy 422.170606 -105.590086) (xy 422.806876 -106.226356)
			(xy 424.344846 -106.226356) (xy 424.516804 -106.398314) (xy 424.516804 -108.584238) (xy 424.93057 -108.998004)
			(xy 425.750228 -108.998004) (xy 425.9961 -109.243876) (xy 427.28642 -109.243876)
		)
		(stroke
			(width 0)
			(type solid)
		)
		(fill yes)
		(layer "F.Cu")
		(net "P3V3_OCP_SFF_R")
	)
	(gr_poly
		(pts
			(xy 31.04007 -402.233638) (xy 31.04007 -390.078976) (xy 30.063186 -389.102092) (xy 29.91358 -389.102092)
			(xy 29.6418 -389.102092) (xy 26.034238 -389.102092) (xy 26.029158 -389.107172) (xy 26.029158 -391.16)
			(xy 26.035508 -391.16635) (xy 27.44216 -391.16635) (xy 27.587956 -391.312146) (xy 27.587956 -392.148314)
			(xy 28.034996 -392.595354) (xy 28.034996 -394.144754) (xy 27.833066 -394.346684) (xy 27.198066 -394.346684)
			(xy 27.095196 -394.449554) (xy 27.095196 -395.287754) (xy 26.764996 -395.617954) (xy 25.647396 -395.617954)
			(xy 25.5143 -395.484858) (xy 25.509728 -395.484858) (xy 25.36698 -395.34211) (xy 25.347676 -395.34211)
			(xy 21.273008 -395.34211) (xy 20.92325 -394.992352) (xy 20.92325 -394.97762) (xy 20.318984 -394.373354)
			(xy 20.318984 -393.158726) (xy 20.50923 -392.96848) (xy 20.50923 -389.277352) (xy 20.378674 -389.146542)
			(xy 19.319494 -389.146542) (xy 19.278092 -389.10514) (xy 16.960596 -389.10514) (xy 16.950944 -389.114792)
			(xy 16.950944 -391.166858) (xy 16.957548 -391.173462) (xy 18.37055 -391.173462) (xy 18.509234 -391.312146)
			(xy 18.509234 -392.276584) (xy 18.841212 -392.608562) (xy 18.884392 -392.651742) (xy 18.884392 -394.358622)
			(xy 18.445988 -394.797026) (xy 18.445734 -394.797026) (xy 18.141442 -395.101318) (xy 18.141442 -401.075144)
			(xy 19.474942 -402.408644) (xy 26.293064 -402.408644) (xy 30.396688 -402.408644) (xy 30.865064 -402.408644)
		)
		(stroke
			(width 0)
			(type solid)
		)
		(fill yes)
		(layer "F.Cu")
		(net "SW_P12V_AUX_P0V9_RETIMER_CPU1_FLT")
	)
	(gr_poly
		(pts
			(arc
				(start 40.090598 -113.87836)
				(mid 40.110121 -113.874459)
				(end 40.126666 -113.863374)
			)
			(arc
				(start 40.200834 -113.789206)
				(mid 40.211945 -113.772672)
				(end 40.21582 -113.753138)
			)
			(arc
				(start 40.21582 -109.236002)
				(mid 40.211919 -109.216479)
				(end 40.200834 -109.199934)
			)
			(arc
				(start 40.139366 -109.138466)
				(mid 40.122832 -109.127355)
				(end 40.103298 -109.12348)
			)
			(arc
				(start 38.961822 -109.12348)
				(mid 38.942299 -109.127381)
				(end 38.925754 -109.138466)
			)
			(arc
				(start 38.816026 -109.248194)
				(mid 38.804915 -109.264728)
				(end 38.80104 -109.284262)
			)
			(arc
				(start 38.80104 -110.227618)
				(mid 38.804941 -110.247141)
				(end 38.816026 -110.263686)
			)
			(arc
				(start 39.017194 -110.464854)
				(mid 39.028305 -110.481388)
				(end 39.03218 -110.500922)
			)
			(xy 39.03218 -111.004096) (xy 39.032688 -111.00435) (xy 39.032688 -111.78667) (xy 39.03218 -111.786924)
			(arc
				(start 39.03218 -111.914178)
				(mid 39.028279 -111.933701)
				(end 39.017194 -111.950246)
			)
			(arc
				(start 38.943026 -112.024414)
				(mid 38.931915 -112.040948)
				(end 38.92804 -112.060482)
			)
			(arc
				(start 38.92804 -113.778538)
				(mid 38.931941 -113.798061)
				(end 38.943026 -113.814606)
			)
			(arc
				(start 38.991794 -113.863374)
				(mid 39.008328 -113.874485)
				(end 39.027862 -113.87836)
			)
		)
		(stroke
			(width 0)
			(type solid)
		)
		(fill yes)
		(layer "F.Cu")
		(net "P12V_AUX_DSC_G2")
	)
	(gr_poly
		(pts
			(arc
				(start 46.892718 -113.7412)
				(mid 46.912241 -113.737299)
				(end 46.928786 -113.726214)
			)
			(arc
				(start 47.002954 -113.652046)
				(mid 47.014065 -113.635512)
				(end 47.01794 -113.615978)
			)
			(arc
				(start 47.01794 -109.098842)
				(mid 47.014039 -109.079319)
				(end 47.002954 -109.062774)
			)
			(arc
				(start 46.941486 -109.001306)
				(mid 46.924952 -108.990195)
				(end 46.905418 -108.98632)
			)
			(arc
				(start 45.763942 -108.98632)
				(mid 45.744419 -108.990221)
				(end 45.727874 -109.001306)
			)
			(arc
				(start 45.618146 -109.111034)
				(mid 45.607035 -109.127568)
				(end 45.60316 -109.147102)
			)
			(arc
				(start 45.60316 -110.090458)
				(mid 45.607061 -110.109981)
				(end 45.618146 -110.126526)
			)
			(arc
				(start 45.819314 -110.327694)
				(mid 45.830425 -110.344228)
				(end 45.8343 -110.363762)
			)
			(xy 45.8343 -110.866936) (xy 45.834808 -110.86719) (xy 45.834808 -111.64951) (xy 45.8343 -111.649764)
			(arc
				(start 45.8343 -111.777018)
				(mid 45.830399 -111.796541)
				(end 45.819314 -111.813086)
			)
			(arc
				(start 45.745146 -111.887254)
				(mid 45.734035 -111.903788)
				(end 45.73016 -111.923322)
			)
			(arc
				(start 45.73016 -113.641378)
				(mid 45.734061 -113.660901)
				(end 45.745146 -113.677446)
			)
			(arc
				(start 45.793914 -113.726214)
				(mid 45.810448 -113.737325)
				(end 45.829982 -113.7412)
			)
		)
		(stroke
			(width 0)
			(type solid)
		)
		(fill yes)
		(layer "F.Cu")
		(net "P3V3_AUX_DSC_G2")
	)
	(gr_poly
		(pts
			(arc
				(start 13.865606 -201.752962)
				(mid 13.880024 -201.750873)
				(end 13.893292 -201.744834)
			)
			(arc
				(start 13.893292 -201.744834)
				(mid 14.025877 -201.683575)
				(end 14.170406 -201.662538)
			)
			(arc
				(start 14.170406 -201.662538)
				(mid 14.314932 -201.683584)
				(end 14.44752 -201.744834)
			)
			(arc
				(start 14.44752 -201.744834)
				(mid 14.460769 -201.750937)
				(end 14.475206 -201.752962)
			)
			(xy 15.549118 -201.752962) (xy 15.80134 -201.50074) (xy 15.80134 -196.925946) (xy 15.65148 -196.776086)
			(arc
				(start 13.455396 -196.776086)
				(mid 13.419475 -196.790965)
				(end 13.404596 -196.826886)
			)
			(xy 13.404596 -197.62597) (xy 13.40866 -197.630034) (xy 13.40866 -197.88124) (xy 13.3604 -197.9295)
			(xy 12.44092 -197.9295) (xy 12.39266 -197.88124) (xy 12.39266 -196.870066) (xy 12.29868 -196.776086)
			(arc
				(start 11.19251 -196.776086)
				(mid 11.172987 -196.779987)
				(end 11.156442 -196.791072)
			)
			(arc
				(start 11.055858 -196.891656)
				(mid 11.044747 -196.90819)
				(end 11.040872 -196.927724)
			)
			(arc
				(start 11.040872 -201.359008)
				(mid 11.044773 -201.378531)
				(end 11.055858 -201.395076)
			)
			(arc
				(start 11.398758 -201.737976)
				(mid 11.415292 -201.749087)
				(end 11.434826 -201.752962)
			)
		)
		(stroke
			(width 0)
			(type solid)
		)
		(fill yes)
		(layer "F.Cu")
		(net "P12V_AUX")
	)
	(gr_poly
		(pts
			(arc
				(start 39.607998 -123.58878)
				(mid 39.627521 -123.584879)
				(end 39.644066 -123.573794)
			)
			(arc
				(start 40.050974 -123.166886)
				(mid 40.062085 -123.150352)
				(end 40.06596 -123.130818)
			)
			(arc
				(start 40.06596 -118.626128)
				(mid 40.053161 -118.592512)
				(end 40.021256 -118.575836)
			)
			(xy 39.818564 -118.575836)
			(arc
				(start 39.818564 -117.934232)
				(mid 39.804016 -117.904638)
				(end 39.774368 -117.890036)
			)
			(xy 39.564564 -117.890036)
			(arc
				(start 39.564564 -114.835432)
				(mid 39.550016 -114.805838)
				(end 39.520368 -114.791236)
			)
			(arc
				(start 35.292792 -114.791236)
				(mid 35.26312 -114.80576)
				(end 35.248596 -114.835432)
			)
			(xy 35.248596 -117.890036)
			(arc
				(start 35.038792 -117.890036)
				(mid 35.00912 -117.90456)
				(end 34.994596 -117.934232)
			)
			(xy 34.994596 -118.575836) (xy 34.923984 -118.575836) (xy 34.89452 -118.6053)
			(arc
				(start 34.89452 -123.270518)
				(mid 34.898421 -123.290041)
				(end 34.909506 -123.306586)
			)
			(arc
				(start 35.152076 -123.549156)
				(mid 35.168522 -123.560082)
				(end 35.18789 -123.563888)
			)
			(arc
				(start 35.977068 -123.563888)
				(mid 36.056875 -123.569694)
				(end 36.135056 -123.586748)
			)
			(xy 36.142168 -123.58878)
		)
		(stroke
			(width 0)
			(type solid)
		)
		(fill yes)
		(layer "F.Cu")
		(net "P12V_AUX_DSC")
	)
	(gr_poly
		(pts
			(arc
				(start 110.579408 -393.889992)
				(mid 110.598931 -393.886091)
				(end 110.615476 -393.875006)
			)
			(arc
				(start 110.669578 -393.820904)
				(mid 110.680689 -393.80437)
				(end 110.684564 -393.784836)
			)
			(xy 110.684564 -393.693904)
			(arc
				(start 110.682532 -393.686792)
				(mid 110.673424 -393.64455)
				(end 110.67034 -393.601448)
			)
			(arc
				(start 110.67034 -392.482324)
				(mid 110.673444 -392.439225)
				(end 110.682532 -392.39698)
			)
			(xy 110.684564 -392.389868)
			(arc
				(start 110.684564 -391.450068)
				(mid 110.680663 -391.430545)
				(end 110.669578 -391.414)
			)
			(arc
				(start 110.531148 -391.27557)
				(mid 110.514614 -391.264459)
				(end 110.49508 -391.260584)
			)
			(arc
				(start 108.852462 -391.260584)
				(mid 108.839743 -391.262202)
				(end 108.827824 -391.266934)
			)
			(arc
				(start 108.827824 -391.266934)
				(mid 108.738631 -391.302362)
				(end 108.64342 -391.314432)
			)
			(arc
				(start 108.64342 -391.314432)
				(mid 108.562045 -391.305597)
				(end 108.484416 -391.279634)
			)
			(xy 108.469938 -391.27303) (xy 108.438696 -391.278618)
			(arc
				(start 108.36148 -391.355834)
				(mid 108.344946 -391.366945)
				(end 108.325412 -391.37082)
			)
			(xy 108.307632 -391.3886)
			(arc
				(start 108.307632 -393.405868)
				(mid 108.311582 -393.425255)
				(end 108.322618 -393.441682)
			)
			(arc
				(start 108.755942 -393.875006)
				(mid 108.772359 -393.886068)
				(end 108.791756 -393.889992)
			)
		)
		(stroke
			(width 0)
			(type solid)
		)
		(fill yes)
		(layer "F.Cu")
		(net "P0V9_CPU1_RT3_2A")
	)
	(gr_poly
		(pts
			(arc
				(start 245.112286 -45.94733)
				(mid 245.131809 -45.943429)
				(end 245.148354 -45.932344)
			)
			(arc
				(start 245.32082 -45.759624)
				(mid 245.331746 -45.743178)
				(end 245.335552 -45.72381)
			)
			(arc
				(start 245.335552 -45.517308)
				(mid 245.338159 -45.478499)
				(end 245.345712 -45.440346)
			)
			(xy 245.347236 -45.433996)
			(arc
				(start 245.347236 -45.332142)
				(mid 245.351137 -45.312619)
				(end 245.362222 -45.296074)
			)
			(arc
				(start 245.477792 -45.180504)
				(mid 245.488903 -45.16397)
				(end 245.492778 -45.144436)
			)
			(arc
				(start 245.492778 -44.227242)
				(mid 245.488877 -44.207719)
				(end 245.477792 -44.191174)
			)
			(arc
				(start 245.470934 -44.184316)
				(mid 245.4544 -44.173205)
				(end 245.434866 -44.16933)
			)
			(arc
				(start 244.78107 -44.16933)
				(mid 244.761547 -44.165429)
				(end 244.745002 -44.154344)
			)
			(arc
				(start 244.653562 -44.062904)
				(mid 244.637028 -44.051793)
				(end 244.617494 -44.047918)
			)
			(arc
				(start 243.431568 -44.047918)
				(mid 243.412045 -44.051819)
				(end 243.3955 -44.062904)
			)
			(arc
				(start 243.379498 -44.078906)
				(mid 243.368387 -44.09544)
				(end 243.364512 -44.114974)
			)
			(arc
				(start 243.364512 -45.18533)
				(mid 243.368413 -45.204853)
				(end 243.379498 -45.221398)
			)
			(arc
				(start 244.090444 -45.932344)
				(mid 244.106978 -45.943455)
				(end 244.126512 -45.94733)
			)
		)
		(stroke
			(width 0)
			(type solid)
		)
		(fill yes)
		(layer "F.Cu")
		(net "GND")
	)
	(gr_poly
		(pts
			(arc
				(start 24.264874 -351.509838)
				(mid 24.284106 -351.505995)
				(end 24.300434 -351.495106)
			)
			(arc
				(start 24.36495 -351.43059)
				(mid 24.375905 -351.414289)
				(end 24.379682 -351.39503)
			)
			(arc
				(start 24.379682 -348.182946)
				(mid 24.383525 -348.163714)
				(end 24.394414 -348.147386)
			)
			(arc
				(start 24.54783 -347.99397)
				(mid 24.564131 -347.983015)
				(end 24.58339 -347.979238)
			)
			(xy 24.634444 -347.979238) (xy 24.647906 -347.975174)
			(arc
				(start 24.654256 -347.97111)
				(mid 24.780273 -347.912852)
				(end 24.917654 -347.892878)
			)
			(arc
				(start 24.917654 -347.892878)
				(mid 25.003738 -347.900655)
				(end 25.087072 -347.923612)
			)
			(xy 25.101042 -347.928946) (xy 25.12949 -347.92285)
			(arc
				(start 25.18791 -347.86443)
				(mid 25.198865 -347.848129)
				(end 25.202642 -347.82887)
			)
			(arc
				(start 25.202642 -346.938346)
				(mid 25.198799 -346.919114)
				(end 25.18791 -346.902786)
			)
			(arc
				(start 25.100534 -346.81541)
				(mid 25.084233 -346.804455)
				(end 25.064974 -346.800678)
			)
			(xy 23.894542 -346.800678) (xy 23.56866 -347.12656) (xy 23.56866 -349.24746) (xy 22.604222 -350.211898)
			(arc
				(start 22.604222 -351.38233)
				(mid 22.608065 -351.401562)
				(end 22.618954 -351.41789)
			)
			(arc
				(start 22.69617 -351.495106)
				(mid 22.712471 -351.506061)
				(end 22.73173 -351.509838)
			)
		)
		(stroke
			(width 0)
			(type solid)
		)
		(fill yes)
		(layer "F.Cu")
		(net "PVDDCR_CPU1_P1_PVCC")
	)
	(gr_poly
		(pts
			(arc
				(start 271.120362 -351.418652)
				(mid 271.139594 -351.414809)
				(end 271.155922 -351.40392)
			)
			(arc
				(start 271.220438 -351.339404)
				(mid 271.231393 -351.323103)
				(end 271.23517 -351.303844)
			)
			(arc
				(start 271.23517 -348.12478)
				(mid 271.239013 -348.105548)
				(end 271.249902 -348.08922)
			)
			(arc
				(start 271.352518 -347.986604)
				(mid 271.368819 -347.975649)
				(end 271.388078 -347.971872)
			)
			(xy 271.459706 -347.971872) (xy 271.473168 -347.967808)
			(arc
				(start 271.479264 -347.963998)
				(mid 271.603754 -347.907434)
				(end 271.739106 -347.888052)
			)
			(arc
				(start 271.739106 -347.888052)
				(mid 271.830832 -347.896938)
				(end 271.919192 -347.923104)
			)
			(xy 271.933416 -347.928692) (xy 271.962372 -347.92285)
			(arc
				(start 271.995138 -347.890084)
				(mid 272.006093 -347.873783)
				(end 272.00987 -347.854524)
			)
			(arc
				(start 272.00987 -346.91828)
				(mid 272.006027 -346.899048)
				(end 271.995138 -346.88272)
			)
			(arc
				(start 271.943322 -346.830904)
				(mid 271.927021 -346.819949)
				(end 271.907762 -346.816172)
			)
			(xy 270.994632 -346.816172) (xy 270.764508 -347.046296) (xy 270.764508 -349.0722) (xy 270.665956 -349.170752)
			(xy 269.50924 -350.327468)
			(arc
				(start 269.50924 -351.300034)
				(mid 269.513083 -351.319266)
				(end 269.523972 -351.335594)
			)
			(arc
				(start 269.592298 -351.40392)
				(mid 269.608599 -351.414875)
				(end 269.627858 -351.418652)
			)
		)
		(stroke
			(width 0)
			(type solid)
		)
		(fill yes)
		(layer "F.Cu")
		(net "PVDDCR_CPU1_P0_PVCC")
	)
	(gr_poly
		(pts
			(arc
				(start 346.949522 -396.207742)
				(mid 346.969045 -396.203841)
				(end 346.98559 -396.192756)
			)
			(xy 346.98813 -396.190216) (xy 346.996004 -396.17142)
			(arc
				(start 346.996004 -395.432534)
				(mid 346.992054 -395.413147)
				(end 346.981018 -395.39672)
			)
			(arc
				(start 346.921836 -395.337538)
				(mid 346.905302 -395.326427)
				(end 346.885768 -395.322552)
			)
			(arc
				(start 346.700348 -395.322552)
				(mid 346.680825 -395.326453)
				(end 346.66428 -395.337538)
			)
			(arc
				(start 346.621608 -395.38021)
				(mid 346.610497 -395.396744)
				(end 346.606622 -395.416278)
			)
			(arc
				(start 346.606622 -395.771116)
				(mid 346.602721 -395.790639)
				(end 346.591636 -395.807184)
			)
			(arc
				(start 346.539566 -395.859254)
				(mid 346.523032 -395.870365)
				(end 346.503498 -395.87424)
			)
			(arc
				(start 346.121482 -395.87424)
				(mid 346.101959 -395.878141)
				(end 346.085414 -395.889226)
			)
			(arc
				(start 346.03944 -395.9352)
				(mid 346.028329 -395.951734)
				(end 346.024454 -395.971268)
			)
			(arc
				(start 346.024454 -396.083536)
				(mid 346.028355 -396.103059)
				(end 346.03944 -396.119604)
			)
			(xy 346.066872 -396.147036) (xy 346.092526 -396.154148)
			(arc
				(start 346.105734 -396.150846)
				(mid 346.151612 -396.142295)
				(end 346.19819 -396.139416)
			)
			(arc
				(start 346.19819 -396.139416)
				(mid 346.252334 -396.143351)
				(end 346.305378 -396.15491)
			)
			(arc
				(start 346.478606 -396.20571)
				(mid 346.485772 -396.207249)
				(end 346.493084 -396.207742)
			)
		)
		(stroke
			(width 0)
			(type solid)
		)
		(fill yes)
		(layer "F.Cu")
		(net "P1V8_CPU0_RT1_1A_1D")
	)
	(gr_poly
		(pts
			(xy 34.328608 -427.211744) (xy 34.328608 -426.673264) (xy 34.475928 -426.525944) (xy 34.943288 -426.525944)
			(xy 35.060128 -426.409104) (xy 35.060128 -425.540424) (xy 35.220148 -425.380404) (xy 35.758628 -425.380404)
			(xy 35.791648 -425.347384) (xy 35.791648 -424.880024) (xy 35.753548 -424.841924) (xy 35.171888 -424.841924)
			(xy 35.055048 -424.725084) (xy 35.055048 -424.341544) (xy 35.207448 -424.189144) (xy 35.740848 -424.189144)
			(xy 35.781488 -424.148504) (xy 35.781488 -424.069764) (xy 35.740848 -424.029124) (xy 35.141408 -424.029124)
			(xy 35.057588 -423.945304) (xy 35.057588 -423.317924) (xy 34.856928 -423.117264) (xy 34.508948 -423.117264)
			(xy 34.310828 -422.919144) (xy 34.310828 -422.195244) (xy 34.287968 -422.172384) (xy 34.211768 -422.172384)
			(xy 34.191448 -422.192704) (xy 34.191448 -422.901364) (xy 34.059368 -423.033444) (xy 33.640268 -423.033444)
			(xy 33.533588 -423.140124) (xy 33.533588 -423.790364) (xy 33.282128 -424.041824) (xy 32.746188 -424.041824)
			(xy 32.723328 -424.064684) (xy 32.723328 -424.153584) (xy 32.746188 -424.176444) (xy 33.315148 -424.176444)
			(xy 33.515808 -424.377104) (xy 33.515808 -425.062904) (xy 33.335468 -425.243244) (xy 32.748728 -425.243244)
			(xy 32.720788 -425.271184) (xy 32.720788 -425.360084) (xy 32.741108 -425.380404) (xy 33.340548 -425.380404)
			(xy 33.487868 -425.527724) (xy 33.487868 -426.289724) (xy 33.670748 -426.472604) (xy 33.995868 -426.472604)
			(xy 34.176208 -426.652944) (xy 34.176208 -427.204124) (xy 34.214308 -427.242224) (xy 34.298128 -427.242224)
		)
		(stroke
			(width 0)
			(type solid)
		)
		(fill yes)
		(layer "F.Cu")
		(net "GND")
	)
	(gr_poly
		(pts
			(arc
				(start 90.94978 -387.825742)
				(mid 90.969303 -387.821841)
				(end 90.985848 -387.810756)
			)
			(arc
				(start 90.992198 -387.804406)
				(mid 91.003309 -387.787872)
				(end 91.007184 -387.768338)
			)
			(arc
				(start 91.007184 -387.06171)
				(mid 91.003283 -387.042187)
				(end 90.992198 -387.025642)
			)
			(arc
				(start 90.922094 -386.955538)
				(mid 90.90556 -386.944427)
				(end 90.886026 -386.940552)
			)
			(arc
				(start 90.700606 -386.940552)
				(mid 90.681083 -386.944453)
				(end 90.664538 -386.955538)
			)
			(arc
				(start 90.621866 -386.99821)
				(mid 90.610755 -387.014744)
				(end 90.60688 -387.034278)
			)
			(arc
				(start 90.60688 -387.389116)
				(mid 90.602979 -387.408639)
				(end 90.591894 -387.425184)
			)
			(arc
				(start 90.539824 -387.477254)
				(mid 90.52329 -387.488365)
				(end 90.503756 -387.49224)
			)
			(arc
				(start 90.12174 -387.49224)
				(mid 90.102217 -387.496141)
				(end 90.085672 -387.507226)
			)
			(arc
				(start 90.039698 -387.5532)
				(mid 90.028587 -387.569734)
				(end 90.024712 -387.589268)
			)
			(arc
				(start 90.024712 -387.701536)
				(mid 90.028613 -387.721059)
				(end 90.039698 -387.737604)
			)
			(xy 90.06713 -387.765036) (xy 90.092784 -387.772148)
			(arc
				(start 90.105992 -387.768846)
				(mid 90.15187 -387.760295)
				(end 90.198448 -387.757416)
			)
			(arc
				(start 90.198448 -387.757416)
				(mid 90.252592 -387.761351)
				(end 90.305636 -387.77291)
			)
			(arc
				(start 90.478864 -387.82371)
				(mid 90.48603 -387.825249)
				(end 90.493342 -387.825742)
			)
		)
		(stroke
			(width 0)
			(type solid)
		)
		(fill yes)
		(layer "F.Cu")
		(net "P1V8_CPU1_RT1_1A_1D")
	)
	(gr_poly
		(pts
			(arc
				(start 125.521974 -387.825742)
				(mid 125.541497 -387.821841)
				(end 125.558042 -387.810756)
			)
			(arc
				(start 125.564392 -387.804406)
				(mid 125.575503 -387.787872)
				(end 125.579378 -387.768338)
			)
			(arc
				(start 125.579378 -387.06171)
				(mid 125.575477 -387.042187)
				(end 125.564392 -387.025642)
			)
			(arc
				(start 125.494288 -386.955538)
				(mid 125.477754 -386.944427)
				(end 125.45822 -386.940552)
			)
			(arc
				(start 125.2728 -386.940552)
				(mid 125.253277 -386.944453)
				(end 125.236732 -386.955538)
			)
			(arc
				(start 125.19406 -386.99821)
				(mid 125.182949 -387.014744)
				(end 125.179074 -387.034278)
			)
			(arc
				(start 125.179074 -387.389116)
				(mid 125.175173 -387.408639)
				(end 125.164088 -387.425184)
			)
			(arc
				(start 125.112018 -387.477254)
				(mid 125.095484 -387.488365)
				(end 125.07595 -387.49224)
			)
			(arc
				(start 124.693934 -387.49224)
				(mid 124.674411 -387.496141)
				(end 124.657866 -387.507226)
			)
			(arc
				(start 124.611892 -387.5532)
				(mid 124.600781 -387.569734)
				(end 124.596906 -387.589268)
			)
			(arc
				(start 124.596906 -387.701536)
				(mid 124.600807 -387.721059)
				(end 124.611892 -387.737604)
			)
			(xy 124.639324 -387.765036) (xy 124.664978 -387.772148)
			(arc
				(start 124.678186 -387.768846)
				(mid 124.724064 -387.760295)
				(end 124.770642 -387.757416)
			)
			(arc
				(start 124.770642 -387.757416)
				(mid 124.824786 -387.761351)
				(end 124.87783 -387.77291)
			)
			(arc
				(start 125.051058 -387.82371)
				(mid 125.058224 -387.825249)
				(end 125.065536 -387.825742)
			)
		)
		(stroke
			(width 0)
			(type solid)
		)
		(fill yes)
		(layer "F.Cu")
		(net "P1V8_CPU1_RT3_1A_1D")
	)
	(gr_poly
		(pts
			(arc
				(start 158.049722 -387.825742)
				(mid 158.069245 -387.821841)
				(end 158.08579 -387.810756)
			)
			(arc
				(start 158.09214 -387.804406)
				(mid 158.103251 -387.787872)
				(end 158.107126 -387.768338)
			)
			(arc
				(start 158.107126 -387.06171)
				(mid 158.103225 -387.042187)
				(end 158.09214 -387.025642)
			)
			(arc
				(start 158.022036 -386.955538)
				(mid 158.005502 -386.944427)
				(end 157.985968 -386.940552)
			)
			(arc
				(start 157.800548 -386.940552)
				(mid 157.781025 -386.944453)
				(end 157.76448 -386.955538)
			)
			(arc
				(start 157.721808 -386.99821)
				(mid 157.710697 -387.014744)
				(end 157.706822 -387.034278)
			)
			(arc
				(start 157.706822 -387.389116)
				(mid 157.702921 -387.408639)
				(end 157.691836 -387.425184)
			)
			(arc
				(start 157.639766 -387.477254)
				(mid 157.623232 -387.488365)
				(end 157.603698 -387.49224)
			)
			(arc
				(start 157.221682 -387.49224)
				(mid 157.202159 -387.496141)
				(end 157.185614 -387.507226)
			)
			(arc
				(start 157.13964 -387.5532)
				(mid 157.128529 -387.569734)
				(end 157.124654 -387.589268)
			)
			(arc
				(start 157.124654 -387.701536)
				(mid 157.128555 -387.721059)
				(end 157.13964 -387.737604)
			)
			(xy 157.167072 -387.765036) (xy 157.192726 -387.772148)
			(arc
				(start 157.205934 -387.768846)
				(mid 157.251812 -387.760295)
				(end 157.29839 -387.757416)
			)
			(arc
				(start 157.29839 -387.757416)
				(mid 157.352534 -387.761351)
				(end 157.405578 -387.77291)
			)
			(arc
				(start 157.578806 -387.82371)
				(mid 157.585972 -387.825249)
				(end 157.593284 -387.825742)
			)
		)
		(stroke
			(width 0)
			(type solid)
		)
		(fill yes)
		(layer "F.Cu")
		(net "P1V8_CPU1_RT2_1A_1D")
	)
	(gr_poly
		(pts
			(arc
				(start 172.675804 -423.154602)
				(mid 172.695327 -423.150701)
				(end 172.711872 -423.139616)
			)
			(arc
				(start 172.797978 -423.05351)
				(mid 172.809089 -423.036976)
				(end 172.812964 -423.017442)
			)
			(arc
				(start 172.812964 -420.548308)
				(mid 172.809063 -420.528785)
				(end 172.797978 -420.51224)
			)
			(xy 172.713396 -420.427658) (xy 172.689012 -420.420546)
			(arc
				(start 172.676312 -420.42334)
				(mid 172.623893 -420.431562)
				(end 172.570902 -420.434262)
			)
			(arc
				(start 172.570902 -420.434262)
				(mid 172.211333 -420.285323)
				(end 172.062394 -419.925754)
			)
			(arc
				(start 172.062394 -419.925754)
				(mid 172.088196 -419.765874)
				(end 172.162978 -419.622224)
			)
			(xy 172.174154 -419.606984) (xy 172.17136 -419.569392)
			(arc
				(start 172.138594 -419.536626)
				(mid 172.12206 -419.525515)
				(end 172.102526 -419.52164)
			)
			(arc
				(start 171.759626 -419.52164)
				(mid 171.740103 -419.525541)
				(end 171.723558 -419.536626)
			)
			(xy 171.719494 -419.54069) (xy 171.711874 -419.559232) (xy 171.711874 -422.759632) (xy 171.711112 -422.760394)
			(xy 171.711112 -423.13479)
			(arc
				(start 171.715938 -423.139616)
				(mid 171.732472 -423.150727)
				(end 171.752006 -423.154602)
			)
		)
		(stroke
			(width 0)
			(type solid)
		)
		(fill yes)
		(layer "F.Cu")
		(net "P1V8_CPU1_RT_1D")
	)
	(gr_poly
		(pts
			(arc
				(start 314.421774 -396.207742)
				(mid 314.441297 -396.203841)
				(end 314.457842 -396.192756)
			)
			(arc
				(start 314.464192 -396.186406)
				(mid 314.475303 -396.169872)
				(end 314.479178 -396.150338)
			)
			(arc
				(start 314.479178 -395.44371)
				(mid 314.475277 -395.424187)
				(end 314.464192 -395.407642)
			)
			(arc
				(start 314.394088 -395.337538)
				(mid 314.377554 -395.326427)
				(end 314.35802 -395.322552)
			)
			(arc
				(start 314.1726 -395.322552)
				(mid 314.153077 -395.326453)
				(end 314.136532 -395.337538)
			)
			(arc
				(start 314.09386 -395.38021)
				(mid 314.082749 -395.396744)
				(end 314.078874 -395.416278)
			)
			(arc
				(start 314.078874 -395.771116)
				(mid 314.074973 -395.790639)
				(end 314.063888 -395.807184)
			)
			(arc
				(start 314.011818 -395.859254)
				(mid 313.995284 -395.870365)
				(end 313.97575 -395.87424)
			)
			(arc
				(start 313.593734 -395.87424)
				(mid 313.574211 -395.878141)
				(end 313.557666 -395.889226)
			)
			(arc
				(start 313.511692 -395.9352)
				(mid 313.500581 -395.951734)
				(end 313.496706 -395.971268)
			)
			(arc
				(start 313.496706 -396.083536)
				(mid 313.500607 -396.103059)
				(end 313.511692 -396.119604)
			)
			(xy 313.539124 -396.147036) (xy 313.564778 -396.154148)
			(arc
				(start 313.577986 -396.150846)
				(mid 313.623864 -396.142295)
				(end 313.670442 -396.139416)
			)
			(arc
				(start 313.670442 -396.139416)
				(mid 313.724586 -396.143351)
				(end 313.77763 -396.15491)
			)
			(arc
				(start 313.950858 -396.20571)
				(mid 313.958024 -396.207249)
				(end 313.965336 -396.207742)
			)
		)
		(stroke
			(width 0)
			(type solid)
		)
		(fill yes)
		(layer "F.Cu")
		(net "P1V8_CPU0_RT0_1A_1D")
	)
	(gr_poly
		(pts
			(arc
				(start 381.52197 -396.207742)
				(mid 381.541493 -396.203841)
				(end 381.558038 -396.192756)
			)
			(arc
				(start 381.564388 -396.186406)
				(mid 381.575499 -396.169872)
				(end 381.579374 -396.150338)
			)
			(arc
				(start 381.579374 -395.44371)
				(mid 381.575473 -395.424187)
				(end 381.564388 -395.407642)
			)
			(arc
				(start 381.494284 -395.337538)
				(mid 381.47775 -395.326427)
				(end 381.458216 -395.322552)
			)
			(arc
				(start 381.272796 -395.322552)
				(mid 381.253273 -395.326453)
				(end 381.236728 -395.337538)
			)
			(arc
				(start 381.194056 -395.38021)
				(mid 381.182945 -395.396744)
				(end 381.17907 -395.416278)
			)
			(arc
				(start 381.17907 -395.771116)
				(mid 381.175169 -395.790639)
				(end 381.164084 -395.807184)
			)
			(arc
				(start 381.112014 -395.859254)
				(mid 381.09548 -395.870365)
				(end 381.075946 -395.87424)
			)
			(arc
				(start 380.69393 -395.87424)
				(mid 380.674407 -395.878141)
				(end 380.657862 -395.889226)
			)
			(arc
				(start 380.611888 -395.9352)
				(mid 380.600777 -395.951734)
				(end 380.596902 -395.971268)
			)
			(arc
				(start 380.596902 -396.083536)
				(mid 380.600803 -396.103059)
				(end 380.611888 -396.119604)
			)
			(xy 380.63932 -396.147036) (xy 380.664974 -396.154148)
			(arc
				(start 380.678182 -396.150846)
				(mid 380.72406 -396.142295)
				(end 380.770638 -396.139416)
			)
			(arc
				(start 380.770638 -396.139416)
				(mid 380.824782 -396.143351)
				(end 380.877826 -396.15491)
			)
			(arc
				(start 381.051054 -396.20571)
				(mid 381.05822 -396.207249)
				(end 381.065532 -396.207742)
			)
		)
		(stroke
			(width 0)
			(type solid)
		)
		(fill yes)
		(layer "F.Cu")
		(net "P1V8_CPU0_RT3_1A_1D")
	)
	(gr_poly
		(pts
			(arc
				(start 414.049718 -396.207742)
				(mid 414.069241 -396.203841)
				(end 414.085786 -396.192756)
			)
			(arc
				(start 414.092136 -396.186406)
				(mid 414.103247 -396.169872)
				(end 414.107122 -396.150338)
			)
			(arc
				(start 414.107122 -395.44371)
				(mid 414.103221 -395.424187)
				(end 414.092136 -395.407642)
			)
			(arc
				(start 414.022032 -395.337538)
				(mid 414.005498 -395.326427)
				(end 413.985964 -395.322552)
			)
			(arc
				(start 413.800544 -395.322552)
				(mid 413.781021 -395.326453)
				(end 413.764476 -395.337538)
			)
			(arc
				(start 413.721804 -395.38021)
				(mid 413.710693 -395.396744)
				(end 413.706818 -395.416278)
			)
			(arc
				(start 413.706818 -395.771116)
				(mid 413.702917 -395.790639)
				(end 413.691832 -395.807184)
			)
			(arc
				(start 413.639762 -395.859254)
				(mid 413.623228 -395.870365)
				(end 413.603694 -395.87424)
			)
			(arc
				(start 413.221678 -395.87424)
				(mid 413.202155 -395.878141)
				(end 413.18561 -395.889226)
			)
			(arc
				(start 413.139636 -395.9352)
				(mid 413.128525 -395.951734)
				(end 413.12465 -395.971268)
			)
			(arc
				(start 413.12465 -396.083536)
				(mid 413.128551 -396.103059)
				(end 413.139636 -396.119604)
			)
			(xy 413.167068 -396.147036) (xy 413.192722 -396.154148)
			(arc
				(start 413.20593 -396.150846)
				(mid 413.251808 -396.142295)
				(end 413.298386 -396.139416)
			)
			(arc
				(start 413.298386 -396.139416)
				(mid 413.35253 -396.143351)
				(end 413.405574 -396.15491)
			)
			(arc
				(start 413.578802 -396.20571)
				(mid 413.585968 -396.207249)
				(end 413.59328 -396.207742)
			)
		)
		(stroke
			(width 0)
			(type solid)
		)
		(fill yes)
		(layer "F.Cu")
		(net "P1V8_CPU0_RT2_1A_1D")
	)
	(gr_poly
		(pts
			(xy 114.025172 -412.45409)
			(arc
				(start 114.031268 -412.439866)
				(mid 114.137995 -412.304676)
				(end 114.298222 -412.241492)
			)
			(xy 114.310668 -412.240222) (xy 114.331242 -412.226252) (xy 114.383058 -412.131256) (xy 114.383566 -412.106364)
			(arc
				(start 114.377978 -412.095188)
				(mid 114.349938 -412.017871)
				(end 114.340386 -411.936184)
			)
			(arc
				(start 114.340386 -411.936184)
				(mid 114.374891 -411.783208)
				(end 114.471704 -411.659832)
			)
			(arc
				(start 114.471704 -411.659832)
				(mid 114.485515 -411.642262)
				(end 114.4905 -411.620462)
			)
			(arc
				(start 114.4905 -410.713174)
				(mid 114.486599 -410.693651)
				(end 114.475514 -410.677106)
			)
			(xy 114.384582 -410.586174) (xy 114.365532 -410.578554) (xy 114.354864 -410.578808)
			(arc
				(start 114.34572 -410.578808)
				(mid 114.299926 -410.57608)
				(end 114.254788 -410.567886)
			)
			(xy 114.248946 -410.566362)
			(arc
				(start 112.915954 -410.566362)
				(mid 112.896431 -410.570263)
				(end 112.879886 -410.581348)
			)
			(arc
				(start 112.813592 -410.647642)
				(mid 112.802481 -410.664176)
				(end 112.798606 -410.68371)
			)
			(arc
				(start 112.798606 -412.319724)
				(mid 112.802507 -412.339247)
				(end 112.813592 -412.355792)
			)
			(arc
				(start 112.913414 -412.455614)
				(mid 112.929948 -412.466725)
				(end 112.949482 -412.4706)
			)
			(xy 114.000026 -412.4706)
		)
		(stroke
			(width 0)
			(type solid)
		)
		(fill yes)
		(layer "F.Cu")
		(net "GND")
	)
	(gr_poly
		(pts
			(arc
				(start 425.74591 -401.099274)
				(mid 425.765433 -401.095373)
				(end 425.781978 -401.084288)
			)
			(arc
				(start 425.840144 -401.026122)
				(mid 425.851255 -401.009588)
				(end 425.85513 -400.990054)
			)
			(arc
				(start 425.85513 -398.202404)
				(mid 425.840251 -398.166483)
				(end 425.80433 -398.151604)
			)
			(arc
				(start 424.719242 -398.151604)
				(mid 424.69568 -398.15072)
				(end 424.672252 -398.148048)
			)
			(xy 424.66006 -398.14627) (xy 424.637454 -398.153636) (xy 424.54449 -398.2466)
			(arc
				(start 424.54068 -398.255236)
				(mid 424.471468 -398.356712)
				(end 424.369992 -398.425924)
			)
			(xy 424.361356 -398.429734) (xy 423.706036 -399.085054) (xy 423.69867 -399.109438)
			(arc
				(start 423.701464 -399.122138)
				(mid 423.707583 -399.161423)
				(end 423.709592 -399.201132)
			)
			(arc
				(start 423.709592 -399.201132)
				(mid 423.694298 -399.308034)
				(end 423.649648 -399.406364)
			)
			(arc
				(start 423.649648 -399.406364)
				(mid 423.643742 -399.419515)
				(end 423.641774 -399.433796)
			)
			(arc
				(start 423.641774 -400.196304)
				(mid 423.645724 -400.215691)
				(end 423.65676 -400.232118)
			)
			(arc
				(start 424.335702 -400.911314)
				(mid 424.343413 -400.917599)
				(end 424.352212 -400.922236)
			)
			(arc
				(start 424.618658 -401.032726)
				(mid 424.663948 -401.056073)
				(end 424.704764 -401.086574)
			)
			(arc
				(start 424.704764 -401.086574)
				(mid 424.720374 -401.095958)
				(end 424.738292 -401.099274)
			)
		)
		(stroke
			(width 0)
			(type solid)
		)
		(fill yes)
		(layer "F.Cu")
		(net "P0V9_CPU0_RT2_2A")
	)
	(gr_poly
		(pts
			(arc
				(start 99.209606 -411.470348)
				(mid 99.245584 -411.485362)
				(end 99.281488 -411.470348)
			)
			(arc
				(start 99.288092 -411.463744)
				(mid 99.47034 -411.341906)
				(end 99.685348 -411.299152)
			)
			(xy 100.076 -411.299152) (xy 100.098606 -411.29966) (xy 100.10902 -411.300168) (xy 100.128324 -411.292802)
			(arc
				(start 100.188776 -411.23489)
				(mid 100.200263 -411.218182)
				(end 100.20427 -411.198314)
			)
			(arc
				(start 100.20427 -410.05379)
				(mid 100.200369 -410.034267)
				(end 100.189284 -410.017722)
			)
			(arc
				(start 100.041456 -409.869894)
				(mid 100.024922 -409.858783)
				(end 100.005388 -409.854908)
			)
			(arc
				(start 98.371152 -409.854908)
				(mid 98.351629 -409.858809)
				(end 98.335084 -409.869894)
			)
			(arc
				(start 98.212656 -409.992322)
				(mid 98.201545 -410.008856)
				(end 98.19767 -410.02839)
			)
			(arc
				(start 98.19767 -411.207966)
				(mid 98.202533 -411.229404)
				(end 98.215958 -411.246828)
			)
			(xy 98.284284 -411.304232) (xy 98.30562 -411.310074)
			(arc
				(start 98.31705 -411.308042)
				(mid 98.366003 -411.301434)
				(end 98.415348 -411.299152)
			)
			(arc
				(start 98.806 -411.299152)
				(mid 99.024849 -411.343634)
				(end 99.209098 -411.46984)
			)
			(xy 99.209352 -411.470094)
		)
		(stroke
			(width 0)
			(type solid)
		)
		(fill yes)
		(layer "F.Cu")
		(net "P3V3_AUX")
	)
	(gr_poly
		(pts
			(arc
				(start 112.810036 -415.824416)
				(mid 112.829423 -415.820466)
				(end 112.84585 -415.80943)
			)
			(arc
				(start 112.877346 -415.777934)
				(mid 113.021157 -415.673802)
				(end 113.190274 -415.619692)
			)
			(xy 113.209324 -415.616898) (xy 113.233708 -415.588704)
			(arc
				(start 113.233708 -415.417)
				(mid 113.276374 -415.202034)
				(end 113.398046 -415.019744)
			)
			(arc
				(start 113.47958 -414.93821)
				(mid 113.490642 -414.921793)
				(end 113.494566 -414.902396)
			)
			(arc
				(start 113.494566 -414.45053)
				(mid 113.490665 -414.431007)
				(end 113.47958 -414.414462)
			)
			(arc
				(start 113.265204 -414.200086)
				(mid 113.24867 -414.188975)
				(end 113.229136 -414.1851)
			)
			(arc
				(start 111.78286 -414.1851)
				(mid 111.763337 -414.189001)
				(end 111.746792 -414.200086)
			)
			(arc
				(start 111.64316 -414.303718)
				(mid 111.632049 -414.320252)
				(end 111.628174 -414.339786)
			)
			(arc
				(start 111.628174 -415.688526)
				(mid 111.632075 -415.708049)
				(end 111.64316 -415.724594)
			)
			(arc
				(start 111.66856 -415.749994)
				(mid 111.685094 -415.761105)
				(end 111.704628 -415.76498)
			)
			(xy 111.77778 -415.76498) (xy 111.781844 -415.769044)
			(arc
				(start 112.040416 -415.769044)
				(mid 112.059939 -415.772945)
				(end 112.076484 -415.78403)
			)
			(arc
				(start 112.101884 -415.80943)
				(mid 112.118418 -415.820541)
				(end 112.137952 -415.824416)
			)
		)
		(stroke
			(width 0)
			(type solid)
		)
		(fill yes)
		(layer "F.Cu")
		(net "P3V3_AUX")
	)
	(gr_poly
		(pts
			(arc
				(start 194.023488 -377.141994)
				(mid 194.046773 -377.136343)
				(end 194.06489 -377.120658)
			)
			(arc
				(start 194.06489 -377.120658)
				(mid 194.789986 -376.746376)
				(end 195.514976 -377.120658)
			)
			(arc
				(start 195.514976 -377.120658)
				(mid 195.533086 -377.136358)
				(end 195.556378 -377.141994)
			)
			(arc
				(start 199.301862 -377.141994)
				(mid 199.321385 -377.138093)
				(end 199.33793 -377.127008)
			)
			(arc
				(start 199.500998 -376.96394)
				(mid 199.512109 -376.947406)
				(end 199.515984 -376.927872)
			)
			(arc
				(start 199.515984 -375.898156)
				(mid 199.512083 -375.878633)
				(end 199.500998 -375.862088)
			)
			(arc
				(start 199.32523 -375.68632)
				(mid 199.308696 -375.675209)
				(end 199.289162 -375.671334)
			)
			(arc
				(start 192.270126 -375.671334)
				(mid 192.250603 -375.675235)
				(end 192.234058 -375.68632)
			)
			(arc
				(start 192.20053 -375.719848)
				(mid 192.189419 -375.736382)
				(end 192.185544 -375.755916)
			)
			(arc
				(start 192.185544 -376.927872)
				(mid 192.189445 -376.947395)
				(end 192.20053 -376.96394)
			)
			(arc
				(start 192.363598 -377.127008)
				(mid 192.380132 -377.138119)
				(end 192.399666 -377.141994)
			)
		)
		(stroke
			(width 0)
			(type solid)
		)
		(fill yes)
		(layer "F.Cu")
		(net "GND")
	)
	(gr_poly
		(pts
			(arc
				(start 179.424838 -34.11728)
				(mid 179.444361 -34.113379)
				(end 179.460906 -34.102294)
			)
			(arc
				(start 179.494434 -34.068766)
				(mid 179.505545 -34.052232)
				(end 179.50942 -34.032698)
			)
			(xy 179.50942 -33.648142) (xy 179.514754 -33.642808)
			(arc
				(start 179.514754 -33.18891)
				(mid 179.510853 -33.169387)
				(end 179.499768 -33.152842)
			)
			(arc
				(start 179.348384 -33.001458)
				(mid 179.33185 -32.990347)
				(end 179.312316 -32.986472)
			)
			(arc
				(start 178.825398 -32.986472)
				(mid 178.805875 -32.990373)
				(end 178.78933 -33.001458)
			)
			(arc
				(start 178.717702 -33.073086)
				(mid 178.701168 -33.084197)
				(end 178.681634 -33.088072)
			)
			(arc
				(start 173.359318 -33.088072)
				(mid 173.339795 -33.091973)
				(end 173.32325 -33.103058)
			)
			(arc
				(start 173.266862 -33.159446)
				(mid 173.255751 -33.17598)
				(end 173.251876 -33.195514)
			)
			(arc
				(start 173.251876 -33.434528)
				(mid 173.261092 -33.463707)
				(end 173.285404 -33.48228)
			)
			(arc
				(start 173.731682 -33.644586)
				(mid 173.740174 -33.64699)
				(end 173.748954 -33.647888)
			)
			(arc
				(start 178.392836 -33.647888)
				(mid 178.551859 -33.670322)
				(end 178.698398 -33.736026)
			)
			(xy 178.704748 -33.74009) (xy 178.71821 -33.7439)
			(arc
				(start 178.779678 -33.7439)
				(mid 178.799201 -33.747801)
				(end 178.815746 -33.758886)
			)
			(xy 178.978814 -33.921954) (xy 178.986434 -33.928304)
			(arc
				(start 179.25669 -34.108644)
				(mid 179.270142 -34.115083)
				(end 179.284884 -34.11728)
			)
		)
		(stroke
			(width 0)
			(type solid)
		)
		(fill yes)
		(layer "F.Cu")
		(net "GND")
	)
	(gr_poly
		(pts
			(arc
				(start 58.373772 -387.903466)
				(mid 58.382147 -387.902771)
				(end 58.390282 -387.900672)
			)
			(arc
				(start 58.434478 -387.885432)
				(mid 58.455578 -387.871366)
				(end 58.467244 -387.848856)
			)
			(xy 58.473594 -387.821678) (xy 58.46826 -387.816344)
			(arc
				(start 58.46826 -386.96265)
				(mid 58.457858 -386.93185)
				(end 58.430922 -386.913628)
			)
			(arc
				(start 58.212228 -386.853684)
				(mid 58.196491 -386.851999)
				(end 58.180986 -386.855208)
			)
			(arc
				(start 58.095896 -386.886958)
				(mid 58.086261 -386.891845)
				(end 58.077862 -386.898642)
			)
			(arc
				(start 58.069988 -386.906516)
				(mid 58.058877 -386.92305)
				(end 58.055002 -386.942584)
			)
			(arc
				(start 58.055002 -387.413246)
				(mid 58.051101 -387.432769)
				(end 58.040016 -387.449314)
			)
			(arc
				(start 58.012076 -387.477254)
				(mid 57.995542 -387.488365)
				(end 57.976008 -387.49224)
			)
			(arc
				(start 57.593992 -387.49224)
				(mid 57.574469 -387.496141)
				(end 57.557924 -387.507226)
			)
			(arc
				(start 57.51195 -387.5532)
				(mid 57.500839 -387.569734)
				(end 57.496964 -387.589268)
			)
			(arc
				(start 57.496964 -387.701536)
				(mid 57.500865 -387.721059)
				(end 57.51195 -387.737604)
			)
			(xy 57.539382 -387.765036) (xy 57.565036 -387.772148)
			(arc
				(start 57.578244 -387.768846)
				(mid 57.624122 -387.760295)
				(end 57.6707 -387.757416)
			)
			(arc
				(start 57.6707 -387.757416)
				(mid 57.724844 -387.761351)
				(end 57.777888 -387.77291)
			)
			(xy 57.958228 -387.825742) (xy 57.967372 -387.825742) (xy 57.971182 -387.829552)
			(arc
				(start 58.216546 -387.901434)
				(mid 58.223586 -387.902955)
				(end 58.23077 -387.903466)
			)
		)
		(stroke
			(width 0)
			(type solid)
		)
		(fill yes)
		(layer "F.Cu")
		(net "P1V8_CPU1_RT0_1A_1D")
	)
	(gr_poly
		(pts
			(arc
				(start 180.65877 -424.001184)
				(mid 180.678293 -423.997283)
				(end 180.694838 -423.986198)
			)
			(arc
				(start 180.835554 -423.845482)
				(mid 180.846665 -423.828948)
				(end 180.85054 -423.809414)
			)
			(arc
				(start 180.85054 -423.254932)
				(mid 180.879496 -423.076677)
				(end 180.96357 -422.916858)
			)
			(arc
				(start 180.96357 -422.916858)
				(mid 180.971123 -422.902442)
				(end 180.97373 -422.886378)
			)
			(arc
				(start 180.97373 -422.579546)
				(mid 180.969829 -422.560023)
				(end 180.958744 -422.543478)
			)
			(xy 180.952902 -422.537636) (xy 180.93436 -422.530016)
			(arc
				(start 180.13807 -422.530016)
				(mid 180.118547 -422.533917)
				(end 180.102002 -422.545002)
			)
			(arc
				(start 179.824888 -422.822116)
				(mid 179.808354 -422.833227)
				(end 179.78882 -422.837102)
			)
			(arc
				(start 178.266598 -422.837102)
				(mid 178.247075 -422.841003)
				(end 178.23053 -422.852088)
			)
			(arc
				(start 178.053492 -423.029126)
				(mid 178.042381 -423.04566)
				(end 178.038506 -423.065194)
			)
			(arc
				(start 178.038506 -423.670984)
				(mid 178.053385 -423.706905)
				(end 178.089306 -423.721784)
			)
			(arc
				(start 178.54168 -423.721784)
				(mid 178.756676 -423.764567)
				(end 178.938936 -423.886376)
			)
			(xy 179.003452 -423.950892) (xy 179.013358 -423.957242)
			(arc
				(start 179.0192 -423.95902)
				(mid 179.064084 -423.975646)
				(end 179.107592 -423.995596)
			)
			(arc
				(start 179.107592 -423.995596)
				(mid 179.118695 -423.999721)
				(end 179.130452 -424.001184)
			)
		)
		(stroke
			(width 0)
			(type solid)
		)
		(fill yes)
		(layer "F.Cu")
		(net "P3V3_AUX")
	)
	(gr_poly
		(pts
			(arc
				(start 74.166222 -391.151364)
				(mid 74.185745 -391.147463)
				(end 74.20229 -391.136378)
			)
			(arc
				(start 74.381868 -390.9568)
				(mid 74.392979 -390.940266)
				(end 74.396854 -390.920732)
			)
			(arc
				(start 74.396854 -390.051544)
				(mid 74.392953 -390.032021)
				(end 74.381868 -390.015476)
			)
			(arc
				(start 74.272902 -389.90651)
				(mid 74.256485 -389.895448)
				(end 74.237088 -389.891524)
			)
			(arc
				(start 73.446894 -389.891524)
				(mid 73.372415 -389.882371)
				(end 73.302368 -389.855456)
			)
			(xy 73.29678 -389.852662) (xy 73.284842 -389.849614)
			(arc
				(start 73.020682 -389.849614)
				(mid 73.001159 -389.845713)
				(end 72.984614 -389.834628)
			)
			(arc
				(start 72.878442 -389.728456)
				(mid 72.861996 -389.71753)
				(end 72.842628 -389.713724)
			)
			(arc
				(start 69.865494 -389.713724)
				(mid 69.829573 -389.728603)
				(end 69.814694 -389.764524)
			)
			(arc
				(start 69.814694 -390.967722)
				(mid 69.818595 -390.987245)
				(end 69.82968 -391.00379)
			)
			(arc
				(start 69.89445 -391.06856)
				(mid 69.910984 -391.079671)
				(end 69.930518 -391.083546)
			)
			(arc
				(start 70.639686 -391.083546)
				(mid 70.659209 -391.079645)
				(end 70.675754 -391.06856)
			)
			(arc
				(start 71.284592 -390.459722)
				(mid 71.301126 -390.448611)
				(end 71.32066 -390.444736)
			)
			(xy 72.113394 -390.444736) (xy 72.139556 -390.44372) (xy 72.165718 -390.444736) (xy 72.748394 -390.444736)
			(xy 72.774556 -390.44372) (xy 72.800718 -390.444736)
			(arc
				(start 73.047606 -390.444736)
				(mid 73.067129 -390.448637)
				(end 73.083674 -390.459722)
			)
			(arc
				(start 73.76033 -391.136378)
				(mid 73.776864 -391.147489)
				(end 73.796398 -391.151364)
			)
		)
		(stroke
			(width 0)
			(type solid)
		)
		(fill yes)
		(layer "F.Cu")
		(net "GND")
	)
	(gr_poly
		(pts
			(arc
				(start 330.228702 -399.577052)
				(mid 330.248225 -399.573151)
				(end 330.26477 -399.562066)
			)
			(arc
				(start 330.38161 -399.445226)
				(mid 330.392721 -399.428692)
				(end 330.396596 -399.409158)
			)
			(arc
				(start 330.396596 -398.433544)
				(mid 330.392695 -398.414021)
				(end 330.38161 -398.397476)
			)
			(arc
				(start 330.272644 -398.28851)
				(mid 330.256227 -398.277448)
				(end 330.23683 -398.273524)
			)
			(arc
				(start 329.446636 -398.273524)
				(mid 329.372157 -398.264371)
				(end 329.30211 -398.237456)
			)
			(xy 329.296522 -398.234662) (xy 329.284584 -398.231614)
			(arc
				(start 329.020424 -398.231614)
				(mid 329.000901 -398.227713)
				(end 328.984356 -398.216628)
			)
			(arc
				(start 328.878184 -398.110456)
				(mid 328.861738 -398.09953)
				(end 328.84237 -398.095724)
			)
			(arc
				(start 325.865236 -398.095724)
				(mid 325.829315 -398.110603)
				(end 325.814436 -398.146524)
			)
			(arc
				(start 325.814436 -399.290286)
				(mid 325.818337 -399.309809)
				(end 325.829422 -399.326354)
			)
			(arc
				(start 325.858886 -399.355818)
				(mid 325.87542 -399.366929)
				(end 325.894954 -399.370804)
			)
			(arc
				(start 326.73417 -399.370804)
				(mid 326.753693 -399.366903)
				(end 326.770238 -399.355818)
			)
			(arc
				(start 327.284334 -398.841722)
				(mid 327.300868 -398.830611)
				(end 327.320402 -398.826736)
			)
			(xy 328.113136 -398.826736) (xy 328.139298 -398.82572) (xy 328.16546 -398.826736) (xy 328.748136 -398.826736)
			(xy 328.774298 -398.82572) (xy 328.80046 -398.826736)
			(arc
				(start 329.047348 -398.826736)
				(mid 329.066871 -398.830637)
				(end 329.083416 -398.841722)
			)
			(arc
				(start 329.80376 -399.562066)
				(mid 329.820294 -399.573177)
				(end 329.839828 -399.577052)
			)
		)
		(stroke
			(width 0)
			(type solid)
		)
		(fill yes)
		(layer "F.Cu")
		(net "GND")
	)
	(gr_poly
		(pts
			(arc
				(start 397.328644 -399.577052)
				(mid 397.348167 -399.573151)
				(end 397.364712 -399.562066)
			)
			(arc
				(start 397.481552 -399.445226)
				(mid 397.492663 -399.428692)
				(end 397.496538 -399.409158)
			)
			(arc
				(start 397.496538 -398.433544)
				(mid 397.492637 -398.414021)
				(end 397.481552 -398.397476)
			)
			(arc
				(start 397.372586 -398.28851)
				(mid 397.356169 -398.277448)
				(end 397.336772 -398.273524)
			)
			(arc
				(start 396.546832 -398.273524)
				(mid 396.472353 -398.264371)
				(end 396.402306 -398.237456)
			)
			(xy 396.396718 -398.234662) (xy 396.38478 -398.231614)
			(arc
				(start 396.120366 -398.231614)
				(mid 396.100843 -398.227713)
				(end 396.084298 -398.216628)
			)
			(arc
				(start 395.978126 -398.110456)
				(mid 395.96168 -398.09953)
				(end 395.942312 -398.095724)
			)
			(arc
				(start 392.965178 -398.095724)
				(mid 392.929257 -398.110603)
				(end 392.914378 -398.146524)
			)
			(arc
				(start 392.914378 -399.425414)
				(mid 392.918279 -399.444937)
				(end 392.929364 -399.461482)
			)
			(arc
				(start 392.954764 -399.486882)
				(mid 392.971298 -399.497993)
				(end 392.990832 -399.501868)
			)
			(arc
				(start 393.703048 -399.501868)
				(mid 393.722571 -399.497967)
				(end 393.739116 -399.486882)
			)
			(arc
				(start 394.384276 -398.841722)
				(mid 394.40081 -398.830611)
				(end 394.420344 -398.826736)
			)
			(xy 395.213078 -398.826736) (xy 395.23924 -398.82572) (xy 395.265402 -398.826736) (xy 395.848078 -398.826736)
			(xy 395.87424 -398.82572) (xy 395.900402 -398.826736)
			(arc
				(start 396.14729 -398.826736)
				(mid 396.166813 -398.830637)
				(end 396.183358 -398.841722)
			)
			(arc
				(start 396.903702 -399.562066)
				(mid 396.920236 -399.573177)
				(end 396.93977 -399.577052)
			)
		)
		(stroke
			(width 0)
			(type solid)
		)
		(fill yes)
		(layer "F.Cu")
		(net "GND")
	)
	(gr_poly
		(pts
			(arc
				(start 322.337938 -363.12094)
				(mid 322.357461 -363.117039)
				(end 322.374006 -363.105954)
			)
			(arc
				(start 322.674234 -362.805726)
				(mid 322.685345 -362.789192)
				(end 322.68922 -362.769658)
			)
			(arc
				(start 322.68922 -361.412282)
				(mid 322.685319 -361.392759)
				(end 322.674234 -361.376214)
			)
			(arc
				(start 320.969386 -359.671366)
				(mid 320.952852 -359.660255)
				(end 320.933318 -359.65638)
			)
			(arc
				(start 319.250822 -359.65638)
				(mid 319.231299 -359.660281)
				(end 319.214754 -359.671366)
			)
			(xy 319.113408 -359.772712) (xy 319.10655 -359.799636)
			(arc
				(start 319.110868 -359.813352)
				(mid 319.123242 -359.868366)
				(end 319.127378 -359.924604)
			)
			(arc
				(start 319.127378 -359.924604)
				(mid 319.113075 -360.028052)
				(end 319.071244 -360.12374)
			)
			(xy 319.067434 -360.13009) (xy 319.063624 -360.143044)
			(arc
				(start 319.063624 -360.192828)
				(mid 319.060009 -360.240879)
				(end 319.049146 -360.287824)
			)
			(xy 319.04686 -360.295444)
			(arc
				(start 319.04686 -360.774996)
				(mid 319.061739 -360.810917)
				(end 319.09766 -360.825796)
			)
			(arc
				(start 319.242186 -360.825796)
				(mid 319.42273 -360.851992)
				(end 319.588388 -360.928412)
			)
			(xy 319.594738 -360.932476) (xy 319.608708 -360.93654)
			(arc
				(start 319.762378 -360.93654)
				(mid 319.781901 -360.940441)
				(end 319.798446 -360.951526)
			)
			(arc
				(start 320.055494 -361.208574)
				(mid 320.066605 -361.225108)
				(end 320.07048 -361.244642)
			)
			(arc
				(start 320.07048 -362.685838)
				(mid 320.074381 -362.705361)
				(end 320.085466 -362.721906)
			)
			(arc
				(start 320.469514 -363.105954)
				(mid 320.486048 -363.117065)
				(end 320.505582 -363.12094)
			)
		)
		(stroke
			(width 0)
			(type solid)
		)
		(fill yes)
		(layer "F.Cu")
		(net "P5V_AUX")
	)
	(gr_poly
		(pts
			(arc
				(start 178.143154 -353.864164)
				(mid 178.182405 -353.859584)
				(end 178.221894 -353.858068)
			)
			(arc
				(start 178.221894 -353.858068)
				(mid 178.261383 -353.859585)
				(end 178.300634 -353.864164)
			)
			(xy 178.304444 -353.864672)
			(arc
				(start 178.429666 -353.864672)
				(mid 178.448898 -353.860829)
				(end 178.465226 -353.84994)
			)
			(arc
				(start 178.506882 -353.808284)
				(mid 178.517837 -353.791983)
				(end 178.521614 -353.772724)
			)
			(arc
				(start 178.521614 -353.02698)
				(mid 178.525457 -353.007748)
				(end 178.536346 -352.99142)
			)
			(xy 178.81346 -352.714306)
			(arc
				(start 178.82108 -352.7044)
				(mid 178.895307 -352.608701)
				(end 178.991006 -352.534474)
			)
			(xy 178.99634 -352.531426) (xy 178.996594 -352.531172)
			(arc
				(start 179.007516 -352.525076)
				(mid 179.118597 -352.481862)
				(end 179.236878 -352.467164)
			)
			(arc
				(start 179.236878 -352.467164)
				(mid 179.323368 -352.474973)
				(end 179.407058 -352.498152)
			)
			(xy 179.420774 -352.503486) (xy 179.44973 -352.497136)
			(arc
				(start 179.533042 -352.413824)
				(mid 179.543997 -352.397523)
				(end 179.547774 -352.378264)
			)
			(arc
				(start 179.547774 -351.51314)
				(mid 179.543931 -351.493908)
				(end 179.533042 -351.47758)
			)
			(arc
				(start 179.455826 -351.400364)
				(mid 179.439525 -351.389409)
				(end 179.420266 -351.385632)
			)
			(arc
				(start 177.099722 -351.385632)
				(mid 177.08049 -351.389475)
				(end 177.064162 -351.400364)
			)
			(arc
				(start 176.699926 -351.7646)
				(mid 176.688971 -351.780901)
				(end 176.685194 -351.80016)
			)
			(arc
				(start 176.685194 -353.617784)
				(mid 176.689037 -353.637016)
				(end 176.699926 -353.653344)
			)
			(arc
				(start 176.896522 -353.84994)
				(mid 176.912823 -353.860895)
				(end 176.932082 -353.864672)
			)
			(xy 178.139344 -353.864672)
		)
		(stroke
			(width 0)
			(type solid)
		)
		(fill yes)
		(layer "F.Cu")
		(net "PVDD11_S3_P1_PVCC")
	)
	(gr_poly
		(pts
			(arc
				(start 2.761742 -157.93466)
				(mid 2.879494 -157.609766)
				(end 3.01117 -157.290262)
			)
			(arc
				(start 3.01117 -157.290262)
				(mid 3.014394 -157.280327)
				(end 3.015488 -157.269942)
			)
			(arc
				(start 3.015488 -81.32826)
				(mid 2.785816 -80.174473)
				(end 2.132076 -79.196438)
			)
			(arc
				(start 1.303528 -78.36789)
				(mid 1.090411 -78.048655)
				(end 1.015492 -77.672184)
			)
			(xy 1.015492 -27.634438) (xy 0.681482 -27.300428) (xy 0.56515 -27.300428) (xy 0.508 -27.357578)
			(arc
				(start 0.508 -77.67193)
				(mid 0.621601 -78.242658)
				(end 0.94488 -78.726538)
			)
			(arc
				(start 1.773428 -79.555086)
				(mid 2.317047 -80.368624)
				(end 2.507996 -81.32826)
			)
			(xy 2.507996 -157.983682) (xy 2.560828 -158.036514) (xy 2.659888 -158.036514)
		)
		(stroke
			(width 0)
			(type solid)
		)
		(fill yes)
		(layer "F.Cu")
		(net "GND")
	)
	(gr_poly
		(pts
			(arc
				(start 104.786938 -143.15948)
				(mid 104.806461 -143.155579)
				(end 104.823006 -143.144494)
			)
			(arc
				(start 105.552494 -142.415006)
				(mid 105.563605 -142.398472)
				(end 105.56748 -142.378938)
			)
			(arc
				(start 105.56748 -137.986262)
				(mid 105.563579 -137.966739)
				(end 105.552494 -137.950194)
			)
			(arc
				(start 105.422446 -137.820146)
				(mid 105.405912 -137.809035)
				(end 105.386378 -137.80516)
			)
			(arc
				(start 104.277922 -137.80516)
				(mid 104.258399 -137.809061)
				(end 104.241854 -137.820146)
			)
			(arc
				(start 104.167686 -137.894314)
				(mid 104.156575 -137.910848)
				(end 104.1527 -137.930382)
			)
			(xy 104.1527 -141.675358) (xy 104.153208 -141.6939) (xy 104.1527 -141.712442) (xy 104.1527 -141.72438)
			(xy 104.152446 -141.724634)
			(arc
				(start 104.15016 -141.741906)
				(mid 104.041456 -141.963656)
				(end 103.819706 -142.07236)
			)
			(xy 103.811324 -142.073376) (xy 103.796338 -142.080742)
			(arc
				(start 103.710486 -142.166594)
				(mid 103.693952 -142.177705)
				(end 103.674418 -142.18158)
			)
			(arc
				(start 102.314502 -142.18158)
				(mid 102.294979 -142.185481)
				(end 102.278434 -142.196566)
			)
			(xy 102.14356 -142.33144) (xy 102.13721 -142.36065)
			(arc
				(start 102.142544 -142.374874)
				(mid 102.173297 -142.485278)
				(end 102.183692 -142.59941)
			)
			(arc
				(start 102.183692 -142.59941)
				(mid 102.165897 -142.748494)
				(end 102.113588 -142.889224)
			)
			(xy 102.110794 -142.894812) (xy 102.108 -142.906242)
			(arc
				(start 102.108 -142.942818)
				(mid 102.111901 -142.962341)
				(end 102.122986 -142.978886)
			)
			(arc
				(start 102.288594 -143.144494)
				(mid 102.305128 -143.155605)
				(end 102.324662 -143.15948)
			)
		)
		(stroke
			(width 0)
			(type solid)
		)
		(fill yes)
		(layer "F.Cu")
		(net "P5V_AUX")
	)
	(gr_poly
		(pts
			(arc
				(start 112.657128 -413.882078)
				(mid 112.676651 -413.878177)
				(end 112.693196 -413.867092)
			)
			(arc
				(start 112.734598 -413.82569)
				(mid 112.745709 -413.809156)
				(end 112.749584 -413.789622)
			)
			(arc
				(start 112.749584 -412.795466)
				(mid 112.745683 -412.775943)
				(end 112.734598 -412.759398)
			)
			(arc
				(start 112.507014 -412.531814)
				(mid 112.495903 -412.51528)
				(end 112.492028 -412.495746)
			)
			(arc
				(start 112.492028 -410.923994)
				(mid 112.488127 -410.904471)
				(end 112.477042 -410.887926)
			)
			(arc
				(start 112.389666 -410.80055)
				(mid 112.373132 -410.789439)
				(end 112.353598 -410.785564)
			)
			(arc
				(start 111.51616 -410.785564)
				(mid 111.496637 -410.781663)
				(end 111.480092 -410.770578)
			)
			(arc
				(start 111.230664 -410.52115)
				(mid 111.21413 -410.510039)
				(end 111.194596 -410.506164)
			)
			(arc
				(start 109.630718 -410.506164)
				(mid 109.611195 -410.510065)
				(end 109.59465 -410.52115)
			)
			(arc
				(start 109.387386 -410.728414)
				(mid 109.370852 -410.739525)
				(end 109.351318 -410.7434)
			)
			(arc
				(start 108.428282 -410.7434)
				(mid 108.408759 -410.747301)
				(end 108.392214 -410.758386)
			)
			(arc
				(start 108.371386 -410.779214)
				(mid 108.360275 -410.795748)
				(end 108.3564 -410.815282)
			)
			(arc
				(start 108.3564 -410.950918)
				(mid 108.360301 -410.970441)
				(end 108.371386 -410.986986)
			)
			(arc
				(start 108.392214 -411.007814)
				(mid 108.408748 -411.018925)
				(end 108.428282 -411.0228)
			)
			(arc
				(start 110.011718 -411.0228)
				(mid 110.031241 -411.026701)
				(end 110.047786 -411.037786)
			)
			(arc
				(start 111.757968 -412.747968)
				(mid 111.769079 -412.764502)
				(end 111.772954 -412.784036)
			)
			(arc
				(start 111.772954 -413.775398)
				(mid 111.776855 -413.794921)
				(end 111.78794 -413.811466)
			)
			(arc
				(start 111.843566 -413.867092)
				(mid 111.8601 -413.878203)
				(end 111.879634 -413.882078)
			)
		)
		(stroke
			(width 0)
			(type solid)
		)
		(fill yes)
		(layer "F.Cu")
		(net "P3V3_9ZXL045_P1_VDDA")
	)
	(gr_poly
		(pts
			(xy 7.515352 -429.658018)
			(arc
				(start 7.515352 -409.528518)
				(mid 7.285694 -408.374511)
				(end 6.63194 -407.396188)
			)
			(arc
				(start 3.303778 -404.068026)
				(mid 3.090447 -403.748703)
				(end 3.015488 -403.372066)
			)
			(arc
				(start 3.015488 -350.932242)
				(mid 3.014364 -350.921864)
				(end 3.01117 -350.911922)
			)
			(arc
				(start 3.01117 -350.911922)
				(mid 2.94165 -350.748082)
				(end 2.875788 -350.582738)
			)
			(xy 2.845816 -350.503998) (xy 2.79908 -350.375728) (xy 2.719832 -350.29648) (xy 2.576576 -350.29648)
			(xy 2.507996 -350.36506)
			(arc
				(start 2.507996 -403.371812)
				(mid 2.621533 -403.942691)
				(end 2.944876 -404.426674)
			)
			(arc
				(start 6.273292 -407.75509)
				(mid 6.817042 -408.568731)
				(end 7.008114 -409.528518)
			)
			(xy 7.008114 -429.94072) (xy 7.050786 -429.983392) (xy 7.189978 -429.983392)
		)
		(stroke
			(width 0)
			(type solid)
		)
		(fill yes)
		(layer "F.Cu")
		(net "GND")
	)
	(gr_poly
		(pts
			(arc
				(start 171.405804 -423.161968)
				(mid 171.441725 -423.147089)
				(end 171.456604 -423.111168)
			)
			(xy 171.456604 -422.654984) (xy 171.45762 -422.654222)
			(arc
				(start 171.45762 -419.624002)
				(mid 171.442741 -419.588081)
				(end 171.40682 -419.573202)
			)
			(arc
				(start 170.746166 -419.573202)
				(mid 170.727474 -419.576766)
				(end 170.711368 -419.586918)
			)
			(arc
				(start 170.711368 -419.586918)
				(mid 170.591035 -419.662791)
				(end 170.451272 -419.68928)
			)
			(xy 170.44035 -419.689026) (xy 170.429936 -419.688772) (xy 170.41114 -419.696138)
			(arc
				(start 170.35145 -419.754304)
				(mid 170.340013 -419.770895)
				(end 170.335956 -419.790626)
			)
			(arc
				(start 170.335956 -419.816788)
				(mid 170.339789 -419.836145)
				(end 170.350688 -419.852602)
			)
			(arc
				(start 170.372278 -419.874192)
				(mid 170.38744 -419.884568)
				(end 170.405298 -419.888924)
			)
			(arc
				(start 170.405298 -419.888924)
				(mid 170.765559 -420.269924)
				(end 170.405298 -420.650924)
			)
			(arc
				(start 170.405298 -420.650924)
				(mid 170.387421 -420.655236)
				(end 170.372278 -420.665656)
			)
			(arc
				(start 170.350688 -420.687246)
				(mid 170.339762 -420.703692)
				(end 170.335956 -420.72306)
			)
			(xy 170.335956 -423.123868) (xy 170.343576 -423.14241)
			(arc
				(start 170.348148 -423.146982)
				(mid 170.364682 -423.158093)
				(end 170.384216 -423.161968)
			)
		)
		(stroke
			(width 0)
			(type solid)
		)
		(fill yes)
		(layer "F.Cu")
		(net "GND")
	)
	(gr_poly
		(pts
			(xy 130.10642 -80.9625) (xy 130.10642 -71.10984) (xy 130.023362 -71.026782) (xy 127.950976 -71.026782)
			(xy 127.714756 -71.263002) (xy 127.714756 -77.563726) (xy 127.45212 -77.826362) (xy 126.805182 -77.826362)
			(xy 125.535182 -77.826362) (xy 124.529342 -78.832202) (xy 122.769122 -78.832202) (xy 122.393202 -79.208122)
			(xy 121.361962 -79.208122) (xy 121.224802 -79.070962) (xy 121.224802 -77.084682) (xy 121.030492 -76.890372)
			(xy 115.297712 -76.890372) (xy 114.95024 -76.5429) (xy 114.90452 -76.49718) (xy 114.90452 -71.66356)
			(xy 114.85372 -71.61276) (xy 114.39652 -71.61276) (xy 114.0206 -71.61276) (xy 113.85042 -71.78294)
			(xy 113.85042 -78.3844) (xy 114.39652 -78.9305) (xy 115.603528 -80.137508) (xy 121.32132 -80.137508)
			(xy 121.325393 -80.081849) (xy 121.337528 -80.027376) (xy 121.357464 -79.97525) (xy 121.384778 -79.926582)
			(xy 121.418886 -79.88241) (xy 121.459063 -79.843675) (xy 121.504451 -79.811203) (xy 121.554083 -79.785685)
			(xy 121.606903 -79.767666) (xy 121.661782 -79.757529) (xy 121.717553 -79.755491) (xy 121.773027 -79.761594)
			(xy 121.82702 -79.77571) (xy 121.878383 -79.797537) (xy 121.926021 -79.82661) (xy 121.968917 -79.862309)
			(xy 122.006159 -79.903873) (xy 122.036953 -79.950417) (xy 122.060641 -80.000948) (xy 122.076719 -80.05439)
			(xy 122.084845 -80.109604) (xy 122.085354 -80.137508) (xy 122.084845 -80.165412) (xy 122.076719 -80.220626)
			(xy 122.060641 -80.274068) (xy 122.036953 -80.324599) (xy 122.006159 -80.371143) (xy 121.968917 -80.412707)
			(xy 121.926021 -80.448406) (xy 121.878383 -80.477479) (xy 121.82702 -80.499306) (xy 121.773027 -80.513422)
			(xy 121.717553 -80.519525) (xy 121.661782 -80.517487) (xy 121.606903 -80.50735) (xy 121.554083 -80.489331)
			(xy 121.504451 -80.463813) (xy 121.459063 -80.431341) (xy 121.418886 -80.392606) (xy 121.384778 -80.348434)
			(xy 121.357464 -80.299766) (xy 121.337528 -80.24764) (xy 121.325393 -80.193167) (xy 121.32132 -80.137508)
			(xy 115.603528 -80.137508) (xy 116.77904 -81.31302) (xy 129.7559 -81.31302)
		)
		(stroke
			(width 0)
			(type solid)
		)
		(fill yes)
		(layer "F.Cu")
		(net "GND")
	)
	(gr_poly
		(pts
			(xy 300.267116 -357.560626) (xy 300.267116 -354.712524) (xy 301.154846 -353.824794) (xy 301.158148 -353.824794)
			(xy 301.371 -353.611942) (xy 301.545752 -353.43719) (xy 304.197512 -353.43719) (xy 304.393346 -353.241356)
			(xy 304.393346 -347.060774) (xy 304.311304 -346.978732) (xy 300.80331 -346.978732) (xy 300.748446 -347.033596)
			(xy 300.748446 -348.983046) (xy 300.830742 -349.065342) (xy 302.181514 -349.065342) (xy 302.312324 -349.195898)
			(xy 302.312324 -349.975424) (xy 302.695102 -350.358202) (xy 302.695102 -351.981516) (xy 302.27524 -352.401632)
			(xy 300.707806 -352.401632) (xy 300.62043 -352.489008) (xy 300.458886 -352.650552) (xy 296.846244 -352.650552)
			(xy 296.036746 -351.841054) (xy 296.036746 -347.187774) (xy 295.853104 -347.004132) (xy 292.44925 -347.004132)
			(xy 292.391846 -347.061536) (xy 292.391846 -348.983046) (xy 292.474142 -349.065342) (xy 293.824914 -349.065342)
			(xy 293.956994 -349.197168) (xy 293.956994 -349.976694) (xy 294.338502 -350.358202) (xy 294.338502 -351.807272)
			(xy 294.334946 -351.810828) (xy 294.334946 -352.170746) (xy 293.867332 -352.63836) (xy 288.556192 -352.63836)
			(xy 287.705546 -351.787714) (xy 287.705546 -347.111574) (xy 287.618424 -347.024452) (xy 284.15361 -347.024452)
			(xy 284.086046 -347.092016) (xy 284.086046 -348.983046) (xy 284.168342 -349.065342) (xy 285.519114 -349.065342)
			(xy 285.612586 -349.15856) (xy 285.648146 -349.19412) (xy 285.648146 -349.973646) (xy 286.032702 -350.358202)
			(xy 286.032702 -351.756472) (xy 286.029146 -351.760028) (xy 286.029146 -352.152712) (xy 285.546546 -352.635312)
			(xy 280.178764 -352.635312) (xy 279.425146 -351.881694) (xy 279.425146 -347.114368) (xy 279.34539 -347.034612)
			(xy 275.85035 -347.034612) (xy 275.805646 -347.079316) (xy 275.805646 -348.983046) (xy 275.887942 -349.065342)
			(xy 277.238714 -349.065342) (xy 277.332186 -349.15856) (xy 277.367746 -349.19412) (xy 277.367746 -350.242124)
			(xy 277.655274 -350.529652) (xy 277.655274 -352.218244) (xy 276.70125 -353.172268) (xy 276.70125 -359.560368)
			(xy 277.08606 -359.945178) (xy 292.17747 -359.945178) (xy 297.882564 -359.945178)
		)
		(stroke
			(width 0)
			(type solid)
		)
		(fill yes)
		(layer "F.Cu")
		(net "SW_P12V_AUX_PVDDIO_P0_FLT")
	)
	(gr_poly
		(pts
			(xy 152.20442 -83.2485) (xy 152.20442 -73.39584) (xy 152.121362 -73.312782) (xy 149.784562 -73.312782)
			(xy 149.712172 -73.385172) (xy 149.712172 -79.776828) (xy 149.352 -80.137) (xy 148.92782 -80.137)
			(xy 148.903182 -80.112362) (xy 147.633182 -80.112362) (xy 146.627342 -81.118202) (xy 144.867122 -81.118202)
			(xy 144.491202 -81.494122) (xy 143.459962 -81.494122) (xy 143.322802 -81.356962) (xy 143.322802 -79.370682)
			(xy 143.128492 -79.176372) (xy 137.395712 -79.176372) (xy 137.04824 -78.8289) (xy 137.04824 -76.345542)
			(xy 137.054844 -76.338684) (xy 137.054844 -73.509378) (xy 136.913874 -73.368408) (xy 136.087612 -73.368408)
			(xy 135.92048 -73.53554) (xy 135.92048 -80.64246) (xy 136.54024 -81.26222) (xy 137.701528 -82.423508)
			(xy 143.41932 -82.423508) (xy 143.423393 -82.367849) (xy 143.435528 -82.313376) (xy 143.455464 -82.26125)
			(xy 143.482778 -82.212582) (xy 143.516886 -82.16841) (xy 143.557063 -82.129675) (xy 143.602451 -82.097203)
			(xy 143.652083 -82.071685) (xy 143.704903 -82.053666) (xy 143.759782 -82.043529) (xy 143.815553 -82.041491)
			(xy 143.871027 -82.047594) (xy 143.92502 -82.06171) (xy 143.976383 -82.083537) (xy 144.024021 -82.11261)
			(xy 144.066917 -82.148309) (xy 144.104159 -82.189873) (xy 144.134953 -82.236417) (xy 144.158641 -82.286948)
			(xy 144.174719 -82.34039) (xy 144.182845 -82.395604) (xy 144.183354 -82.423508) (xy 144.182845 -82.451412)
			(xy 144.174719 -82.506626) (xy 144.158641 -82.560068) (xy 144.134953 -82.610599) (xy 144.104159 -82.657143)
			(xy 144.066917 -82.698707) (xy 144.024021 -82.734406) (xy 143.976383 -82.763479) (xy 143.92502 -82.785306)
			(xy 143.871027 -82.799422) (xy 143.815553 -82.805525) (xy 143.759782 -82.803487) (xy 143.704903 -82.79335)
			(xy 143.652083 -82.775331) (xy 143.602451 -82.749813) (xy 143.557063 -82.717341) (xy 143.516886 -82.678606)
			(xy 143.482778 -82.634434) (xy 143.455464 -82.585766) (xy 143.435528 -82.53364) (xy 143.423393 -82.479167)
			(xy 143.41932 -82.423508) (xy 137.701528 -82.423508) (xy 138.87704 -83.59902) (xy 151.8539 -83.59902)
		)
		(stroke
			(width 0)
			(type solid)
		)
		(fill yes)
		(layer "F.Cu")
		(net "GND")
	)
	(gr_poly
		(pts
			(arc
				(start 169.745914 -392.717274)
				(mid 169.765437 -392.713373)
				(end 169.781982 -392.702288)
			)
			(arc
				(start 169.840148 -392.644122)
				(mid 169.851259 -392.627588)
				(end 169.855134 -392.608054)
			)
			(arc
				(start 169.855134 -389.820404)
				(mid 169.840255 -389.784483)
				(end 169.804334 -389.769604)
			)
			(arc
				(start 168.7195 -389.769604)
				(mid 168.693888 -389.768642)
				(end 168.668446 -389.76554)
			)
			(xy 168.659302 -389.764016) (xy 168.641014 -389.767572) (xy 168.56837 -389.812784) (xy 168.55694 -389.827516)
			(arc
				(start 168.5544 -389.836406)
				(mid 168.434901 -390.006334)
				(end 168.237662 -390.07161)
			)
			(arc
				(start 168.237662 -390.07161)
				(mid 168.067619 -390.024503)
				(end 167.94607 -389.896604)
			)
			(xy 167.942514 -389.89)
			(arc
				(start 167.93718 -389.884666)
				(mid 167.901276 -389.869906)
				(end 167.865298 -389.884666)
			)
			(arc
				(start 167.827452 -389.922512)
				(mid 167.816341 -389.939046)
				(end 167.812466 -389.95858)
			)
			(arc
				(start 167.812466 -390.514586)
				(mid 167.808565 -390.534109)
				(end 167.79748 -390.550654)
			)
			(xy 167.691816 -390.656318) (xy 167.685212 -390.684004)
			(arc
				(start 167.690038 -390.697974)
				(mid 167.704741 -390.75776)
				(end 167.709596 -390.819132)
			)
			(arc
				(start 167.709596 -390.819132)
				(mid 167.70283 -390.890896)
				(end 167.682672 -390.960102)
			)
			(xy 167.679116 -390.969246)
			(arc
				(start 167.679116 -391.851642)
				(mid 167.683066 -391.871029)
				(end 167.694102 -391.887456)
			)
			(arc
				(start 168.335706 -392.529314)
				(mid 168.343417 -392.535599)
				(end 168.352216 -392.540236)
			)
			(arc
				(start 168.618662 -392.650726)
				(mid 168.663952 -392.674073)
				(end 168.704768 -392.704574)
			)
			(arc
				(start 168.704768 -392.704574)
				(mid 168.720378 -392.713958)
				(end 168.738296 -392.717274)
			)
		)
		(stroke
			(width 0)
			(type solid)
		)
		(fill yes)
		(layer "F.Cu")
		(net "P0V9_CPU1_RT2_2A")
	)
	(gr_poly
		(pts
			(arc
				(start 467.63813 -155.401772)
				(mid 467.653467 -155.403476)
				(end 467.66861 -155.400502)
			)
			(arc
				(start 467.758526 -155.36799)
				(mid 467.782821 -155.349406)
				(end 467.792054 -155.320238)
			)
			(arc
				(start 467.792054 -82.82813)
				(mid 467.983012 -81.868498)
				(end 468.526622 -81.054956)
			)
			(arc
				(start 470.85504 -78.726538)
				(mid 471.178373 -78.242681)
				(end 471.29192 -77.67193)
			)
			(xy 471.29192 -27.393646) (xy 471.252296 -27.354022) (xy 471.12682 -27.354022) (xy 470.784428 -27.696414)
			(arc
				(start 470.784428 -77.672184)
				(mid 470.709659 -78.048522)
				(end 470.496646 -78.367636)
			)
			(arc
				(start 468.167974 -80.696308)
				(mid 467.514407 -81.674395)
				(end 467.284816 -82.82813)
			)
			(arc
				(start 467.284816 -154.985466)
				(mid 467.285724 -154.995026)
				(end 467.288372 -155.004262)
			)
			(xy 467.298532 -155.029662)
			(arc
				(start 467.305136 -155.036774)
				(mid 467.461207 -155.208662)
				(end 467.612222 -155.385008)
			)
			(xy 467.617302 -155.391104) (xy 467.63051 -155.399486)
		)
		(stroke
			(width 0)
			(type solid)
		)
		(fill yes)
		(layer "F.Cu")
		(net "GND")
	)
	(gr_poly
		(pts
			(xy 451.154038 -428.40529) (xy 451.164105 -428.40486) (xy 451.182698 -428.397134) (xy 451.190106 -428.390304)
			(xy 451.19798 -428.38243) (xy 451.204817 -428.375029) (xy 451.21253 -428.35643) (xy 451.212966 -428.346362)
			(xy 451.212966 -422.07307) (xy 451.212537 -422.063003) (xy 451.204811 -422.04441) (xy 451.19798 -422.037002)
			(xy 450.805042 -421.644064) (xy 450.797633 -421.637377) (xy 450.779197 -421.629785) (xy 450.769228 -421.629332)
			(xy 449.743576 -421.629332) (xy 449.733611 -421.629811) (xy 449.715179 -421.637392) (xy 449.707762 -421.644064)
			(xy 449.610988 -421.740838) (xy 449.604138 -421.748234) (xy 449.596403 -421.766833) (xy 449.596002 -421.776906)
			(xy 449.596002 -425.92371) (xy 450.299834 -425.92371) (xy 450.303905 -425.868088) (xy 450.316031 -425.813651)
			(xy 450.335954 -425.76156) (xy 450.36325 -425.712925) (xy 450.397336 -425.668782) (xy 450.437485 -425.630073)
			(xy 450.482843 -425.597622) (xy 450.532443 -425.572121) (xy 450.585227 -425.554114) (xy 450.64007 -425.543984)
			(xy 450.695804 -425.541947) (xy 450.751241 -425.548047) (xy 450.805198 -425.562153) (xy 450.856527 -425.583965)
			(xy 450.904133 -425.613019) (xy 450.947001 -425.648694) (xy 450.984218 -425.690231) (xy 451.014991 -425.736744)
			(xy 451.038663 -425.787241) (xy 451.054731 -425.840648) (xy 451.062851 -425.895824) (xy 451.06336 -425.92371)
			(xy 451.062851 -425.951596) (xy 451.054731 -426.006772) (xy 451.038663 -426.060179) (xy 451.014991 -426.110676)
			(xy 450.984218 -426.157189) (xy 450.947001 -426.198726) (xy 450.904133 -426.234401) (xy 450.856527 -426.263455)
			(xy 450.805198 -426.285267) (xy 450.751241 -426.299373) (xy 450.695804 -426.305473) (xy 450.64007 -426.303436)
			(xy 450.585227 -426.293306) (xy 450.532443 -426.275299) (xy 450.482843 -426.249798) (xy 450.437485 -426.217347)
			(xy 450.397336 -426.178638) (xy 450.36325 -426.134495) (xy 450.335954 -426.08586) (xy 450.316031 -426.033769)
			(xy 450.303905 -425.979332) (xy 450.299834 -425.92371) (xy 449.596002 -425.92371) (xy 449.596002 -428.303944)
			(xy 449.596433 -428.314011) (xy 449.604159 -428.332603) (xy 449.610988 -428.340012) (xy 449.65112 -428.380144)
			(xy 449.658517 -428.386993) (xy 449.677116 -428.394729) (xy 449.687188 -428.39513) (xy 450.039486 -428.39513)
			(xy 450.058028 -428.40275) (xy 450.060568 -428.40529)
		)
		(stroke
			(width 0)
			(type solid)
		)
		(fill yes)
		(layer "F.Cu")
		(net "GND")
	)
	(gr_poly
		(pts
			(xy 372.168928 -205.002892) (xy 374.59666 -202.57516) (xy 392.77036 -202.57516) (xy 393.511278 -201.834242)
			(arc
				(start 393.511278 -195.086986)
				(mid 393.507377 -195.067463)
				(end 393.496292 -195.050918)
			)
			(xy 392.904472 -194.459352) (xy 369.908582 -194.459352) (xy 369.660678 -194.211448) (xy 369.660678 -194.079622)
			(arc
				(start 369.660678 -193.026792)
				(mid 369.656777 -193.007269)
				(end 369.645692 -192.990724)
			)
			(xy 369.142264 -192.487296) (xy 369.135152 -192.47993) (xy 369.116356 -192.47231)
			(arc
				(start 367.37036 -192.47231)
				(mid 367.350837 -192.468409)
				(end 367.334292 -192.457324)
			)
			(arc
				(start 366.475264 -191.598296)
				(mid 366.464153 -191.581762)
				(end 366.460278 -191.562228)
			)
			(xy 366.460278 -189.645798) (xy 366.310164 -189.495684) (xy 361.569508 -189.495684) (xy 361.253278 -189.179454)
			(arc
				(start 361.253278 -187.794392)
				(mid 361.249377 -187.774869)
				(end 361.238292 -187.758324)
			)
			(xy 360.887264 -187.407296) (xy 360.880152 -187.39993) (xy 360.861356 -187.39231)
			(arc
				(start 359.412032 -187.39231)
				(mid 359.392509 -187.388409)
				(end 359.375964 -187.377324)
			)
			(arc
				(start 358.220264 -186.221624)
				(mid 358.209153 -186.20509)
				(end 358.205278 -186.185556)
			)
			(xy 358.205278 -181.392322) (xy 358.031288 -181.218332) (xy 353.400106 -181.218332) (xy 352.998278 -180.816504)
			(arc
				(start 352.998278 -179.539392)
				(mid 352.994377 -179.519869)
				(end 352.983292 -179.503324)
			)
			(xy 352.632264 -179.152296) (xy 352.625152 -179.14493) (xy 352.606356 -179.13731)
			(arc
				(start 351.24136 -179.13731)
				(mid 351.221837 -179.133409)
				(end 351.205292 -179.122324)
			)
			(arc
				(start 350.092264 -178.009296)
				(mid 350.081153 -177.992762)
				(end 350.077278 -177.973228)
			)
			(xy 350.077278 -173.141386) (xy 349.792544 -172.856652) (xy 344.045032 -172.856652)
			(arc
				(start 343.572084 -173.3296)
				(mid 343.55555 -173.340711)
				(end 343.536016 -173.344586)
			)
			(arc
				(start 337.11134 -173.344586)
				(mid 337.091817 -173.348487)
				(end 337.075272 -173.359572)
			)
			(xy 335.327244 -175.1076) (xy 335.319878 -175.114712) (xy 335.312258 -175.133508) (xy 335.312258 -198.84517)
			(xy 335.312258 -200.765918) (xy 342.7984 -208.25206) (xy 368.91976 -208.25206)
		)
		(stroke
			(width 0)
			(type solid)
		)
		(fill yes)
		(layer "F.Cu")
		(net "PVDDCR_CPU0_P0")
	)
	(gr_poly
		(pts
			(arc
				(start 108.182918 -418.1856)
				(mid 108.202441 -418.181699)
				(end 108.218986 -418.170614)
			)
			(arc
				(start 108.290614 -418.098986)
				(mid 108.301725 -418.082452)
				(end 108.3056 -418.062918)
			)
			(arc
				(start 108.3056 -412.948882)
				(mid 108.301699 -412.929359)
				(end 108.290614 -412.912814)
			)
			(arc
				(start 107.768898 -412.391098)
				(mid 107.736167 -412.376193)
				(end 107.701842 -412.38678)
			)
			(arc
				(start 107.701842 -412.38678)
				(mid 107.664973 -412.406764)
				(end 107.62361 -412.413704)
			)
			(arc
				(start 107.56392 -412.413704)
				(mid 107.536591 -412.421844)
				(end 107.517946 -412.443422)
			)
			(arc
				(start 107.517946 -412.443422)
				(mid 107.503758 -412.472166)
				(end 107.487974 -412.500064)
			)
			(xy 107.484418 -412.505906) (xy 107.480608 -412.519114)
			(arc
				(start 107.480608 -412.624524)
				(mid 107.470651 -412.730627)
				(end 107.441238 -412.833058)
			)
			(arc
				(start 107.441238 -412.833058)
				(mid 107.438818 -412.862054)
				(end 107.452668 -412.887668)
			)
			(arc
				(start 107.541314 -412.976314)
				(mid 107.552425 -412.992848)
				(end 107.5563 -413.012382)
			)
			(arc
				(start 107.5563 -414.265618)
				(mid 107.552399 -414.285141)
				(end 107.541314 -414.301686)
			)
			(arc
				(start 107.101386 -414.741614)
				(mid 107.090275 -414.758148)
				(end 107.0864 -414.777682)
			)
			(xy 107.0864 -415.31413) (xy 107.107228 -415.341308)
			(arc
				(start 107.123738 -415.34588)
				(mid 107.403705 -415.713672)
				(end 107.123738 -416.081464)
			)
			(xy 107.107228 -416.086036) (xy 107.0864 -416.113214)
			(arc
				(start 107.0864 -418.088318)
				(mid 107.090301 -418.107841)
				(end 107.101386 -418.124386)
			)
			(arc
				(start 107.147614 -418.170614)
				(mid 107.164148 -418.181725)
				(end 107.183682 -418.1856)
			)
		)
		(stroke
			(width 0)
			(type solid)
		)
		(fill yes)
		(layer "F.Cu")
		(net "P3V3_9ZXL045_P1_VDDR")
	)
	(gr_poly
		(pts
			(xy 112.293654 -201.6506) (xy 112.293654 -189.988952) (xy 112.0013 -189.696598)
			(arc
				(start 110.69574 -189.696598)
				(mid 110.679206 -189.685487)
				(end 110.659672 -189.681612)
			)
			(arc
				(start 104.883458 -189.681612)
				(mid 104.863935 -189.685513)
				(end 104.84739 -189.696598)
			)
			(arc
				(start 104.448864 -190.095124)
				(mid 104.437753 -190.111658)
				(end 104.433878 -190.131192)
			)
			(arc
				(start 104.433878 -192.999614)
				(mid 104.429977 -193.019137)
				(end 104.418892 -193.035682)
			)
			(arc
				(start 103.064818 -194.389756)
				(mid 103.048284 -194.400867)
				(end 103.02875 -194.404742)
			)
			(arc
				(start 79.787496 -194.404742)
				(mid 79.767973 -194.400841)
				(end 79.751428 -194.389756)
			)
			(xy 79.398114 -194.036442) (xy 79.398114 -192.462912) (xy 79.190342 -192.25514) (xy 77.617066 -192.25514)
			(arc
				(start 76.762864 -191.401192)
				(mid 76.751753 -191.384658)
				(end 76.747878 -191.365124)
			)
			(arc
				(start 76.747878 -189.483492)
				(mid 76.743977 -189.463969)
				(end 76.732892 -189.447424)
			)
			(arc
				(start 76.635864 -189.350396)
				(mid 76.61933 -189.339285)
				(end 76.599796 -189.33541)
			)
			(arc
				(start 71.30796 -189.33541)
				(mid 71.288437 -189.331509)
				(end 71.271892 -189.320424)
			)
			(xy 71.064374 -189.112906) (xy 71.064374 -187.367672) (xy 70.857618 -187.160916) (xy 69.11213 -187.160916)
			(arc
				(start 67.822064 -185.870596)
				(mid 67.810953 -185.854062)
				(end 67.807078 -185.834528)
			)
			(arc
				(start 67.807078 -180.796692)
				(mid 67.803177 -180.777169)
				(end 67.792092 -180.760624)
			)
			(arc
				(start 67.695064 -180.663596)
				(mid 67.67853 -180.652485)
				(end 67.658996 -180.64861)
			)
			(arc
				(start 61.96076 -180.64861)
				(mid 61.941237 -180.652511)
				(end 61.924692 -180.663596)
			)
			(arc
				(start 61.740796 -180.847492)
				(mid 61.729685 -180.864026)
				(end 61.72581 -180.88356)
			)
			(arc
				(start 61.72581 -181.191408)
				(mid 61.721909 -181.210931)
				(end 61.710824 -181.227476)
			)
			(arc
				(start 61.529722 -181.408578)
				(mid 61.513188 -181.419689)
				(end 61.493654 -181.423564)
			)
			(xy 59.657234 -181.423564) (xy 59.52109 -181.559708) (xy 59.52109 -184.269888) (xy 61.044074 -185.792872)
			(xy 77.059028 -201.807572) (xy 112.136682 -201.807572)
		)
		(stroke
			(width 0)
			(type solid)
		)
		(fill yes)
		(layer "F.Cu")
		(net "PVDDCR_CPU0_P1")
	)
	(gr_poly
		(pts
			(arc
				(start 362.699554 -402.222462)
				(mid 362.719929 -402.218086)
				(end 362.736892 -402.205952)
			)
			(arc
				(start 362.736892 -402.205952)
				(mid 362.906176 -402.084926)
				(end 363.109764 -402.041868)
			)
			(xy 363.119924 -402.041868) (xy 363.138212 -402.034248)
			(arc
				(start 363.261148 -401.911312)
				(mid 363.275483 -401.883531)
				(end 363.2708 -401.852638)
			)
			(arc
				(start 363.2708 -401.852638)
				(mid 363.230404 -401.741755)
				(end 363.216698 -401.624546)
			)
			(arc
				(start 363.216698 -401.624546)
				(mid 363.233247 -401.495618)
				(end 363.281976 -401.375118)
			)
			(xy 363.285278 -401.369276) (xy 363.28858 -401.35683)
			(arc
				(start 363.28858 -401.277582)
				(mid 363.292481 -401.258059)
				(end 363.303566 -401.241514)
			)
			(arc
				(start 363.703616 -400.841464)
				(mid 363.714727 -400.82493)
				(end 363.718602 -400.805396)
			)
			(arc
				(start 363.718602 -398.849342)
				(mid 363.714701 -398.829819)
				(end 363.703616 -398.813274)
			)
			(arc
				(start 363.326426 -398.436084)
				(mid 363.309892 -398.424973)
				(end 363.290358 -398.421098)
			)
			(arc
				(start 363.290104 -398.421098)
				(mid 363.270717 -398.425048)
				(end 363.25429 -398.436084)
			)
			(arc
				(start 363.180884 -398.509236)
				(mid 363.164438 -398.520162)
				(end 363.14507 -398.523968)
			)
			(arc
				(start 361.770168 -398.523968)
				(mid 361.750645 -398.527869)
				(end 361.7341 -398.538954)
			)
			(xy 361.733084 -398.53997) (xy 361.725464 -398.558766)
			(arc
				(start 361.725464 -399.56486)
				(mid 361.721514 -399.584247)
				(end 361.710478 -399.600674)
			)
			(arc
				(start 361.466638 -399.844514)
				(mid 361.455527 -399.861048)
				(end 361.451652 -399.880582)
			)
			(arc
				(start 361.451652 -401.6502)
				(mid 361.447819 -401.669557)
				(end 361.43692 -401.686014)
			)
			(arc
				(start 361.327446 -401.795742)
				(mid 361.316384 -401.812159)
				(end 361.31246 -401.831556)
			)
			(arc
				(start 361.31246 -402.113242)
				(mid 361.316361 -402.132765)
				(end 361.327446 -402.14931)
			)
			(arc
				(start 361.385612 -402.207476)
				(mid 361.402146 -402.218587)
				(end 361.42168 -402.222462)
			)
		)
		(stroke
			(width 0)
			(type solid)
		)
		(fill yes)
		(layer "F.Cu")
		(net "P0V9_CPU0_RT_2D")
	)
	(gr_poly
		(pts
			(xy 441.414916 -21.829014) (xy 441.414916 -21.04771) (xy 441.789312 -20.673314) (xy 441.789312 -20.33143)
			(xy 441.789312 -17.10436) (xy 441.789312 -9.85901) (xy 441.663074 -9.732772) (xy 437.476646 -9.732772)
			(xy 437.46658 -9.733204) (xy 437.447987 -9.740929) (xy 437.440578 -9.747758) (xy 437.19877 -9.989566)
			(xy 437.191404 -9.996678) (xy 437.183784 -10.015474) (xy 437.183784 -11.99388) (xy 437.557418 -11.99388)
			(xy 437.557418 -10.54608) (xy 437.608218 -10.49528) (xy 437.725566 -10.49528) (xy 437.776366 -10.54608)
			(xy 437.776366 -11.99388) (xy 438.157366 -11.99388) (xy 438.157366 -10.54608) (xy 438.208166 -10.49528)
			(xy 438.325514 -10.49528) (xy 438.376314 -10.54608) (xy 438.376314 -11.99388) (xy 438.757314 -11.99388)
			(xy 438.757314 -10.54608) (xy 438.808114 -10.49528) (xy 438.925462 -10.49528) (xy 438.976262 -10.54608)
			(xy 438.976262 -11.99388) (xy 439.357262 -11.99388) (xy 439.357262 -10.54608) (xy 439.408062 -10.49528)
			(xy 439.52541 -10.49528) (xy 439.57621 -10.54608) (xy 439.57621 -11.99388) (xy 439.957464 -11.99388)
			(xy 439.957464 -10.54608) (xy 440.008264 -10.49528) (xy 440.125612 -10.49528) (xy 440.176412 -10.54608)
			(xy 440.176412 -11.99388) (xy 440.125612 -12.04468) (xy 440.008264 -12.04468) (xy 439.957464 -11.99388)
			(xy 439.57621 -11.99388) (xy 439.52541 -12.04468) (xy 439.408062 -12.04468) (xy 439.357262 -11.99388)
			(xy 438.976262 -11.99388) (xy 438.925462 -12.04468) (xy 438.808114 -12.04468) (xy 438.757314 -11.99388)
			(xy 438.376314 -11.99388) (xy 438.325514 -12.04468) (xy 438.208166 -12.04468) (xy 438.157366 -11.99388)
			(xy 437.776366 -11.99388) (xy 437.725566 -12.04468) (xy 437.608218 -12.04468) (xy 437.557418 -11.99388)
			(xy 437.183784 -11.99388) (xy 437.183784 -12.33805) (xy 437.183784 -12.677394) (xy 437.786526 -13.280136)
			(xy 438.104788 -13.280136) (xy 439.381138 -13.280136) (xy 439.50763 -13.280136) (xy 439.665618 -13.122148)
			(xy 440.326018 -13.122148) (xy 440.5122 -13.30833) (xy 440.5122 -13.427456) (xy 440.5122 -13.973048)
			(xy 440.5122 -16.578072) (xy 439.926222 -17.16405) (xy 438.177178 -17.16405) (xy 437.913018 -17.42821)
			(xy 437.913018 -20.611084) (xy 438.131458 -20.829524) (xy 440.346592 -20.829524) (xy 440.863482 -21.346414)
			(xy 440.863482 -21.788628) (xy 440.961272 -21.886418) (xy 441.357512 -21.886418)
		)
		(stroke
			(width 0)
			(type solid)
		)
		(fill yes)
		(layer "F.Cu")
		(net "P12V_OCP_SFF_R")
	)
	(gr_poly
		(pts
			(arc
				(start 464.760056 -430.084484)
				(mid 464.783337 -430.065785)
				(end 464.79206 -430.03724)
			)
			(arc
				(start 464.79206 -409.528264)
				(mid 464.983018 -408.568632)
				(end 465.526628 -407.75509)
			)
			(arc
				(start 467.355174 -405.926544)
				(mid 467.678507 -405.442687)
				(end 467.792054 -404.871936)
			)
			(arc
				(start 467.792054 -352.879406)
				(mid 467.782838 -352.850227)
				(end 467.758526 -352.831654)
			)
			(xy 467.653624 -352.793808) (xy 467.622636 -352.80219)
			(arc
				(start 467.612222 -352.814382)
				(mid 467.458011 -352.994506)
				(end 467.298532 -353.169982)
			)
			(arc
				(start 467.298532 -353.169982)
				(mid 467.28833 -353.186068)
				(end 467.284816 -353.20478)
			)
			(xy 467.284816 -358.942132) (xy 467.284816 -362.566712)
			(arc
				(start 467.28761 -362.569506)
				(mid 467.285545 -362.577646)
				(end 467.284816 -362.586016)
			)
			(arc
				(start 467.284816 -404.871936)
				(mid 467.209909 -405.248606)
				(end 466.996526 -405.567896)
			)
			(arc
				(start 465.16798 -407.396442)
				(mid 464.514413 -408.374529)
				(end 464.284822 -409.528264)
			)
			(xy 464.284568 -409.528264)
			(arc
				(start 464.284568 -429.753776)
				(mid 464.2888 -429.773823)
				(end 464.30057 -429.790606)
			)
			(arc
				(start 464.30057 -429.790606)
				(mid 464.460769 -429.946641)
				(end 464.616546 -430.10709)
			)
			(xy 464.627468 -430.11852) (xy 464.657694 -430.125124)
		)
		(stroke
			(width 0)
			(type solid)
		)
		(fill yes)
		(layer "F.Cu")
		(net "GND")
	)
	(gr_poly
		(pts
			(arc
				(start 5.876798 -368.05108)
				(mid 5.896321 -368.047179)
				(end 5.912866 -368.036094)
			)
			(arc
				(start 6.251194 -367.697766)
				(mid 6.262305 -367.681232)
				(end 6.26618 -367.661698)
			)
			(arc
				(start 6.26618 -362.82249)
				(mid 6.26449 -362.809497)
				(end 6.259576 -362.797344)
			)
			(arc
				(start 6.259576 -362.797344)
				(mid 6.055331 -362.297107)
				(end 5.985764 -361.761278)
			)
			(arc
				(start 5.985764 -361.761278)
				(mid 6.055343 -361.225453)
				(end 6.259576 -360.725212)
			)
			(arc
				(start 6.259576 -360.725212)
				(mid 6.264538 -360.713072)
				(end 6.26618 -360.700066)
			)
			(arc
				(start 6.26618 -359.039922)
				(mid 6.270081 -359.020399)
				(end 6.281166 -359.003854)
			)
			(arc
				(start 9.355074 -355.929946)
				(mid 9.371608 -355.918835)
				(end 9.391142 -355.91496)
			)
			(arc
				(start 24.035258 -355.91496)
				(mid 24.054781 -355.911059)
				(end 24.071326 -355.899974)
			)
			(arc
				(start 25.120854 -354.850446)
				(mid 25.131965 -354.833912)
				(end 25.13584 -354.814378)
			)
			(arc
				(start 25.13584 -351.869502)
				(mid 25.131939 -351.849979)
				(end 25.120854 -351.833434)
			)
			(arc
				(start 25.061926 -351.774506)
				(mid 25.045392 -351.763395)
				(end 25.025858 -351.75952)
			)
			(xy 24.318468 -351.75952)
			(arc
				(start 24.314404 -351.760282)
				(mid 24.289843 -351.763188)
				(end 24.265128 -351.764092)
			)
			(arc
				(start 23.877016 -351.764092)
				(mid 23.857629 -351.768042)
				(end 23.841202 -351.779078)
			)
			(arc
				(start 23.804626 -351.815654)
				(mid 23.793515 -351.832188)
				(end 23.78964 -351.851722)
			)
			(arc
				(start 23.78964 -353.066858)
				(mid 23.785739 -353.086381)
				(end 23.774654 -353.102926)
			)
			(arc
				(start 22.885146 -353.992434)
				(mid 22.868612 -354.003545)
				(end 22.849078 -354.00742)
			)
			(arc
				(start 6.840982 -354.00742)
				(mid 6.821459 -354.011321)
				(end 6.804914 -354.022406)
			)
			(arc
				(start 4.014216 -356.813104)
				(mid 4.00329 -356.82955)
				(end 3.999484 -356.848918)
			)
			(arc
				(start 3.999484 -367.622582)
				(mid 4.003317 -367.641939)
				(end 4.014216 -367.658396)
			)
			(arc
				(start 4.391914 -368.036094)
				(mid 4.408448 -368.047205)
				(end 4.427982 -368.05108)
			)
		)
		(stroke
			(width 0)
			(type solid)
		)
		(fill yes)
		(layer "F.Cu")
		(net "P5V_AUX")
	)
	(gr_poly
		(pts
			(arc
				(start 195.543932 -33.736788)
				(mid 195.563455 -33.732887)
				(end 195.58 -33.721802)
			)
			(arc
				(start 195.95465 -33.347152)
				(mid 195.965761 -33.330618)
				(end 195.969636 -33.311084)
			)
			(arc
				(start 195.969636 -25.276302)
				(mid 195.968728 -25.266742)
				(end 195.96608 -25.257506)
			)
			(arc
				(start 195.96608 -25.257506)
				(mid 195.542211 -23.805632)
				(end 195.399152 -22.29993)
			)
			(arc
				(start 195.399152 -22.29993)
				(mid 195.54221 -20.794228)
				(end 195.96608 -19.342354)
			)
			(xy 195.969636 -19.33321)
			(arc
				(start 195.969636 -18.618962)
				(mid 195.965735 -18.599439)
				(end 195.95465 -18.582894)
			)
			(arc
				(start 195.932806 -18.56105)
				(mid 195.916272 -18.549939)
				(end 195.896738 -18.546064)
			)
			(arc
				(start 191.743838 -18.546064)
				(mid 191.724315 -18.549965)
				(end 191.70777 -18.56105)
			)
			(arc
				(start 191.641222 -18.627598)
				(mid 191.630111 -18.644132)
				(end 191.626236 -18.663666)
			)
			(arc
				(start 191.626236 -20.82927)
				(mid 191.630137 -20.848793)
				(end 191.641222 -20.865338)
			)
			(arc
				(start 191.967358 -21.191474)
				(mid 191.983892 -21.202585)
				(end 192.003426 -21.20646)
			)
			(arc
				(start 193.435478 -21.20646)
				(mid 193.455001 -21.210361)
				(end 193.471546 -21.221446)
			)
			(arc
				(start 194.68465 -22.43455)
				(mid 194.695761 -22.451084)
				(end 194.699636 -22.470618)
			)
			(arc
				(start 194.699636 -29.843222)
				(mid 194.695735 -29.862745)
				(end 194.68465 -29.87929)
			)
			(arc
				(start 193.719958 -30.843982)
				(mid 193.703424 -30.855093)
				(end 193.68389 -30.858968)
			)
			(arc
				(start 191.100456 -30.858968)
				(mid 191.080933 -30.862869)
				(end 191.064388 -30.873954)
			)
			(arc
				(start 190.701422 -31.23692)
				(mid 190.690311 -31.253454)
				(end 190.686436 -31.272988)
			)
			(arc
				(start 190.686436 -33.45307)
				(mid 190.690337 -33.472593)
				(end 190.701422 -33.489138)
			)
			(arc
				(start 190.934086 -33.721802)
				(mid 190.95062 -33.732913)
				(end 190.970154 -33.736788)
			)
		)
		(stroke
			(width 0)
			(type solid)
		)
		(fill yes)
		(layer "F.Cu")
		(net "GND")
	)
	(gr_poly
		(pts
			(arc
				(start 419.537388 -163.625784)
				(mid 419.556483 -163.621892)
				(end 419.572694 -163.611052)
			)
			(xy 419.612826 -163.570666) (xy 419.620446 -163.550346)
			(arc
				(start 419.619684 -163.539678)
				(mid 419.613734 -163.425066)
				(end 419.61181 -163.310316)
			)
			(arc
				(start 419.61181 -163.310316)
				(mid 419.624938 -163.016779)
				(end 419.664388 -162.725608)
			)
			(xy 419.66515 -162.721036)
			(arc
				(start 419.66515 -160.97123)
				(mid 419.668993 -160.951998)
				(end 419.679882 -160.93567)
			)
			(arc
				(start 419.874446 -160.741106)
				(mid 419.885352 -160.724923)
				(end 419.889178 -160.7058)
			)
			(arc
				(start 419.889178 -160.00476)
				(mid 419.893021 -159.985528)
				(end 419.90391 -159.9692)
			)
			(arc
				(start 420.575486 -159.297624)
				(mid 420.586441 -159.281323)
				(end 420.590218 -159.262064)
			)
			(arc
				(start 420.590218 -157.85592)
				(mid 420.586375 -157.836688)
				(end 420.575486 -157.82036)
			)
			(arc
				(start 420.47287 -157.717744)
				(mid 420.456569 -157.706789)
				(end 420.43731 -157.703012)
			)
			(xy 420.262304 -157.703012)
			(arc
				(start 420.257224 -157.704028)
				(mid 420.205556 -157.712042)
				(end 420.153338 -157.714696)
			)
			(arc
				(start 420.153338 -157.714696)
				(mid 420.101121 -157.712033)
				(end 420.049452 -157.704028)
			)
			(xy 420.044372 -157.703012) (xy 419.249098 -157.703012)
			(arc
				(start 419.24224 -157.705044)
				(mid 419.169258 -157.721398)
				(end 419.094666 -157.726888)
			)
			(arc
				(start 419.094666 -157.726888)
				(mid 419.016526 -157.720924)
				(end 418.940234 -157.703012)
			)
			(xy 418.934138 -157.703012)
			(arc
				(start 418.72027 -157.91688)
				(mid 418.709315 -157.933181)
				(end 418.705538 -157.95244)
			)
			(arc
				(start 418.705538 -162.304984)
				(mid 418.701695 -162.324216)
				(end 418.690806 -162.340544)
			)
			(arc
				(start 418.54755 -162.4838)
				(mid 418.531249 -162.494755)
				(end 418.51199 -162.498532)
			)
			(xy 418.504116 -162.498532)
			(arc
				(start 418.491162 -162.507676)
				(mid 418.358813 -162.573437)
				(end 418.212778 -162.596068)
			)
			(arc
				(start 418.212778 -162.596068)
				(mid 418.139012 -162.590364)
				(end 418.066982 -162.573462)
			)
			(xy 418.053266 -162.569144) (xy 418.026342 -162.575748)
			(arc
				(start 417.95827 -162.64382)
				(mid 417.947315 -162.660121)
				(end 417.943538 -162.67938)
			)
			(arc
				(start 417.943538 -163.572444)
				(mid 417.947381 -163.591676)
				(end 417.95827 -163.608004)
			)
			(arc
				(start 417.961318 -163.611052)
				(mid 417.977501 -163.621958)
				(end 417.996624 -163.625784)
			)
		)
		(stroke
			(width 0)
			(type solid)
		)
		(fill yes)
		(layer "F.Cu")
		(net "PVDDCR_CPU0_P0_PVCC")
	)
	(gr_poly
		(pts
			(arc
				(start 406.395428 -194.512184)
				(mid 406.406539 -194.49565)
				(end 406.410414 -194.476116)
			)
			(arc
				(start 406.410414 -190.6397)
				(mid 406.414315 -190.620177)
				(end 406.4254 -190.603632)
			)
			(xy 410.100526 -186.928506) (xy 411.007814 -186.928506) (xy 412.89478 -185.04154) (xy 414.095184 -185.04154)
			(xy 416.503612 -182.633112) (xy 416.510724 -182.625746)
			(arc
				(start 418.157152 -180.979318)
				(mid 418.168263 -180.962784)
				(end 418.172138 -180.94325)
			)
			(arc
				(start 418.172138 -177.810414)
				(mid 418.176039 -177.790891)
				(end 418.187124 -177.774346)
			)
			(xy 418.492432 -177.469038) (xy 418.499798 -177.461926) (xy 418.507418 -177.44313) (xy 418.507418 -175.660812)
			(xy 418.499798 -175.642016) (xy 418.492432 -175.634904)
			(arc
				(start 418.377624 -175.520096)
				(mid 418.36109 -175.508985)
				(end 418.341556 -175.50511)
			)
			(arc
				(start 412.63316 -175.50511)
				(mid 412.613637 -175.509011)
				(end 412.597092 -175.520096)
			)
			(arc
				(start 412.449264 -175.667924)
				(mid 412.438153 -175.684458)
				(end 412.434278 -175.703992)
			)
			(arc
				(start 412.434278 -177.287428)
				(mid 412.430377 -177.306951)
				(end 412.419292 -177.323496)
			)
			(arc
				(start 411.509464 -178.233324)
				(mid 411.49293 -178.244435)
				(end 411.473396 -178.24831)
			)
			(arc
				(start 409.66136 -178.24831)
				(mid 409.641837 -178.252211)
				(end 409.625292 -178.263296)
			)
			(arc
				(start 409.401264 -178.487324)
				(mid 409.390153 -178.503858)
				(end 409.386278 -178.523392)
			)
			(arc
				(start 409.386278 -179.878228)
				(mid 409.382377 -179.897751)
				(end 409.371292 -179.914296)
			)
			(xy 408.963876 -180.321712) (xy 404.772876 -180.321712) (xy 404.672546 -180.422042) (xy 404.672292 -180.422296)
			(arc
				(start 404.067264 -181.027324)
				(mid 404.056153 -181.043858)
				(end 404.052278 -181.063392)
			)
			(arc
				(start 404.052278 -185.593228)
				(mid 404.048377 -185.612751)
				(end 404.037292 -185.629296)
			)
			(arc
				(start 402.844762 -186.821826)
				(mid 402.828228 -186.832937)
				(end 402.808694 -186.836812)
			)
			(arc
				(start 400.85772 -186.836812)
				(mid 400.838197 -186.840713)
				(end 400.821652 -186.851798)
			)
			(arc
				(start 400.673824 -186.999626)
				(mid 400.662713 -187.01616)
				(end 400.658838 -187.035694)
			)
			(arc
				(start 400.658838 -188.36513)
				(mid 400.654937 -188.384653)
				(end 400.643852 -188.401198)
			)
			(arc
				(start 400.434556 -188.610494)
				(mid 400.418022 -188.621605)
				(end 400.398488 -188.62548)
			)
			(arc
				(start 394.670534 -188.62548)
				(mid 394.651011 -188.629381)
				(end 394.634466 -188.640466)
			)
			(arc
				(start 394.28928 -188.985652)
				(mid 394.278169 -189.002186)
				(end 394.274294 -189.02172)
			)
			(xy 394.274294 -198.991474) (xy 394.520166 -199.237346) (xy 401.670266 -199.237346)
		)
		(stroke
			(width 0)
			(type solid)
		)
		(fill yes)
		(layer "F.Cu")
		(net "PVDDCR_SOC_P0")
	)
	(gr_poly
		(pts
			(arc
				(start 106.658918 -417.8808)
				(mid 106.678441 -417.876899)
				(end 106.694986 -417.865814)
			)
			(arc
				(start 106.792014 -417.768786)
				(mid 106.803125 -417.752252)
				(end 106.807 -417.732718)
			)
			(arc
				(start 106.807 -416.05454)
				(mid 106.801839 -416.032231)
				(end 106.787442 -416.014408)
			)
			(arc
				(start 106.787442 -416.014408)
				(mid 106.640661 -415.713672)
				(end 106.787442 -415.412936)
			)
			(arc
				(start 106.787442 -415.412936)
				(mid 106.801892 -415.395139)
				(end 106.807 -415.372804)
			)
			(arc
				(start 106.807 -414.777682)
				(mid 106.803099 -414.758159)
				(end 106.792014 -414.741614)
			)
			(arc
				(start 106.720386 -414.669986)
				(mid 106.703852 -414.658875)
				(end 106.684318 -414.655)
			)
			(arc
				(start 105.913682 -414.655)
				(mid 105.894159 -414.658901)
				(end 105.877614 -414.669986)
			)
			(xy 105.433368 -415.114232)
			(arc
				(start 105.429812 -415.121344)
				(mid 105.337578 -415.24755)
				(end 105.211372 -415.339784)
			)
			(xy 105.20426 -415.34334)
			(arc
				(start 105.120186 -415.427414)
				(mid 105.109075 -415.443948)
				(end 105.1052 -415.463482)
			)
			(arc
				(start 105.1052 -415.848038)
				(mid 105.109859 -415.86929)
				(end 105.12298 -415.886646)
			)
			(xy 105.19029 -415.94405) (xy 105.211626 -415.950146)
			(arc
				(start 105.222802 -415.948368)
				(mid 105.252805 -415.944765)
				(end 105.283 -415.943542)
			)
			(arc
				(start 105.283 -415.943542)
				(mid 105.664508 -416.32505)
				(end 105.283 -416.706558)
			)
			(arc
				(start 105.283 -416.706558)
				(mid 105.252805 -416.705341)
				(end 105.222802 -416.701732)
			)
			(xy 105.211626 -416.699954) (xy 105.19029 -416.70605)
			(arc
				(start 105.12298 -416.763454)
				(mid 105.109857 -416.780809)
				(end 105.1052 -416.802062)
			)
			(arc
				(start 105.1052 -417.504118)
				(mid 105.109101 -417.523641)
				(end 105.120186 -417.540186)
			)
			(arc
				(start 105.445814 -417.865814)
				(mid 105.462348 -417.876925)
				(end 105.481882 -417.8808)
			)
		)
		(stroke
			(width 0)
			(type solid)
		)
		(fill yes)
		(layer "F.Cu")
		(net "GND")
	)
	(gr_poly
		(pts
			(arc
				(start 174.072804 -441.481972)
				(mid 174.101088 -441.47337)
				(end 174.119794 -441.450476)
			)
			(xy 174.161196 -441.348876) (xy 174.1551 -441.318904)
			(arc
				(start 174.143924 -441.307982)
				(mid 173.989094 -441.15171)
				(end 173.838616 -440.991244)
			)
			(arc
				(start 173.838616 -440.991244)
				(mid 173.821586 -440.978925)
				(end 173.801024 -440.97448)
			)
			(xy 154.910282 -440.97448)
			(arc
				(start 154.902916 -440.97702)
				(mid 154.827352 -440.994523)
				(end 154.750008 -441.000388)
			)
			(arc
				(start 154.750008 -441.000388)
				(mid 154.672663 -440.994534)
				(end 154.5971 -440.97702)
			)
			(xy 154.589734 -440.97448) (xy 150.91029 -440.97448)
			(arc
				(start 150.902924 -440.97702)
				(mid 150.82736 -440.994523)
				(end 150.750016 -441.000388)
			)
			(arc
				(start 150.750016 -441.000388)
				(mid 150.672671 -440.994534)
				(end 150.597108 -440.97702)
			)
			(xy 150.589742 -440.97448) (xy 146.910298 -440.97448)
			(arc
				(start 146.902932 -440.97702)
				(mid 146.827368 -440.994523)
				(end 146.750024 -441.000388)
			)
			(arc
				(start 146.750024 -441.000388)
				(mid 146.672679 -440.994534)
				(end 146.597116 -440.97702)
			)
			(xy 146.58975 -440.97448) (xy 143.218408 -440.97448) (xy 143.2052 -440.97829)
			(arc
				(start 143.199104 -440.981846)
				(mid 143.167362 -440.995688)
				(end 143.133064 -441.000388)
			)
			(arc
				(start 142.367 -441.000388)
				(mid 142.332723 -440.995614)
				(end 142.30096 -440.981846)
			)
			(xy 142.294864 -440.97829) (xy 142.281656 -440.97448) (xy 137.910062 -440.97448)
			(arc
				(start 137.902696 -440.97702)
				(mid 137.827132 -440.994523)
				(end 137.749788 -441.000388)
			)
			(arc
				(start 137.749788 -441.000388)
				(mid 137.672443 -440.994534)
				(end 137.59688 -440.97702)
			)
			(xy 137.589514 -440.97448) (xy 133.91007 -440.97448)
			(arc
				(start 133.902704 -440.97702)
				(mid 133.82714 -440.994523)
				(end 133.749796 -441.000388)
			)
			(arc
				(start 133.749796 -441.000388)
				(mid 133.672451 -440.994534)
				(end 133.596888 -440.97702)
			)
			(xy 133.589522 -440.97448) (xy 129.910078 -440.97448)
			(arc
				(start 129.902712 -440.97702)
				(mid 129.827148 -440.994523)
				(end 129.749804 -441.000388)
			)
			(arc
				(start 129.749804 -441.000388)
				(mid 129.672459 -440.994534)
				(end 129.596896 -440.97702)
			)
			(xy 129.58953 -440.97448) (xy 126.218188 -440.97448) (xy 126.20498 -440.97829)
			(arc
				(start 126.198884 -440.981846)
				(mid 126.167142 -440.995688)
				(end 126.132844 -441.000388)
			)
			(arc
				(start 125.36678 -441.000388)
				(mid 125.332503 -440.995614)
				(end 125.30074 -440.981846)
			)
			(xy 125.294644 -440.97829) (xy 125.281436 -440.97448)
			(arc
				(start 106.449368 -440.97448)
				(mid 106.42877 -440.978843)
				(end 106.411776 -440.991244)
			)
			(arc
				(start 106.411776 -440.991244)
				(mid 106.261301 -441.151713)
				(end 106.106468 -441.307982)
			)
			(xy 106.095292 -441.318904) (xy 106.089196 -441.348876)
			(arc
				(start 106.130598 -441.450476)
				(mid 106.149303 -441.47337)
				(end 106.177588 -441.481972)
			)
		)
		(stroke
			(width 0)
			(type solid)
		)
		(fill yes)
		(layer "F.Cu")
		(net "GND")
	)
	(gr_poly
		(pts
			(arc
				(start 426.294296 -397.312896)
				(mid 426.330217 -397.298017)
				(end 426.345096 -397.262096)
			)
			(arc
				(start 426.345096 -395.938756)
				(mid 426.341195 -395.919233)
				(end 426.33011 -395.902688)
			)
			(arc
				(start 426.039534 -395.612112)
				(mid 426.028423 -395.595578)
				(end 426.024548 -395.576044)
			)
			(arc
				(start 426.024548 -392.393932)
				(mid 426.020647 -392.374409)
				(end 426.009562 -392.357864)
			)
			(arc
				(start 425.919392 -392.267694)
				(mid 425.902858 -392.256583)
				(end 425.883324 -392.252708)
			)
			(arc
				(start 424.06697 -392.252708)
				(mid 424.047447 -392.256609)
				(end 424.030902 -392.267694)
			)
			(arc
				(start 423.856404 -392.442192)
				(mid 423.845293 -392.458726)
				(end 423.841418 -392.47826)
			)
			(xy 423.841418 -392.59764) (xy 423.846498 -392.613134)
			(arc
				(start 423.851578 -392.619738)
				(mid 423.934893 -392.779058)
				(end 423.963592 -392.956542)
			)
			(arc
				(start 423.963592 -392.956542)
				(mid 423.945325 -393.09912)
				(end 423.891456 -393.232386)
			)
			(arc
				(start 423.891456 -393.232386)
				(mid 423.884823 -393.256112)
				(end 423.890186 -393.280138)
			)
			(arc
				(start 423.890186 -393.280138)
				(mid 423.934406 -393.402295)
				(end 423.949368 -393.531344)
			)
			(arc
				(start 423.949368 -393.531344)
				(mid 423.885323 -393.791791)
				(end 423.707814 -393.992862)
			)
			(arc
				(start 423.615104 -394.057378)
				(mid 423.599101 -394.075532)
				(end 423.59326 -394.099034)
			)
			(arc
				(start 423.59326 -394.574014)
				(mid 423.595811 -394.58991)
				(end 423.603166 -394.60424)
			)
			(arc
				(start 423.603166 -394.60424)
				(mid 423.640219 -394.669686)
				(end 423.660316 -394.742162)
			)
			(xy 423.661332 -394.750544) (xy 423.668698 -394.764768) (xy 424.158664 -395.254988) (xy 424.161966 -395.254988)
			(xy 424.161966 -395.25829)
			(arc
				(start 424.191684 -395.287754)
				(mid 424.258333 -395.387641)
				(end 424.2816 -395.505432)
			)
			(arc
				(start 424.2816 -396.063216)
				(mid 424.285501 -396.082739)
				(end 424.296586 -396.099284)
			)
			(arc
				(start 424.764962 -396.567406)
				(mid 424.781379 -396.578468)
				(end 424.800776 -396.582392)
			)
			(arc
				(start 425.5389 -396.582392)
				(mid 425.558423 -396.586293)
				(end 425.574968 -396.597378)
			)
			(arc
				(start 425.757086 -396.779496)
				(mid 425.768197 -396.79603)
				(end 425.772072 -396.815564)
			)
			(arc
				(start 425.772072 -397.262096)
				(mid 425.786951 -397.298017)
				(end 425.822872 -397.312896)
			)
		)
		(stroke
			(width 0)
			(type solid)
		)
		(fill yes)
		(layer "F.Cu")
		(net "P1V8_CPU0_RT2_1A")
	)
	(gr_poly
		(pts
			(xy 70.423786 -17.708118) (xy 70.423786 -15.79753) (xy 70.423786 -14.704822) (xy 70.423786 -13.591032)
			(xy 68.5038 -11.6713) (xy 67.36461 -10.53211) (xy 66.20129 -10.53211)
			(arc
				(start 65.728088 -10.53211)
				(mid 65.693364 -10.545738)
				(end 65.677288 -10.579354)
			)
			(xy 65.677288 -11.994134) (xy 65.62598 -12.045696) (xy 65.508124 -12.045696) (xy 65.456816 -11.994134)
			(arc
				(start 65.456816 -10.579354)
				(mid 65.440665 -10.545819)
				(end 65.406016 -10.53211)
			)
			(arc
				(start 65.12814 -10.53211)
				(mid 65.093416 -10.545738)
				(end 65.07734 -10.579354)
			)
			(xy 65.07734 -11.994134) (xy 65.026032 -12.045696) (xy 64.908176 -12.045696) (xy 64.856868 -11.994134)
			(arc
				(start 64.856868 -10.579354)
				(mid 64.840717 -10.545819)
				(end 64.806068 -10.53211)
			)
			(arc
				(start 64.527684 -10.53211)
				(mid 64.494068 -10.544909)
				(end 64.477392 -10.576814)
			)
			(xy 64.477392 -11.994134) (xy 64.42583 -12.045696) (xy 64.307974 -12.045696) (xy 64.256412 -11.994134)
			(arc
				(start 64.256412 -10.576814)
				(mid 64.239792 -10.544846)
				(end 64.20612 -10.53211)
			)
			(arc
				(start 63.927736 -10.53211)
				(mid 63.89412 -10.544909)
				(end 63.877444 -10.576814)
			)
			(xy 63.877444 -11.994134) (xy 63.825882 -12.045696) (xy 63.708026 -12.045696) (xy 63.656464 -11.994134)
			(arc
				(start 63.656464 -10.576814)
				(mid 63.639844 -10.544846)
				(end 63.606172 -10.53211)
			)
			(arc
				(start 63.327788 -10.53211)
				(mid 63.294172 -10.544909)
				(end 63.277496 -10.576814)
			)
			(xy 63.277496 -11.994134) (xy 63.225934 -12.045696) (xy 63.108078 -12.045696) (xy 63.056516 -11.994134)
			(arc
				(start 63.056516 -10.576814)
				(mid 63.039896 -10.544846)
				(end 63.006224 -10.53211)
			)
			(arc
				(start 62.951868 -10.53211)
				(mid 62.932345 -10.536011)
				(end 62.9158 -10.547096)
			)
			(arc
				(start 62.70625 -10.756646)
				(mid 62.695139 -10.77318)
				(end 62.691264 -10.792714)
			)
			(xy 62.691264 -12.771628) (xy 62.69228 -12.781026)
			(arc
				(start 62.69228 -12.781534)
				(mid 62.697172 -12.79532)
				(end 62.705742 -12.807188)
			)
			(xy 63.197994 -13.29944) (xy 65.327784 -13.29944) (xy 65.50406 -13.475716) (xy 65.50406 -17.807432)
			(xy 65.619122 -17.922494) (xy 65.676526 -17.979898) (xy 70.152006 -17.979898)
		)
		(stroke
			(width 0)
			(type solid)
		)
		(fill yes)
		(layer "F.Cu")
		(net "P12V_OCP_V3_2_R")
	)
	(gr_poly
		(pts
			(arc
				(start 63.006224 -9.03605)
				(mid 63.03984 -9.023251)
				(end 63.056516 -8.991346)
			)
			(xy 63.056516 -7.59587) (xy 63.108078 -7.544308) (xy 63.225934 -7.544308) (xy 63.277496 -7.59587)
			(arc
				(start 63.277496 -8.991346)
				(mid 63.294116 -9.023314)
				(end 63.327788 -9.03605)
			)
			(arc
				(start 63.606172 -9.03605)
				(mid 63.639788 -9.023251)
				(end 63.656464 -8.991346)
			)
			(xy 63.656464 -7.59587) (xy 63.708026 -7.544308) (xy 63.825882 -7.544308) (xy 63.877444 -7.59587)
			(arc
				(start 63.877444 -8.991346)
				(mid 63.894064 -9.023314)
				(end 63.927736 -9.03605)
			)
			(arc
				(start 64.20612 -9.03605)
				(mid 64.239736 -9.023251)
				(end 64.256412 -8.991346)
			)
			(xy 64.256412 -7.59587) (xy 64.307974 -7.544308) (xy 64.42583 -7.544308) (xy 64.477392 -7.59587)
			(arc
				(start 64.477392 -8.991346)
				(mid 64.494012 -9.023314)
				(end 64.527684 -9.03605)
			)
			(arc
				(start 64.806068 -9.03605)
				(mid 64.839684 -9.023251)
				(end 64.85636 -8.991346)
			)
			(xy 64.85636 -7.59587) (xy 64.907922 -7.544308) (xy 65.025778 -7.544308) (xy 65.07734 -7.59587)
			(arc
				(start 65.07734 -8.991346)
				(mid 65.09396 -9.023314)
				(end 65.127632 -9.03605)
			)
			(arc
				(start 65.406016 -9.03605)
				(mid 65.44074 -9.022422)
				(end 65.456816 -8.988806)
			)
			(xy 65.456816 -7.59587) (xy 65.508124 -7.544308) (xy 65.62598 -7.544308) (xy 65.677288 -7.59587)
			(arc
				(start 65.677288 -8.988806)
				(mid 65.693439 -9.022341)
				(end 65.728088 -9.03605)
			)
			(arc
				(start 66.200782 -9.03605)
				(mid 66.220305 -9.032149)
				(end 66.23685 -9.021064)
			)
			(arc
				(start 66.443098 -8.814816)
				(mid 66.454209 -8.798282)
				(end 66.458084 -8.778748)
			)
			(arc
				(start 66.458084 -6.735572)
				(mid 66.454183 -6.716049)
				(end 66.443098 -6.699504)
			)
			(arc
				(start 66.39687 -6.653276)
				(mid 66.380336 -6.642165)
				(end 66.360802 -6.63829)
			)
			(arc
				(start 63.403226 -6.63829)
				(mid 63.383703 -6.642191)
				(end 63.367158 -6.653276)
			)
			(arc
				(start 62.67069 -7.349744)
				(mid 62.659579 -7.366278)
				(end 62.655704 -7.385812)
			)
			(arc
				(start 62.655704 -8.997188)
				(mid 62.659605 -9.016711)
				(end 62.67069 -9.033256)
			)
			(xy 62.673484 -9.03605)
		)
		(stroke
			(width 0)
			(type solid)
		)
		(fill yes)
		(layer "F.Cu")
		(net "GND")
	)
	(gr_poly
		(pts
			(arc
				(start 106.075734 -394.354812)
				(mid 106.095228 -394.351028)
				(end 106.111802 -394.34008)
			)
			(arc
				(start 106.15168 -394.299948)
				(mid 106.333928 -394.17811)
				(end 106.548936 -394.135356)
			)
			(xy 106.57713 -394.135356) (xy 106.605324 -394.111226)
			(arc
				(start 106.608372 -394.092176)
				(mid 106.779572 -393.782876)
				(end 107.111038 -393.659868)
			)
			(arc
				(start 107.111038 -393.659868)
				(mid 107.19036 -393.666053)
				(end 107.267756 -393.684506)
			)
			(arc
				(start 107.267756 -393.684506)
				(mid 107.298283 -393.684812)
				(end 107.323382 -393.667488)
			)
			(arc
				(start 107.331002 -393.657836)
				(mid 107.339443 -393.642813)
				(end 107.342432 -393.625832)
			)
			(arc
				(start 107.342432 -393.59586)
				(mid 107.339502 -393.578858)
				(end 107.331002 -393.563856)
			)
			(arc
				(start 107.331002 -393.563856)
				(mid 107.246127 -393.413064)
				(end 107.216702 -393.242546)
			)
			(arc
				(start 107.216702 -393.242546)
				(mid 107.365641 -392.882977)
				(end 107.72521 -392.734038)
			)
			(arc
				(start 107.72521 -392.734038)
				(mid 107.775367 -392.736518)
				(end 107.825032 -392.743944)
			)
			(xy 107.836208 -392.74623) (xy 107.858052 -392.740642)
			(arc
				(start 107.927902 -392.683492)
				(mid 107.941503 -392.665999)
				(end 107.946444 -392.644376)
			)
			(arc
				(start 107.946444 -390.214612)
				(mid 107.942543 -390.195089)
				(end 107.931458 -390.178544)
			)
			(arc
				(start 107.778804 -390.02589)
				(mid 107.76227 -390.014779)
				(end 107.742736 -390.010904)
			)
			(arc
				(start 107.318556 -390.010904)
				(mid 107.299169 -390.014854)
				(end 107.282742 -390.02589)
			)
			(arc
				(start 107.181142 -390.127236)
				(mid 107.164696 -390.138162)
				(end 107.145328 -390.141968)
			)
			(arc
				(start 105.826052 -390.141968)
				(mid 105.790131 -390.156847)
				(end 105.775252 -390.192768)
			)
			(arc
				(start 105.775252 -391.13333)
				(mid 105.771302 -391.152717)
				(end 105.760266 -391.169144)
			)
			(arc
				(start 105.466896 -391.462514)
				(mid 105.455922 -391.479077)
				(end 105.452164 -391.498582)
			)
			(arc
				(start 105.452164 -394.043154)
				(mid 105.455997 -394.062511)
				(end 105.466896 -394.078968)
			)
			(arc
				(start 105.728008 -394.34008)
				(mid 105.744454 -394.351006)
				(end 105.763822 -394.354812)
			)
		)
		(stroke
			(width 0)
			(type solid)
		)
		(fill yes)
		(layer "F.Cu")
		(net "P0V9_CPU1_RT_2D")
	)
	(gr_poly
		(pts
			(xy 1.015492 -16.947388)
			(arc
				(start 1.015492 -13.780008)
				(mid 1.303847 -13.083859)
				(end 1.999996 -12.795504)
			)
			(arc
				(start 11.102086 -12.795504)
				(mid 13.234194 -11.912198)
				(end 14.11732 -9.780016)
			)
			(xy 14.11732 -4.064) (xy 13.76934 -3.71602) (xy 13.676122 -3.71602) (xy 13.610082 -3.78206)
			(arc
				(start 13.610082 -9.780016)
				(mid 12.875507 -11.553437)
				(end 11.102086 -12.288012)
			)
			(arc
				(start 1.999996 -12.288012)
				(mid 0.944996 -12.725008)
				(end 0.508 -13.780008)
			)
			(xy 0.508 -17.276064) (xy 0.556768 -17.324832) (xy 0.638048 -17.324832)
		)
		(stroke
			(width 0)
			(type solid)
		)
		(fill yes)
		(layer "F.Cu")
		(net "GND")
	)
	(gr_poly
		(pts
			(xy 197.248272 -364.482634) (xy 197.248272 -352.048064) (xy 196.740272 -351.540064) (xy 191.65697 -351.540064)
			(xy 191.619632 -351.577402) (xy 191.619632 -353.589336) (xy 191.701928 -353.671632) (xy 193.059812 -353.671632)
			(xy 193.19113 -353.80295) (xy 193.19113 -353.915726) (xy 193.191384 -353.92233) (xy 193.191384 -354.142802)
			(xy 193.192146 -354.142802) (xy 193.192146 -354.58146) (xy 193.557652 -354.946966) (xy 193.557652 -355.835966)
			(xy 193.55562 -355.837998) (xy 193.55562 -356.853998) (xy 192.896744 -357.512874) (xy 187.9346 -357.512874)
			(xy 186.9186 -356.496874) (xy 186.9186 -351.616264) (xy 186.817 -351.514664) (xy 183.330342 -351.514664)
			(xy 183.293004 -351.552002) (xy 183.293004 -353.563936) (xy 183.3753 -353.646232) (xy 184.733184 -353.646232)
			(xy 184.864502 -353.77755) (xy 184.864502 -353.890326) (xy 184.864756 -353.89693) (xy 184.864756 -353.90201)
			(xy 184.865518 -353.90201) (xy 184.865518 -354.55606) (xy 185.231024 -354.921566) (xy 185.231024 -355.810566)
			(xy 185.228992 -355.812598) (xy 185.228992 -356.740714) (xy 183.959754 -358.009952) (xy 183.959754 -364.973051)
			(xy 190.790572 -364.973051) (xy 190.790572 -364.888329) (xy 190.798625 -364.803992) (xy 190.814659 -364.720802)
			(xy 190.838527 -364.639512) (xy 190.870015 -364.56086) (xy 190.908837 -364.485557) (xy 190.95464 -364.414285)
			(xy 191.007011 -364.347689) (xy 191.065476 -364.286374) (xy 191.129504 -364.230893) (xy 191.198516 -364.18175)
			(xy 191.271886 -364.13939) (xy 191.348951 -364.104195) (xy 191.429013 -364.076486) (xy 191.511346 -364.056512)
			(xy 191.595205 -364.044455) (xy 191.67983 -364.040424) (xy 191.764455 -364.044455) (xy 191.848314 -364.056512)
			(xy 191.930647 -364.076486) (xy 192.010709 -364.104195) (xy 192.087774 -364.13939) (xy 192.161144 -364.18175)
			(xy 192.230156 -364.230893) (xy 192.294184 -364.286374) (xy 192.352649 -364.347689) (xy 192.40502 -364.414285)
			(xy 192.450823 -364.485557) (xy 192.489645 -364.56086) (xy 192.521133 -364.639512) (xy 192.545001 -364.720802)
			(xy 192.561035 -364.803992) (xy 192.569088 -364.888329) (xy 192.569592 -364.93069) (xy 192.569088 -364.973051)
			(xy 192.561035 -365.057388) (xy 192.545001 -365.140578) (xy 192.521133 -365.221868) (xy 192.489645 -365.30052)
			(xy 192.450823 -365.375823) (xy 192.40502 -365.447095) (xy 192.352649 -365.513691) (xy 192.294184 -365.575006)
			(xy 192.230156 -365.630487) (xy 192.161144 -365.67963) (xy 192.087774 -365.72199) (xy 192.010709 -365.757185)
			(xy 191.930647 -365.784894) (xy 191.848314 -365.804868) (xy 191.764455 -365.816925) (xy 191.67983 -365.820957)
			(xy 191.595205 -365.816925) (xy 191.511346 -365.804868) (xy 191.429013 -365.784894) (xy 191.348951 -365.757185)
			(xy 191.271886 -365.72199) (xy 191.198516 -365.67963) (xy 191.129504 -365.630487) (xy 191.065476 -365.575006)
			(xy 191.007011 -365.513691) (xy 190.95464 -365.447095) (xy 190.908837 -365.375823) (xy 190.870015 -365.30052)
			(xy 190.838527 -365.221868) (xy 190.814659 -365.140578) (xy 190.798625 -365.057388) (xy 190.790572 -364.973051)
			(xy 183.959754 -364.973051) (xy 183.959754 -365.424212) (xy 184.898284 -366.362742) (xy 195.368164 -366.362742)
		)
		(stroke
			(width 0)
			(type solid)
		)
		(fill yes)
		(layer "F.Cu")
		(net "SW_P12V_AUX_PVDD11_S3_P1_FLT")
	)
	(gr_poly
		(pts
			(arc
				(start 54.898798 -387.86054)
				(mid 54.907173 -387.859845)
				(end 54.915308 -387.857746)
			)
			(arc
				(start 55.146702 -387.778244)
				(mid 55.207816 -387.762711)
				(end 55.270654 -387.757416)
			)
			(arc
				(start 55.270654 -387.757416)
				(mid 55.324798 -387.761351)
				(end 55.377842 -387.77291)
			)
			(arc
				(start 55.670196 -387.858508)
				(mid 55.677236 -387.860029)
				(end 55.68442 -387.86054)
			)
			(arc
				(start 56.098694 -387.86054)
				(mid 56.107069 -387.859845)
				(end 56.115204 -387.857746)
			)
			(arc
				(start 56.346598 -387.778244)
				(mid 56.407712 -387.762711)
				(end 56.47055 -387.757416)
			)
			(arc
				(start 56.47055 -387.757416)
				(mid 56.524694 -387.761351)
				(end 56.577738 -387.77291)
			)
			(arc
				(start 56.870092 -387.858508)
				(mid 56.877132 -387.860029)
				(end 56.884316 -387.86054)
			)
			(arc
				(start 57.126124 -387.86054)
				(mid 57.145647 -387.856639)
				(end 57.162192 -387.845554)
			)
			(arc
				(start 57.227724 -387.780022)
				(mid 57.23865 -387.763576)
				(end 57.242456 -387.744208)
			)
			(arc
				(start 57.242456 -387.483858)
				(mid 57.246406 -387.464471)
				(end 57.257442 -387.448044)
			)
			(xy 57.258966 -387.44652) (xy 57.266586 -387.427978) (xy 57.266586 -387.420104) (xy 57.352184 -387.334506)
			(xy 57.370726 -387.326886) (xy 57.3786 -387.326886)
			(arc
				(start 57.452768 -387.252718)
				(mid 57.469185 -387.241656)
				(end 57.488582 -387.237732)
			)
			(arc
				(start 57.749948 -387.237732)
				(mid 57.785869 -387.222853)
				(end 57.800748 -387.186932)
			)
			(arc
				(start 57.800748 -387.120892)
				(mid 57.796516 -387.100845)
				(end 57.784746 -387.084062)
			)
			(xy 57.723024 -387.025896) (xy 57.70372 -387.018784) (xy 57.693052 -387.019546)
			(arc
				(start 57.6707 -387.020308)
				(mid 57.619821 -387.016832)
				(end 57.569862 -387.006592)
			)
			(xy 57.259474 -386.921502) (xy 57.246012 -386.919724)
			(arc
				(start 56.817514 -386.919724)
				(mid 56.808477 -386.92058)
				(end 56.799734 -386.923026)
			)
			(arc
				(start 56.6039 -386.996178)
				(mid 56.538306 -387.014225)
				(end 56.47055 -387.020308)
			)
			(arc
				(start 56.47055 -387.020308)
				(mid 56.419671 -387.016832)
				(end 56.369712 -387.006592)
			)
			(xy 56.059578 -386.921502) (xy 56.046116 -386.919724)
			(arc
				(start 55.617618 -386.919724)
				(mid 55.608581 -386.92058)
				(end 55.599838 -386.923026)
			)
			(arc
				(start 55.404004 -386.996178)
				(mid 55.33841 -387.014225)
				(end 55.270654 -387.020308)
			)
			(arc
				(start 55.270654 -387.020308)
				(mid 55.219775 -387.016832)
				(end 55.169816 -387.006592)
			)
			(xy 54.859428 -386.921502) (xy 54.845966 -386.919724)
			(arc
				(start 54.49189 -386.919724)
				(mid 54.472367 -386.923625)
				(end 54.455822 -386.93471)
			)
			(arc
				(start 54.426612 -386.96392)
				(mid 54.415501 -386.980454)
				(end 54.411626 -386.999988)
			)
			(arc
				(start 54.411626 -387.672834)
				(mid 54.415527 -387.692357)
				(end 54.426612 -387.708902)
			)
			(arc
				(start 54.563264 -387.845554)
				(mid 54.579798 -387.856665)
				(end 54.599332 -387.86054)
			)
		)
		(stroke
			(width 0)
			(type solid)
		)
		(fill yes)
		(layer "F.Cu")
		(net "P1V8_CPU1_RT0_1A")
	)
	(gr_poly
		(pts
			(arc
				(start 170.2943 -388.930896)
				(mid 170.330221 -388.916017)
				(end 170.3451 -388.880096)
			)
			(arc
				(start 170.3451 -387.556756)
				(mid 170.341199 -387.537233)
				(end 170.330114 -387.520688)
			)
			(arc
				(start 170.039538 -387.230112)
				(mid 170.028427 -387.213578)
				(end 170.024552 -387.194044)
			)
			(arc
				(start 170.024552 -384.011932)
				(mid 170.020651 -383.992409)
				(end 170.009566 -383.975864)
			)
			(arc
				(start 169.919396 -383.885694)
				(mid 169.902862 -383.874583)
				(end 169.883328 -383.870708)
			)
			(arc
				(start 168.848024 -383.870708)
				(mid 168.828501 -383.866807)
				(end 168.811956 -383.855722)
			)
			(arc
				(start 168.787826 -383.831592)
				(mid 168.77138 -383.820666)
				(end 168.752012 -383.81686)
			)
			(arc
				(start 168.120822 -383.81686)
				(mid 168.101465 -383.820693)
				(end 168.085008 -383.831592)
			)
			(arc
				(start 167.856408 -384.060192)
				(mid 167.845297 -384.076726)
				(end 167.841422 -384.09626)
			)
			(xy 167.841422 -384.21564) (xy 167.846502 -384.231134)
			(arc
				(start 167.851582 -384.237738)
				(mid 167.934897 -384.397058)
				(end 167.963596 -384.574542)
			)
			(arc
				(start 167.963596 -384.574542)
				(mid 167.945329 -384.71712)
				(end 167.89146 -384.850386)
			)
			(arc
				(start 167.89146 -384.850386)
				(mid 167.884827 -384.874112)
				(end 167.89019 -384.898138)
			)
			(arc
				(start 167.89019 -384.898138)
				(mid 167.93441 -385.020295)
				(end 167.949372 -385.149344)
			)
			(arc
				(start 167.949372 -385.149344)
				(mid 167.885327 -385.409791)
				(end 167.707818 -385.610862)
			)
			(arc
				(start 167.615108 -385.675378)
				(mid 167.599105 -385.693532)
				(end 167.593264 -385.717034)
			)
			(arc
				(start 167.593264 -386.0165)
				(mid 167.597165 -386.036023)
				(end 167.60825 -386.052568)
			)
			(arc
				(start 168.146984 -386.591302)
				(mid 168.158095 -386.607836)
				(end 168.16197 -386.62737)
			)
			(arc
				(start 168.16197 -386.755132)
				(mid 168.16592 -386.774519)
				(end 168.176956 -386.790946)
			)
			(arc
				(start 168.191942 -386.805932)
				(mid 168.258674 -386.905804)
				(end 168.282112 -387.02361)
			)
			(arc
				(start 168.282112 -387.681216)
				(mid 168.285896 -387.70071)
				(end 168.296844 -387.717284)
			)
			(arc
				(start 168.76522 -388.185406)
				(mid 168.781637 -388.196468)
				(end 168.801034 -388.200392)
			)
			(arc
				(start 169.538904 -388.200392)
				(mid 169.558427 -388.204293)
				(end 169.574972 -388.215378)
			)
			(arc
				(start 169.75709 -388.397496)
				(mid 169.768201 -388.41403)
				(end 169.772076 -388.433564)
			)
			(arc
				(start 169.772076 -388.880096)
				(mid 169.786955 -388.916017)
				(end 169.822876 -388.930896)
			)
		)
		(stroke
			(width 0)
			(type solid)
		)
		(fill yes)
		(layer "F.Cu")
		(net "P1V8_CPU1_RT2_1A")
	)
	(gr_poly
		(pts
			(arc
				(start 87.426546 -387.86054)
				(mid 87.434921 -387.859845)
				(end 87.443056 -387.857746)
			)
			(arc
				(start 87.67445 -387.778244)
				(mid 87.735564 -387.762711)
				(end 87.798402 -387.757416)
			)
			(arc
				(start 87.798402 -387.757416)
				(mid 87.852546 -387.761351)
				(end 87.90559 -387.77291)
			)
			(arc
				(start 88.197944 -387.858508)
				(mid 88.204984 -387.860029)
				(end 88.212168 -387.86054)
			)
			(arc
				(start 88.626442 -387.86054)
				(mid 88.634817 -387.859845)
				(end 88.642952 -387.857746)
			)
			(arc
				(start 88.874346 -387.778244)
				(mid 88.93546 -387.762711)
				(end 88.998298 -387.757416)
			)
			(arc
				(start 88.998298 -387.757416)
				(mid 89.052442 -387.761351)
				(end 89.105486 -387.77291)
			)
			(arc
				(start 89.39784 -387.858508)
				(mid 89.40488 -387.860029)
				(end 89.412064 -387.86054)
			)
			(arc
				(start 89.653872 -387.86054)
				(mid 89.673395 -387.856639)
				(end 89.68994 -387.845554)
			)
			(arc
				(start 89.755472 -387.780022)
				(mid 89.766398 -387.763576)
				(end 89.770204 -387.744208)
			)
			(arc
				(start 89.770204 -387.483858)
				(mid 89.774154 -387.464471)
				(end 89.78519 -387.448044)
			)
			(xy 89.786714 -387.44652) (xy 89.794334 -387.427978) (xy 89.794334 -387.420104) (xy 89.879932 -387.334506)
			(xy 89.898474 -387.326886) (xy 89.906348 -387.326886)
			(arc
				(start 89.980516 -387.252718)
				(mid 89.996933 -387.241656)
				(end 90.01633 -387.237732)
			)
			(arc
				(start 90.301572 -387.237732)
				(mid 90.337568 -387.222928)
				(end 90.352372 -387.186932)
			)
			(arc
				(start 90.352372 -387.11886)
				(mid 90.34806 -387.098124)
				(end 90.335608 -387.081014)
			)
			(xy 90.271092 -387.023356) (xy 90.250772 -387.016752)
			(arc
				(start 90.23985 -387.018022)
				(mid 90.21918 -387.019725)
				(end 90.198448 -387.020308)
			)
			(arc
				(start 90.198448 -387.020308)
				(mid 90.147569 -387.016832)
				(end 90.09761 -387.006592)
			)
			(xy 89.787222 -386.921502) (xy 89.77376 -386.919724)
			(arc
				(start 89.345262 -386.919724)
				(mid 89.336225 -386.92058)
				(end 89.327482 -386.923026)
			)
			(arc
				(start 89.131648 -386.996178)
				(mid 89.066054 -387.014225)
				(end 88.998298 -387.020308)
			)
			(arc
				(start 88.998298 -387.020308)
				(mid 88.947419 -387.016832)
				(end 88.89746 -387.006592)
			)
			(xy 88.587326 -386.921502) (xy 88.573864 -386.919724)
			(arc
				(start 88.145366 -386.919724)
				(mid 88.136329 -386.92058)
				(end 88.127586 -386.923026)
			)
			(arc
				(start 87.931752 -386.996178)
				(mid 87.866158 -387.014225)
				(end 87.798402 -387.020308)
			)
			(arc
				(start 87.798402 -387.020308)
				(mid 87.747523 -387.016832)
				(end 87.697564 -387.006592)
			)
			(xy 87.387176 -386.921502) (xy 87.373714 -386.919724)
			(arc
				(start 87.019638 -386.919724)
				(mid 87.000115 -386.923625)
				(end 86.98357 -386.93471)
			)
			(arc
				(start 86.95436 -386.96392)
				(mid 86.943249 -386.980454)
				(end 86.939374 -386.999988)
			)
			(arc
				(start 86.939374 -387.672834)
				(mid 86.943275 -387.692357)
				(end 86.95436 -387.708902)
			)
			(arc
				(start 87.091012 -387.845554)
				(mid 87.107546 -387.856665)
				(end 87.12708 -387.86054)
			)
		)
		(stroke
			(width 0)
			(type solid)
		)
		(fill yes)
		(layer "F.Cu")
		(net "P1V8_CPU1_RT1_1A")
	)
	(gr_poly
		(pts
			(arc
				(start 121.99874 -387.86054)
				(mid 122.007115 -387.859845)
				(end 122.01525 -387.857746)
			)
			(arc
				(start 122.246644 -387.778244)
				(mid 122.307758 -387.762711)
				(end 122.370596 -387.757416)
			)
			(arc
				(start 122.370596 -387.757416)
				(mid 122.42474 -387.761351)
				(end 122.477784 -387.77291)
			)
			(arc
				(start 122.770138 -387.858508)
				(mid 122.777178 -387.860029)
				(end 122.784362 -387.86054)
			)
			(arc
				(start 123.198636 -387.86054)
				(mid 123.207011 -387.859845)
				(end 123.215146 -387.857746)
			)
			(arc
				(start 123.44654 -387.778244)
				(mid 123.507654 -387.762711)
				(end 123.570492 -387.757416)
			)
			(arc
				(start 123.570492 -387.757416)
				(mid 123.624636 -387.761351)
				(end 123.67768 -387.77291)
			)
			(arc
				(start 123.970034 -387.858508)
				(mid 123.977074 -387.860029)
				(end 123.984258 -387.86054)
			)
			(arc
				(start 124.226066 -387.86054)
				(mid 124.245589 -387.856639)
				(end 124.262134 -387.845554)
			)
			(arc
				(start 124.327666 -387.780022)
				(mid 124.338728 -387.763605)
				(end 124.342652 -387.744208)
			)
			(arc
				(start 124.342652 -387.483858)
				(mid 124.346485 -387.464501)
				(end 124.357384 -387.448044)
			)
			(xy 124.358908 -387.44652) (xy 124.366528 -387.427978) (xy 124.366528 -387.420104) (xy 124.452126 -387.334506)
			(xy 124.470668 -387.326886) (xy 124.478542 -387.326886)
			(arc
				(start 124.55271 -387.252718)
				(mid 124.569127 -387.241656)
				(end 124.588524 -387.237732)
			)
			(arc
				(start 124.87402 -387.237732)
				(mid 124.909941 -387.222853)
				(end 124.92482 -387.186932)
			)
			(arc
				(start 124.92482 -387.11886)
				(mid 124.920383 -387.098098)
				(end 124.907802 -387.081014)
			)
			(xy 124.843286 -387.023356) (xy 124.822966 -387.016752)
			(arc
				(start 124.812044 -387.018022)
				(mid 124.791374 -387.019725)
				(end 124.770642 -387.020308)
			)
			(arc
				(start 124.770642 -387.020308)
				(mid 124.719763 -387.016832)
				(end 124.669804 -387.006592)
			)
			(xy 124.359416 -386.921502) (xy 124.345954 -386.919724)
			(arc
				(start 123.917456 -386.919724)
				(mid 123.908419 -386.92058)
				(end 123.899676 -386.923026)
			)
			(arc
				(start 123.703842 -386.996178)
				(mid 123.638248 -387.014225)
				(end 123.570492 -387.020308)
			)
			(arc
				(start 123.570492 -387.020308)
				(mid 123.519613 -387.016832)
				(end 123.469654 -387.006592)
			)
			(xy 123.15952 -386.921502) (xy 123.146058 -386.919724)
			(arc
				(start 122.71756 -386.919724)
				(mid 122.708523 -386.92058)
				(end 122.69978 -386.923026)
			)
			(arc
				(start 122.503946 -386.996178)
				(mid 122.438352 -387.014225)
				(end 122.370596 -387.020308)
			)
			(arc
				(start 122.370596 -387.020308)
				(mid 122.319717 -387.016832)
				(end 122.269758 -387.006592)
			)
			(xy 121.95937 -386.921502) (xy 121.945908 -386.919724)
			(arc
				(start 121.591832 -386.919724)
				(mid 121.572309 -386.923625)
				(end 121.555764 -386.93471)
			)
			(arc
				(start 121.526554 -386.96392)
				(mid 121.515443 -386.980454)
				(end 121.511568 -386.999988)
			)
			(arc
				(start 121.511568 -387.672834)
				(mid 121.515469 -387.692357)
				(end 121.526554 -387.708902)
			)
			(arc
				(start 121.663206 -387.845554)
				(mid 121.67974 -387.856665)
				(end 121.699274 -387.86054)
			)
		)
		(stroke
			(width 0)
			(type solid)
		)
		(fill yes)
		(layer "F.Cu")
		(net "P1V8_CPU1_RT3_1A")
	)
	(gr_poly
		(pts
			(arc
				(start 154.526488 -387.86054)
				(mid 154.534863 -387.859845)
				(end 154.542998 -387.857746)
			)
			(arc
				(start 154.774392 -387.778244)
				(mid 154.835506 -387.762711)
				(end 154.898344 -387.757416)
			)
			(arc
				(start 154.898344 -387.757416)
				(mid 154.952488 -387.761351)
				(end 155.005532 -387.77291)
			)
			(arc
				(start 155.297886 -387.858508)
				(mid 155.304926 -387.860029)
				(end 155.31211 -387.86054)
			)
			(arc
				(start 155.726384 -387.86054)
				(mid 155.734759 -387.859845)
				(end 155.742894 -387.857746)
			)
			(arc
				(start 155.974288 -387.778244)
				(mid 156.035402 -387.762711)
				(end 156.09824 -387.757416)
			)
			(arc
				(start 156.09824 -387.757416)
				(mid 156.152384 -387.761351)
				(end 156.205428 -387.77291)
			)
			(arc
				(start 156.497782 -387.858508)
				(mid 156.504822 -387.860029)
				(end 156.512006 -387.86054)
			)
			(arc
				(start 156.753814 -387.86054)
				(mid 156.773337 -387.856639)
				(end 156.789882 -387.845554)
			)
			(arc
				(start 156.855414 -387.780022)
				(mid 156.866476 -387.763605)
				(end 156.8704 -387.744208)
			)
			(arc
				(start 156.8704 -387.483858)
				(mid 156.874233 -387.464501)
				(end 156.885132 -387.448044)
			)
			(xy 156.886656 -387.44652) (xy 156.894276 -387.427978) (xy 156.894276 -387.420104) (xy 156.979874 -387.334506)
			(xy 156.998416 -387.326886) (xy 157.00629 -387.326886)
			(arc
				(start 157.080458 -387.252718)
				(mid 157.096875 -387.241656)
				(end 157.116272 -387.237732)
			)
			(arc
				(start 157.401768 -387.237732)
				(mid 157.437689 -387.222853)
				(end 157.452568 -387.186932)
			)
			(arc
				(start 157.452568 -387.11886)
				(mid 157.448131 -387.098098)
				(end 157.43555 -387.081014)
			)
			(xy 157.371034 -387.023356) (xy 157.350714 -387.016752)
			(arc
				(start 157.339792 -387.018022)
				(mid 157.319122 -387.019725)
				(end 157.29839 -387.020308)
			)
			(arc
				(start 157.29839 -387.020308)
				(mid 157.247511 -387.016832)
				(end 157.197552 -387.006592)
			)
			(xy 156.887164 -386.921502) (xy 156.873702 -386.919724)
			(arc
				(start 156.445204 -386.919724)
				(mid 156.436167 -386.92058)
				(end 156.427424 -386.923026)
			)
			(arc
				(start 156.23159 -386.996178)
				(mid 156.165996 -387.014225)
				(end 156.09824 -387.020308)
			)
			(arc
				(start 156.09824 -387.020308)
				(mid 156.047361 -387.016832)
				(end 155.997402 -387.006592)
			)
			(xy 155.687268 -386.921502) (xy 155.673806 -386.919724)
			(arc
				(start 155.245308 -386.919724)
				(mid 155.236271 -386.92058)
				(end 155.227528 -386.923026)
			)
			(arc
				(start 155.031694 -386.996178)
				(mid 154.9661 -387.014225)
				(end 154.898344 -387.020308)
			)
			(arc
				(start 154.898344 -387.020308)
				(mid 154.847465 -387.016832)
				(end 154.797506 -387.006592)
			)
			(xy 154.487118 -386.921502) (xy 154.473656 -386.919724)
			(arc
				(start 154.11958 -386.919724)
				(mid 154.100057 -386.923625)
				(end 154.083512 -386.93471)
			)
			(arc
				(start 154.054302 -386.96392)
				(mid 154.043191 -386.980454)
				(end 154.039316 -386.999988)
			)
			(arc
				(start 154.039316 -387.672834)
				(mid 154.043217 -387.692357)
				(end 154.054302 -387.708902)
			)
			(arc
				(start 154.190954 -387.845554)
				(mid 154.207488 -387.856665)
				(end 154.227022 -387.86054)
			)
		)
		(stroke
			(width 0)
			(type solid)
		)
		(fill yes)
		(layer "F.Cu")
		(net "P1V8_CPU1_RT2_1A")
	)
	(gr_poly
		(pts
			(arc
				(start 310.89854 -396.24254)
				(mid 310.906915 -396.241845)
				(end 310.91505 -396.239746)
			)
			(arc
				(start 311.146444 -396.160244)
				(mid 311.207558 -396.144711)
				(end 311.270396 -396.139416)
			)
			(arc
				(start 311.270396 -396.139416)
				(mid 311.32454 -396.143351)
				(end 311.377584 -396.15491)
			)
			(arc
				(start 311.669938 -396.240508)
				(mid 311.676978 -396.242029)
				(end 311.684162 -396.24254)
			)
			(arc
				(start 312.098436 -396.24254)
				(mid 312.106811 -396.241845)
				(end 312.114946 -396.239746)
			)
			(arc
				(start 312.34634 -396.160244)
				(mid 312.407454 -396.144711)
				(end 312.470292 -396.139416)
			)
			(arc
				(start 312.470292 -396.139416)
				(mid 312.524436 -396.143351)
				(end 312.57748 -396.15491)
			)
			(arc
				(start 312.869834 -396.240508)
				(mid 312.876874 -396.242029)
				(end 312.884058 -396.24254)
			)
			(arc
				(start 313.125866 -396.24254)
				(mid 313.145389 -396.238639)
				(end 313.161934 -396.227554)
			)
			(arc
				(start 313.227466 -396.162022)
				(mid 313.238528 -396.145605)
				(end 313.242452 -396.126208)
			)
			(arc
				(start 313.242452 -395.865858)
				(mid 313.246285 -395.846501)
				(end 313.257184 -395.830044)
			)
			(xy 313.258708 -395.82852) (xy 313.266328 -395.809978) (xy 313.266328 -395.802104) (xy 313.351926 -395.716506)
			(xy 313.370468 -395.708886) (xy 313.378342 -395.708886)
			(arc
				(start 313.45251 -395.634718)
				(mid 313.468927 -395.623656)
				(end 313.488324 -395.619732)
			)
			(arc
				(start 313.77382 -395.619732)
				(mid 313.809741 -395.604853)
				(end 313.82462 -395.568932)
			)
			(arc
				(start 313.82462 -395.50086)
				(mid 313.820183 -395.480098)
				(end 313.807602 -395.463014)
			)
			(xy 313.743086 -395.405356) (xy 313.722766 -395.398752)
			(arc
				(start 313.711844 -395.400022)
				(mid 313.691174 -395.401725)
				(end 313.670442 -395.402308)
			)
			(arc
				(start 313.670442 -395.402308)
				(mid 313.619563 -395.398832)
				(end 313.569604 -395.388592)
			)
			(xy 313.259216 -395.303502) (xy 313.245754 -395.301724)
			(arc
				(start 312.817256 -395.301724)
				(mid 312.808219 -395.30258)
				(end 312.799476 -395.305026)
			)
			(arc
				(start 312.603642 -395.378178)
				(mid 312.538048 -395.396225)
				(end 312.470292 -395.402308)
			)
			(arc
				(start 312.470292 -395.402308)
				(mid 312.419413 -395.398832)
				(end 312.369454 -395.388592)
			)
			(xy 312.05932 -395.303502) (xy 312.045858 -395.301724)
			(arc
				(start 311.61736 -395.301724)
				(mid 311.608323 -395.30258)
				(end 311.59958 -395.305026)
			)
			(arc
				(start 311.403746 -395.378178)
				(mid 311.338152 -395.396225)
				(end 311.270396 -395.402308)
			)
			(arc
				(start 311.270396 -395.402308)
				(mid 311.219517 -395.398832)
				(end 311.169558 -395.388592)
			)
			(xy 310.85917 -395.303502) (xy 310.845708 -395.301724)
			(arc
				(start 310.491632 -395.301724)
				(mid 310.472109 -395.305625)
				(end 310.455564 -395.31671)
			)
			(arc
				(start 310.426354 -395.34592)
				(mid 310.415243 -395.362454)
				(end 310.411368 -395.381988)
			)
			(arc
				(start 310.411368 -396.054834)
				(mid 310.415269 -396.074357)
				(end 310.426354 -396.090902)
			)
			(arc
				(start 310.563006 -396.227554)
				(mid 310.57954 -396.238665)
				(end 310.599074 -396.24254)
			)
		)
		(stroke
			(width 0)
			(type solid)
		)
		(fill yes)
		(layer "F.Cu")
		(net "P1V8_CPU0_RT0_1A")
	)
	(gr_poly
		(pts
			(arc
				(start 343.426288 -396.24254)
				(mid 343.434663 -396.241845)
				(end 343.442798 -396.239746)
			)
			(arc
				(start 343.674192 -396.160244)
				(mid 343.735306 -396.144711)
				(end 343.798144 -396.139416)
			)
			(arc
				(start 343.798144 -396.139416)
				(mid 343.852288 -396.143351)
				(end 343.905332 -396.15491)
			)
			(arc
				(start 344.197686 -396.240508)
				(mid 344.204726 -396.242029)
				(end 344.21191 -396.24254)
			)
			(arc
				(start 344.626184 -396.24254)
				(mid 344.634559 -396.241845)
				(end 344.642694 -396.239746)
			)
			(arc
				(start 344.874088 -396.160244)
				(mid 344.935202 -396.144711)
				(end 344.99804 -396.139416)
			)
			(arc
				(start 344.99804 -396.139416)
				(mid 345.052184 -396.143351)
				(end 345.105228 -396.15491)
			)
			(arc
				(start 345.397582 -396.240508)
				(mid 345.404622 -396.242029)
				(end 345.411806 -396.24254)
			)
			(arc
				(start 345.653614 -396.24254)
				(mid 345.673137 -396.238639)
				(end 345.689682 -396.227554)
			)
			(arc
				(start 345.755214 -396.162022)
				(mid 345.766276 -396.145605)
				(end 345.7702 -396.126208)
			)
			(arc
				(start 345.7702 -395.865858)
				(mid 345.774033 -395.846501)
				(end 345.784932 -395.830044)
			)
			(xy 345.786456 -395.82852) (xy 345.794076 -395.809978) (xy 345.794076 -395.802104) (xy 345.879674 -395.716506)
			(xy 345.898216 -395.708886) (xy 345.90609 -395.708886)
			(arc
				(start 345.980258 -395.634718)
				(mid 345.996675 -395.623656)
				(end 346.016072 -395.619732)
			)
			(arc
				(start 346.301568 -395.619732)
				(mid 346.337489 -395.604853)
				(end 346.352368 -395.568932)
			)
			(arc
				(start 346.352368 -395.50086)
				(mid 346.347931 -395.480098)
				(end 346.33535 -395.463014)
			)
			(xy 346.270834 -395.405356) (xy 346.250514 -395.398752)
			(arc
				(start 346.239592 -395.400022)
				(mid 346.218922 -395.401725)
				(end 346.19819 -395.402308)
			)
			(arc
				(start 346.19819 -395.402308)
				(mid 346.147311 -395.398832)
				(end 346.097352 -395.388592)
			)
			(xy 345.786964 -395.303502) (xy 345.773502 -395.301724)
			(arc
				(start 345.345004 -395.301724)
				(mid 345.335967 -395.30258)
				(end 345.327224 -395.305026)
			)
			(arc
				(start 345.13139 -395.378178)
				(mid 345.065796 -395.396225)
				(end 344.99804 -395.402308)
			)
			(arc
				(start 344.99804 -395.402308)
				(mid 344.947161 -395.398832)
				(end 344.897202 -395.388592)
			)
			(xy 344.587068 -395.303502) (xy 344.573606 -395.301724)
			(arc
				(start 344.145108 -395.301724)
				(mid 344.136071 -395.30258)
				(end 344.127328 -395.305026)
			)
			(arc
				(start 343.931494 -395.378178)
				(mid 343.8659 -395.396225)
				(end 343.798144 -395.402308)
			)
			(arc
				(start 343.798144 -395.402308)
				(mid 343.747265 -395.398832)
				(end 343.697306 -395.388592)
			)
			(xy 343.386918 -395.303502) (xy 343.373456 -395.301724)
			(arc
				(start 343.01938 -395.301724)
				(mid 342.999857 -395.305625)
				(end 342.983312 -395.31671)
			)
			(arc
				(start 342.954102 -395.34592)
				(mid 342.942991 -395.362454)
				(end 342.939116 -395.381988)
			)
			(arc
				(start 342.939116 -396.054834)
				(mid 342.943017 -396.074357)
				(end 342.954102 -396.090902)
			)
			(arc
				(start 343.090754 -396.227554)
				(mid 343.107288 -396.238665)
				(end 343.126822 -396.24254)
			)
		)
		(stroke
			(width 0)
			(type solid)
		)
		(fill yes)
		(layer "F.Cu")
		(net "P1V8_CPU0_RT1_1A")
	)
	(gr_poly
		(pts
			(arc
				(start 377.998736 -396.24254)
				(mid 378.007111 -396.241845)
				(end 378.015246 -396.239746)
			)
			(arc
				(start 378.24664 -396.160244)
				(mid 378.307754 -396.144711)
				(end 378.370592 -396.139416)
			)
			(arc
				(start 378.370592 -396.139416)
				(mid 378.424736 -396.143351)
				(end 378.47778 -396.15491)
			)
			(arc
				(start 378.770134 -396.240508)
				(mid 378.777174 -396.242029)
				(end 378.784358 -396.24254)
			)
			(arc
				(start 379.198632 -396.24254)
				(mid 379.207007 -396.241845)
				(end 379.215142 -396.239746)
			)
			(arc
				(start 379.446536 -396.160244)
				(mid 379.50765 -396.144711)
				(end 379.570488 -396.139416)
			)
			(arc
				(start 379.570488 -396.139416)
				(mid 379.624632 -396.143351)
				(end 379.677676 -396.15491)
			)
			(arc
				(start 379.97003 -396.240508)
				(mid 379.97707 -396.242029)
				(end 379.984254 -396.24254)
			)
			(arc
				(start 380.226062 -396.24254)
				(mid 380.245585 -396.238639)
				(end 380.26213 -396.227554)
			)
			(arc
				(start 380.327662 -396.162022)
				(mid 380.338724 -396.145605)
				(end 380.342648 -396.126208)
			)
			(arc
				(start 380.342648 -395.865858)
				(mid 380.346481 -395.846501)
				(end 380.35738 -395.830044)
			)
			(xy 380.358904 -395.82852) (xy 380.366524 -395.809978) (xy 380.366524 -395.802104) (xy 380.452122 -395.716506)
			(xy 380.470664 -395.708886) (xy 380.478538 -395.708886)
			(arc
				(start 380.552706 -395.634718)
				(mid 380.569123 -395.623656)
				(end 380.58852 -395.619732)
			)
			(arc
				(start 380.874016 -395.619732)
				(mid 380.909937 -395.604853)
				(end 380.924816 -395.568932)
			)
			(arc
				(start 380.924816 -395.50086)
				(mid 380.920379 -395.480098)
				(end 380.907798 -395.463014)
			)
			(xy 380.843282 -395.405356) (xy 380.822962 -395.398752)
			(arc
				(start 380.81204 -395.400022)
				(mid 380.79137 -395.401725)
				(end 380.770638 -395.402308)
			)
			(arc
				(start 380.770638 -395.402308)
				(mid 380.719759 -395.398832)
				(end 380.6698 -395.388592)
			)
			(xy 380.359412 -395.303502) (xy 380.34595 -395.301724)
			(arc
				(start 379.917452 -395.301724)
				(mid 379.908415 -395.30258)
				(end 379.899672 -395.305026)
			)
			(arc
				(start 379.703838 -395.378178)
				(mid 379.638244 -395.396225)
				(end 379.570488 -395.402308)
			)
			(arc
				(start 379.570488 -395.402308)
				(mid 379.519609 -395.398832)
				(end 379.46965 -395.388592)
			)
			(xy 379.159516 -395.303502) (xy 379.146054 -395.301724)
			(arc
				(start 378.717556 -395.301724)
				(mid 378.708519 -395.30258)
				(end 378.699776 -395.305026)
			)
			(arc
				(start 378.503942 -395.378178)
				(mid 378.438348 -395.396225)
				(end 378.370592 -395.402308)
			)
			(arc
				(start 378.370592 -395.402308)
				(mid 378.319713 -395.398832)
				(end 378.269754 -395.388592)
			)
			(xy 377.959366 -395.303502) (xy 377.945904 -395.301724)
			(arc
				(start 377.591828 -395.301724)
				(mid 377.572305 -395.305625)
				(end 377.55576 -395.31671)
			)
			(arc
				(start 377.52655 -395.34592)
				(mid 377.515439 -395.362454)
				(end 377.511564 -395.381988)
			)
			(arc
				(start 377.511564 -396.054834)
				(mid 377.515465 -396.074357)
				(end 377.52655 -396.090902)
			)
			(arc
				(start 377.663202 -396.227554)
				(mid 377.679736 -396.238665)
				(end 377.69927 -396.24254)
			)
		)
		(stroke
			(width 0)
			(type solid)
		)
		(fill yes)
		(layer "F.Cu")
		(net "P1V8_CPU0_RT3_1A")
	)
	(gr_poly
		(pts
			(arc
				(start 410.526484 -396.24254)
				(mid 410.534859 -396.241845)
				(end 410.542994 -396.239746)
			)
			(arc
				(start 410.774388 -396.160244)
				(mid 410.835502 -396.144711)
				(end 410.89834 -396.139416)
			)
			(arc
				(start 410.89834 -396.139416)
				(mid 410.952484 -396.143351)
				(end 411.005528 -396.15491)
			)
			(arc
				(start 411.297882 -396.240508)
				(mid 411.304922 -396.242029)
				(end 411.312106 -396.24254)
			)
			(arc
				(start 411.72638 -396.24254)
				(mid 411.734755 -396.241845)
				(end 411.74289 -396.239746)
			)
			(arc
				(start 411.974284 -396.160244)
				(mid 412.035398 -396.144711)
				(end 412.098236 -396.139416)
			)
			(arc
				(start 412.098236 -396.139416)
				(mid 412.15238 -396.143351)
				(end 412.205424 -396.15491)
			)
			(arc
				(start 412.497778 -396.240508)
				(mid 412.504818 -396.242029)
				(end 412.512002 -396.24254)
			)
			(arc
				(start 412.75381 -396.24254)
				(mid 412.773333 -396.238639)
				(end 412.789878 -396.227554)
			)
			(arc
				(start 412.85541 -396.162022)
				(mid 412.866472 -396.145605)
				(end 412.870396 -396.126208)
			)
			(arc
				(start 412.870396 -395.865858)
				(mid 412.874229 -395.846501)
				(end 412.885128 -395.830044)
			)
			(xy 412.886652 -395.82852) (xy 412.894272 -395.809978) (xy 412.894272 -395.802104) (xy 412.97987 -395.716506)
			(xy 412.998412 -395.708886) (xy 413.006286 -395.708886)
			(arc
				(start 413.080454 -395.634718)
				(mid 413.096871 -395.623656)
				(end 413.116268 -395.619732)
			)
			(arc
				(start 413.401764 -395.619732)
				(mid 413.437685 -395.604853)
				(end 413.452564 -395.568932)
			)
			(arc
				(start 413.452564 -395.50086)
				(mid 413.448127 -395.480098)
				(end 413.435546 -395.463014)
			)
			(xy 413.37103 -395.405356) (xy 413.35071 -395.398752)
			(arc
				(start 413.339788 -395.400022)
				(mid 413.319118 -395.401725)
				(end 413.298386 -395.402308)
			)
			(arc
				(start 413.298386 -395.402308)
				(mid 413.247507 -395.398832)
				(end 413.197548 -395.388592)
			)
			(xy 412.88716 -395.303502) (xy 412.873698 -395.301724)
			(arc
				(start 412.4452 -395.301724)
				(mid 412.436163 -395.30258)
				(end 412.42742 -395.305026)
			)
			(arc
				(start 412.231586 -395.378178)
				(mid 412.165992 -395.396225)
				(end 412.098236 -395.402308)
			)
			(arc
				(start 412.098236 -395.402308)
				(mid 412.047357 -395.398832)
				(end 411.997398 -395.388592)
			)
			(xy 411.687264 -395.303502) (xy 411.673802 -395.301724)
			(arc
				(start 411.245304 -395.301724)
				(mid 411.236267 -395.30258)
				(end 411.227524 -395.305026)
			)
			(arc
				(start 411.03169 -395.378178)
				(mid 410.966096 -395.396225)
				(end 410.89834 -395.402308)
			)
			(arc
				(start 410.89834 -395.402308)
				(mid 410.847461 -395.398832)
				(end 410.797502 -395.388592)
			)
			(xy 410.487114 -395.303502) (xy 410.473652 -395.301724)
			(arc
				(start 410.119576 -395.301724)
				(mid 410.100053 -395.305625)
				(end 410.083508 -395.31671)
			)
			(arc
				(start 410.054298 -395.34592)
				(mid 410.043187 -395.362454)
				(end 410.039312 -395.381988)
			)
			(arc
				(start 410.039312 -396.054834)
				(mid 410.043213 -396.074357)
				(end 410.054298 -396.090902)
			)
			(arc
				(start 410.19095 -396.227554)
				(mid 410.207484 -396.238665)
				(end 410.227018 -396.24254)
			)
		)
		(stroke
			(width 0)
			(type solid)
		)
		(fill yes)
		(layer "F.Cu")
		(net "P1V8_CPU0_RT2_1A")
	)
	(gr_poly
		(pts
			(xy 113.577116 -171.643802) (xy 115.254278 -171.643802) (xy 115.290854 -171.607226) (xy 115.290854 -169.674286)
			(xy 115.279678 -169.66311) (xy 113.857278 -169.66311) (xy 113.764314 -169.570146) (xy 113.764314 -168.673526)
			(xy 113.263934 -168.173146) (xy 113.263934 -166.422832) (xy 114.247168 -165.439598) (xy 115.13058 -165.439598)
			(xy 115.788694 -166.097712) (xy 117.82425 -166.097712) (xy 118.95836 -164.963602) (xy 121.806716 -164.963602)
			(xy 121.857516 -164.912802) (xy 123.560078 -164.912802) (xy 123.584716 -164.888164) (xy 123.584716 -162.952684)
			(xy 123.564142 -162.93211) (xy 122.196098 -162.93211) (xy 122.004074 -162.740086) (xy 122.004074 -161.927032)
			(xy 121.54916 -161.472372) (xy 121.54916 -159.501586) (xy 121.854214 -159.196532) (xy 126.748794 -159.196532)
			(xy 126.949454 -158.995872) (xy 126.949454 -156.718508) (xy 127.36576 -156.302202) (xy 130.264916 -156.302202)
			(xy 130.315716 -156.251402) (xy 132.013198 -156.251402) (xy 132.042916 -156.221684) (xy 132.042916 -154.291284)
			(xy 132.022342 -154.27071) (xy 130.616198 -154.27071) (xy 130.518154 -154.172666) (xy 130.518154 -153.24836)
			(xy 130.01498 -152.745186) (xy 130.01498 -149.056852) (xy 129.593848 -148.63572) (xy 107.678474 -148.63572)
			(xy 105.95102 -150.363174) (xy 105.95102 -150.984147) (xy 111.75136 -150.984147) (xy 111.75136 -150.899425)
			(xy 111.759413 -150.815088) (xy 111.775447 -150.731898) (xy 111.799315 -150.650608) (xy 111.830803 -150.571956)
			(xy 111.869625 -150.496653) (xy 111.915428 -150.425381) (xy 111.967799 -150.358785) (xy 112.026264 -150.29747)
			(xy 112.090292 -150.241989) (xy 112.159304 -150.192846) (xy 112.232674 -150.150486) (xy 112.309739 -150.115291)
			(xy 112.389801 -150.087582) (xy 112.472134 -150.067608) (xy 112.555993 -150.055551) (xy 112.640618 -150.05152)
			(xy 112.725243 -150.055551) (xy 112.809102 -150.067608) (xy 112.891435 -150.087582) (xy 112.971497 -150.115291)
			(xy 113.048562 -150.150486) (xy 113.121932 -150.192846) (xy 113.190944 -150.241989) (xy 113.254972 -150.29747)
			(xy 113.313437 -150.358785) (xy 113.365808 -150.425381) (xy 113.411611 -150.496653) (xy 113.450433 -150.571956)
			(xy 113.481921 -150.650608) (xy 113.505789 -150.731898) (xy 113.521823 -150.815088) (xy 113.529876 -150.899425)
			(xy 113.53038 -150.941786) (xy 113.529876 -150.984147) (xy 113.521823 -151.068484) (xy 113.505789 -151.151674)
			(xy 113.481921 -151.232964) (xy 113.450433 -151.311616) (xy 113.411611 -151.386919) (xy 113.365808 -151.458191)
			(xy 113.313437 -151.524787) (xy 113.254972 -151.586102) (xy 113.190944 -151.641583) (xy 113.121932 -151.690726)
			(xy 113.048562 -151.733086) (xy 112.971497 -151.768281) (xy 112.891435 -151.79599) (xy 112.809102 -151.815964)
			(xy 112.725243 -151.828021) (xy 112.640618 -151.832053) (xy 112.555993 -151.828021) (xy 112.472134 -151.815964)
			(xy 112.389801 -151.79599) (xy 112.309739 -151.768281) (xy 112.232674 -151.733086) (xy 112.159304 -151.690726)
			(xy 112.090292 -151.641583) (xy 112.026264 -151.586102) (xy 111.967799 -151.524787) (xy 111.915428 -151.458191)
			(xy 111.869625 -151.386919) (xy 111.830803 -151.311616) (xy 111.799315 -151.232964) (xy 111.775447 -151.151674)
			(xy 111.759413 -151.068484) (xy 111.75136 -150.984147) (xy 105.95102 -150.984147) (xy 105.95102 -160.753552)
			(xy 110.096554 -164.899086) (xy 110.096554 -171.248832) (xy 110.52556 -171.677838) (xy 113.54308 -171.677838)
		)
		(stroke
			(width 0)
			(type solid)
		)
		(fill yes)
		(layer "F.Cu")
		(net "SW_P12V_AUX_PVDDCR_SOC_P1_FLT")
	)
	(gr_poly
		(pts
			(arc
				(start 137.562336 -391.260838)
				(mid 137.581859 -391.256937)
				(end 137.598404 -391.245852)
			)
			(arc
				(start 138.384534 -390.459722)
				(mid 138.401068 -390.448611)
				(end 138.420602 -390.444736)
			)
			(arc
				(start 139.456668 -390.444736)
				(mid 139.477016 -390.440483)
				(end 139.494006 -390.42848)
			)
			(xy 139.551918 -390.36625) (xy 139.558776 -390.346438) (xy 139.558014 -390.33577)
			(arc
				(start 139.556998 -390.308084)
				(mid 139.938506 -389.926576)
				(end 140.320014 -390.308084)
			)
			(arc
				(start 140.320014 -390.308084)
				(mid 140.307622 -390.404562)
				(end 140.271246 -390.494774)
			)
			(xy 140.262864 -390.50976) (xy 140.267436 -390.543542)
			(arc
				(start 140.877036 -391.153142)
				(mid 140.89357 -391.164253)
				(end 140.913104 -391.168128)
			)
			(arc
				(start 141.32052 -391.168128)
				(mid 141.340043 -391.164227)
				(end 141.356588 -391.153142)
			)
			(arc
				(start 141.48181 -391.02792)
				(mid 141.492921 -391.011386)
				(end 141.496796 -390.991852)
			)
			(arc
				(start 141.496796 -390.051544)
				(mid 141.492895 -390.032021)
				(end 141.48181 -390.015476)
			)
			(arc
				(start 141.283182 -389.816848)
				(mid 141.266736 -389.805922)
				(end 141.247368 -389.802116)
			)
			(arc
				(start 140.816584 -389.802116)
				(mid 140.756484 -389.796152)
				(end 140.698728 -389.778494)
			)
			(arc
				(start 140.17371 -389.56107)
				(mid 140.164244 -389.558221)
				(end 140.154406 -389.55726)
			)
			(arc
				(start 138.702542 -389.55726)
				(mid 138.683019 -389.553359)
				(end 138.666474 -389.542274)
			)
			(arc
				(start 138.533886 -389.409686)
				(mid 138.517352 -389.398575)
				(end 138.497818 -389.3947)
			)
			(arc
				(start 137.979404 -389.3947)
				(mid 137.960017 -389.39865)
				(end 137.94359 -389.409686)
			)
			(arc
				(start 137.77468 -389.578596)
				(mid 137.674793 -389.645245)
				(end 137.557002 -389.668512)
			)
			(arc
				(start 136.971786 -389.668512)
				(mid 136.952399 -389.672462)
				(end 136.935972 -389.683498)
			)
			(arc
				(start 136.929622 -389.689848)
				(mid 136.918511 -389.706382)
				(end 136.914636 -389.725916)
			)
			(arc
				(start 136.914636 -390.038844)
				(mid 136.910735 -390.058367)
				(end 136.89965 -390.074912)
			)
			(arc
				(start 136.77392 -390.200642)
				(mid 136.762809 -390.217176)
				(end 136.758934 -390.23671)
			)
			(arc
				(start 136.758934 -390.59231)
				(mid 136.762835 -390.611833)
				(end 136.77392 -390.628378)
			)
			(arc
				(start 136.847326 -390.701784)
				(mid 136.858437 -390.718318)
				(end 136.862312 -390.737852)
			)
			(xy 136.862312 -391.242042)
			(arc
				(start 136.866122 -391.245852)
				(mid 136.882656 -391.256963)
				(end 136.90219 -391.260838)
			)
		)
		(stroke
			(width 0)
			(type solid)
		)
		(fill yes)
		(layer "F.Cu")
		(net "GND")
	)
	(gr_poly
		(pts
			(arc
				(start 194.446144 -441.481972)
				(mid 194.482065 -441.467093)
				(end 194.496944 -441.431172)
			)
			(arc
				(start 194.496944 -441.17006)
				(mid 194.792217 -440.457207)
				(end 195.50507 -440.161934)
			)
			(arc
				(start 276.314916 -440.161934)
				(mid 277.027769 -440.457207)
				(end 277.323042 -441.17006)
			)
			(arc
				(start 277.323042 -441.431172)
				(mid 277.337921 -441.467093)
				(end 277.373842 -441.481972)
			)
			(arc
				(start 287.872424 -441.481972)
				(mid 287.900708 -441.47337)
				(end 287.919414 -441.450476)
			)
			(xy 287.960816 -441.348876) (xy 287.95472 -441.318904)
			(arc
				(start 287.943544 -441.307982)
				(mid 287.78871 -441.151585)
				(end 287.638236 -440.99099)
			)
			(arc
				(start 287.638236 -440.99099)
				(mid 287.621189 -440.978731)
				(end 287.600644 -440.97448)
			)
			(arc
				(start 277.817834 -440.97448)
				(mid 277.314992 -440.031472)
				(end 276.314916 -439.654696)
			)
			(arc
				(start 195.50507 -439.654696)
				(mid 194.504998 -440.031475)
				(end 194.002152 -440.97448)
			)
			(arc
				(start 185.699146 -440.97448)
				(mid 185.678634 -440.978805)
				(end 185.661554 -440.99099)
			)
			(arc
				(start 185.661554 -440.99099)
				(mid 185.51108 -441.151586)
				(end 185.356246 -441.307982)
			)
			(xy 185.34507 -441.318904) (xy 185.338974 -441.348876)
			(arc
				(start 185.380376 -441.450476)
				(mid 185.399081 -441.47337)
				(end 185.427366 -441.481972)
			)
		)
		(stroke
			(width 0)
			(type solid)
		)
		(fill yes)
		(layer "F.Cu")
		(net "GND")
	)
	(gr_poly
		(pts
			(arc
				(start 365.621062 -441.481972)
				(mid 365.649346 -441.47337)
				(end 365.668052 -441.450476)
			)
			(xy 365.709454 -441.348876) (xy 365.703358 -441.318904)
			(arc
				(start 365.692182 -441.307982)
				(mid 365.537348 -441.151585)
				(end 365.386874 -440.99099)
			)
			(arc
				(start 365.386874 -440.99099)
				(mid 365.369827 -440.978731)
				(end 365.349282 -440.97448)
			)
			(xy 343.82202 -440.97448) (xy 343.814654 -440.974988) (xy 343.803732 -440.976766)
			(arc
				(start 343.803224 -440.976766)
				(mid 343.728171 -440.994313)
				(end 343.651332 -441.000388)
			)
			(arc
				(start 343.648284 -441.000388)
				(mid 343.571441 -440.99434)
				(end 343.496392 -440.976766)
			)
			(xy 343.488772 -440.97448) (xy 339.822028 -440.97448) (xy 339.814662 -440.974988) (xy 339.80374 -440.976766)
			(arc
				(start 339.803232 -440.976766)
				(mid 339.728179 -440.994313)
				(end 339.65134 -441.000388)
			)
			(arc
				(start 339.648292 -441.000388)
				(mid 339.571449 -440.99434)
				(end 339.4964 -440.976766)
			)
			(xy 339.48878 -440.97448) (xy 335.822036 -440.97448) (xy 335.81467 -440.974988) (xy 335.803748 -440.976766)
			(arc
				(start 335.80324 -440.976766)
				(mid 335.728187 -440.994313)
				(end 335.651348 -441.000388)
			)
			(arc
				(start 335.6483 -441.000388)
				(mid 335.571457 -440.99434)
				(end 335.496408 -440.976766)
			)
			(xy 335.488788 -440.97448) (xy 332.118462 -440.97448) (xy 332.105254 -440.97829)
			(arc
				(start 332.099158 -440.981846)
				(mid 332.067294 -440.995722)
				(end 332.032864 -441.000388)
			)
			(arc
				(start 331.2668 -441.000388)
				(mid 331.232391 -440.995648)
				(end 331.200506 -440.981846)
			)
			(xy 331.19441 -440.97829) (xy 331.181202 -440.97448) (xy 326.822054 -440.97448) (xy 326.814688 -440.974988)
			(xy 326.803766 -440.976766)
			(arc
				(start 326.803258 -440.976766)
				(mid 326.728205 -440.994313)
				(end 326.651366 -441.000388)
			)
			(arc
				(start 326.648318 -441.000388)
				(mid 326.571475 -440.99434)
				(end 326.496426 -440.976766)
			)
			(xy 326.488806 -440.97448) (xy 322.822062 -440.97448) (xy 322.814696 -440.974988) (xy 322.803774 -440.976766)
			(arc
				(start 322.803266 -440.976766)
				(mid 322.728213 -440.994313)
				(end 322.651374 -441.000388)
			)
			(arc
				(start 322.648326 -441.000388)
				(mid 322.571483 -440.99434)
				(end 322.496434 -440.976766)
			)
			(xy 322.488814 -440.97448) (xy 318.82207 -440.97448) (xy 318.814704 -440.974988) (xy 318.803782 -440.976766)
			(arc
				(start 318.803274 -440.976766)
				(mid 318.728221 -440.994313)
				(end 318.651382 -441.000388)
			)
			(arc
				(start 318.648334 -441.000388)
				(mid 318.571491 -440.99434)
				(end 318.496442 -440.976766)
			)
			(xy 318.488822 -440.97448) (xy 315.118496 -440.97448) (xy 315.105288 -440.97829)
			(arc
				(start 315.099192 -440.981846)
				(mid 315.06745 -440.995688)
				(end 315.033152 -441.000388)
			)
			(arc
				(start 314.26658 -441.000388)
				(mid 314.232303 -440.995614)
				(end 314.20054 -440.981846)
			)
			(xy 314.194444 -440.97829) (xy 314.181236 -440.97448)
			(arc
				(start 299.499528 -440.97448)
				(mid 299.479016 -440.978805)
				(end 299.461936 -440.99099)
			)
			(arc
				(start 299.461936 -440.99099)
				(mid 299.311462 -441.151586)
				(end 299.156628 -441.307982)
			)
			(xy 299.145452 -441.318904) (xy 299.139356 -441.348876)
			(arc
				(start 299.180758 -441.450476)
				(mid 299.199463 -441.47337)
				(end 299.227748 -441.481972)
			)
		)
		(stroke
			(width 0)
			(type solid)
		)
		(fill yes)
		(layer "F.Cu")
		(net "GND")
	)
	(gr_poly
		(pts
			(arc
				(start 453.12203 -441.481972)
				(mid 453.150314 -441.47337)
				(end 453.16902 -441.450476)
			)
			(xy 453.210422 -441.348876) (xy 453.204326 -441.318904)
			(arc
				(start 453.19315 -441.307982)
				(mid 453.038316 -441.151585)
				(end 452.887842 -440.99099)
			)
			(arc
				(start 452.887842 -440.99099)
				(mid 452.870795 -440.978731)
				(end 452.85025 -440.97448)
			)
			(xy 410.922216 -440.97448) (xy 410.91485 -440.974988) (xy 410.903928 -440.976766)
			(arc
				(start 410.90342 -440.976766)
				(mid 410.828367 -440.994313)
				(end 410.751528 -441.000388)
			)
			(arc
				(start 410.74848 -441.000388)
				(mid 410.671637 -440.99434)
				(end 410.596588 -440.976766)
			)
			(xy 410.588968 -440.97448) (xy 406.922224 -440.97448) (xy 406.914858 -440.974988) (xy 406.903936 -440.976766)
			(arc
				(start 406.903428 -440.976766)
				(mid 406.828375 -440.994313)
				(end 406.751536 -441.000388)
			)
			(arc
				(start 406.748488 -441.000388)
				(mid 406.671645 -440.99434)
				(end 406.596596 -440.976766)
			)
			(xy 406.588976 -440.97448) (xy 402.922232 -440.97448) (xy 402.914866 -440.974988) (xy 402.903944 -440.976766)
			(arc
				(start 402.903436 -440.976766)
				(mid 402.828383 -440.994313)
				(end 402.751544 -441.000388)
			)
			(arc
				(start 402.748496 -441.000388)
				(mid 402.671653 -440.99434)
				(end 402.596604 -440.976766)
			)
			(xy 402.588984 -440.97448) (xy 399.218658 -440.97448) (xy 399.20545 -440.97829)
			(arc
				(start 399.199354 -440.981846)
				(mid 399.16749 -440.995722)
				(end 399.13306 -441.000388)
			)
			(arc
				(start 398.366996 -441.000388)
				(mid 398.332587 -440.995648)
				(end 398.300702 -440.981846)
			)
			(xy 398.294606 -440.97829) (xy 398.281398 -440.97448) (xy 393.921996 -440.97448) (xy 393.91463 -440.974988)
			(xy 393.903708 -440.976766)
			(arc
				(start 393.9032 -440.976766)
				(mid 393.828147 -440.994313)
				(end 393.751308 -441.000388)
			)
			(arc
				(start 393.74826 -441.000388)
				(mid 393.671417 -440.99434)
				(end 393.596368 -440.976766)
			)
			(xy 393.588748 -440.97448) (xy 389.922004 -440.97448) (xy 389.914638 -440.974988) (xy 389.903716 -440.976766)
			(arc
				(start 389.903208 -440.976766)
				(mid 389.828155 -440.994313)
				(end 389.751316 -441.000388)
			)
			(arc
				(start 389.748268 -441.000388)
				(mid 389.671425 -440.99434)
				(end 389.596376 -440.976766)
			)
			(xy 389.588756 -440.97448) (xy 385.922012 -440.97448) (xy 385.914646 -440.974988) (xy 385.903724 -440.976766)
			(arc
				(start 385.903216 -440.976766)
				(mid 385.828163 -440.994313)
				(end 385.751324 -441.000388)
			)
			(arc
				(start 385.748276 -441.000388)
				(mid 385.671433 -440.99434)
				(end 385.596384 -440.976766)
			)
			(xy 385.588764 -440.97448) (xy 382.218438 -440.97448) (xy 382.20523 -440.97829)
			(arc
				(start 382.199134 -440.981846)
				(mid 382.16727 -440.995722)
				(end 382.13284 -441.000388)
			)
			(arc
				(start 381.366776 -441.000388)
				(mid 381.332367 -440.995648)
				(end 381.300482 -440.981846)
			)
			(xy 381.294386 -440.97829) (xy 381.281178 -440.97448)
			(arc
				(start 377.248166 -440.97448)
				(mid 377.227654 -440.978805)
				(end 377.210574 -440.99099)
			)
			(arc
				(start 377.210574 -440.99099)
				(mid 377.0601 -441.151586)
				(end 376.905266 -441.307982)
			)
			(xy 376.89409 -441.318904) (xy 376.887994 -441.348876)
			(arc
				(start 376.929396 -441.450476)
				(mid 376.948101 -441.47337)
				(end 376.976386 -441.481972)
			)
		)
		(stroke
			(width 0)
			(type solid)
		)
		(fill yes)
		(layer "F.Cu")
		(net "GND")
	)
	(gr_poly
		(pts
			(arc
				(start 58.984642 -163.556696)
				(mid 59.004165 -163.552795)
				(end 59.02071 -163.54171)
			)
			(arc
				(start 59.247024 -163.315396)
				(mid 59.258135 -163.298862)
				(end 59.26201 -163.279328)
			)
			(xy 59.26201 -158.626302) (xy 59.26963 -158.60776) (xy 59.2709 -158.60649)
			(arc
				(start 59.2709 -158.261558)
				(mid 59.274801 -158.242035)
				(end 59.285886 -158.22549)
			)
			(xy 60.81141 -156.699966) (xy 60.811664 -156.699712) (xy 61.256672 -156.254704) (xy 63.144146 -156.254704)
			(xy 63.151258 -156.26207) (xy 63.170054 -156.26969) (xy 79.263494 -156.26969) (xy 79.268066 -156.264864)
			(xy 81.296256 -156.264864) (xy 81.482184 -156.078936) (xy 81.482184 -153.356818) (xy 81.422748 -153.297382)
			(xy 68.548504 -153.297382) (xy 68.521834 -153.324052)
			(arc
				(start 68.521834 -153.643076)
				(mid 68.529829 -153.687463)
				(end 68.532502 -153.732484)
			)
			(arc
				(start 68.532502 -154.484324)
				(mid 68.528552 -154.503711)
				(end 68.517516 -154.520138)
			)
			(xy 68.495418 -154.542236) (xy 68.495418 -155.484068) (xy 68.267834 -155.711652) (xy 67.782694 -155.711652)
			(arc
				(start 67.17284 -155.101798)
				(mid 67.161729 -155.085264)
				(end 67.157854 -155.06573)
			)
			(arc
				(start 67.157854 -154.193494)
				(mid 67.153953 -154.173971)
				(end 67.142868 -154.157426)
			)
			(arc
				(start 66.84264 -153.857198)
				(mid 66.826106 -153.846087)
				(end 66.806572 -153.842212)
			)
			(xy 61.42609 -153.842212) (xy 61.056012 -153.472134) (xy 61.056012 -144.193006) (xy 60.690252 -143.827246)
			(xy 58.89244 -143.827246) (xy 58.723022 -143.996664)
			(arc
				(start 58.723022 -155.531566)
				(mid 58.715469 -155.545982)
				(end 58.712862 -155.562046)
			)
			(arc
				(start 58.712862 -160.973516)
				(mid 58.708961 -160.993039)
				(end 58.697876 -161.009584)
			)
			(arc
				(start 58.325258 -161.382202)
				(mid 58.308724 -161.393313)
				(end 58.28919 -161.397188)
			)
			(arc
				(start 53.599842 -161.397188)
				(mid 53.580319 -161.393287)
				(end 53.563774 -161.382202)
			)
			(arc
				(start 53.33746 -161.155888)
				(mid 53.326349 -161.139354)
				(end 53.322474 -161.11982)
			)
			(arc
				(start 53.322474 -158.582614)
				(mid 53.318573 -158.563091)
				(end 53.307488 -158.546546)
			)
			(arc
				(start 52.151026 -157.390084)
				(mid 52.14012 -157.373901)
				(end 52.136294 -157.354778)
			)
			(arc
				(start 52.136294 -149.486874)
				(mid 52.132393 -149.467351)
				(end 52.121308 -149.450806)
			)
			(arc
				(start 51.93157 -149.261068)
				(mid 51.915036 -149.249957)
				(end 51.895502 -149.246082)
			)
			(arc
				(start 50.472848 -149.246082)
				(mid 50.453325 -149.249983)
				(end 50.43678 -149.261068)
			)
			(arc
				(start 50.247042 -149.450806)
				(mid 50.235931 -149.46734)
				(end 50.232056 -149.486874)
			)
			(arc
				(start 50.232056 -151.213566)
				(mid 50.231119 -151.223534)
				(end 50.228246 -151.233124)
			)
			(arc
				(start 50.221134 -151.249634)
				(mid 50.218261 -151.259224)
				(end 50.217324 -151.269192)
			)
			(arc
				(start 50.217324 -163.12134)
				(mid 50.221225 -163.140863)
				(end 50.23231 -163.157408)
			)
			(arc
				(start 50.592228 -163.517326)
				(mid 50.608762 -163.528437)
				(end 50.628296 -163.532312)
			)
			(arc
				(start 52.714398 -163.532312)
				(mid 52.733921 -163.536213)
				(end 52.750466 -163.547298)
			)
			(xy 52.752244 -163.549076) (xy 52.770786 -163.556696)
		)
		(stroke
			(width 0)
			(type solid)
		)
		(fill yes)
		(layer "F.Cu")
		(net "GND")
	)
	(gr_poly
		(pts
			(xy 471.29192 -17.195038)
			(arc
				(start 471.29192 -13.780008)
				(mid 470.854924 -12.725008)
				(end 469.799924 -12.288012)
			)
			(arc
				(start 458.20203 -12.288012)
				(mid 456.428609 -11.553437)
				(end 455.694034 -9.780016)
			)
			(arc
				(start 455.694034 -3.638042)
				(mid 455.682987 -3.606667)
				(end 455.654918 -3.588766)
			)
			(xy 455.541634 -3.561842) (xy 455.50963 -3.576828)
			(arc
				(start 455.501756 -3.592576)
				(mid 455.375805 -3.781776)
				(end 455.208132 -3.935222)
			)
			(arc
				(start 455.208132 -3.935222)
				(mid 455.192432 -3.953332)
				(end 455.186796 -3.976624)
			)
			(arc
				(start 455.186796 -9.780524)
				(mid 456.070027 -11.912452)
				(end 458.20203 -12.795504)
			)
			(arc
				(start 469.799924 -12.795504)
				(mid 470.496073 -13.083859)
				(end 470.784428 -13.780008)
			)
			(xy 470.784428 -16.987012) (xy 471.041984 -17.244568) (xy 471.24239 -17.244568)
		)
		(stroke
			(width 0)
			(type solid)
		)
		(fill yes)
		(layer "F.Cu")
		(net "GND")
	)
	(gr_poly
		(pts
			(arc
				(start 437.505856 -9.044432)
				(mid 437.54058 -9.030804)
				(end 437.556656 -8.997188)
			)
			(xy 437.556656 -7.59587) (xy 437.607964 -7.544308) (xy 437.72582 -7.544308) (xy 437.777128 -7.59587)
			(arc
				(start 437.777128 -8.997188)
				(mid 437.793279 -9.030723)
				(end 437.827928 -9.044432)
			)
			(arc
				(start 438.105804 -9.044432)
				(mid 438.140528 -9.030804)
				(end 438.156604 -8.997188)
			)
			(xy 438.156604 -7.59587) (xy 438.207912 -7.544308) (xy 438.325768 -7.544308) (xy 438.377076 -7.59587)
			(arc
				(start 438.377076 -8.997188)
				(mid 438.393227 -9.030723)
				(end 438.427876 -9.044432)
			)
			(arc
				(start 438.705752 -9.044432)
				(mid 438.740476 -9.030804)
				(end 438.756552 -8.997188)
			)
			(xy 438.756552 -7.59587) (xy 438.80786 -7.544308) (xy 438.925716 -7.544308) (xy 438.977024 -7.59587)
			(arc
				(start 438.977024 -8.997188)
				(mid 438.993175 -9.030723)
				(end 439.027824 -9.044432)
			)
			(arc
				(start 439.3057 -9.044432)
				(mid 439.340424 -9.030804)
				(end 439.3565 -8.997188)
			)
			(xy 439.3565 -7.59587) (xy 439.407808 -7.544308) (xy 439.525664 -7.544308) (xy 439.576972 -7.59587)
			(arc
				(start 439.576972 -8.997188)
				(mid 439.593123 -9.030723)
				(end 439.627772 -9.044432)
			)
			(arc
				(start 439.906156 -9.044432)
				(mid 439.939772 -9.031633)
				(end 439.956448 -8.999728)
			)
			(xy 439.956448 -7.59587) (xy 440.00801 -7.544308) (xy 440.125866 -7.544308) (xy 440.177428 -7.59587)
			(arc
				(start 440.177428 -8.999728)
				(mid 440.194048 -9.031696)
				(end 440.22772 -9.044432)
			)
			(arc
				(start 440.944762 -9.044432)
				(mid 440.964285 -9.040531)
				(end 440.98083 -9.029446)
			)
			(arc
				(start 441.179458 -8.830818)
				(mid 441.190569 -8.814284)
				(end 441.194444 -8.79475)
			)
			(arc
				(start 441.194444 -7.008114)
				(mid 441.190543 -6.988591)
				(end 441.179458 -6.972046)
			)
			(arc
				(start 440.90463 -6.697218)
				(mid 440.888096 -6.686107)
				(end 440.868562 -6.682232)
			)
			(xy 437.797956 -6.682232) (xy 437.772302 -6.700012)
			(arc
				(start 437.766714 -6.714998)
				(mid 437.626756 -6.894368)
				(end 437.40959 -6.96214)
			)
			(arc
				(start 437.409082 -6.96214)
				(mid 437.36743 -6.959832)
				(end 437.326278 -6.952996)
			)
			(xy 437.313324 -6.949948) (xy 437.288686 -6.957314)
			(arc
				(start 437.19623 -7.04977)
				(mid 437.185168 -7.066187)
				(end 437.181244 -7.085584)
			)
			(arc
				(start 437.181244 -8.97255)
				(mid 437.185145 -8.992073)
				(end 437.19623 -9.008618)
			)
			(arc
				(start 437.217058 -9.029446)
				(mid 437.233592 -9.040557)
				(end 437.253126 -9.044432)
			)
		)
		(stroke
			(width 0)
			(type solid)
		)
		(fill yes)
		(layer "F.Cu")
		(net "GND")
	)
	(gr_poly
		(pts
			(arc
				(start 47.697898 -387.860794)
				(mid 47.706273 -387.860099)
				(end 47.714408 -387.858)
			)
			(arc
				(start 47.946564 -387.778244)
				(mid 48.007678 -387.762711)
				(end 48.070516 -387.757416)
			)
			(arc
				(start 48.070516 -387.757416)
				(mid 48.12466 -387.761351)
				(end 48.177704 -387.77291)
			)
			(arc
				(start 48.47082 -387.858762)
				(mid 48.47786 -387.860283)
				(end 48.485044 -387.860794)
			)
			(arc
				(start 48.898048 -387.860794)
				(mid 48.906423 -387.860099)
				(end 48.914558 -387.858)
			)
			(arc
				(start 49.146714 -387.778244)
				(mid 49.207828 -387.762711)
				(end 49.270666 -387.757416)
			)
			(arc
				(start 49.270666 -387.757416)
				(mid 49.32481 -387.761351)
				(end 49.377854 -387.77291)
			)
			(arc
				(start 49.67097 -387.858762)
				(mid 49.67801 -387.860283)
				(end 49.685194 -387.860794)
			)
			(arc
				(start 50.097944 -387.860794)
				(mid 50.106319 -387.860099)
				(end 50.114454 -387.858)
			)
			(arc
				(start 50.34661 -387.778244)
				(mid 50.407724 -387.762711)
				(end 50.470562 -387.757416)
			)
			(arc
				(start 50.470562 -387.757416)
				(mid 50.524706 -387.761351)
				(end 50.57775 -387.77291)
			)
			(arc
				(start 50.870866 -387.858762)
				(mid 50.877906 -387.860283)
				(end 50.88509 -387.860794)
			)
			(arc
				(start 51.298094 -387.860794)
				(mid 51.306469 -387.860099)
				(end 51.314604 -387.858)
			)
			(arc
				(start 51.54676 -387.778244)
				(mid 51.597628 -387.764642)
				(end 51.649884 -387.758178)
			)
			(xy 51.65979 -387.75767) (xy 51.677316 -387.749542)
			(arc
				(start 51.73218 -387.69163)
				(mid 51.742429 -387.675425)
				(end 51.745896 -387.656578)
			)
			(arc
				(start 51.745896 -387.121146)
				(mid 51.742379 -387.102318)
				(end 51.73218 -387.086094)
			)
			(xy 51.677316 -387.028182) (xy 51.65979 -387.020054)
			(arc
				(start 51.649884 -387.019546)
				(mid 51.609533 -387.015203)
				(end 51.569874 -387.006592)
			)
			(xy 51.259486 -386.921502) (xy 51.246024 -386.919724)
			(arc
				(start 50.817526 -386.919724)
				(mid 50.808489 -386.92058)
				(end 50.799746 -386.923026)
			)
			(arc
				(start 50.603912 -386.996178)
				(mid 50.538318 -387.014225)
				(end 50.470562 -387.020308)
			)
			(arc
				(start 50.470562 -387.020308)
				(mid 50.419683 -387.016832)
				(end 50.369724 -387.006592)
			)
			(xy 50.05959 -386.921502) (xy 50.046128 -386.919724)
			(arc
				(start 49.61763 -386.919724)
				(mid 49.608593 -386.92058)
				(end 49.59985 -386.923026)
			)
			(arc
				(start 49.404016 -386.996178)
				(mid 49.338422 -387.014225)
				(end 49.270666 -387.020308)
			)
			(arc
				(start 49.270666 -387.020308)
				(mid 49.219787 -387.016832)
				(end 49.169828 -387.006592)
			)
			(xy 48.85944 -386.921502) (xy 48.845978 -386.919724)
			(arc
				(start 48.41748 -386.919724)
				(mid 48.408443 -386.92058)
				(end 48.3997 -386.923026)
			)
			(arc
				(start 48.203866 -386.996178)
				(mid 48.138272 -387.014225)
				(end 48.070516 -387.020308)
			)
			(arc
				(start 48.070516 -387.020308)
				(mid 48.019637 -387.016832)
				(end 47.969678 -387.006592)
			)
			(xy 47.659544 -386.921502) (xy 47.646082 -386.919724)
			(arc
				(start 47.28972 -386.919724)
				(mid 47.270197 -386.923625)
				(end 47.253652 -386.93471)
			)
			(arc
				(start 47.212504 -386.975858)
				(mid 47.201393 -386.992392)
				(end 47.197518 -387.011926)
			)
			(arc
				(start 47.197518 -387.763004)
				(mid 47.206505 -387.791854)
				(end 47.230284 -387.810502)
			)
			(arc
				(start 47.35322 -387.857492)
				(mid 47.362211 -387.859989)
				(end 47.371508 -387.860794)
			)
		)
		(stroke
			(width 0)
			(type solid)
		)
		(fill yes)
		(layer "F.Cu")
		(net "P0V9_CPU1_RT0_2A")
	)
	(gr_poly
		(pts
			(arc
				(start 80.225646 -387.860794)
				(mid 80.234021 -387.860099)
				(end 80.242156 -387.858)
			)
			(arc
				(start 80.474312 -387.778244)
				(mid 80.535426 -387.762711)
				(end 80.598264 -387.757416)
			)
			(arc
				(start 80.598264 -387.757416)
				(mid 80.652408 -387.761351)
				(end 80.705452 -387.77291)
			)
			(arc
				(start 80.998568 -387.858762)
				(mid 81.005608 -387.860283)
				(end 81.012792 -387.860794)
			)
			(arc
				(start 81.425796 -387.860794)
				(mid 81.434171 -387.860099)
				(end 81.442306 -387.858)
			)
			(arc
				(start 81.674462 -387.778244)
				(mid 81.735576 -387.762711)
				(end 81.798414 -387.757416)
			)
			(arc
				(start 81.798414 -387.757416)
				(mid 81.852558 -387.761351)
				(end 81.905602 -387.77291)
			)
			(arc
				(start 82.198718 -387.858762)
				(mid 82.205758 -387.860283)
				(end 82.212942 -387.860794)
			)
			(arc
				(start 82.625692 -387.860794)
				(mid 82.634067 -387.860099)
				(end 82.642202 -387.858)
			)
			(arc
				(start 82.874358 -387.778244)
				(mid 82.935472 -387.762711)
				(end 82.99831 -387.757416)
			)
			(arc
				(start 82.99831 -387.757416)
				(mid 83.052454 -387.761351)
				(end 83.105498 -387.77291)
			)
			(arc
				(start 83.398614 -387.858762)
				(mid 83.405654 -387.860283)
				(end 83.412838 -387.860794)
			)
			(arc
				(start 83.825842 -387.860794)
				(mid 83.834217 -387.860099)
				(end 83.842352 -387.858)
			)
			(arc
				(start 84.074508 -387.778244)
				(mid 84.125376 -387.764642)
				(end 84.177632 -387.758178)
			)
			(xy 84.187538 -387.75767) (xy 84.205064 -387.749542)
			(arc
				(start 84.259928 -387.69163)
				(mid 84.270177 -387.675425)
				(end 84.273644 -387.656578)
			)
			(arc
				(start 84.273644 -387.121146)
				(mid 84.270127 -387.102318)
				(end 84.259928 -387.086094)
			)
			(xy 84.205064 -387.028182) (xy 84.187538 -387.020054)
			(arc
				(start 84.177632 -387.019546)
				(mid 84.137281 -387.015203)
				(end 84.097622 -387.006592)
			)
			(xy 83.787234 -386.921502) (xy 83.773772 -386.919724)
			(arc
				(start 83.345274 -386.919724)
				(mid 83.336237 -386.92058)
				(end 83.327494 -386.923026)
			)
			(arc
				(start 83.13166 -386.996178)
				(mid 83.066066 -387.014225)
				(end 82.99831 -387.020308)
			)
			(arc
				(start 82.99831 -387.020308)
				(mid 82.947431 -387.016832)
				(end 82.897472 -387.006592)
			)
			(xy 82.587338 -386.921502) (xy 82.573876 -386.919724)
			(arc
				(start 82.145378 -386.919724)
				(mid 82.136341 -386.92058)
				(end 82.127598 -386.923026)
			)
			(arc
				(start 81.931764 -386.996178)
				(mid 81.86617 -387.014225)
				(end 81.798414 -387.020308)
			)
			(arc
				(start 81.798414 -387.020308)
				(mid 81.747535 -387.016832)
				(end 81.697576 -387.006592)
			)
			(xy 81.387188 -386.921502) (xy 81.373726 -386.919724)
			(arc
				(start 80.945228 -386.919724)
				(mid 80.936191 -386.92058)
				(end 80.927448 -386.923026)
			)
			(arc
				(start 80.731614 -386.996178)
				(mid 80.66602 -387.014225)
				(end 80.598264 -387.020308)
			)
			(arc
				(start 80.598264 -387.020308)
				(mid 80.547385 -387.016832)
				(end 80.497426 -387.006592)
			)
			(xy 80.187292 -386.921502) (xy 80.17383 -386.919724)
			(arc
				(start 79.817468 -386.919724)
				(mid 79.797945 -386.923625)
				(end 79.7814 -386.93471)
			)
			(arc
				(start 79.740252 -386.975858)
				(mid 79.729141 -386.992392)
				(end 79.725266 -387.011926)
			)
			(arc
				(start 79.725266 -387.763004)
				(mid 79.734253 -387.791854)
				(end 79.758032 -387.810502)
			)
			(arc
				(start 79.880968 -387.857492)
				(mid 79.889959 -387.859989)
				(end 79.899256 -387.860794)
			)
		)
		(stroke
			(width 0)
			(type solid)
		)
		(fill yes)
		(layer "F.Cu")
		(net "P0V9_CPU1_RT1_2A")
	)
	(gr_poly
		(pts
			(arc
				(start 114.79784 -387.860794)
				(mid 114.806215 -387.860099)
				(end 114.81435 -387.858)
			)
			(arc
				(start 115.046506 -387.778244)
				(mid 115.10762 -387.762711)
				(end 115.170458 -387.757416)
			)
			(arc
				(start 115.170458 -387.757416)
				(mid 115.224602 -387.761351)
				(end 115.277646 -387.77291)
			)
			(arc
				(start 115.570762 -387.858762)
				(mid 115.577802 -387.860283)
				(end 115.584986 -387.860794)
			)
			(arc
				(start 115.99799 -387.860794)
				(mid 116.006365 -387.860099)
				(end 116.0145 -387.858)
			)
			(arc
				(start 116.246656 -387.778244)
				(mid 116.30777 -387.762711)
				(end 116.370608 -387.757416)
			)
			(arc
				(start 116.370608 -387.757416)
				(mid 116.424752 -387.761351)
				(end 116.477796 -387.77291)
			)
			(arc
				(start 116.770912 -387.858762)
				(mid 116.777952 -387.860283)
				(end 116.785136 -387.860794)
			)
			(arc
				(start 117.197886 -387.860794)
				(mid 117.206261 -387.860099)
				(end 117.214396 -387.858)
			)
			(arc
				(start 117.446552 -387.778244)
				(mid 117.507666 -387.762711)
				(end 117.570504 -387.757416)
			)
			(arc
				(start 117.570504 -387.757416)
				(mid 117.624648 -387.761351)
				(end 117.677692 -387.77291)
			)
			(arc
				(start 117.970808 -387.858762)
				(mid 117.977848 -387.860283)
				(end 117.985032 -387.860794)
			)
			(arc
				(start 118.398036 -387.860794)
				(mid 118.406411 -387.860099)
				(end 118.414546 -387.858)
			)
			(arc
				(start 118.646702 -387.778244)
				(mid 118.69757 -387.764642)
				(end 118.749826 -387.758178)
			)
			(xy 118.759732 -387.75767) (xy 118.777258 -387.749542)
			(arc
				(start 118.832122 -387.69163)
				(mid 118.842503 -387.675453)
				(end 118.846092 -387.656578)
			)
			(arc
				(start 118.846092 -387.121146)
				(mid 118.842462 -387.102287)
				(end 118.832122 -387.086094)
			)
			(xy 118.777258 -387.028182) (xy 118.759732 -387.020054)
			(arc
				(start 118.749826 -387.019546)
				(mid 118.709475 -387.015203)
				(end 118.669816 -387.006592)
			)
			(xy 118.359428 -386.921502) (xy 118.345966 -386.919724)
			(arc
				(start 117.917468 -386.919724)
				(mid 117.908431 -386.92058)
				(end 117.899688 -386.923026)
			)
			(arc
				(start 117.703854 -386.996178)
				(mid 117.63826 -387.014225)
				(end 117.570504 -387.020308)
			)
			(arc
				(start 117.570504 -387.020308)
				(mid 117.519625 -387.016832)
				(end 117.469666 -387.006592)
			)
			(xy 117.159532 -386.921502) (xy 117.14607 -386.919724)
			(arc
				(start 116.717572 -386.919724)
				(mid 116.708535 -386.92058)
				(end 116.699792 -386.923026)
			)
			(arc
				(start 116.503958 -386.996178)
				(mid 116.438364 -387.014225)
				(end 116.370608 -387.020308)
			)
			(arc
				(start 116.370608 -387.020308)
				(mid 116.319729 -387.016832)
				(end 116.26977 -387.006592)
			)
			(xy 115.959382 -386.921502) (xy 115.94592 -386.919724)
			(arc
				(start 115.517422 -386.919724)
				(mid 115.508385 -386.92058)
				(end 115.499642 -386.923026)
			)
			(arc
				(start 115.303808 -386.996178)
				(mid 115.238214 -387.014225)
				(end 115.170458 -387.020308)
			)
			(arc
				(start 115.170458 -387.020308)
				(mid 115.119579 -387.016832)
				(end 115.06962 -387.006592)
			)
			(xy 114.759486 -386.921502) (xy 114.746024 -386.919724)
			(arc
				(start 114.389662 -386.919724)
				(mid 114.370139 -386.923625)
				(end 114.353594 -386.93471)
			)
			(arc
				(start 114.312446 -386.975858)
				(mid 114.301335 -386.992392)
				(end 114.29746 -387.011926)
			)
			(arc
				(start 114.29746 -387.763004)
				(mid 114.306447 -387.791854)
				(end 114.330226 -387.810502)
			)
			(arc
				(start 114.453162 -387.857492)
				(mid 114.462153 -387.859989)
				(end 114.47145 -387.860794)
			)
		)
		(stroke
			(width 0)
			(type solid)
		)
		(fill yes)
		(layer "F.Cu")
		(net "P0V9_CPU1_RT3_2A")
	)
	(gr_poly
		(pts
			(arc
				(start 147.325588 -387.860794)
				(mid 147.333963 -387.860099)
				(end 147.342098 -387.858)
			)
			(arc
				(start 147.574254 -387.778244)
				(mid 147.635368 -387.762711)
				(end 147.698206 -387.757416)
			)
			(arc
				(start 147.698206 -387.757416)
				(mid 147.75235 -387.761351)
				(end 147.805394 -387.77291)
			)
			(arc
				(start 148.09851 -387.858762)
				(mid 148.10555 -387.860283)
				(end 148.112734 -387.860794)
			)
			(arc
				(start 148.525738 -387.860794)
				(mid 148.534113 -387.860099)
				(end 148.542248 -387.858)
			)
			(arc
				(start 148.774404 -387.778244)
				(mid 148.835518 -387.762711)
				(end 148.898356 -387.757416)
			)
			(arc
				(start 148.898356 -387.757416)
				(mid 148.9525 -387.761351)
				(end 149.005544 -387.77291)
			)
			(arc
				(start 149.29866 -387.858762)
				(mid 149.3057 -387.860283)
				(end 149.312884 -387.860794)
			)
			(arc
				(start 149.725634 -387.860794)
				(mid 149.734009 -387.860099)
				(end 149.742144 -387.858)
			)
			(arc
				(start 149.9743 -387.778244)
				(mid 150.035414 -387.762711)
				(end 150.098252 -387.757416)
			)
			(arc
				(start 150.098252 -387.757416)
				(mid 150.152396 -387.761351)
				(end 150.20544 -387.77291)
			)
			(arc
				(start 150.498556 -387.858762)
				(mid 150.505596 -387.860283)
				(end 150.51278 -387.860794)
			)
			(arc
				(start 150.925784 -387.860794)
				(mid 150.934159 -387.860099)
				(end 150.942294 -387.858)
			)
			(arc
				(start 151.17445 -387.778244)
				(mid 151.225318 -387.764642)
				(end 151.277574 -387.758178)
			)
			(xy 151.28748 -387.75767) (xy 151.305006 -387.749542)
			(arc
				(start 151.35987 -387.69163)
				(mid 151.370251 -387.675453)
				(end 151.37384 -387.656578)
			)
			(arc
				(start 151.37384 -387.121146)
				(mid 151.37021 -387.102287)
				(end 151.35987 -387.086094)
			)
			(xy 151.305006 -387.028182) (xy 151.28748 -387.020054)
			(arc
				(start 151.277574 -387.019546)
				(mid 151.237223 -387.015203)
				(end 151.197564 -387.006592)
			)
			(xy 150.887176 -386.921502) (xy 150.873714 -386.919724)
			(arc
				(start 150.445216 -386.919724)
				(mid 150.436179 -386.92058)
				(end 150.427436 -386.923026)
			)
			(arc
				(start 150.231602 -386.996178)
				(mid 150.166008 -387.014225)
				(end 150.098252 -387.020308)
			)
			(arc
				(start 150.098252 -387.020308)
				(mid 150.047373 -387.016832)
				(end 149.997414 -387.006592)
			)
			(xy 149.68728 -386.921502) (xy 149.673818 -386.919724)
			(arc
				(start 149.24532 -386.919724)
				(mid 149.236283 -386.92058)
				(end 149.22754 -386.923026)
			)
			(arc
				(start 149.031706 -386.996178)
				(mid 148.966112 -387.014225)
				(end 148.898356 -387.020308)
			)
			(arc
				(start 148.898356 -387.020308)
				(mid 148.847477 -387.016832)
				(end 148.797518 -387.006592)
			)
			(xy 148.48713 -386.921502) (xy 148.473668 -386.919724)
			(arc
				(start 148.04517 -386.919724)
				(mid 148.036133 -386.92058)
				(end 148.02739 -386.923026)
			)
			(arc
				(start 147.831556 -386.996178)
				(mid 147.765962 -387.014225)
				(end 147.698206 -387.020308)
			)
			(arc
				(start 147.698206 -387.020308)
				(mid 147.647327 -387.016832)
				(end 147.597368 -387.006592)
			)
			(xy 147.287234 -386.921502) (xy 147.273772 -386.919724)
			(arc
				(start 146.91741 -386.919724)
				(mid 146.897887 -386.923625)
				(end 146.881342 -386.93471)
			)
			(arc
				(start 146.840194 -386.975858)
				(mid 146.829083 -386.992392)
				(end 146.825208 -387.011926)
			)
			(arc
				(start 146.825208 -387.763004)
				(mid 146.834195 -387.791854)
				(end 146.857974 -387.810502)
			)
			(arc
				(start 146.98091 -387.857492)
				(mid 146.989901 -387.859989)
				(end 146.999198 -387.860794)
			)
		)
		(stroke
			(width 0)
			(type solid)
		)
		(fill yes)
		(layer "F.Cu")
		(net "P0V9_CPU1_RT2_2A")
	)
	(gr_poly
		(pts
			(arc
				(start 303.69764 -396.242794)
				(mid 303.706015 -396.242099)
				(end 303.71415 -396.24)
			)
			(arc
				(start 303.946306 -396.160244)
				(mid 304.00742 -396.144711)
				(end 304.070258 -396.139416)
			)
			(arc
				(start 304.070258 -396.139416)
				(mid 304.124402 -396.143351)
				(end 304.177446 -396.15491)
			)
			(arc
				(start 304.470562 -396.240762)
				(mid 304.477602 -396.242283)
				(end 304.484786 -396.242794)
			)
			(arc
				(start 304.89779 -396.242794)
				(mid 304.906165 -396.242099)
				(end 304.9143 -396.24)
			)
			(arc
				(start 305.146456 -396.160244)
				(mid 305.20757 -396.144711)
				(end 305.270408 -396.139416)
			)
			(arc
				(start 305.270408 -396.139416)
				(mid 305.324552 -396.143351)
				(end 305.377596 -396.15491)
			)
			(arc
				(start 305.670712 -396.240762)
				(mid 305.677752 -396.242283)
				(end 305.684936 -396.242794)
			)
			(arc
				(start 306.097686 -396.242794)
				(mid 306.106061 -396.242099)
				(end 306.114196 -396.24)
			)
			(arc
				(start 306.346352 -396.160244)
				(mid 306.407466 -396.144711)
				(end 306.470304 -396.139416)
			)
			(arc
				(start 306.470304 -396.139416)
				(mid 306.524448 -396.143351)
				(end 306.577492 -396.15491)
			)
			(arc
				(start 306.870608 -396.240762)
				(mid 306.877648 -396.242283)
				(end 306.884832 -396.242794)
			)
			(arc
				(start 307.297836 -396.242794)
				(mid 307.306211 -396.242099)
				(end 307.314346 -396.24)
			)
			(arc
				(start 307.546502 -396.160244)
				(mid 307.59737 -396.146642)
				(end 307.649626 -396.140178)
			)
			(xy 307.659532 -396.13967) (xy 307.677058 -396.131542)
			(arc
				(start 307.731922 -396.07363)
				(mid 307.742303 -396.057453)
				(end 307.745892 -396.038578)
			)
			(arc
				(start 307.745892 -395.503146)
				(mid 307.742262 -395.484287)
				(end 307.731922 -395.468094)
			)
			(xy 307.677058 -395.410182) (xy 307.659532 -395.402054)
			(arc
				(start 307.649626 -395.401546)
				(mid 307.609275 -395.397203)
				(end 307.569616 -395.388592)
			)
			(xy 307.259228 -395.303502) (xy 307.245766 -395.301724)
			(arc
				(start 306.817268 -395.301724)
				(mid 306.808231 -395.30258)
				(end 306.799488 -395.305026)
			)
			(arc
				(start 306.603654 -395.378178)
				(mid 306.53806 -395.396225)
				(end 306.470304 -395.402308)
			)
			(arc
				(start 306.470304 -395.402308)
				(mid 306.419425 -395.398832)
				(end 306.369466 -395.388592)
			)
			(xy 306.059332 -395.303502) (xy 306.04587 -395.301724)
			(arc
				(start 305.617372 -395.301724)
				(mid 305.608335 -395.30258)
				(end 305.599592 -395.305026)
			)
			(arc
				(start 305.403758 -395.378178)
				(mid 305.338164 -395.396225)
				(end 305.270408 -395.402308)
			)
			(arc
				(start 305.270408 -395.402308)
				(mid 305.219529 -395.398832)
				(end 305.16957 -395.388592)
			)
			(xy 304.859182 -395.303502) (xy 304.84572 -395.301724)
			(arc
				(start 304.417222 -395.301724)
				(mid 304.408185 -395.30258)
				(end 304.399442 -395.305026)
			)
			(arc
				(start 304.203608 -395.378178)
				(mid 304.138014 -395.396225)
				(end 304.070258 -395.402308)
			)
			(arc
				(start 304.070258 -395.402308)
				(mid 304.019379 -395.398832)
				(end 303.96942 -395.388592)
			)
			(xy 303.659286 -395.303502) (xy 303.645824 -395.301724)
			(arc
				(start 303.289462 -395.301724)
				(mid 303.269939 -395.305625)
				(end 303.253394 -395.31671)
			)
			(arc
				(start 303.212246 -395.357858)
				(mid 303.201135 -395.374392)
				(end 303.19726 -395.393926)
			)
			(arc
				(start 303.19726 -396.145004)
				(mid 303.206247 -396.173854)
				(end 303.230026 -396.192502)
			)
			(arc
				(start 303.352962 -396.239492)
				(mid 303.361953 -396.241989)
				(end 303.37125 -396.242794)
			)
		)
		(stroke
			(width 0)
			(type solid)
		)
		(fill yes)
		(layer "F.Cu")
		(net "P0V9_CPU0_RT0_2A")
	)
	(gr_poly
		(pts
			(arc
				(start 336.225388 -396.242794)
				(mid 336.233763 -396.242099)
				(end 336.241898 -396.24)
			)
			(arc
				(start 336.474054 -396.160244)
				(mid 336.535168 -396.144711)
				(end 336.598006 -396.139416)
			)
			(arc
				(start 336.598006 -396.139416)
				(mid 336.65215 -396.143351)
				(end 336.705194 -396.15491)
			)
			(arc
				(start 336.99831 -396.240762)
				(mid 337.00535 -396.242283)
				(end 337.012534 -396.242794)
			)
			(arc
				(start 337.425538 -396.242794)
				(mid 337.433913 -396.242099)
				(end 337.442048 -396.24)
			)
			(arc
				(start 337.674204 -396.160244)
				(mid 337.735318 -396.144711)
				(end 337.798156 -396.139416)
			)
			(arc
				(start 337.798156 -396.139416)
				(mid 337.8523 -396.143351)
				(end 337.905344 -396.15491)
			)
			(arc
				(start 338.19846 -396.240762)
				(mid 338.2055 -396.242283)
				(end 338.212684 -396.242794)
			)
			(arc
				(start 338.625434 -396.242794)
				(mid 338.633809 -396.242099)
				(end 338.641944 -396.24)
			)
			(arc
				(start 338.8741 -396.160244)
				(mid 338.935214 -396.144711)
				(end 338.998052 -396.139416)
			)
			(arc
				(start 338.998052 -396.139416)
				(mid 339.052196 -396.143351)
				(end 339.10524 -396.15491)
			)
			(arc
				(start 339.398356 -396.240762)
				(mid 339.405396 -396.242283)
				(end 339.41258 -396.242794)
			)
			(arc
				(start 339.825584 -396.242794)
				(mid 339.833959 -396.242099)
				(end 339.842094 -396.24)
			)
			(arc
				(start 340.07425 -396.160244)
				(mid 340.125118 -396.146642)
				(end 340.177374 -396.140178)
			)
			(xy 340.18728 -396.13967) (xy 340.204806 -396.131542)
			(arc
				(start 340.25967 -396.07363)
				(mid 340.270051 -396.057453)
				(end 340.27364 -396.038578)
			)
			(arc
				(start 340.27364 -395.503146)
				(mid 340.27001 -395.484287)
				(end 340.25967 -395.468094)
			)
			(xy 340.204806 -395.410182) (xy 340.18728 -395.402054)
			(arc
				(start 340.177374 -395.401546)
				(mid 340.137023 -395.397203)
				(end 340.097364 -395.388592)
			)
			(xy 339.786976 -395.303502) (xy 339.773514 -395.301724)
			(arc
				(start 339.345016 -395.301724)
				(mid 339.335979 -395.30258)
				(end 339.327236 -395.305026)
			)
			(arc
				(start 339.131402 -395.378178)
				(mid 339.065808 -395.396225)
				(end 338.998052 -395.402308)
			)
			(arc
				(start 338.998052 -395.402308)
				(mid 338.947173 -395.398832)
				(end 338.897214 -395.388592)
			)
			(xy 338.58708 -395.303502) (xy 338.573618 -395.301724)
			(arc
				(start 338.14512 -395.301724)
				(mid 338.136083 -395.30258)
				(end 338.12734 -395.305026)
			)
			(arc
				(start 337.931506 -395.378178)
				(mid 337.865912 -395.396225)
				(end 337.798156 -395.402308)
			)
			(arc
				(start 337.798156 -395.402308)
				(mid 337.747277 -395.398832)
				(end 337.697318 -395.388592)
			)
			(xy 337.38693 -395.303502) (xy 337.373468 -395.301724)
			(arc
				(start 336.94497 -395.301724)
				(mid 336.935933 -395.30258)
				(end 336.92719 -395.305026)
			)
			(arc
				(start 336.731356 -395.378178)
				(mid 336.665762 -395.396225)
				(end 336.598006 -395.402308)
			)
			(arc
				(start 336.598006 -395.402308)
				(mid 336.547127 -395.398832)
				(end 336.497168 -395.388592)
			)
			(xy 336.187034 -395.303502) (xy 336.173572 -395.301724)
			(arc
				(start 335.81721 -395.301724)
				(mid 335.797687 -395.305625)
				(end 335.781142 -395.31671)
			)
			(arc
				(start 335.739994 -395.357858)
				(mid 335.728883 -395.374392)
				(end 335.725008 -395.393926)
			)
			(arc
				(start 335.725008 -396.145004)
				(mid 335.733995 -396.173854)
				(end 335.757774 -396.192502)
			)
			(arc
				(start 335.88071 -396.239492)
				(mid 335.889701 -396.241989)
				(end 335.898998 -396.242794)
			)
		)
		(stroke
			(width 0)
			(type solid)
		)
		(fill yes)
		(layer "F.Cu")
		(net "P0V9_CPU0_RT1_2A")
	)
	(gr_poly
		(pts
			(arc
				(start 370.797836 -396.242794)
				(mid 370.806211 -396.242099)
				(end 370.814346 -396.24)
			)
			(arc
				(start 371.046502 -396.160244)
				(mid 371.107616 -396.144711)
				(end 371.170454 -396.139416)
			)
			(arc
				(start 371.170454 -396.139416)
				(mid 371.224598 -396.143351)
				(end 371.277642 -396.15491)
			)
			(arc
				(start 371.570758 -396.240762)
				(mid 371.577798 -396.242283)
				(end 371.584982 -396.242794)
			)
			(arc
				(start 371.997986 -396.242794)
				(mid 372.006361 -396.242099)
				(end 372.014496 -396.24)
			)
			(arc
				(start 372.246652 -396.160244)
				(mid 372.307766 -396.144711)
				(end 372.370604 -396.139416)
			)
			(arc
				(start 372.370604 -396.139416)
				(mid 372.424748 -396.143351)
				(end 372.477792 -396.15491)
			)
			(arc
				(start 372.770908 -396.240762)
				(mid 372.777948 -396.242283)
				(end 372.785132 -396.242794)
			)
			(arc
				(start 373.197882 -396.242794)
				(mid 373.206257 -396.242099)
				(end 373.214392 -396.24)
			)
			(arc
				(start 373.446548 -396.160244)
				(mid 373.507662 -396.144711)
				(end 373.5705 -396.139416)
			)
			(arc
				(start 373.5705 -396.139416)
				(mid 373.624644 -396.143351)
				(end 373.677688 -396.15491)
			)
			(arc
				(start 373.970804 -396.240762)
				(mid 373.977844 -396.242283)
				(end 373.985028 -396.242794)
			)
			(arc
				(start 374.398032 -396.242794)
				(mid 374.406407 -396.242099)
				(end 374.414542 -396.24)
			)
			(arc
				(start 374.646698 -396.160244)
				(mid 374.697566 -396.146642)
				(end 374.749822 -396.140178)
			)
			(xy 374.759728 -396.13967) (xy 374.777254 -396.131542)
			(arc
				(start 374.832118 -396.07363)
				(mid 374.842499 -396.057453)
				(end 374.846088 -396.038578)
			)
			(arc
				(start 374.846088 -395.503146)
				(mid 374.842458 -395.484287)
				(end 374.832118 -395.468094)
			)
			(xy 374.777254 -395.410182) (xy 374.759728 -395.402054)
			(arc
				(start 374.749822 -395.401546)
				(mid 374.709471 -395.397203)
				(end 374.669812 -395.388592)
			)
			(xy 374.359424 -395.303502) (xy 374.345962 -395.301724)
			(arc
				(start 373.917464 -395.301724)
				(mid 373.908427 -395.30258)
				(end 373.899684 -395.305026)
			)
			(arc
				(start 373.70385 -395.378178)
				(mid 373.638256 -395.396225)
				(end 373.5705 -395.402308)
			)
			(arc
				(start 373.5705 -395.402308)
				(mid 373.519621 -395.398832)
				(end 373.469662 -395.388592)
			)
			(xy 373.159528 -395.303502) (xy 373.146066 -395.301724)
			(arc
				(start 372.717568 -395.301724)
				(mid 372.708531 -395.30258)
				(end 372.699788 -395.305026)
			)
			(arc
				(start 372.503954 -395.378178)
				(mid 372.43836 -395.396225)
				(end 372.370604 -395.402308)
			)
			(arc
				(start 372.370604 -395.402308)
				(mid 372.319725 -395.398832)
				(end 372.269766 -395.388592)
			)
			(xy 371.959378 -395.303502) (xy 371.945916 -395.301724)
			(arc
				(start 371.517418 -395.301724)
				(mid 371.508381 -395.30258)
				(end 371.499638 -395.305026)
			)
			(arc
				(start 371.303804 -395.378178)
				(mid 371.23821 -395.396225)
				(end 371.170454 -395.402308)
			)
			(arc
				(start 371.170454 -395.402308)
				(mid 371.119575 -395.398832)
				(end 371.069616 -395.388592)
			)
			(xy 370.759482 -395.303502) (xy 370.74602 -395.301724)
			(arc
				(start 370.389658 -395.301724)
				(mid 370.370135 -395.305625)
				(end 370.35359 -395.31671)
			)
			(arc
				(start 370.312442 -395.357858)
				(mid 370.301331 -395.374392)
				(end 370.297456 -395.393926)
			)
			(arc
				(start 370.297456 -396.145004)
				(mid 370.306443 -396.173854)
				(end 370.330222 -396.192502)
			)
			(arc
				(start 370.453158 -396.239492)
				(mid 370.462149 -396.241989)
				(end 370.471446 -396.242794)
			)
		)
		(stroke
			(width 0)
			(type solid)
		)
		(fill yes)
		(layer "F.Cu")
		(net "P0V9_CPU0_RT3_2A")
	)
	(gr_poly
		(pts
			(arc
				(start 403.325584 -396.242794)
				(mid 403.333959 -396.242099)
				(end 403.342094 -396.24)
			)
			(arc
				(start 403.57425 -396.160244)
				(mid 403.635364 -396.144711)
				(end 403.698202 -396.139416)
			)
			(arc
				(start 403.698202 -396.139416)
				(mid 403.752346 -396.143351)
				(end 403.80539 -396.15491)
			)
			(arc
				(start 404.098506 -396.240762)
				(mid 404.105546 -396.242283)
				(end 404.11273 -396.242794)
			)
			(arc
				(start 404.525734 -396.242794)
				(mid 404.534109 -396.242099)
				(end 404.542244 -396.24)
			)
			(arc
				(start 404.7744 -396.160244)
				(mid 404.835514 -396.144711)
				(end 404.898352 -396.139416)
			)
			(arc
				(start 404.898352 -396.139416)
				(mid 404.952496 -396.143351)
				(end 405.00554 -396.15491)
			)
			(arc
				(start 405.298656 -396.240762)
				(mid 405.305696 -396.242283)
				(end 405.31288 -396.242794)
			)
			(arc
				(start 405.72563 -396.242794)
				(mid 405.734005 -396.242099)
				(end 405.74214 -396.24)
			)
			(arc
				(start 405.974296 -396.160244)
				(mid 406.03541 -396.144711)
				(end 406.098248 -396.139416)
			)
			(arc
				(start 406.098248 -396.139416)
				(mid 406.152392 -396.143351)
				(end 406.205436 -396.15491)
			)
			(arc
				(start 406.498552 -396.240762)
				(mid 406.505592 -396.242283)
				(end 406.512776 -396.242794)
			)
			(arc
				(start 406.92578 -396.242794)
				(mid 406.934155 -396.242099)
				(end 406.94229 -396.24)
			)
			(arc
				(start 407.174446 -396.160244)
				(mid 407.225314 -396.146642)
				(end 407.27757 -396.140178)
			)
			(xy 407.287476 -396.13967) (xy 407.305002 -396.131542)
			(arc
				(start 407.359866 -396.07363)
				(mid 407.370247 -396.057453)
				(end 407.373836 -396.038578)
			)
			(arc
				(start 407.373836 -395.503146)
				(mid 407.370206 -395.484287)
				(end 407.359866 -395.468094)
			)
			(xy 407.305002 -395.410182) (xy 407.287476 -395.402054)
			(arc
				(start 407.27757 -395.401546)
				(mid 407.237219 -395.397203)
				(end 407.19756 -395.388592)
			)
			(xy 406.887172 -395.303502) (xy 406.87371 -395.301724)
			(arc
				(start 406.445212 -395.301724)
				(mid 406.436175 -395.30258)
				(end 406.427432 -395.305026)
			)
			(arc
				(start 406.231598 -395.378178)
				(mid 406.166004 -395.396225)
				(end 406.098248 -395.402308)
			)
			(arc
				(start 406.098248 -395.402308)
				(mid 406.047369 -395.398832)
				(end 405.99741 -395.388592)
			)
			(xy 405.687276 -395.303502) (xy 405.673814 -395.301724)
			(arc
				(start 405.245316 -395.301724)
				(mid 405.236279 -395.30258)
				(end 405.227536 -395.305026)
			)
			(arc
				(start 405.031702 -395.378178)
				(mid 404.966108 -395.396225)
				(end 404.898352 -395.402308)
			)
			(arc
				(start 404.898352 -395.402308)
				(mid 404.847473 -395.398832)
				(end 404.797514 -395.388592)
			)
			(xy 404.487126 -395.303502) (xy 404.473664 -395.301724)
			(arc
				(start 404.045166 -395.301724)
				(mid 404.036129 -395.30258)
				(end 404.027386 -395.305026)
			)
			(arc
				(start 403.831552 -395.378178)
				(mid 403.765958 -395.396225)
				(end 403.698202 -395.402308)
			)
			(arc
				(start 403.698202 -395.402308)
				(mid 403.647323 -395.398832)
				(end 403.597364 -395.388592)
			)
			(xy 403.28723 -395.303502) (xy 403.273768 -395.301724)
			(arc
				(start 402.917406 -395.301724)
				(mid 402.897883 -395.305625)
				(end 402.881338 -395.31671)
			)
			(arc
				(start 402.84019 -395.357858)
				(mid 402.829079 -395.374392)
				(end 402.825204 -395.393926)
			)
			(arc
				(start 402.825204 -396.145004)
				(mid 402.834191 -396.173854)
				(end 402.85797 -396.192502)
			)
			(arc
				(start 402.980906 -396.239492)
				(mid 402.989897 -396.241989)
				(end 402.999194 -396.242794)
			)
		)
		(stroke
			(width 0)
			(type solid)
		)
		(fill yes)
		(layer "F.Cu")
		(net "P0V9_CPU0_RT2_2A")
	)
	(gr_poly
		(pts
			(arc
				(start 129.197862 -387.860794)
				(mid 129.206237 -387.860099)
				(end 129.214372 -387.858)
			)
			(arc
				(start 129.446528 -387.778244)
				(mid 129.507642 -387.762711)
				(end 129.57048 -387.757416)
			)
			(arc
				(start 129.57048 -387.757416)
				(mid 129.624624 -387.761351)
				(end 129.677668 -387.77291)
			)
			(arc
				(start 129.970784 -387.858762)
				(mid 129.977824 -387.860283)
				(end 129.985008 -387.860794)
			)
			(arc
				(start 130.398012 -387.860794)
				(mid 130.406387 -387.860099)
				(end 130.414522 -387.858)
			)
			(arc
				(start 130.646678 -387.778244)
				(mid 130.707792 -387.762711)
				(end 130.77063 -387.757416)
			)
			(arc
				(start 130.77063 -387.757416)
				(mid 130.824774 -387.761351)
				(end 130.877818 -387.77291)
			)
			(arc
				(start 131.170934 -387.858762)
				(mid 131.177974 -387.860283)
				(end 131.185158 -387.860794)
			)
			(arc
				(start 131.597908 -387.860794)
				(mid 131.606283 -387.860099)
				(end 131.614418 -387.858)
			)
			(arc
				(start 131.846574 -387.778244)
				(mid 131.907688 -387.762711)
				(end 131.970526 -387.757416)
			)
			(arc
				(start 131.970526 -387.757416)
				(mid 132.02467 -387.761351)
				(end 132.077714 -387.77291)
			)
			(arc
				(start 132.37083 -387.858762)
				(mid 132.37787 -387.860283)
				(end 132.385054 -387.860794)
			)
			(arc
				(start 132.632958 -387.860794)
				(mid 132.646965 -387.858898)
				(end 132.659882 -387.853174)
			)
			(xy 132.72897 -387.80974) (xy 132.738114 -387.802628)
			(arc
				(start 132.754624 -387.786118)
				(mid 132.765735 -387.769584)
				(end 132.76961 -387.75005)
			)
			(arc
				(start 132.76961 -386.992114)
				(mid 132.765709 -386.972591)
				(end 132.754624 -386.956046)
			)
			(arc
				(start 132.733288 -386.93471)
				(mid 132.716754 -386.923599)
				(end 132.69722 -386.919724)
			)
			(arc
				(start 132.31749 -386.919724)
				(mid 132.308453 -386.92058)
				(end 132.29971 -386.923026)
			)
			(arc
				(start 132.103876 -386.996178)
				(mid 132.038282 -387.014225)
				(end 131.970526 -387.020308)
			)
			(arc
				(start 131.970526 -387.020308)
				(mid 131.919647 -387.016832)
				(end 131.869688 -387.006592)
			)
			(xy 131.559554 -386.921502) (xy 131.546092 -386.919724)
			(arc
				(start 131.117594 -386.919724)
				(mid 131.108557 -386.92058)
				(end 131.099814 -386.923026)
			)
			(arc
				(start 130.90398 -386.996178)
				(mid 130.838386 -387.014225)
				(end 130.77063 -387.020308)
			)
			(arc
				(start 130.77063 -387.020308)
				(mid 130.719751 -387.016832)
				(end 130.669792 -387.006592)
			)
			(xy 130.359404 -386.921502) (xy 130.345942 -386.919724)
			(arc
				(start 129.917444 -386.919724)
				(mid 129.908407 -386.92058)
				(end 129.899664 -386.923026)
			)
			(arc
				(start 129.70383 -386.996178)
				(mid 129.638236 -387.014225)
				(end 129.57048 -387.020308)
			)
			(arc
				(start 129.57048 -387.020308)
				(mid 129.519601 -387.016832)
				(end 129.469642 -387.006592)
			)
			(xy 129.159508 -386.921502) (xy 129.146046 -386.919724)
			(arc
				(start 128.717548 -386.919724)
				(mid 128.708511 -386.92058)
				(end 128.699768 -386.923026)
			)
			(arc
				(start 128.503934 -386.996178)
				(mid 128.44956 -387.011981)
				(end 128.393444 -387.019546)
			)
			(xy 128.383538 -387.020054) (xy 128.366012 -387.028182)
			(arc
				(start 128.311656 -387.086094)
				(mid 128.301454 -387.10218)
				(end 128.29794 -387.120892)
			)
			(arc
				(start 128.29794 -387.656832)
				(mid 128.301504 -387.675524)
				(end 128.311656 -387.69163)
			)
			(xy 128.366012 -387.749542) (xy 128.383538 -387.75767)
			(arc
				(start 128.393444 -387.758178)
				(mid 128.436021 -387.763176)
				(end 128.477772 -387.77291)
			)
			(arc
				(start 128.770888 -387.858762)
				(mid 128.777928 -387.860283)
				(end 128.785112 -387.860794)
			)
		)
		(stroke
			(width 0)
			(type solid)
		)
		(fill yes)
		(layer "F.Cu")
		(net "P0V9_CPU1_RT3_2A")
	)
	(gr_poly
		(pts
			(arc
				(start 161.72561 -387.860794)
				(mid 161.733985 -387.860099)
				(end 161.74212 -387.858)
			)
			(arc
				(start 161.974276 -387.778244)
				(mid 162.03539 -387.762711)
				(end 162.098228 -387.757416)
			)
			(arc
				(start 162.098228 -387.757416)
				(mid 162.152372 -387.761351)
				(end 162.205416 -387.77291)
			)
			(arc
				(start 162.498532 -387.858762)
				(mid 162.505572 -387.860283)
				(end 162.512756 -387.860794)
			)
			(arc
				(start 162.92576 -387.860794)
				(mid 162.934135 -387.860099)
				(end 162.94227 -387.858)
			)
			(arc
				(start 163.174426 -387.778244)
				(mid 163.23554 -387.762711)
				(end 163.298378 -387.757416)
			)
			(arc
				(start 163.298378 -387.757416)
				(mid 163.352522 -387.761351)
				(end 163.405566 -387.77291)
			)
			(arc
				(start 163.698682 -387.858762)
				(mid 163.705722 -387.860283)
				(end 163.712906 -387.860794)
			)
			(arc
				(start 164.125656 -387.860794)
				(mid 164.134031 -387.860099)
				(end 164.142166 -387.858)
			)
			(arc
				(start 164.374322 -387.778244)
				(mid 164.435436 -387.762711)
				(end 164.498274 -387.757416)
			)
			(arc
				(start 164.498274 -387.757416)
				(mid 164.552418 -387.761351)
				(end 164.605462 -387.77291)
			)
			(arc
				(start 164.898578 -387.858762)
				(mid 164.905618 -387.860283)
				(end 164.912802 -387.860794)
			)
			(arc
				(start 165.160706 -387.860794)
				(mid 165.174713 -387.858898)
				(end 165.18763 -387.853174)
			)
			(xy 165.256718 -387.80974) (xy 165.265862 -387.802628)
			(arc
				(start 165.282372 -387.786118)
				(mid 165.293483 -387.769584)
				(end 165.297358 -387.75005)
			)
			(arc
				(start 165.297358 -386.992114)
				(mid 165.293457 -386.972591)
				(end 165.282372 -386.956046)
			)
			(arc
				(start 165.261036 -386.93471)
				(mid 165.244502 -386.923599)
				(end 165.224968 -386.919724)
			)
			(arc
				(start 164.845238 -386.919724)
				(mid 164.836201 -386.92058)
				(end 164.827458 -386.923026)
			)
			(arc
				(start 164.631624 -386.996178)
				(mid 164.56603 -387.014225)
				(end 164.498274 -387.020308)
			)
			(arc
				(start 164.498274 -387.020308)
				(mid 164.447395 -387.016832)
				(end 164.397436 -387.006592)
			)
			(xy 164.087302 -386.921502) (xy 164.07384 -386.919724)
			(arc
				(start 163.645342 -386.919724)
				(mid 163.636305 -386.92058)
				(end 163.627562 -386.923026)
			)
			(arc
				(start 163.431728 -386.996178)
				(mid 163.366134 -387.014225)
				(end 163.298378 -387.020308)
			)
			(arc
				(start 163.298378 -387.020308)
				(mid 163.247499 -387.016832)
				(end 163.19754 -387.006592)
			)
			(xy 162.887152 -386.921502) (xy 162.87369 -386.919724)
			(arc
				(start 162.445192 -386.919724)
				(mid 162.436155 -386.92058)
				(end 162.427412 -386.923026)
			)
			(arc
				(start 162.231578 -386.996178)
				(mid 162.165984 -387.014225)
				(end 162.098228 -387.020308)
			)
			(arc
				(start 162.098228 -387.020308)
				(mid 162.047349 -387.016832)
				(end 161.99739 -387.006592)
			)
			(xy 161.687256 -386.921502) (xy 161.673794 -386.919724)
			(arc
				(start 161.245296 -386.919724)
				(mid 161.236259 -386.92058)
				(end 161.227516 -386.923026)
			)
			(arc
				(start 161.031682 -386.996178)
				(mid 160.977308 -387.011981)
				(end 160.921192 -387.019546)
			)
			(xy 160.911286 -387.020054) (xy 160.89376 -387.028182)
			(arc
				(start 160.839404 -387.086094)
				(mid 160.829202 -387.10218)
				(end 160.825688 -387.120892)
			)
			(arc
				(start 160.825688 -387.656832)
				(mid 160.829252 -387.675524)
				(end 160.839404 -387.69163)
			)
			(xy 160.89376 -387.749542) (xy 160.911286 -387.75767)
			(arc
				(start 160.921192 -387.758178)
				(mid 160.963769 -387.763176)
				(end 161.00552 -387.77291)
			)
			(arc
				(start 161.298636 -387.858762)
				(mid 161.305676 -387.860283)
				(end 161.31286 -387.860794)
			)
		)
		(stroke
			(width 0)
			(type solid)
		)
		(fill yes)
		(layer "F.Cu")
		(net "P0V9_CPU1_RT2_2A")
	)
	(gr_poly
		(pts
			(arc
				(start 350.62541 -396.242794)
				(mid 350.633785 -396.242099)
				(end 350.64192 -396.24)
			)
			(arc
				(start 350.874076 -396.160244)
				(mid 350.93519 -396.144711)
				(end 350.998028 -396.139416)
			)
			(arc
				(start 350.998028 -396.139416)
				(mid 351.052172 -396.143351)
				(end 351.105216 -396.15491)
			)
			(arc
				(start 351.398332 -396.240762)
				(mid 351.405372 -396.242283)
				(end 351.412556 -396.242794)
			)
			(arc
				(start 351.82556 -396.242794)
				(mid 351.833935 -396.242099)
				(end 351.84207 -396.24)
			)
			(arc
				(start 352.074226 -396.160244)
				(mid 352.13534 -396.144711)
				(end 352.198178 -396.139416)
			)
			(arc
				(start 352.198178 -396.139416)
				(mid 352.252322 -396.143351)
				(end 352.305366 -396.15491)
			)
			(arc
				(start 352.598482 -396.240762)
				(mid 352.605522 -396.242283)
				(end 352.612706 -396.242794)
			)
			(arc
				(start 353.025456 -396.242794)
				(mid 353.033831 -396.242099)
				(end 353.041966 -396.24)
			)
			(arc
				(start 353.274122 -396.160244)
				(mid 353.335236 -396.144711)
				(end 353.398074 -396.139416)
			)
			(arc
				(start 353.398074 -396.139416)
				(mid 353.452218 -396.143351)
				(end 353.505262 -396.15491)
			)
			(arc
				(start 353.798378 -396.240762)
				(mid 353.805418 -396.242283)
				(end 353.812602 -396.242794)
			)
			(arc
				(start 354.060506 -396.242794)
				(mid 354.074513 -396.240898)
				(end 354.08743 -396.235174)
			)
			(xy 354.156518 -396.19174) (xy 354.165662 -396.184628)
			(arc
				(start 354.182172 -396.168118)
				(mid 354.193283 -396.151584)
				(end 354.197158 -396.13205)
			)
			(arc
				(start 354.197158 -395.374114)
				(mid 354.193257 -395.354591)
				(end 354.182172 -395.338046)
			)
			(arc
				(start 354.160836 -395.31671)
				(mid 354.144302 -395.305599)
				(end 354.124768 -395.301724)
			)
			(arc
				(start 353.745038 -395.301724)
				(mid 353.736001 -395.30258)
				(end 353.727258 -395.305026)
			)
			(arc
				(start 353.531424 -395.378178)
				(mid 353.46583 -395.396225)
				(end 353.398074 -395.402308)
			)
			(arc
				(start 353.398074 -395.402308)
				(mid 353.347195 -395.398832)
				(end 353.297236 -395.388592)
			)
			(xy 352.987102 -395.303502) (xy 352.97364 -395.301724)
			(arc
				(start 352.545142 -395.301724)
				(mid 352.536105 -395.30258)
				(end 352.527362 -395.305026)
			)
			(arc
				(start 352.331528 -395.378178)
				(mid 352.265934 -395.396225)
				(end 352.198178 -395.402308)
			)
			(arc
				(start 352.198178 -395.402308)
				(mid 352.147299 -395.398832)
				(end 352.09734 -395.388592)
			)
			(xy 351.786952 -395.303502) (xy 351.77349 -395.301724)
			(arc
				(start 351.344992 -395.301724)
				(mid 351.335955 -395.30258)
				(end 351.327212 -395.305026)
			)
			(arc
				(start 351.131378 -395.378178)
				(mid 351.065784 -395.396225)
				(end 350.998028 -395.402308)
			)
			(arc
				(start 350.998028 -395.402308)
				(mid 350.947149 -395.398832)
				(end 350.89719 -395.388592)
			)
			(xy 350.587056 -395.303502) (xy 350.573594 -395.301724)
			(arc
				(start 350.145096 -395.301724)
				(mid 350.136059 -395.30258)
				(end 350.127316 -395.305026)
			)
			(arc
				(start 349.931482 -395.378178)
				(mid 349.877108 -395.393981)
				(end 349.820992 -395.401546)
			)
			(xy 349.811086 -395.402054) (xy 349.79356 -395.410182)
			(arc
				(start 349.739204 -395.468094)
				(mid 349.729002 -395.48418)
				(end 349.725488 -395.502892)
			)
			(arc
				(start 349.725488 -396.038832)
				(mid 349.729052 -396.057524)
				(end 349.739204 -396.07363)
			)
			(xy 349.79356 -396.131542) (xy 349.811086 -396.13967)
			(arc
				(start 349.820992 -396.140178)
				(mid 349.863569 -396.145176)
				(end 349.90532 -396.15491)
			)
			(arc
				(start 350.198436 -396.240762)
				(mid 350.205476 -396.242283)
				(end 350.21266 -396.242794)
			)
		)
		(stroke
			(width 0)
			(type solid)
		)
		(fill yes)
		(layer "F.Cu")
		(net "P0V9_CPU0_RT1_2A")
	)
	(gr_poly
		(pts
			(arc
				(start 417.725606 -396.242794)
				(mid 417.733981 -396.242099)
				(end 417.742116 -396.24)
			)
			(arc
				(start 417.974272 -396.160244)
				(mid 418.035386 -396.144711)
				(end 418.098224 -396.139416)
			)
			(arc
				(start 418.098224 -396.139416)
				(mid 418.152368 -396.143351)
				(end 418.205412 -396.15491)
			)
			(arc
				(start 418.498528 -396.240762)
				(mid 418.505568 -396.242283)
				(end 418.512752 -396.242794)
			)
			(arc
				(start 418.925756 -396.242794)
				(mid 418.934131 -396.242099)
				(end 418.942266 -396.24)
			)
			(arc
				(start 419.174422 -396.160244)
				(mid 419.235536 -396.144711)
				(end 419.298374 -396.139416)
			)
			(arc
				(start 419.298374 -396.139416)
				(mid 419.352518 -396.143351)
				(end 419.405562 -396.15491)
			)
			(arc
				(start 419.698678 -396.240762)
				(mid 419.705718 -396.242283)
				(end 419.712902 -396.242794)
			)
			(arc
				(start 420.125652 -396.242794)
				(mid 420.134027 -396.242099)
				(end 420.142162 -396.24)
			)
			(arc
				(start 420.374318 -396.160244)
				(mid 420.435432 -396.144711)
				(end 420.49827 -396.139416)
			)
			(arc
				(start 420.49827 -396.139416)
				(mid 420.552414 -396.143351)
				(end 420.605458 -396.15491)
			)
			(arc
				(start 420.898574 -396.240762)
				(mid 420.905614 -396.242283)
				(end 420.912798 -396.242794)
			)
			(arc
				(start 421.160702 -396.242794)
				(mid 421.174709 -396.240898)
				(end 421.187626 -396.235174)
			)
			(xy 421.256714 -396.19174) (xy 421.265858 -396.184628)
			(arc
				(start 421.282368 -396.168118)
				(mid 421.293479 -396.151584)
				(end 421.297354 -396.13205)
			)
			(arc
				(start 421.297354 -395.374114)
				(mid 421.293453 -395.354591)
				(end 421.282368 -395.338046)
			)
			(arc
				(start 421.261032 -395.31671)
				(mid 421.244498 -395.305599)
				(end 421.224964 -395.301724)
			)
			(arc
				(start 420.845234 -395.301724)
				(mid 420.836197 -395.30258)
				(end 420.827454 -395.305026)
			)
			(arc
				(start 420.63162 -395.378178)
				(mid 420.566026 -395.396225)
				(end 420.49827 -395.402308)
			)
			(arc
				(start 420.49827 -395.402308)
				(mid 420.447391 -395.398832)
				(end 420.397432 -395.388592)
			)
			(xy 420.087298 -395.303502) (xy 420.073836 -395.301724)
			(arc
				(start 419.645338 -395.301724)
				(mid 419.636301 -395.30258)
				(end 419.627558 -395.305026)
			)
			(arc
				(start 419.431724 -395.378178)
				(mid 419.36613 -395.396225)
				(end 419.298374 -395.402308)
			)
			(arc
				(start 419.298374 -395.402308)
				(mid 419.247495 -395.398832)
				(end 419.197536 -395.388592)
			)
			(xy 418.887148 -395.303502) (xy 418.873686 -395.301724)
			(arc
				(start 418.445188 -395.301724)
				(mid 418.436151 -395.30258)
				(end 418.427408 -395.305026)
			)
			(arc
				(start 418.231574 -395.378178)
				(mid 418.16598 -395.396225)
				(end 418.098224 -395.402308)
			)
			(arc
				(start 418.098224 -395.402308)
				(mid 418.047345 -395.398832)
				(end 417.997386 -395.388592)
			)
			(xy 417.687252 -395.303502) (xy 417.67379 -395.301724)
			(arc
				(start 417.245292 -395.301724)
				(mid 417.236255 -395.30258)
				(end 417.227512 -395.305026)
			)
			(arc
				(start 417.031678 -395.378178)
				(mid 416.977304 -395.393981)
				(end 416.921188 -395.401546)
			)
			(xy 416.911282 -395.402054) (xy 416.893756 -395.410182)
			(arc
				(start 416.8394 -395.468094)
				(mid 416.829198 -395.48418)
				(end 416.825684 -395.502892)
			)
			(arc
				(start 416.825684 -396.038832)
				(mid 416.829248 -396.057524)
				(end 416.8394 -396.07363)
			)
			(xy 416.893756 -396.131542) (xy 416.911282 -396.13967)
			(arc
				(start 416.921188 -396.140178)
				(mid 416.963765 -396.145176)
				(end 417.005516 -396.15491)
			)
			(arc
				(start 417.298632 -396.240762)
				(mid 417.305672 -396.242283)
				(end 417.312856 -396.242794)
			)
		)
		(stroke
			(width 0)
			(type solid)
		)
		(fill yes)
		(layer "F.Cu")
		(net "P0V9_CPU0_RT2_2A")
	)
	(gr_poly
		(pts
			(arc
				(start 62.09792 -387.860794)
				(mid 62.106295 -387.860099)
				(end 62.11443 -387.858)
			)
			(arc
				(start 62.346586 -387.778244)
				(mid 62.4077 -387.762711)
				(end 62.470538 -387.757416)
			)
			(arc
				(start 62.470538 -387.757416)
				(mid 62.524682 -387.761351)
				(end 62.577726 -387.77291)
			)
			(arc
				(start 62.870842 -387.858762)
				(mid 62.877882 -387.860283)
				(end 62.885066 -387.860794)
			)
			(arc
				(start 63.29807 -387.860794)
				(mid 63.306445 -387.860099)
				(end 63.31458 -387.858)
			)
			(arc
				(start 63.546736 -387.778244)
				(mid 63.60785 -387.762711)
				(end 63.670688 -387.757416)
			)
			(arc
				(start 63.670688 -387.757416)
				(mid 63.724832 -387.761351)
				(end 63.777876 -387.77291)
			)
			(arc
				(start 64.070992 -387.858762)
				(mid 64.078032 -387.860283)
				(end 64.085216 -387.860794)
			)
			(arc
				(start 64.497966 -387.860794)
				(mid 64.506341 -387.860099)
				(end 64.514476 -387.858)
			)
			(arc
				(start 64.746632 -387.778244)
				(mid 64.807746 -387.762711)
				(end 64.870584 -387.757416)
			)
			(arc
				(start 64.870584 -387.757416)
				(mid 64.924728 -387.761351)
				(end 64.977772 -387.77291)
			)
			(arc
				(start 65.270888 -387.858762)
				(mid 65.277928 -387.860283)
				(end 65.285112 -387.860794)
			)
			(arc
				(start 65.533016 -387.860794)
				(mid 65.547023 -387.858898)
				(end 65.55994 -387.853174)
			)
			(xy 65.629028 -387.80974) (xy 65.638172 -387.802628)
			(arc
				(start 65.654682 -387.786118)
				(mid 65.665793 -387.769584)
				(end 65.669668 -387.75005)
			)
			(arc
				(start 65.669668 -386.992114)
				(mid 65.665767 -386.972591)
				(end 65.654682 -386.956046)
			)
			(arc
				(start 65.633346 -386.93471)
				(mid 65.616812 -386.923599)
				(end 65.597278 -386.919724)
			)
			(arc
				(start 65.217548 -386.919724)
				(mid 65.208511 -386.92058)
				(end 65.199768 -386.923026)
			)
			(arc
				(start 65.003934 -386.996178)
				(mid 64.93834 -387.014225)
				(end 64.870584 -387.020308)
			)
			(arc
				(start 64.870584 -387.020308)
				(mid 64.819705 -387.016832)
				(end 64.769746 -387.006592)
			)
			(xy 64.459612 -386.921502) (xy 64.44615 -386.919724)
			(arc
				(start 64.017652 -386.919724)
				(mid 64.008615 -386.92058)
				(end 63.999872 -386.923026)
			)
			(arc
				(start 63.804038 -386.996178)
				(mid 63.738444 -387.014225)
				(end 63.670688 -387.020308)
			)
			(arc
				(start 63.670688 -387.020308)
				(mid 63.619809 -387.016832)
				(end 63.56985 -387.006592)
			)
			(xy 63.259462 -386.921502) (xy 63.246 -386.919724)
			(arc
				(start 62.817502 -386.919724)
				(mid 62.808465 -386.92058)
				(end 62.799722 -386.923026)
			)
			(arc
				(start 62.603888 -386.996178)
				(mid 62.538294 -387.014225)
				(end 62.470538 -387.020308)
			)
			(arc
				(start 62.470538 -387.020308)
				(mid 62.419659 -387.016832)
				(end 62.3697 -387.006592)
			)
			(xy 62.059566 -386.921502) (xy 62.046104 -386.919724)
			(arc
				(start 61.617606 -386.919724)
				(mid 61.608569 -386.92058)
				(end 61.599826 -386.923026)
			)
			(arc
				(start 61.403992 -386.996178)
				(mid 61.338398 -387.014225)
				(end 61.270642 -387.020308)
			)
			(xy 61.257942 -387.020054) (xy 61.247528 -387.019546) (xy 61.228224 -387.026912)
			(arc
				(start 61.16828 -387.085078)
				(mid 61.156982 -387.101699)
				(end 61.15304 -387.1214)
			)
			(arc
				(start 61.15304 -387.656324)
				(mid 61.157011 -387.676013)
				(end 61.16828 -387.692646)
			)
			(xy 61.228224 -387.750812) (xy 61.247528 -387.758178) (xy 61.257942 -387.75767)
			(arc
				(start 61.270642 -387.757416)
				(mid 61.324786 -387.761351)
				(end 61.37783 -387.77291)
			)
			(arc
				(start 61.670946 -387.858762)
				(mid 61.677986 -387.860283)
				(end 61.68517 -387.860794)
			)
		)
		(stroke
			(width 0)
			(type solid)
		)
		(fill yes)
		(layer "F.Cu")
		(net "P0V9_CPU1_RT0_2A")
	)
	(gr_poly
		(pts
			(arc
				(start 456.272392 -34.359342)
				(mid 456.291915 -34.355441)
				(end 456.30846 -34.344356)
			)
			(arc
				(start 456.511406 -34.14141)
				(mid 456.524024 -34.120416)
				(end 456.525376 -34.095944)
			)
			(xy 456.507342 -34.000948) (xy 456.491594 -33.98139)
			(arc
				(start 456.47991 -33.97631)
				(mid 455.561468 -33.203398)
				(end 455.217784 -32.053276)
			)
			(arc
				(start 455.217784 -32.053276)
				(mid 455.641961 -30.789065)
				(end 456.7428 -30.036516)
			)
			(arc
				(start 456.7428 -30.036516)
				(mid 456.769639 -30.01826)
				(end 456.779884 -29.987494)
			)
			(arc
				(start 456.779884 -18.643854)
				(mid 456.783785 -18.624331)
				(end 456.79487 -18.607786)
			)
			(arc
				(start 458.710538 -16.692118)
				(mid 458.727072 -16.681007)
				(end 458.746606 -16.677132)
			)
			(xy 459.09738 -16.677132) (xy 459.115922 -16.669258)
			(arc
				(start 459.123288 -16.662146)
				(mid 459.636869 -16.188246)
				(end 460.189834 -15.760954)
			)
			(arc
				(start 460.189834 -15.760954)
				(mid 460.205701 -15.742888)
				(end 460.211424 -15.719552)
			)
			(arc
				(start 460.211424 -14.071854)
				(mid 460.207523 -14.052331)
				(end 460.196438 -14.035786)
			)
			(arc
				(start 460.069692 -13.90904)
				(mid 460.053158 -13.897929)
				(end 460.033624 -13.894054)
			)
			(arc
				(start 456.033378 -13.894054)
				(mid 456.013855 -13.897955)
				(end 455.99731 -13.90904)
			)
			(arc
				(start 455.930762 -13.975588)
				(mid 455.919651 -13.992122)
				(end 455.915776 -14.011656)
			)
			(arc
				(start 455.915776 -16.17726)
				(mid 455.919677 -16.196783)
				(end 455.930762 -16.213328)
			)
			(arc
				(start 456.149202 -16.432022)
				(mid 456.160313 -16.448556)
				(end 456.164188 -16.46809)
			)
			(arc
				(start 456.164188 -25.440386)
				(mid 456.160287 -25.459909)
				(end 456.149202 -25.476454)
			)
			(arc
				(start 454.990962 -26.634694)
				(mid 454.979851 -26.651228)
				(end 454.975976 -26.670762)
			)
			(arc
				(start 454.975976 -28.80106)
				(mid 454.972075 -28.820583)
				(end 454.96099 -28.837128)
			)
			(arc
				(start 453.517762 -30.280356)
				(mid 453.501228 -30.291467)
				(end 453.481694 -30.295342)
			)
			(arc
				(start 447.834258 -30.295342)
				(mid 447.814735 -30.299243)
				(end 447.79819 -30.310328)
			)
			(xy 447.795396 -30.313122) (xy 447.787776 -30.331664)
			(arc
				(start 447.787776 -33.83026)
				(mid 447.791677 -33.849783)
				(end 447.802762 -33.866328)
			)
			(arc
				(start 448.28079 -34.344356)
				(mid 448.297324 -34.355467)
				(end 448.316858 -34.359342)
			)
		)
		(stroke
			(width 0)
			(type solid)
		)
		(fill yes)
		(layer "F.Cu")
		(net "GND")
	)
	(gr_poly
		(pts
			(xy 200.597262 -391.205974) (xy 200.607327 -391.205539) (xy 200.625912 -391.197806) (xy 200.63333 -391.190988)
			(xy 200.895458 -390.92886) (xy 200.902303 -390.921461) (xy 200.910029 -390.902863) (xy 200.910444 -390.892792)
			(xy 200.910444 -388.303262) (xy 200.909864 -388.291601) (xy 200.899527 -388.270696) (xy 200.890632 -388.26313)
			(xy 200.867868 -388.24495) (xy 200.827601 -388.202854) (xy 200.794199 -388.155126) (xy 200.768439 -388.102876)
			(xy 200.75092 -388.047318) (xy 200.742049 -387.989743) (xy 200.741534 -387.960616) (xy 200.741943 -387.936359)
			(xy 200.748154 -387.888242) (xy 200.760414 -387.8413) (xy 200.778526 -387.796292) (xy 200.790048 -387.774942)
			(xy 200.794978 -387.765066) (xy 200.796727 -387.743087) (xy 200.789091 -387.722403) (xy 200.781666 -387.714236)
			(xy 200.76541 -387.69798) (xy 200.758016 -387.691123) (xy 200.739417 -387.683372) (xy 200.729342 -387.682994)
			(xy 199.709786 -387.682994) (xy 199.699717 -387.683419) (xy 199.681115 -387.691137) (xy 199.673718 -387.69798)
			(xy 199.53605 -387.835648) (xy 199.528651 -387.842492) (xy 199.510053 -387.850217) (xy 199.499982 -387.850634)
			(xy 196.176646 -387.850634) (xy 196.166582 -387.850199) (xy 196.147998 -387.842464) (xy 196.140578 -387.835648)
			(xy 195.64731 -387.34238) (xy 195.639916 -387.335523) (xy 195.621317 -387.327772) (xy 195.611242 -387.327394)
			(xy 192.038986 -387.327394) (xy 192.028917 -387.327819) (xy 192.010315 -387.335537) (xy 192.002918 -387.34238)
			(xy 191.96939 -387.375908) (xy 191.962535 -387.383303) (xy 191.954789 -387.401902) (xy 191.954404 -387.411976)
			(xy 191.954404 -388.727385) (xy 193.900548 -388.727385) (xy 193.900548 -388.642663) (xy 193.908601 -388.558326)
			(xy 193.924635 -388.475136) (xy 193.948503 -388.393846) (xy 193.979991 -388.315194) (xy 194.018813 -388.239891)
			(xy 194.064616 -388.168619) (xy 194.116987 -388.102023) (xy 194.175452 -388.040708) (xy 194.23948 -387.985227)
			(xy 194.308492 -387.936084) (xy 194.381862 -387.893724) (xy 194.458927 -387.858529) (xy 194.538989 -387.83082)
			(xy 194.621322 -387.810846) (xy 194.705181 -387.798789) (xy 194.789806 -387.794758) (xy 194.874431 -387.798789)
			(xy 194.95829 -387.810846) (xy 195.040623 -387.83082) (xy 195.120685 -387.858529) (xy 195.19775 -387.893724)
			(xy 195.27112 -387.936084) (xy 195.340132 -387.985227) (xy 195.40416 -388.040708) (xy 195.462625 -388.102023)
			(xy 195.514996 -388.168619) (xy 195.560799 -388.239891) (xy 195.599621 -388.315194) (xy 195.631109 -388.393846)
			(xy 195.654977 -388.475136) (xy 195.671011 -388.558326) (xy 195.679064 -388.642663) (xy 195.679568 -388.685024)
			(xy 195.679064 -388.727385) (xy 195.671011 -388.811722) (xy 195.654977 -388.894912) (xy 195.631109 -388.976202)
			(xy 195.599621 -389.054854) (xy 195.560799 -389.130157) (xy 195.514996 -389.201429) (xy 195.462625 -389.268025)
			(xy 195.40416 -389.32934) (xy 195.340132 -389.384821) (xy 195.27112 -389.433964) (xy 195.19775 -389.476324)
			(xy 195.120685 -389.511519) (xy 195.040623 -389.539228) (xy 194.95829 -389.559202) (xy 194.874431 -389.571259)
			(xy 194.789806 -389.575291) (xy 194.705181 -389.571259) (xy 194.621322 -389.559202) (xy 194.538989 -389.539228)
			(xy 194.458927 -389.511519) (xy 194.381862 -389.476324) (xy 194.308492 -389.433964) (xy 194.23948 -389.384821)
			(xy 194.175452 -389.32934) (xy 194.116987 -389.268025) (xy 194.064616 -389.201429) (xy 194.018813 -389.130157)
			(xy 193.979991 -389.054854) (xy 193.948503 -388.976202) (xy 193.924635 -388.894912) (xy 193.908601 -388.811722)
			(xy 193.900548 -388.727385) (xy 191.954404 -388.727385) (xy 191.954404 -390.890252) (xy 191.954837 -390.900318)
			(xy 191.962565 -390.918908) (xy 191.96939 -390.92632) (xy 192.234058 -391.190988) (xy 192.241459 -391.197827)
			(xy 192.260057 -391.205542) (xy 192.270126 -391.205974)
		)
		(stroke
			(width 0)
			(type solid)
		)
		(fill yes)
		(layer "F.Cu")
		(net "GND")
	)
	(gr_poly
		(pts
			(arc
				(start 94.625668 -387.860794)
				(mid 94.634043 -387.860099)
				(end 94.642178 -387.858)
			)
			(arc
				(start 94.874334 -387.778244)
				(mid 94.935448 -387.762711)
				(end 94.998286 -387.757416)
			)
			(arc
				(start 94.998286 -387.757416)
				(mid 95.05243 -387.761351)
				(end 95.105474 -387.77291)
			)
			(arc
				(start 95.39859 -387.858762)
				(mid 95.40563 -387.860283)
				(end 95.412814 -387.860794)
			)
			(arc
				(start 95.825818 -387.860794)
				(mid 95.834193 -387.860099)
				(end 95.842328 -387.858)
			)
			(arc
				(start 96.074484 -387.778244)
				(mid 96.135598 -387.762711)
				(end 96.198436 -387.757416)
			)
			(arc
				(start 96.198436 -387.757416)
				(mid 96.25258 -387.761351)
				(end 96.305624 -387.77291)
			)
			(arc
				(start 96.59874 -387.858762)
				(mid 96.60578 -387.860283)
				(end 96.612964 -387.860794)
			)
			(arc
				(start 97.025714 -387.860794)
				(mid 97.034089 -387.860099)
				(end 97.042224 -387.858)
			)
			(arc
				(start 97.27438 -387.778244)
				(mid 97.335494 -387.762711)
				(end 97.398332 -387.757416)
			)
			(arc
				(start 97.398332 -387.757416)
				(mid 97.452476 -387.761351)
				(end 97.50552 -387.77291)
			)
			(arc
				(start 97.798636 -387.858762)
				(mid 97.805676 -387.860283)
				(end 97.81286 -387.860794)
			)
			(arc
				(start 98.060764 -387.860794)
				(mid 98.074771 -387.858898)
				(end 98.087688 -387.853174)
			)
			(xy 98.156776 -387.80974) (xy 98.16592 -387.802628)
			(arc
				(start 98.18243 -387.786118)
				(mid 98.193541 -387.769584)
				(end 98.197416 -387.75005)
			)
			(arc
				(start 98.197416 -386.992114)
				(mid 98.193515 -386.972591)
				(end 98.18243 -386.956046)
			)
			(arc
				(start 98.161094 -386.93471)
				(mid 98.14456 -386.923599)
				(end 98.125026 -386.919724)
			)
			(arc
				(start 97.745296 -386.919724)
				(mid 97.736259 -386.92058)
				(end 97.727516 -386.923026)
			)
			(arc
				(start 97.531682 -386.996178)
				(mid 97.466088 -387.014225)
				(end 97.398332 -387.020308)
			)
			(arc
				(start 97.398332 -387.020308)
				(mid 97.347453 -387.016832)
				(end 97.297494 -387.006592)
			)
			(xy 96.98736 -386.921502) (xy 96.973898 -386.919724)
			(arc
				(start 96.5454 -386.919724)
				(mid 96.536363 -386.92058)
				(end 96.52762 -386.923026)
			)
			(arc
				(start 96.331786 -386.996178)
				(mid 96.266192 -387.014225)
				(end 96.198436 -387.020308)
			)
			(arc
				(start 96.198436 -387.020308)
				(mid 96.147557 -387.016832)
				(end 96.097598 -387.006592)
			)
			(xy 95.78721 -386.921502) (xy 95.773748 -386.919724)
			(arc
				(start 95.34525 -386.919724)
				(mid 95.336213 -386.92058)
				(end 95.32747 -386.923026)
			)
			(arc
				(start 95.131636 -386.996178)
				(mid 95.066042 -387.014225)
				(end 94.998286 -387.020308)
			)
			(arc
				(start 94.998286 -387.020308)
				(mid 94.947407 -387.016832)
				(end 94.897448 -387.006592)
			)
			(xy 94.587314 -386.921502) (xy 94.573852 -386.919724)
			(arc
				(start 94.145354 -386.919724)
				(mid 94.136317 -386.92058)
				(end 94.127574 -386.923026)
			)
			(arc
				(start 93.93174 -386.996178)
				(mid 93.866146 -387.014225)
				(end 93.79839 -387.020308)
			)
			(arc
				(start 93.79839 -387.020308)
				(mid 93.774207 -387.019428)
				(end 93.75013 -387.017006)
			)
			(xy 93.739208 -387.015736) (xy 93.718634 -387.022086)
			(arc
				(start 93.653102 -387.079744)
				(mid 93.640384 -387.096938)
				(end 93.63583 -387.117844)
			)
			(arc
				(start 93.63583 -387.65988)
				(mid 93.64034 -387.680806)
				(end 93.653102 -387.69798)
			)
			(xy 93.718634 -387.755638) (xy 93.739208 -387.761988)
			(arc
				(start 93.75013 -387.760718)
				(mid 93.774208 -387.758307)
				(end 93.79839 -387.757416)
			)
			(arc
				(start 93.79839 -387.757416)
				(mid 93.852534 -387.761351)
				(end 93.905578 -387.77291)
			)
			(arc
				(start 94.198694 -387.858762)
				(mid 94.205734 -387.860283)
				(end 94.212918 -387.860794)
			)
		)
		(stroke
			(width 0)
			(type solid)
		)
		(fill yes)
		(layer "F.Cu")
		(net "P0V9_CPU1_RT1_2A")
	)
	(gr_poly
		(pts
			(arc
				(start 318.097662 -396.242794)
				(mid 318.106037 -396.242099)
				(end 318.114172 -396.24)
			)
			(arc
				(start 318.346328 -396.160244)
				(mid 318.407442 -396.144711)
				(end 318.47028 -396.139416)
			)
			(arc
				(start 318.47028 -396.139416)
				(mid 318.524424 -396.143351)
				(end 318.577468 -396.15491)
			)
			(arc
				(start 318.870584 -396.240762)
				(mid 318.877624 -396.242283)
				(end 318.884808 -396.242794)
			)
			(arc
				(start 319.297812 -396.242794)
				(mid 319.306187 -396.242099)
				(end 319.314322 -396.24)
			)
			(arc
				(start 319.546478 -396.160244)
				(mid 319.607592 -396.144711)
				(end 319.67043 -396.139416)
			)
			(arc
				(start 319.67043 -396.139416)
				(mid 319.724574 -396.143351)
				(end 319.777618 -396.15491)
			)
			(arc
				(start 320.070734 -396.240762)
				(mid 320.077774 -396.242283)
				(end 320.084958 -396.242794)
			)
			(arc
				(start 320.497708 -396.242794)
				(mid 320.506083 -396.242099)
				(end 320.514218 -396.24)
			)
			(arc
				(start 320.746374 -396.160244)
				(mid 320.807488 -396.144711)
				(end 320.870326 -396.139416)
			)
			(arc
				(start 320.870326 -396.139416)
				(mid 320.92447 -396.143351)
				(end 320.977514 -396.15491)
			)
			(arc
				(start 321.27063 -396.240762)
				(mid 321.27767 -396.242283)
				(end 321.284854 -396.242794)
			)
			(arc
				(start 321.532758 -396.242794)
				(mid 321.546765 -396.240898)
				(end 321.559682 -396.235174)
			)
			(xy 321.62877 -396.19174) (xy 321.637914 -396.184628)
			(arc
				(start 321.654424 -396.168118)
				(mid 321.665535 -396.151584)
				(end 321.66941 -396.13205)
			)
			(arc
				(start 321.66941 -395.374114)
				(mid 321.665509 -395.354591)
				(end 321.654424 -395.338046)
			)
			(arc
				(start 321.633088 -395.31671)
				(mid 321.616554 -395.305599)
				(end 321.59702 -395.301724)
			)
			(arc
				(start 321.21729 -395.301724)
				(mid 321.208253 -395.30258)
				(end 321.19951 -395.305026)
			)
			(arc
				(start 321.003676 -395.378178)
				(mid 320.938082 -395.396225)
				(end 320.870326 -395.402308)
			)
			(arc
				(start 320.870326 -395.402308)
				(mid 320.819447 -395.398832)
				(end 320.769488 -395.388592)
			)
			(xy 320.459354 -395.303502) (xy 320.445892 -395.301724)
			(arc
				(start 320.017394 -395.301724)
				(mid 320.008357 -395.30258)
				(end 319.999614 -395.305026)
			)
			(arc
				(start 319.80378 -395.378178)
				(mid 319.738186 -395.396225)
				(end 319.67043 -395.402308)
			)
			(arc
				(start 319.67043 -395.402308)
				(mid 319.619551 -395.398832)
				(end 319.569592 -395.388592)
			)
			(xy 319.259204 -395.303502) (xy 319.245742 -395.301724)
			(arc
				(start 318.817244 -395.301724)
				(mid 318.808207 -395.30258)
				(end 318.799464 -395.305026)
			)
			(arc
				(start 318.60363 -395.378178)
				(mid 318.538036 -395.396225)
				(end 318.47028 -395.402308)
			)
			(arc
				(start 318.47028 -395.402308)
				(mid 318.419401 -395.398832)
				(end 318.369442 -395.388592)
			)
			(xy 318.059308 -395.303502) (xy 318.045846 -395.301724)
			(arc
				(start 317.617348 -395.301724)
				(mid 317.608311 -395.30258)
				(end 317.599568 -395.305026)
			)
			(arc
				(start 317.403734 -395.378178)
				(mid 317.33814 -395.396225)
				(end 317.270384 -395.402308)
			)
			(arc
				(start 317.270384 -395.402308)
				(mid 317.246201 -395.401428)
				(end 317.222124 -395.399006)
			)
			(xy 317.211202 -395.397736) (xy 317.190628 -395.404086)
			(arc
				(start 317.125096 -395.461744)
				(mid 317.112378 -395.478938)
				(end 317.107824 -395.499844)
			)
			(arc
				(start 317.107824 -396.04188)
				(mid 317.112334 -396.062806)
				(end 317.125096 -396.07998)
			)
			(xy 317.190628 -396.137638) (xy 317.211202 -396.143988)
			(arc
				(start 317.222124 -396.142718)
				(mid 317.246202 -396.140307)
				(end 317.270384 -396.139416)
			)
			(arc
				(start 317.270384 -396.139416)
				(mid 317.324528 -396.143351)
				(end 317.377572 -396.15491)
			)
			(arc
				(start 317.670688 -396.240762)
				(mid 317.677728 -396.242283)
				(end 317.684912 -396.242794)
			)
		)
		(stroke
			(width 0)
			(type solid)
		)
		(fill yes)
		(layer "F.Cu")
		(net "P0V9_CPU0_RT0_2A")
	)
	(gr_poly
		(pts
			(arc
				(start 385.197858 -396.242794)
				(mid 385.206233 -396.242099)
				(end 385.214368 -396.24)
			)
			(arc
				(start 385.446524 -396.160244)
				(mid 385.507638 -396.144711)
				(end 385.570476 -396.139416)
			)
			(arc
				(start 385.570476 -396.139416)
				(mid 385.62462 -396.143351)
				(end 385.677664 -396.15491)
			)
			(arc
				(start 385.97078 -396.240762)
				(mid 385.97782 -396.242283)
				(end 385.985004 -396.242794)
			)
			(arc
				(start 386.398008 -396.242794)
				(mid 386.406383 -396.242099)
				(end 386.414518 -396.24)
			)
			(arc
				(start 386.646674 -396.160244)
				(mid 386.707788 -396.144711)
				(end 386.770626 -396.139416)
			)
			(arc
				(start 386.770626 -396.139416)
				(mid 386.82477 -396.143351)
				(end 386.877814 -396.15491)
			)
			(arc
				(start 387.17093 -396.240762)
				(mid 387.17797 -396.242283)
				(end 387.185154 -396.242794)
			)
			(arc
				(start 387.597904 -396.242794)
				(mid 387.606279 -396.242099)
				(end 387.614414 -396.24)
			)
			(arc
				(start 387.84657 -396.160244)
				(mid 387.907684 -396.144711)
				(end 387.970522 -396.139416)
			)
			(arc
				(start 387.970522 -396.139416)
				(mid 388.024666 -396.143351)
				(end 388.07771 -396.15491)
			)
			(arc
				(start 388.370826 -396.240762)
				(mid 388.377866 -396.242283)
				(end 388.38505 -396.242794)
			)
			(arc
				(start 388.632954 -396.242794)
				(mid 388.646961 -396.240898)
				(end 388.659878 -396.235174)
			)
			(xy 388.728966 -396.19174) (xy 388.73811 -396.184628)
			(arc
				(start 388.75462 -396.168118)
				(mid 388.765731 -396.151584)
				(end 388.769606 -396.13205)
			)
			(arc
				(start 388.769606 -395.374114)
				(mid 388.765705 -395.354591)
				(end 388.75462 -395.338046)
			)
			(arc
				(start 388.733284 -395.31671)
				(mid 388.71675 -395.305599)
				(end 388.697216 -395.301724)
			)
			(arc
				(start 388.317486 -395.301724)
				(mid 388.308449 -395.30258)
				(end 388.299706 -395.305026)
			)
			(arc
				(start 388.103872 -395.378178)
				(mid 388.038278 -395.396225)
				(end 387.970522 -395.402308)
			)
			(arc
				(start 387.970522 -395.402308)
				(mid 387.919643 -395.398832)
				(end 387.869684 -395.388592)
			)
			(xy 387.55955 -395.303502) (xy 387.546088 -395.301724)
			(arc
				(start 387.11759 -395.301724)
				(mid 387.108553 -395.30258)
				(end 387.09981 -395.305026)
			)
			(arc
				(start 386.903976 -395.378178)
				(mid 386.838382 -395.396225)
				(end 386.770626 -395.402308)
			)
			(arc
				(start 386.770626 -395.402308)
				(mid 386.719747 -395.398832)
				(end 386.669788 -395.388592)
			)
			(xy 386.3594 -395.303502) (xy 386.345938 -395.301724)
			(arc
				(start 385.91744 -395.301724)
				(mid 385.908403 -395.30258)
				(end 385.89966 -395.305026)
			)
			(arc
				(start 385.703826 -395.378178)
				(mid 385.638232 -395.396225)
				(end 385.570476 -395.402308)
			)
			(arc
				(start 385.570476 -395.402308)
				(mid 385.519597 -395.398832)
				(end 385.469638 -395.388592)
			)
			(xy 385.159504 -395.303502) (xy 385.146042 -395.301724)
			(arc
				(start 384.717544 -395.301724)
				(mid 384.708507 -395.30258)
				(end 384.699764 -395.305026)
			)
			(arc
				(start 384.50393 -395.378178)
				(mid 384.438336 -395.396225)
				(end 384.37058 -395.402308)
			)
			(arc
				(start 384.37058 -395.402308)
				(mid 384.346397 -395.401428)
				(end 384.32232 -395.399006)
			)
			(xy 384.311398 -395.397736) (xy 384.290824 -395.404086)
			(arc
				(start 384.225292 -395.461744)
				(mid 384.212574 -395.478938)
				(end 384.20802 -395.499844)
			)
			(arc
				(start 384.20802 -396.04188)
				(mid 384.21253 -396.062806)
				(end 384.225292 -396.07998)
			)
			(xy 384.290824 -396.137638) (xy 384.311398 -396.143988)
			(arc
				(start 384.32232 -396.142718)
				(mid 384.346398 -396.140307)
				(end 384.37058 -396.139416)
			)
			(arc
				(start 384.37058 -396.139416)
				(mid 384.424724 -396.143351)
				(end 384.477768 -396.15491)
			)
			(arc
				(start 384.770884 -396.240762)
				(mid 384.777924 -396.242283)
				(end 384.785108 -396.242794)
			)
		)
		(stroke
			(width 0)
			(type solid)
		)
		(fill yes)
		(layer "F.Cu")
		(net "P0V9_CPU0_RT3_2A")
	)
	(gr_poly
		(pts
			(arc
				(start 94.82328 -441.481972)
				(mid 94.851564 -441.47337)
				(end 94.87027 -441.450476)
			)
			(xy 94.911672 -441.348876) (xy 94.905576 -441.318904)
			(arc
				(start 94.8944 -441.307982)
				(mid 94.73957 -441.15171)
				(end 94.589092 -440.991244)
			)
			(arc
				(start 94.589092 -440.991244)
				(mid 94.572062 -440.978925)
				(end 94.5515 -440.97448)
			)
			(xy 87.822278 -440.97448) (xy 87.82177 -440.97448) (xy 87.81034 -440.97448) (xy 87.803736 -440.976766)
			(arc
				(start 87.803482 -440.976766)
				(mid 87.729812 -440.994133)
				(end 87.654384 -441.000388)
			)
			(xy 87.650574 -441.000388) (xy 87.649558 -441.000388)
			(arc
				(start 87.645748 -441.000388)
				(mid 87.570325 -440.994103)
				(end 87.49665 -440.976766)
			)
			(xy 87.494872 -440.976258) (xy 87.489792 -440.97448) (xy 83.822286 -440.97448) (xy 83.821778 -440.97448)
			(xy 83.810348 -440.97448) (xy 83.803744 -440.976766)
			(arc
				(start 83.80349 -440.976766)
				(mid 83.72982 -440.994133)
				(end 83.654392 -441.000388)
			)
			(xy 83.650582 -441.000388) (xy 83.649566 -441.000388)
			(arc
				(start 83.645756 -441.000388)
				(mid 83.570333 -440.994103)
				(end 83.496658 -440.976766)
			)
			(xy 83.49488 -440.976258) (xy 83.4898 -440.97448) (xy 79.822294 -440.97448) (xy 79.821786 -440.97448)
			(xy 79.810356 -440.97448) (xy 79.803752 -440.976766)
			(arc
				(start 79.803498 -440.976766)
				(mid 79.729828 -440.994133)
				(end 79.6544 -441.000388)
			)
			(xy 79.65059 -441.000388) (xy 79.649574 -441.000388)
			(arc
				(start 79.645764 -441.000388)
				(mid 79.570341 -440.994103)
				(end 79.496666 -440.976766)
			)
			(xy 79.494888 -440.976258) (xy 79.489808 -440.97448) (xy 76.118466 -440.97448) (xy 76.105258 -440.97829)
			(arc
				(start 76.099162 -440.981846)
				(mid 76.067542 -440.995653)
				(end 76.033376 -441.000388)
			)
			(arc
				(start 75.266804 -441.000388)
				(mid 75.232659 -440.99558)
				(end 75.201018 -440.981846)
			)
			(xy 75.194922 -440.97829) (xy 75.181714 -440.97448) (xy 70.822058 -440.97448) (xy 70.82155 -440.97448)
			(xy 70.81012 -440.97448) (xy 70.803516 -440.976766)
			(arc
				(start 70.803262 -440.976766)
				(mid 70.729592 -440.994133)
				(end 70.654164 -441.000388)
			)
			(xy 70.650354 -441.000388) (xy 70.649338 -441.000388)
			(arc
				(start 70.645528 -441.000388)
				(mid 70.570105 -440.994103)
				(end 70.49643 -440.976766)
			)
			(xy 70.494652 -440.976258) (xy 70.489572 -440.97448) (xy 66.822066 -440.97448) (xy 66.821558 -440.97448)
			(xy 66.810128 -440.97448) (xy 66.803524 -440.976766)
			(arc
				(start 66.80327 -440.976766)
				(mid 66.7296 -440.994133)
				(end 66.654172 -441.000388)
			)
			(xy 66.650362 -441.000388) (xy 66.649346 -441.000388)
			(arc
				(start 66.645536 -441.000388)
				(mid 66.570113 -440.994103)
				(end 66.496438 -440.976766)
			)
			(xy 66.49466 -440.976258) (xy 66.48958 -440.97448) (xy 62.822074 -440.97448) (xy 62.821566 -440.97448)
			(xy 62.810136 -440.97448) (xy 62.803532 -440.976766)
			(arc
				(start 62.803278 -440.976766)
				(mid 62.729608 -440.994133)
				(end 62.65418 -441.000388)
			)
			(xy 62.65037 -441.000388) (xy 62.649354 -441.000388)
			(arc
				(start 62.645544 -441.000388)
				(mid 62.570121 -440.994103)
				(end 62.496446 -440.976766)
			)
			(xy 62.494668 -440.976258) (xy 62.489588 -440.97448) (xy 59.118246 -440.97448) (xy 59.105038 -440.97829)
			(arc
				(start 59.098942 -440.981846)
				(mid 59.067322 -440.995653)
				(end 59.033156 -441.000388)
			)
			(arc
				(start 58.266584 -441.000388)
				(mid 58.232439 -440.99558)
				(end 58.200798 -440.981846)
			)
			(xy 58.194702 -440.97829) (xy 58.181494 -440.97448) (xy 19.036284 -440.97448) (xy 18.6944 -441.316364)
			(xy 18.6944 -441.419234) (xy 18.757138 -441.481972)
		)
		(stroke
			(width 0)
			(type solid)
		)
		(fill yes)
		(layer "F.Cu")
		(net "GND")
	)
	(gr_poly
		(pts
			(arc
				(start 69.779134 -26.902664)
				(mid 69.788972 -26.901702)
				(end 69.798438 -26.898854)
			)
			(xy 69.807582 -26.895044) (xy 69.810122 -26.892504) (xy 69.810122 -24.896318) (xy 69.811138 -24.886158)
			(xy 69.812408 -24.881078) (xy 69.812408 -24.824436) (xy 69.820028 -24.805894) (xy 69.82714 -24.798782)
			(xy 70.352666 -24.273002) (xy 70.354444 -24.271224) (xy 70.354952 -24.27097) (xy 70.355968 -24.269954)
			(xy 70.360032 -24.26589) (xy 70.378574 -24.258016)
			(arc
				(start 72.84593 -24.258016)
				(mid 72.862007 -24.253274)
				(end 72.875648 -24.243538)
			)
			(arc
				(start 73.481184 -23.638002)
				(mid 73.489817 -23.626167)
				(end 73.494646 -23.612348)
			)
			(xy 73.494646 -23.61184) (xy 73.495662 -23.602442) (xy 73.495662 -18.5547) (xy 73.668382 -18.38198)
			(xy 74.472546 -18.38198) (xy 74.840338 -18.014188) (xy 74.840338 -16.721328) (xy 74.897742 -16.663924)
			(xy 76.890372 -16.663924) (xy 77.093318 -16.86687) (xy 77.889608 -16.86687) (xy 78.115414 -17.092676)
			(arc
				(start 78.12405 -17.096486)
				(mid 78.173611 -17.124048)
				(end 78.217268 -17.16024)
			)
			(arc
				(start 79.138272 -18.081244)
				(mid 79.174456 -18.124907)
				(end 79.202026 -18.174462)
			)
			(xy 79.205836 -18.183098)
			(arc
				(start 79.213456 -18.190718)
				(mid 79.224567 -18.207252)
				(end 79.228442 -18.226786)
			)
			(xy 79.228442 -19.196304)
			(arc
				(start 79.229458 -19.201384)
				(mid 79.234816 -19.235502)
				(end 79.237078 -19.269964)
			)
			(arc
				(start 79.237078 -19.27733)
				(mid 79.235164 -19.315493)
				(end 79.229458 -19.353276)
			)
			(xy 79.228442 -19.358356) (xy 79.228442 -21.496528) (xy 79.288386 -21.556472) (xy 79.370174 -21.556472)
			(xy 79.376524 -21.562822) (xy 79.472282 -21.467064)
			(arc
				(start 79.472282 -19.669506)
				(mid 79.476183 -19.649983)
				(end 79.487268 -19.633438)
			)
			(arc
				(start 79.640176 -19.48053)
				(mid 79.65671 -19.469419)
				(end 79.676244 -19.465544)
			)
			(arc
				(start 80.03286 -19.465544)
				(mid 80.052383 -19.469445)
				(end 80.068928 -19.48053)
			)
			(arc
				(start 80.21701 -19.628612)
				(mid 80.223295 -19.636323)
				(end 80.227932 -19.645122)
			)
			(xy 80.231742 -19.654266)
			(arc
				(start 80.231742 -19.66087)
				(mid 80.232841 -19.671378)
				(end 80.23606 -19.681444)
			)
			(xy 80.23606 -20.991068) (xy 80.302862 -21.05787) (xy 80.40751 -21.05787) (xy 80.474312 -20.991068)
			(xy 80.474312 -19.658838) (xy 80.738726 -19.394424)
			(arc
				(start 80.749394 -19.380962)
				(mid 80.753926 -19.374046)
				(end 80.757268 -19.366484)
			)
			(xy 80.760062 -19.358356) (xy 80.760062 -14.462506) (xy 80.627982 -14.330426) (xy 76.482956 -14.330426)
			(xy 76.211684 -14.601698) (xy 71.806562 -14.601698) (xy 71.594218 -14.814042) (xy 71.594218 -15.267432)
			(xy 71.594218 -18.140426) (xy 71.320152 -18.414492) (xy 71.320152 -21.172678) (xy 70.89902 -21.59381)
			(xy 69.129402 -21.59381) (xy 68.446142 -21.59381) (xy 68.216018 -21.363686) (xy 68.216018 -18.713704)
			(xy 67.916806 -18.414492) (xy 65.894966 -18.414492) (xy 65.305178 -18.414492) (xy 65.2399 -18.47977)
			(xy 65.2399 -20.697698) (xy 65.406016 -20.863814) (xy 65.90665 -20.863814) (xy 66.044064 -21.001228)
			(xy 66.04508 -21.010626)
			(arc
				(start 66.04508 -21.011134)
				(mid 66.049972 -21.02492)
				(end 66.058542 -21.036788)
			)
			(arc
				(start 66.079878 -21.058124)
				(mid 66.090989 -21.074658)
				(end 66.094864 -21.094192)
			)
			(arc
				(start 66.094864 -21.81606)
				(mid 66.090963 -21.835583)
				(end 66.079878 -21.852128)
			)
			(xy 66.055494 -21.876512) (xy 66.053716 -21.87829)
			(arc
				(start 66.053716 -26.86685)
				(mid 66.055264 -26.879294)
				(end 66.059812 -26.89098)
			)
			(xy 66.065654 -26.901902) (xy 66.06667 -26.902664)
		)
		(stroke
			(width 0)
			(type solid)
		)
		(fill yes)
		(layer "F.Cu")
		(net "P12V_OCP_V3_2")
	)
	(gr_poly
		(pts
			(arc
				(start 110.522004 -418.70122)
				(mid 110.545446 -418.695488)
				(end 110.56366 -418.67963)
			)
			(arc
				(start 110.56366 -418.67963)
				(mid 110.702362 -418.546349)
				(end 110.880652 -418.474144)
			)
			(xy 110.888272 -418.47262) (xy 110.90148 -418.465508)
			(arc
				(start 111.703612 -417.663376)
				(mid 111.714723 -417.646842)
				(end 111.718598 -417.627308)
			)
			(arc
				(start 111.718598 -416.303968)
				(mid 111.714697 -416.284445)
				(end 111.703612 -416.2679)
			)
			(arc
				(start 111.253778 -415.818066)
				(mid 111.242667 -415.801532)
				(end 111.238792 -415.781998)
			)
			(arc
				(start 111.238792 -413.072072)
				(mid 111.234891 -413.052549)
				(end 111.223806 -413.036004)
			)
			(arc
				(start 111.17326 -412.985458)
				(mid 111.156726 -412.974347)
				(end 111.137192 -412.970472)
			)
			(arc
				(start 110.362746 -412.970472)
				(mid 110.343223 -412.974373)
				(end 110.326678 -412.985458)
			)
			(arc
				(start 110.27283 -413.039306)
				(mid 110.261856 -413.055869)
				(end 110.258098 -413.075374)
			)
			(arc
				(start 110.258098 -413.525208)
				(mid 110.254197 -413.544731)
				(end 110.243112 -413.561276)
			)
			(arc
				(start 109.641386 -414.163002)
				(mid 109.630275 -414.179536)
				(end 109.6264 -414.19907)
			)
			(arc
				(start 109.6264 -416.017202)
				(mid 109.630301 -416.036725)
				(end 109.641386 -416.05327)
			)
			(arc
				(start 109.788452 -416.20059)
				(mid 109.863498 -416.300327)
				(end 109.907832 -416.416998)
			)
			(arc
				(start 109.907832 -416.416998)
				(mid 109.910176 -416.424471)
				(end 109.913674 -416.431476)
			)
			(arc
				(start 109.913674 -416.431476)
				(mid 109.925218 -416.452427)
				(end 109.935772 -416.473894)
			)
			(xy 109.940344 -416.4838) (xy 109.957108 -416.498278) (xy 110.052612 -416.525456) (xy 110.074456 -416.522154)
			(arc
				(start 110.0836 -416.516058)
				(mid 110.217183 -416.453818)
				(end 110.363 -416.432492)
			)
			(arc
				(start 110.363 -416.432492)
				(mid 110.871508 -416.941)
				(end 110.363 -417.449508)
			)
			(arc
				(start 110.363 -417.449508)
				(mid 110.08893 -417.36933)
				(end 109.901228 -417.154106)
			)
			(xy 109.896656 -417.1442) (xy 109.879892 -417.129722) (xy 109.784388 -417.102544) (xy 109.762544 -417.105846)
			(arc
				(start 109.7534 -417.111942)
				(mid 109.685261 -417.149611)
				(end 109.612176 -417.176458)
			)
			(xy 109.605826 -417.178236) (xy 109.594904 -417.184586)
			(arc
				(start 109.47273 -417.30676)
				(mid 109.456196 -417.317871)
				(end 109.436662 -417.321746)
			)
			(arc
				(start 108.732066 -417.321746)
				(mid 108.712543 -417.325647)
				(end 108.695998 -417.336732)
			)
			(arc
				(start 108.676186 -417.356544)
				(mid 108.665075 -417.373078)
				(end 108.6612 -417.392612)
			)
			(arc
				(start 108.6612 -418.483796)
				(mid 108.665101 -418.503319)
				(end 108.676186 -418.519864)
			)
			(arc
				(start 108.842556 -418.686234)
				(mid 108.85909 -418.697345)
				(end 108.878624 -418.70122)
			)
		)
		(stroke
			(width 0)
			(type solid)
		)
		(fill yes)
		(layer "F.Cu")
		(net "P3V3_9ZXL045_P1")
	)
	(gr_poly
		(pts
			(arc
				(start 387.575298 -406.78862)
				(mid 387.594821 -406.784719)
				(end 387.611366 -406.773634)
			)
			(xy 388.421372 -405.963628) (xy 388.428992 -405.945594)
			(arc
				(start 388.428992 -405.935434)
				(mid 388.615115 -405.490875)
				(end 389.059674 -405.304752)
			)
			(xy 389.069834 -405.304752) (xy 389.087868 -405.297132)
			(arc
				(start 389.984234 -404.400766)
				(mid 389.995345 -404.384232)
				(end 389.99922 -404.364698)
			)
			(arc
				(start 389.99922 -404.262082)
				(mid 389.995436 -404.242588)
				(end 389.984488 -404.226014)
			)
			(arc
				(start 389.850376 -404.091902)
				(mid 389.833842 -404.080791)
				(end 389.814308 -404.076916)
			)
			(arc
				(start 389.43534 -404.076916)
				(mid 389.415817 -404.080817)
				(end 389.399272 -404.091902)
			)
			(arc
				(start 388.530084 -404.96109)
				(mid 388.51355 -404.972201)
				(end 388.494016 -404.976076)
			)
			(xy 369.516152 -404.976076) (xy 369.487958 -404.99919)
			(arc
				(start 369.484402 -405.017224)
				(mid 369.264832 -405.386387)
				(end 368.860578 -405.531574)
			)
			(arc
				(start 368.860578 -405.531574)
				(mid 368.411206 -405.345438)
				(end 368.22507 -404.896066)
			)
			(arc
				(start 368.22507 -404.896066)
				(mid 368.37114 -404.4907)
				(end 368.742214 -404.271734)
			)
			(xy 368.760248 -404.268178) (xy 368.783616 -404.240238)
			(arc
				(start 368.783616 -403.96668)
				(mid 368.779666 -403.947293)
				(end 368.76863 -403.930866)
			)
			(xy 368.761772 -403.924008) (xy 368.74323 -403.916388)
			(arc
				(start 367.514886 -403.916388)
				(mid 367.495363 -403.920289)
				(end 367.478818 -403.931374)
			)
			(arc
				(start 367.374678 -404.035514)
				(mid 367.363567 -404.052048)
				(end 367.359692 -404.071582)
			)
			(arc
				(start 367.359692 -405.224234)
				(mid 367.368229 -405.252421)
				(end 367.390934 -405.271224)
			)
			(xy 368.975132 -405.92756) (xy 369.00104 -405.924512)
			(arc
				(start 369.011962 -405.916638)
				(mid 369.18916 -405.826325)
				(end 369.385596 -405.795226)
			)
			(arc
				(start 369.385596 -405.795226)
				(mid 369.777496 -405.930449)
				(end 370.002562 -406.278588)
			)
			(xy 370.00688 -406.29586) (xy 370.034312 -406.317196)
			(arc
				(start 370.1415 -406.317196)
				(mid 370.161023 -406.321097)
				(end 370.177568 -406.332182)
			)
			(arc
				(start 370.61902 -406.773634)
				(mid 370.635554 -406.784745)
				(end 370.655088 -406.78862)
			)
		)
		(stroke
			(width 0)
			(type solid)
		)
		(fill yes)
		(layer "F.Cu")
		(net "P1V8_CPU0_RT_1D")
	)
	(gr_poly
		(pts
			(xy 445.67348 -356.832662) (xy 445.67348 -355.72446) (xy 445.67348 -342.44534) (xy 445.44742 -342.21928)
			(xy 415.53892 -342.21928) (xy 414.82518 -341.50554) (xy 414.82518 -336.169) (xy 412.39694 -333.74076)
			(xy 412.39694 -331.77226) (xy 412.81604 -331.35316) (xy 415.358326 -331.35316) (xy 415.747454 -331.742288)
			(xy 415.747454 -332.232254) (xy 415.970212 -332.455012) (xy 443.874398 -332.455012) (xy 444.374778 -331.954632)
			(xy 444.374778 -329.005692) (xy 443.999366 -328.63028) (xy 434.906674 -328.63028) (xy 439.622184 -328.629772)
			(xy 412.011368 -328.629772) (xy 411.52826 -329.11288) (xy 411.52826 -337.81746) (xy 410.5021 -338.84362)
			(xy 408.630882 -340.714838) (xy 408.630882 -348.982538) (xy 419.062408 -348.982538) (xy 419.062408 -347.62948)
			(xy 419.312598 -347.37929) (xy 420.529766 -347.37929) (xy 421.154606 -346.75445) (xy 421.154606 -343.833704)
			(xy 421.418258 -343.570052) (xy 425.992798 -343.570052) (xy 426.236638 -343.813892) (xy 426.236638 -348.870778)
			(xy 426.192696 -348.91472) (xy 420.650924 -348.91472) (xy 420.557706 -349.007938) (xy 427.389036 -349.007938)
			(xy 427.389036 -347.70441) (xy 427.617382 -347.476064) (xy 428.891954 -347.476064) (xy 429.481234 -346.886784)
			(xy 429.481234 -343.835736) (xy 429.706278 -343.610692) (xy 434.351938 -343.610692) (xy 434.563266 -343.82202)
			(xy 434.563266 -348.878398) (xy 434.501544 -348.94012) (xy 429.09363 -348.94012) (xy 428.833788 -349.199962)
			(xy 428.833788 -349.337884) (xy 428.64151 -349.530162) (xy 427.91126 -349.530162) (xy 427.389036 -349.007938)
			(xy 420.557706 -349.007938) (xy 420.50716 -349.058484) (xy 420.50716 -349.312484) (xy 420.314882 -349.504762)
			(xy 419.584632 -349.504762) (xy 419.062408 -348.982538) (xy 408.630882 -348.982538) (xy 408.630882 -354.432108)
			(xy 408.914346 -354.715572) (xy 410.849318 -354.715572) (xy 415.434018 -354.715572) (xy 417.166298 -352.983292)
			(xy 417.166298 -351.590864) (xy 417.962334 -350.794828) (xy 420.686992 -350.794828) (xy 421.154606 -350.327214)
			(xy 422.729914 -350.327214) (xy 422.729914 -351.035112) (xy 422.360344 -351.404682) (xy 421.813482 -351.404682)
			(xy 421.742616 -351.475548) (xy 420.928038 -351.475548) (xy 420.916862 -351.486724) (xy 420.916862 -351.694496)
			(xy 420.925752 -351.703386) (xy 421.8432 -351.703386) (xy 421.894 -351.754186) (xy 421.894 -352.7298)
			(xy 421.796972 -352.826828) (xy 420.859966 -352.826828) (xy 420.78656 -352.900234) (xy 420.78656 -352.965766)
			(xy 420.870888 -353.050094) (xy 421.781732 -353.050094) (xy 421.894 -353.162362) (xy 421.894 -353.365562)
			(xy 421.90162 -353.373182) (xy 423.63898 -353.373182) (xy 423.6466 -353.365562) (xy 423.6466 -351.37344)
			(xy 424.005248 -351.014792) (xy 426.407072 -351.014792) (xy 426.4406 -351.04832) (xy 427.513496 -351.04832)
			(xy 427.56328 -350.998536) (xy 428.543466 -350.998536) (xy 428.737776 -350.80448) (xy 429.049434 -350.80448)
			(xy 429.5013 -350.352614) (xy 431.056542 -350.352614) (xy 431.056542 -351.085658) (xy 430.712118 -351.430082)
			(xy 429.960786 -351.430082) (xy 429.88992 -351.500948) (xy 429.26127 -351.500948) (xy 429.215804 -351.546414)
			(xy 429.215804 -351.68332) (xy 429.261524 -351.72904) (xy 430.170082 -351.72904) (xy 430.220628 -351.779586)
			(xy 430.220628 -352.769932) (xy 430.12995 -352.86061) (xy 429.128428 -352.86061) (xy 429.113188 -352.87585)
			(xy 429.113188 -353.00666) (xy 429.181514 -353.074986) (xy 430.107852 -353.074986) (xy 430.220628 -353.187762)
			(xy 430.220628 -353.390962) (xy 430.228248 -353.398582) (xy 431.965608 -353.398582) (xy 431.973228 -353.390962)
			(xy 431.973228 -351.390712) (xy 432.28768 -351.07626) (xy 435.734968 -351.07626) (xy 435.710584 -351.098358)
			(xy 435.712362 -351.100136) (xy 435.979316 -351.100136) (xy 435.979316 -351.096326) (xy 438.466992 -351.096326)
			(xy 438.944258 -351.573592) (xy 438.944258 -352.739452) (xy 438.96026 -352.7552) (xy 438.96026 -355.86162)
			(xy 438.96026 -356.977696) (xy 439.278014 -357.29545) (xy 445.210692 -357.29545)
		)
		(stroke
			(width 0)
			(type solid)
		)
		(fill yes)
		(layer "F.Cu")
		(net "GND")
	)
	(gr_poly
		(pts
			(arc
				(start 8.557768 -102.1715)
				(mid 8.577291 -102.167599)
				(end 8.593836 -102.156514)
			)
			(arc
				(start 8.636762 -102.113588)
				(mid 8.647873 -102.097054)
				(end 8.651748 -102.07752)
			)
			(xy 8.651748 -101.880162) (xy 8.646922 -101.875336)
			(arc
				(start 8.646922 -101.482652)
				(mid 8.650823 -101.463129)
				(end 8.661908 -101.446584)
			)
			(arc
				(start 8.744204 -101.364288)
				(mid 8.760738 -101.353177)
				(end 8.780272 -101.349302)
			)
			(arc
				(start 9.480804 -101.349302)
				(mid 9.500327 -101.345401)
				(end 9.516872 -101.334316)
			)
			(arc
				(start 10.202418 -100.64877)
				(mid 10.213529 -100.632236)
				(end 10.217404 -100.612702)
			)
			(arc
				(start 10.217404 -100.307394)
				(mid 10.213503 -100.287871)
				(end 10.202418 -100.271326)
			)
			(arc
				(start 10.068814 -100.137722)
				(mid 10.05228 -100.126611)
				(end 10.032746 -100.122736)
			)
			(arc
				(start 8.714994 -100.122736)
				(mid 8.695471 -100.118835)
				(end 8.678926 -100.10775)
			)
			(arc
				(start 8.385556 -99.81438)
				(mid 8.369022 -99.803269)
				(end 8.349488 -99.799394)
			)
			(arc
				(start 7.450836 -99.799394)
				(mid 7.431313 -99.803295)
				(end 7.414768 -99.81438)
			)
			(arc
				(start 7.37489 -99.854258)
				(mid 7.363779 -99.870792)
				(end 7.359904 -99.890326)
			)
			(arc
				(start 7.359904 -100.862892)
				(mid 7.356003 -100.882415)
				(end 7.344918 -100.89896)
			)
			(arc
				(start 7.238238 -101.00564)
				(mid 7.221704 -101.016751)
				(end 7.20217 -101.020626)
			)
			(arc
				(start 5.847588 -101.020626)
				(mid 5.828065 -101.016725)
				(end 5.81152 -101.00564)
			)
			(arc
				(start 5.696712 -100.890832)
				(mid 5.685601 -100.874298)
				(end 5.681726 -100.854764)
			)
			(arc
				(start 5.681726 -99.342956)
				(mid 5.685627 -99.323433)
				(end 5.696712 -99.306888)
			)
			(arc
				(start 5.858002 -99.145598)
				(mid 5.874536 -99.134487)
				(end 5.89407 -99.130612)
			)
			(arc
				(start 6.761734 -99.130612)
				(mid 6.781257 -99.126711)
				(end 6.797802 -99.115626)
			)
			(arc
				(start 6.87705 -99.036378)
				(mid 6.888161 -99.019844)
				(end 6.892036 -99.00031)
			)
			(arc
				(start 6.892036 -97.968562)
				(mid 6.895937 -97.949039)
				(end 6.907022 -97.932494)
			)
			(arc
				(start 7.040626 -97.79889)
				(mid 7.05716 -97.787779)
				(end 7.076694 -97.783904)
			)
			(arc
				(start 8.76808 -97.783904)
				(mid 8.787603 -97.787805)
				(end 8.804148 -97.79889)
			)
			(xy 8.833358 -97.8281) (xy 8.851138 -97.83572)
			(arc
				(start 8.861044 -97.835974)
				(mid 8.975275 -97.860523)
				(end 9.072118 -97.92589)
			)
			(arc
				(start 9.201912 -98.055684)
				(mid 9.218329 -98.066746)
				(end 9.237726 -98.07067)
			)
			(arc
				(start 10.128504 -98.07067)
				(mid 10.148027 -98.066769)
				(end 10.164572 -98.055684)
			)
			(arc
				(start 10.253726 -97.96653)
				(mid 10.264837 -97.949996)
				(end 10.268712 -97.930462)
			)
			(arc
				(start 10.268712 -97.513394)
				(mid 10.264811 -97.493871)
				(end 10.253726 -97.477326)
			)
			(arc
				(start 9.990582 -97.214182)
				(mid 9.974048 -97.203071)
				(end 9.954514 -97.199196)
			)
			(arc
				(start 6.21538 -97.199196)
				(mid 6.195857 -97.203097)
				(end 6.179312 -97.214182)
			)
			(arc
				(start 5.100066 -98.293428)
				(mid 5.088955 -98.309962)
				(end 5.08508 -98.329496)
			)
			(arc
				(start 5.08508 -101.013006)
				(mid 5.088981 -101.032529)
				(end 5.100066 -101.049074)
			)
			(arc
				(start 5.625084 -101.574092)
				(mid 5.641618 -101.585203)
				(end 5.661152 -101.589078)
			)
			(arc
				(start 6.919976 -101.589078)
				(mid 6.939499 -101.592979)
				(end 6.956044 -101.604064)
			)
			(arc
				(start 7.508494 -102.156514)
				(mid 7.525028 -102.167625)
				(end 7.544562 -102.1715)
			)
		)
		(stroke
			(width 0)
			(type solid)
		)
		(fill yes)
		(layer "F.Cu")
		(net "GND")
	)
	(gr_poly
		(pts
			(arc
				(start 138.629898 -402.58238)
				(mid 138.649421 -402.578479)
				(end 138.665966 -402.567394)
			)
			(arc
				(start 139.583414 -401.649946)
				(mid 139.599948 -401.638835)
				(end 139.619482 -401.63496)
			)
			(arc
				(start 143.016478 -401.63496)
				(mid 143.036001 -401.631059)
				(end 143.052546 -401.619974)
			)
			(arc
				(start 143.253714 -401.418806)
				(mid 143.264825 -401.402272)
				(end 143.2687 -401.382738)
			)
			(arc
				(start 143.2687 -398.199102)
				(mid 143.264799 -398.179579)
				(end 143.253714 -398.163034)
			)
			(arc
				(start 142.232126 -397.141446)
				(mid 142.215592 -397.130335)
				(end 142.196058 -397.12646)
			)
			(arc
				(start 142.139162 -397.12646)
				(mid 142.119639 -397.122559)
				(end 142.103094 -397.111474)
			)
			(xy 139.676124 -394.684504) (xy 139.65682 -394.67663) (xy 139.64666 -394.676884)
			(arc
				(start 139.638786 -394.676884)
				(mid 139.130278 -394.168376)
				(end 139.638786 -393.659868)
			)
			(arc
				(start 139.64412 -393.659868)
				(mid 139.663251 -393.656334)
				(end 139.67968 -393.645898)
			)
			(xy 139.71778 -393.60983) (xy 139.71778 -393.601448) (xy 139.720574 -393.598654)
			(arc
				(start 139.720574 -393.166346)
				(mid 139.724475 -393.146823)
				(end 139.73556 -393.130278)
			)
			(xy 139.759944 -393.105894) (xy 139.76604 -393.095734)
			(arc
				(start 139.767818 -393.089892)
				(mid 139.89333 -392.882918)
				(end 140.100304 -392.757406)
			)
			(xy 140.106146 -392.755628) (xy 140.116306 -392.749532)
			(arc
				(start 140.249656 -392.616182)
				(mid 140.260767 -392.599648)
				(end 140.264642 -392.580114)
			)
			(arc
				(start 140.264642 -390.921494)
				(mid 140.260692 -390.902107)
				(end 140.249656 -390.88568)
			)
			(arc
				(start 140.078206 -390.713976)
				(mid 140.061643 -390.703002)
				(end 140.042138 -390.699244)
			)
			(arc
				(start 138.526012 -390.699244)
				(mid 138.506518 -390.703028)
				(end 138.489944 -390.713976)
			)
			(arc
				(start 137.70356 -391.50036)
				(mid 137.687114 -391.511286)
				(end 137.667746 -391.515092)
			)
			(xy 137.66292 -391.515092) (xy 137.644124 -391.522966)
			(arc
				(start 137.433304 -391.733786)
				(mid 137.41677 -391.744897)
				(end 137.397236 -391.748772)
			)
			(arc
				(start 136.798812 -391.748772)
				(mid 136.779289 -391.752673)
				(end 136.762744 -391.763758)
			)
			(arc
				(start 136.652762 -391.87374)
				(mid 136.641651 -391.890274)
				(end 136.637776 -391.909808)
			)
			(arc
				(start 136.637776 -393.225782)
				(mid 136.633875 -393.245305)
				(end 136.62279 -393.26185)
			)
			(arc
				(start 136.58342 -393.30122)
				(mid 136.572494 -393.317666)
				(end 136.568688 -393.337034)
			)
			(arc
				(start 136.568688 -395.68628)
				(mid 136.5575 -395.768518)
				(end 136.524746 -395.844776)
			)
			(arc
				(start 136.524746 -395.844776)
				(mid 136.519264 -395.857353)
				(end 136.51738 -395.870938)
			)
			(arc
				(start 136.51738 -396.282418)
				(mid 136.513479 -396.301941)
				(end 136.502394 -396.318486)
			)
			(arc
				(start 136.146286 -396.674594)
				(mid 136.135175 -396.691128)
				(end 136.1313 -396.710662)
			)
			(arc
				(start 136.1313 -402.076158)
				(mid 136.135201 -402.095681)
				(end 136.146286 -402.112226)
			)
			(arc
				(start 136.601454 -402.567394)
				(mid 136.617988 -402.578505)
				(end 136.637522 -402.58238)
			)
		)
		(stroke
			(width 0)
			(type solid)
		)
		(fill yes)
		(layer "F.Cu")
		(net "P0V9_CPU1_RT_2D")
	)
	(gr_poly
		(pts
			(arc
				(start 8.242808 -135.398256)
				(mid 8.262331 -135.394355)
				(end 8.278876 -135.38327)
			)
			(xy 8.853424 -134.808722) (xy 8.861044 -134.792212)
			(arc
				(start 8.861806 -134.783068)
				(mid 8.933936 -134.63365)
				(end 9.088628 -134.573772)
			)
			(arc
				(start 9.388348 -134.573772)
				(mid 9.549184 -134.639442)
				(end 9.615932 -134.799832)
			)
			(xy 9.615932 -135.016748) (xy 9.615932 -135.037576) (xy 9.58596 -135.067548) (xy 9.585706 -135.067548)
			(xy 9.555988 -135.097012)
			(arc
				(start 9.555988 -135.304276)
				(mid 9.570867 -135.340197)
				(end 9.606788 -135.355076)
			)
			(arc
				(start 9.98728 -135.355076)
				(mid 10.008718 -135.350213)
				(end 10.026142 -135.336788)
			)
			(arc
				(start 10.026142 -135.336788)
				(mid 10.100347 -135.264384)
				(end 10.187686 -135.208518)
			)
			(arc
				(start 10.187686 -135.208518)
				(mid 10.20661 -135.192101)
				(end 10.215372 -135.16864)
			)
			(arc
				(start 10.218928 -135.137144)
				(mid 10.215667 -135.113168)
				(end 10.201656 -135.093456)
			)
			(xy 10.186162 -135.078978)
			(arc
				(start 9.93394 -134.826756)
				(mid 9.867291 -134.726869)
				(end 9.844024 -134.609078)
			)
			(arc
				(start 9.844024 -134.02564)
				(mid 9.841714 -134.010748)
				(end 9.835134 -133.997192)
			)
			(arc
				(start 9.835134 -133.997192)
				(mid 9.799125 -133.93)
				(end 9.777222 -133.856984)
			)
			(xy 9.775698 -133.849618) (xy 9.768586 -133.836156)
			(arc
				(start 9.609328 -133.676898)
				(mid 9.592794 -133.665787)
				(end 9.57326 -133.661912)
			)
			(arc
				(start 9.238996 -133.661912)
				(mid 9.203075 -133.676791)
				(end 9.188196 -133.712712)
			)
			(arc
				(start 9.188196 -133.796278)
				(mid 9.164762 -133.914086)
				(end 9.098026 -134.013956)
			)
			(arc
				(start 8.717026 -134.394956)
				(mid 8.705964 -134.411373)
				(end 8.70204 -134.43077)
			)
			(arc
				(start 8.70204 -134.482078)
				(mid 8.633309 -134.644514)
				(end 8.468868 -134.708138)
			)
			(xy 8.468106 -134.707884) (xy 8.1788 -134.707884)
			(arc
				(start 8.178292 -134.708138)
				(mid 8.094026 -134.693775)
				(end 8.021066 -134.64921)
			)
			(arc
				(start 8.021066 -134.64921)
				(mid 8.00519 -134.639231)
				(end 7.986776 -134.635748)
			)
			(arc
				(start 7.616952 -134.635748)
				(mid 7.581105 -134.650701)
				(end 7.566152 -134.686548)
			)
			(arc
				(start 7.566152 -134.92226)
				(mid 7.57108 -134.944087)
				(end 7.584948 -134.96163)
			)
			(arc
				(start 7.6454 -135.011414)
				(mid 7.665313 -135.021319)
				(end 7.687564 -135.021828)
			)
			(arc
				(start 7.687818 -135.021828)
				(mid 7.724721 -135.016323)
				(end 7.761986 -135.014462)
			)
			(arc
				(start 7.762748 -135.014462)
				(mid 8.00537 -135.101551)
				(end 8.137144 -135.323072)
			)
			(xy 8.138668 -135.330438) (xy 8.14578 -135.3439)
			(arc
				(start 8.18515 -135.38327)
				(mid 8.201684 -135.394381)
				(end 8.221218 -135.398256)
			)
		)
		(stroke
			(width 0)
			(type solid)
		)
		(fill yes)
		(layer "F.Cu")
		(net "GND")
	)
	(gr_poly
		(pts
			(arc
				(start 259.431536 -17.21231)
				(mid 259.462114 -17.213563)
				(end 259.487924 -17.19707)
			)
			(arc
				(start 259.487924 -17.19707)
				(mid 259.642243 -17.016176)
				(end 259.801868 -16.839946)
			)
			(arc
				(start 259.801868 -16.839946)
				(mid 259.812023 -16.823978)
				(end 259.815584 -16.805402)
			)
			(arc
				(start 259.815584 -13.780008)
				(mid 260.103939 -13.083859)
				(end 260.800088 -12.795504)
			)
			(arc
				(start 296.936414 -12.795504)
				(mid 296.955937 -12.791603)
				(end 296.972482 -12.780518)
			)
			(arc
				(start 297.071796 -12.68095)
				(mid 297.171668 -12.614218)
				(end 297.289474 -12.59078)
			)
			(xy 298.63034 -12.59078) (xy 301.72279 -12.59078) (xy 301.927514 -12.795504)
			(arc
				(start 385.601972 -12.795504)
				(mid 387.734244 -11.912288)
				(end 388.61746 -9.780016)
			)
			(arc
				(start 388.61746 -3.976878)
				(mid 388.611809 -3.953593)
				(end 388.596124 -3.935476)
			)
			(arc
				(start 388.596124 -3.935476)
				(mid 388.428347 -3.782165)
				(end 388.302246 -3.593084)
			)
			(xy 388.294372 -3.577336) (xy 388.262368 -3.56235)
			(arc
				(start 388.149084 -3.589528)
				(mid 388.120945 -3.607374)
				(end 388.109968 -3.638804)
			)
			(arc
				(start 388.109968 -9.780016)
				(mid 387.375393 -11.553437)
				(end 385.601972 -12.288012)
			)
			(arc
				(start 260.800088 -12.288012)
				(mid 259.745088 -12.725008)
				(end 259.308092 -13.780008)
			)
			(arc
				(start 259.308092 -17.1323)
				(mid 259.317308 -17.161479)
				(end 259.34162 -17.180052)
			)
		)
		(stroke
			(width 0)
			(type solid)
		)
		(fill yes)
		(layer "F.Cu")
		(net "GND")
	)
	(gr_poly
		(pts
			(arc
				(start 327.529698 -410.96438)
				(mid 327.549221 -410.960479)
				(end 327.565766 -410.949394)
			)
			(arc
				(start 328.483214 -410.031946)
				(mid 328.499748 -410.020835)
				(end 328.519282 -410.01696)
			)
			(arc
				(start 331.586078 -410.01696)
				(mid 331.605601 -410.013059)
				(end 331.622146 -410.001974)
			)
			(arc
				(start 331.736954 -409.887166)
				(mid 331.748065 -409.870632)
				(end 331.75194 -409.851098)
			)
			(arc
				(start 331.75194 -406.164542)
				(mid 331.748039 -406.145019)
				(end 331.736954 -406.128474)
			)
			(arc
				(start 331.131926 -405.523446)
				(mid 331.115392 -405.512335)
				(end 331.095858 -405.50846)
			)
			(arc
				(start 331.038962 -405.50846)
				(mid 331.019439 -405.504559)
				(end 331.002894 -405.493474)
			)
			(xy 328.575924 -403.066504) (xy 328.55662 -403.05863) (xy 328.54646 -403.058884)
			(arc
				(start 328.538586 -403.058884)
				(mid 328.030078 -402.550376)
				(end 328.538586 -402.041868)
			)
			(arc
				(start 328.54392 -402.041868)
				(mid 328.563051 -402.038334)
				(end 328.57948 -402.027898)
			)
			(xy 328.61758 -401.99183) (xy 328.61758 -401.982432)
			(arc
				(start 328.6887 -401.911312)
				(mid 328.703035 -401.883531)
				(end 328.698352 -401.852638)
			)
			(arc
				(start 328.698352 -401.852638)
				(mid 328.657956 -401.741755)
				(end 328.64425 -401.624546)
			)
			(arc
				(start 328.64425 -401.624546)
				(mid 328.660799 -401.495618)
				(end 328.709528 -401.375118)
			)
			(xy 328.71283 -401.369276) (xy 328.716132 -401.35683)
			(arc
				(start 328.716132 -401.277582)
				(mid 328.720033 -401.258059)
				(end 328.731118 -401.241514)
			)
			(arc
				(start 329.131168 -400.841464)
				(mid 329.142279 -400.82493)
				(end 329.146154 -400.805396)
			)
			(arc
				(start 329.146154 -399.285206)
				(mid 329.142204 -399.265819)
				(end 329.131168 -399.249392)
			)
			(arc
				(start 328.978006 -399.095976)
				(mid 328.961443 -399.085002)
				(end 328.941938 -399.081244)
			)
			(arc
				(start 327.425812 -399.081244)
				(mid 327.406318 -399.085028)
				(end 327.389744 -399.095976)
			)
			(arc
				(start 326.875394 -399.610326)
				(mid 326.858977 -399.621388)
				(end 326.83958 -399.625312)
			)
			(xy 326.83704 -399.625312)
			(arc
				(start 325.482204 -400.979894)
				(mid 325.471093 -400.996428)
				(end 325.467218 -401.015962)
			)
			(xy 325.467218 -401.6883) (xy 325.459598 -401.706842) (xy 325.459344 -401.707096)
			(arc
				(start 325.462392 -401.731734)
				(mid 325.463966 -401.750245)
				(end 325.464424 -401.768818)
			)
			(arc
				(start 325.464424 -401.91563)
				(mid 325.465466 -401.925617)
				(end 325.468488 -401.935188)
			)
			(arc
				(start 325.653654 -402.382482)
				(mid 325.671312 -402.440238)
				(end 325.677276 -402.500338)
			)
			(arc
				(start 325.677276 -402.88083)
				(mid 325.653842 -402.998638)
				(end 325.587106 -403.098508)
			)
			(arc
				(start 325.432166 -403.253448)
				(mid 325.421104 -403.269865)
				(end 325.41718 -403.289262)
			)
			(arc
				(start 325.41718 -404.664418)
				(mid 325.413279 -404.683941)
				(end 325.402194 -404.700486)
			)
			(arc
				(start 325.046086 -405.056594)
				(mid 325.034975 -405.073128)
				(end 325.0311 -405.092662)
			)
			(arc
				(start 325.0311 -410.458158)
				(mid 325.035001 -410.477681)
				(end 325.046086 -410.494226)
			)
			(arc
				(start 325.501254 -410.949394)
				(mid 325.517788 -410.960505)
				(end 325.537322 -410.96438)
			)
		)
		(stroke
			(width 0)
			(type solid)
		)
		(fill yes)
		(layer "F.Cu")
		(net "P0V9_CPU0_RT_2D")
	)
	(gr_poly
		(pts
			(arc
				(start 394.629894 -410.96438)
				(mid 394.649417 -410.960479)
				(end 394.665962 -410.949394)
			)
			(arc
				(start 395.58341 -410.031946)
				(mid 395.599944 -410.020835)
				(end 395.619478 -410.01696)
			)
			(arc
				(start 398.603978 -410.01696)
				(mid 398.623501 -410.013059)
				(end 398.640046 -410.001974)
			)
			(arc
				(start 398.721834 -409.920186)
				(mid 398.732945 -409.903652)
				(end 398.73682 -409.884118)
			)
			(arc
				(start 398.73682 -406.049226)
				(mid 398.732919 -406.029703)
				(end 398.721834 -406.013158)
			)
			(arc
				(start 398.232122 -405.523446)
				(mid 398.215588 -405.512335)
				(end 398.196054 -405.50846)
			)
			(arc
				(start 398.139158 -405.50846)
				(mid 398.119635 -405.504559)
				(end 398.10309 -405.493474)
			)
			(xy 395.67612 -403.066504) (xy 395.656816 -403.05863) (xy 395.646656 -403.058884)
			(arc
				(start 395.638782 -403.058884)
				(mid 395.130274 -402.550376)
				(end 395.638782 -402.041868)
			)
			(arc
				(start 395.644116 -402.041868)
				(mid 395.663247 -402.038334)
				(end 395.679676 -402.027898)
			)
			(xy 395.717776 -401.99183) (xy 395.717776 -401.982432)
			(arc
				(start 395.788896 -401.911312)
				(mid 395.803231 -401.883531)
				(end 395.798548 -401.852638)
			)
			(arc
				(start 395.798548 -401.852638)
				(mid 395.758152 -401.741755)
				(end 395.744446 -401.624546)
			)
			(arc
				(start 395.744446 -401.624546)
				(mid 395.760995 -401.495618)
				(end 395.809724 -401.375118)
			)
			(xy 395.813026 -401.369276) (xy 395.816328 -401.35683)
			(arc
				(start 395.816328 -401.277582)
				(mid 395.820229 -401.258059)
				(end 395.831314 -401.241514)
			)
			(arc
				(start 396.231364 -400.841464)
				(mid 396.242475 -400.82493)
				(end 396.24635 -400.805396)
			)
			(arc
				(start 396.24635 -399.28546)
				(mid 396.2424 -399.266073)
				(end 396.231364 -399.249646)
			)
			(arc
				(start 396.077948 -399.095976)
				(mid 396.061385 -399.085002)
				(end 396.04188 -399.081244)
			)
			(arc
				(start 394.525754 -399.081244)
				(mid 394.50626 -399.085028)
				(end 394.489686 -399.095976)
			)
			(arc
				(start 393.844272 -399.74139)
				(mid 393.827855 -399.752452)
				(end 393.808458 -399.756376)
			)
			(xy 393.806172 -399.756376)
			(arc
				(start 392.5824 -400.979894)
				(mid 392.571289 -400.996428)
				(end 392.567414 -401.015962)
			)
			(xy 392.567414 -401.699222) (xy 392.561826 -401.70481)
			(arc
				(start 392.566398 -401.730972)
				(mid 392.569978 -401.757537)
				(end 392.571224 -401.784312)
			)
			(arc
				(start 392.571224 -402.081238)
				(mid 392.575008 -402.100732)
				(end 392.585956 -402.117306)
			)
			(arc
				(start 392.687302 -402.218398)
				(mid 392.754034 -402.31827)
				(end 392.777472 -402.436076)
			)
			(arc
				(start 392.777472 -402.869654)
				(mid 392.754038 -402.987462)
				(end 392.687302 -403.087332)
			)
			(arc
				(start 392.532362 -403.242272)
				(mid 392.5213 -403.258689)
				(end 392.517376 -403.278086)
			)
			(arc
				(start 392.517376 -404.664418)
				(mid 392.513475 -404.683941)
				(end 392.50239 -404.700486)
			)
			(arc
				(start 392.146282 -405.056594)
				(mid 392.135171 -405.073128)
				(end 392.131296 -405.092662)
			)
			(arc
				(start 392.131296 -410.458158)
				(mid 392.135197 -410.477681)
				(end 392.146282 -410.494226)
			)
			(arc
				(start 392.60145 -410.949394)
				(mid 392.617984 -410.960505)
				(end 392.637518 -410.96438)
			)
		)
		(stroke
			(width 0)
			(type solid)
		)
		(fill yes)
		(layer "F.Cu")
		(net "P0V9_CPU0_RT_2D")
	)
	(gr_poly
		(pts
			(arc
				(start 71.529956 -402.58238)
				(mid 71.549479 -402.578479)
				(end 71.566024 -402.567394)
			)
			(arc
				(start 72.483472 -401.649946)
				(mid 72.500006 -401.638835)
				(end 72.51954 -401.63496)
			)
			(arc
				(start 77.012038 -401.63496)
				(mid 77.031561 -401.631059)
				(end 77.048106 -401.619974)
			)
			(arc
				(start 77.231494 -401.436586)
				(mid 77.242605 -401.420052)
				(end 77.24648 -401.400518)
			)
			(arc
				(start 77.24648 -399.276824)
				(mid 77.242579 -399.257301)
				(end 77.231494 -399.240756)
			)
			(arc
				(start 75.132184 -397.141446)
				(mid 75.11565 -397.130335)
				(end 75.096116 -397.12646)
			)
			(arc
				(start 75.03922 -397.12646)
				(mid 75.019697 -397.122559)
				(end 75.003152 -397.111474)
			)
			(xy 72.576182 -394.684504) (xy 72.556878 -394.67663) (xy 72.546718 -394.676884)
			(arc
				(start 72.538844 -394.676884)
				(mid 72.179275 -394.527945)
				(end 72.030336 -394.168376)
			)
			(arc
				(start 72.030336 -394.168376)
				(mid 72.172691 -393.815513)
				(end 72.520048 -393.660122)
			)
			(xy 72.529954 -393.659868) (xy 72.547734 -393.651994)
			(arc
				(start 72.603614 -393.593828)
				(mid 72.614127 -393.577678)
				(end 72.617838 -393.558776)
			)
			(xy 72.617838 -393.550902) (xy 72.684386 -393.484354) (xy 72.690228 -393.454128)
			(arc
				(start 72.684386 -393.43965)
				(mid 72.654614 -393.343088)
				(end 72.644508 -393.242546)
			)
			(arc
				(start 72.644508 -393.242546)
				(mid 72.70278 -393.006181)
				(end 72.864218 -392.823954)
			)
			(xy 72.868028 -392.821414)
			(arc
				(start 73.15073 -392.538712)
				(mid 73.161841 -392.522178)
				(end 73.165716 -392.502644)
			)
			(arc
				(start 73.165716 -390.92251)
				(mid 73.161766 -390.903123)
				(end 73.15073 -390.886696)
			)
			(arc
				(start 72.978264 -390.713976)
				(mid 72.961701 -390.703002)
				(end 72.942196 -390.699244)
			)
			(arc
				(start 71.42607 -390.699244)
				(mid 71.406576 -390.703028)
				(end 71.390002 -390.713976)
			)
			(arc
				(start 70.78091 -391.323068)
				(mid 70.764464 -391.333994)
				(end 70.745096 -391.3378)
			)
			(xy 69.814948 -391.3378) (xy 69.796406 -391.33018) (xy 69.79158 -391.325354)
			(arc
				(start 69.540882 -391.576052)
				(mid 69.529771 -391.592586)
				(end 69.525896 -391.61212)
			)
			(arc
				(start 69.525896 -393.23772)
				(mid 69.521995 -393.257243)
				(end 69.51091 -393.273788)
			)
			(xy 69.471286 -393.313412) (xy 69.463666 -393.33678)
			(arc
				(start 69.465698 -393.348972)
				(mid 69.468872 -393.373903)
				(end 69.470016 -393.39901)
			)
			(arc
				(start 69.470016 -393.535916)
				(mid 69.470953 -393.545884)
				(end 69.473826 -393.555474)
			)
			(arc
				(start 69.653912 -393.990576)
				(mid 69.671407 -394.048352)
				(end 69.67728 -394.108432)
			)
			(arc
				(start 69.67728 -394.505942)
				(mid 69.653949 -394.623707)
				(end 69.587364 -394.72362)
			)
			(arc
				(start 69.432424 -394.87856)
				(mid 69.421362 -394.894977)
				(end 69.417438 -394.914374)
			)
			(arc
				(start 69.417438 -396.282418)
				(mid 69.413537 -396.301941)
				(end 69.402452 -396.318486)
			)
			(arc
				(start 69.046344 -396.674594)
				(mid 69.035233 -396.691128)
				(end 69.031358 -396.710662)
			)
			(arc
				(start 69.031358 -402.076158)
				(mid 69.035259 -402.095681)
				(end 69.046344 -402.112226)
			)
			(arc
				(start 69.501512 -402.567394)
				(mid 69.518046 -402.578505)
				(end 69.53758 -402.58238)
			)
		)
		(stroke
			(width 0)
			(type solid)
		)
		(fill yes)
		(layer "F.Cu")
		(net "P0V9_CPU1_RT_2D")
	)
	(gr_poly
		(pts
			(xy 236.22254 -320.463164) (xy 236.22254 -288.914332) (xy 237.439962 -287.69691) (xy 240.432082 -287.69691)
			(xy 240.496852 -287.63214) (xy 240.496852 -275.74113) (xy 241.766344 -274.471638) (xy 241.766344 -269.937992)
			(xy 242.46586 -269.238476) (xy 248.152666 -269.238476) (xy 248.463562 -268.92758) (xy 248.463562 -267.399008)
			(xy 248.69648 -267.16609) (xy 252.452886 -267.16609) (xy 252.841506 -267.55471) (xy 252.841506 -273.564858)
			(xy 252.400816 -274.005548) (xy 249.124216 -274.005548) (xy 248.849642 -274.280122) (xy 248.849642 -278.460708)
			(xy 247.770396 -279.539954) (xy 246.511572 -279.539954) (xy 244.688868 -281.362912) (xy 244.673628 -281.378152)
			(xy 244.673628 -288.384996) (xy 244.659912 -288.398712) (xy 244.34546 -288.713418) (xy 244.34546 -292.940232)
			(xy 244.471952 -293.066724) (xy 246.554498 -293.066724) (xy 246.794782 -293.307008) (xy 246.794782 -293.986458)
			(xy 246.690896 -294.090344) (xy 245.967504 -294.090344) (xy 245.700804 -294.357044) (xy 245.700804 -306.993544)
			(xy 245.95074 -307.24348) (xy 248.698766 -307.24348) (xy 249.709178 -308.253892) (xy 249.709178 -315.93028)
			(xy 249.495056 -316.144402) (xy 237.455456 -316.144402) (xy 237.390178 -316.20968) (xy 237.390178 -319.807082)
			(xy 237.669578 -320.086482) (xy 255.335278 -320.086482) (xy 257.58267 -317.83909) (xy 257.58267 -259.964174)
			(xy 256.960624 -259.342128) (xy 219.526104 -259.342128) (xy 219.137484 -259.730748) (xy 219.137484 -263.481566)
			(xy 254.402588 -263.481566) (xy 254.406661 -263.425907) (xy 254.418796 -263.371434) (xy 254.438732 -263.319308)
			(xy 254.466046 -263.27064) (xy 254.500154 -263.226468) (xy 254.540331 -263.187733) (xy 254.585719 -263.155261)
			(xy 254.635351 -263.129743) (xy 254.688171 -263.111724) (xy 254.74305 -263.101587) (xy 254.798821 -263.099549)
			(xy 254.854295 -263.105652) (xy 254.908288 -263.119768) (xy 254.959651 -263.141595) (xy 255.007289 -263.170668)
			(xy 255.050185 -263.206367) (xy 255.087427 -263.247931) (xy 255.118221 -263.294475) (xy 255.141909 -263.345006)
			(xy 255.157987 -263.398448) (xy 255.166113 -263.453662) (xy 255.166622 -263.481566) (xy 255.166113 -263.50947)
			(xy 255.157987 -263.564684) (xy 255.141909 -263.618126) (xy 255.118221 -263.668657) (xy 255.087427 -263.715201)
			(xy 255.050185 -263.756765) (xy 255.007289 -263.792464) (xy 254.959651 -263.821537) (xy 254.908288 -263.843364)
			(xy 254.854295 -263.85748) (xy 254.798821 -263.863583) (xy 254.74305 -263.861545) (xy 254.688171 -263.851408)
			(xy 254.635351 -263.833389) (xy 254.585719 -263.807871) (xy 254.540331 -263.775399) (xy 254.500154 -263.736664)
			(xy 254.466046 -263.692492) (xy 254.438732 -263.643824) (xy 254.418796 -263.591698) (xy 254.406661 -263.537225)
			(xy 254.402588 -263.481566) (xy 219.137484 -263.481566) (xy 219.137484 -274.517612) (xy 219.085414 -274.569682)
			(xy 219.085414 -315.727842) (xy 220.937836 -315.727842) (xy 220.937836 -296.815764) (xy 220.937836 -296.149522)
			(xy 224.862644 -292.224714) (xy 224.862644 -288.253932) (xy 225.49358 -287.622996) (xy 227.15347 -287.622996)
			(xy 227.625656 -288.095182) (xy 229.426262 -288.095182) (xy 229.585012 -287.936432) (xy 229.585012 -281.61869)
			(xy 228.861112 -280.89479) (xy 225.928936 -280.89479) (xy 225.260916 -280.22677) (xy 225.260916 -274.376642)
			(xy 225.054668 -274.170394) (xy 221.455996 -274.170394) (xy 221.1324 -273.846798) (xy 221.1324 -268.015212)
			(xy 221.567248 -267.580364) (xy 225.43262 -267.580364) (xy 225.63963 -267.787374) (xy 225.63963 -269.031212)
			(xy 226.131882 -269.523464) (xy 231.209596 -269.523464) (xy 231.68864 -270.002508) (xy 231.68864 -275.274532)
			(xy 233.571288 -277.15718) (xy 233.571288 -281.12085) (xy 233.549952 -281.142186) (xy 233.549952 -288.163)
			(xy 232.423208 -289.289744) (xy 232.423208 -293.02837) (xy 232.476548 -293.08171) (xy 234.800902 -293.08171)
			(xy 234.80903 -293.089838) (xy 234.80903 -293.928546) (xy 234.666282 -294.071294) (xy 234.323636 -294.071294)
			(xy 234.29976 -294.094916) (xy 234.29976 -294.09517) (xy 233.895392 -294.499538) (xy 233.895392 -306.861718)
			(xy 235.011722 -307.978048) (xy 235.011722 -315.754004) (xy 234.621324 -316.144402) (xy 221.354396 -316.144402)
			(xy 220.937836 -315.727842) (xy 219.085414 -315.727842) (xy 219.085414 -315.921898) (xy 221.21622 -318.052704)
			(xy 221.21622 -320.484754) (xy 221.714822 -320.983356) (xy 235.702348 -320.983356)
		)
		(stroke
			(width 0)
			(type solid)
		)
		(fill yes)
		(layer "F.Cu")
		(net "GND")
	)
	(gr_poly
		(pts
			(arc
				(start 254.339852 -53.161946)
				(mid 254.359375 -53.158045)
				(end 254.37592 -53.14696)
			)
			(arc
				(start 254.549148 -52.973732)
				(mid 254.560259 -52.957198)
				(end 254.564134 -52.937664)
			)
			(arc
				(start 254.564134 -49.093628)
				(mid 254.568035 -49.074105)
				(end 254.57912 -49.05756)
			)
			(arc
				(start 255.107948 -48.528732)
				(mid 255.124482 -48.517621)
				(end 255.144016 -48.513746)
			)
			(arc
				(start 258.683252 -48.513746)
				(mid 258.702775 -48.509845)
				(end 258.71932 -48.49876)
			)
			(arc
				(start 259.171948 -48.046132)
				(mid 259.183059 -48.029598)
				(end 259.186934 -48.010064)
			)
			(arc
				(start 259.186934 -47.722028)
				(mid 259.190835 -47.702505)
				(end 259.20192 -47.68596)
			)
			(arc
				(start 259.425948 -47.461932)
				(mid 259.442482 -47.450821)
				(end 259.462016 -47.446946)
			)
			(arc
				(start 260.359652 -47.446946)
				(mid 260.379175 -47.443045)
				(end 260.39572 -47.43196)
			)
			(arc
				(start 260.492748 -47.334932)
				(mid 260.503859 -47.318398)
				(end 260.507734 -47.298864)
			)
			(arc
				(start 260.507734 -40.823388)
				(mid 260.503833 -40.803865)
				(end 260.492748 -40.78732)
			)
			(arc
				(start 260.20776 -40.502332)
				(mid 260.191226 -40.491221)
				(end 260.171692 -40.487346)
			)
			(xy 258.834128 -40.487346) (xy 258.568698 -40.752776) (xy 258.568698 -41.266618) (xy 258.40817 -41.427146)
			(xy 258.093972 -41.427146)
			(arc
				(start 252.070616 -41.427146)
				(mid 252.051229 -41.431096)
				(end 252.034802 -41.442132)
			)
			(xy 251.973588 -41.503346) (xy 251.973588 -41.50995) (xy 251.973334 -41.50995)
			(arc
				(start 251.973334 -41.583864)
				(mid 251.977235 -41.603387)
				(end 251.98832 -41.619932)
			)
			(arc
				(start 252.009148 -41.64076)
				(mid 252.025682 -41.651871)
				(end 252.045216 -41.655746)
			)
			(arc
				(start 253.908052 -41.655746)
				(mid 253.927575 -41.659647)
				(end 253.94412 -41.670732)
			)
			(arc
				(start 253.990348 -41.71696)
				(mid 254.001459 -41.733494)
				(end 254.005334 -41.753028)
			)
			(arc
				(start 254.005334 -42.345864)
				(mid 254.001433 -42.365387)
				(end 253.990348 -42.381932)
			)
			(arc
				(start 253.94412 -42.42816)
				(mid 253.927586 -42.439271)
				(end 253.908052 -42.443146)
			)
			(xy 253.652274 -42.443146) (xy 253.6444 -42.4434)
			(arc
				(start 252.578362 -42.4434)
				(mid 252.559005 -42.447233)
				(end 252.542548 -42.458132)
			)
			(arc
				(start 252.47092 -42.52976)
				(mid 252.459809 -42.546294)
				(end 252.455934 -42.565828)
			)
			(arc
				(start 252.455934 -42.599864)
				(mid 252.459835 -42.619387)
				(end 252.47092 -42.635932)
			)
			(arc
				(start 252.491748 -42.65676)
				(mid 252.508282 -42.667871)
				(end 252.527816 -42.671746)
			)
			(arc
				(start 255.787652 -42.671746)
				(mid 255.807175 -42.675647)
				(end 255.82372 -42.686732)
			)
			(arc
				(start 256.123948 -42.98696)
				(mid 256.140482 -42.998071)
				(end 256.160016 -43.001946)
			)
			(arc
				(start 256.879852 -43.001946)
				(mid 256.899375 -43.005847)
				(end 256.91592 -43.016932)
			)
			(arc
				(start 256.974848 -43.07586)
				(mid 256.985959 -43.092394)
				(end 256.989834 -43.111928)
			)
			(xy 256.989834 -43.997372) (xy 256.997454 -44.015914) (xy 257.002788 -44.021248) (xy 257.002788 -45.407834)
			(xy 256.995168 -45.426376) (xy 256.989834 -45.43171)
			(arc
				(start 256.989834 -45.444664)
				(mid 256.985933 -45.464187)
				(end 256.974848 -45.480732)
			)
			(arc
				(start 254.89662 -47.55896)
				(mid 254.880086 -47.570071)
				(end 254.860552 -47.573946)
			)
			(xy 254.847598 -47.573946) (xy 254.847344 -47.5742)
			(arc
				(start 253.441708 -47.5742)
				(mid 253.422321 -47.57815)
				(end 253.405894 -47.589186)
			)
			(arc
				(start 253.20752 -47.78756)
				(mid 253.196409 -47.804094)
				(end 253.192534 -47.823628)
			)
			(arc
				(start 253.192534 -53.013864)
				(mid 253.188633 -53.033387)
				(end 253.177548 -53.049932)
			)
			(xy 253.174754 -53.052726) (xy 253.167134 -53.071268)
			(arc
				(start 253.167134 -53.090064)
				(mid 253.171035 -53.109587)
				(end 253.18212 -53.126132)
			)
			(arc
				(start 253.202948 -53.14696)
				(mid 253.219482 -53.158071)
				(end 253.239016 -53.161946)
			)
		)
		(stroke
			(width 0)
			(type solid)
		)
		(fill yes)
		(layer "F.Cu")
		(net "P12V_AUX")
	)
	(gr_poly
		(pts
			(arc
				(start 124.102114 -12.795504)
				(mid 126.234222 -11.912198)
				(end 127.117348 -9.780016)
			)
			(arc
				(start 127.117348 -9.256776)
				(mid 127.111697 -9.233491)
				(end 127.096012 -9.215374)
			)
			(arc
				(start 127.096012 -9.215374)
				(mid 126.928345 -9.062058)
				(end 126.802388 -8.872982)
			)
			(xy 126.794514 -8.857234) (xy 126.76251 -8.842248)
			(arc
				(start 126.649226 -8.869426)
				(mid 126.621087 -8.887272)
				(end 126.61011 -8.918702)
			)
			(arc
				(start 126.61011 -9.780016)
				(mid 125.875535 -11.553437)
				(end 124.102114 -12.288012)
			)
			(arc
				(start 83.70189 -12.288012)
				(mid 81.928469 -11.553437)
				(end 81.193894 -9.780016)
			)
			(arc
				(start 81.193894 -3.638804)
				(mid 81.182847 -3.607429)
				(end 81.154778 -3.589528)
			)
			(xy 81.041494 -3.56235) (xy 81.00949 -3.577336)
			(arc
				(start 81.001616 -3.593084)
				(mid 80.87562 -3.782127)
				(end 80.707992 -3.935476)
			)
			(arc
				(start 80.707992 -3.935476)
				(mid 80.692292 -3.953586)
				(end 80.686656 -3.976878)
			)
			(arc
				(start 80.686656 -9.780524)
				(mid 81.569887 -11.912452)
				(end 83.70189 -12.795504)
			)
		)
		(stroke
			(width 0)
			(type solid)
		)
		(fill yes)
		(layer "F.Cu")
		(net "GND")
	)
	(gr_poly
		(pts
			(xy 188.93536 -33.18764) (xy 189.684152 -33.18764) (xy 190.01232 -33.18764) (xy 190.371476 -32.828484)
			(xy 190.371476 -32.500316) (xy 190.371476 -28.174696) (xy 190.369444 -28.160726) (xy 190.363856 -28.141168)
			(arc
				(start 190.360554 -28.13558)
				(mid 190.328924 -28.060436)
				(end 190.318136 -27.979624)
			)
			(arc
				(start 190.318136 -27.476196)
				(mid 190.317205 -27.466765)
				(end 190.31458 -27.457654)
			)
			(xy 190.304674 -27.432508)
			(arc
				(start 190.298578 -27.42565)
				(mid 190.202902 -27.268235)
				(end 190.169546 -27.087068)
			)
			(arc
				(start 190.169546 -27.087068)
				(mid 190.217734 -26.870999)
				(end 190.353188 -26.695908)
			)
			(arc
				(start 190.353188 -26.695908)
				(mid 190.366724 -26.678395)
				(end 190.371476 -26.656792)
			)
			(arc
				(start 190.371476 -24.869394)
				(mid 190.367575 -24.849871)
				(end 190.35649 -24.833326)
			)
			(arc
				(start 190.342266 -24.819102)
				(mid 190.325732 -24.807991)
				(end 190.306198 -24.804116)
			)
			(arc
				(start 190.183516 -24.804116)
				(mid 190.147595 -24.818995)
				(end 190.132716 -24.854916)
			)
			(arc
				(start 190.132716 -26.46299)
				(mid 190.128815 -26.482513)
				(end 190.11773 -26.499058)
			)
			(arc
				(start 190.117222 -26.499566)
				(mid 190.10616 -26.515983)
				(end 190.102236 -26.53538)
			)
			(xy 190.102236 -26.539952) (xy 190.094616 -26.558494) (xy 189.897004 -26.756106) (xy 189.878462 -26.76398)
			(xy 189.870588 -26.76398) (xy 189.58941 -26.76398) (xy 189.58687 -26.76144) (xy 189.571884 -26.754074)
			(arc
				(start 189.563248 -26.752804)
				(mid 189.547171 -26.748062)
				(end 189.53353 -26.738326)
			)
			(arc
				(start 189.373002 -26.577798)
				(mid 189.361891 -26.561264)
				(end 189.358016 -26.54173)
			)
			(arc
				(start 189.358016 -25.349454)
				(mid 189.354115 -25.329931)
				(end 189.34303 -25.313386)
			)
			(xy 189.324742 -25.295098) (xy 189.31763 -25.287732) (xy 189.298834 -25.280112)
			(arc
				(start 189.173358 -25.280112)
				(mid 189.153835 -25.284013)
				(end 189.13729 -25.295098)
			)
			(arc
				(start 189.134242 -25.298146)
				(mid 189.123131 -25.31468)
				(end 189.119256 -25.334214)
			)
			(arc
				(start 189.119256 -27.66441)
				(mid 189.115355 -27.683933)
				(end 189.10427 -27.700478)
			)
			(arc
				(start 188.663072 -28.141676)
				(mid 188.652146 -28.158122)
				(end 188.64834 -28.17749)
			)
			(xy 188.64834 -28.407614) (xy 188.648086 -28.415234) (xy 188.648086 -29.15539)
			(arc
				(start 188.650372 -29.162756)
				(mid 188.657593 -29.195168)
				(end 188.660024 -29.228288)
			)
			(xy 188.660024 -29.496004) (xy 188.648086 -29.496004)
			(arc
				(start 188.648086 -29.713174)
				(mid 188.644185 -29.732697)
				(end 188.6331 -29.749242)
			)
			(arc
				(start 188.43752 -29.944822)
				(mid 188.420986 -29.955933)
				(end 188.401452 -29.959808)
			)
			(arc
				(start 184.879996 -29.959808)
				(mid 184.860473 -29.955907)
				(end 184.843928 -29.944822)
			)
			(xy 183.14162 -28.242514) (xy 183.134508 -28.235148) (xy 183.115712 -28.227528)
			(arc
				(start 176.081436 -28.227528)
				(mid 176.061913 -28.231429)
				(end 176.045368 -28.242514)
			)
			(xy 175.91532 -28.372562) (xy 175.907954 -28.379674) (xy 175.900334 -28.39847)
			(arc
				(start 175.900334 -29.440886)
				(mid 175.904235 -29.460409)
				(end 175.91532 -29.476954)
			)
			(arc
				(start 176.045368 -29.607002)
				(mid 176.061902 -29.618113)
				(end 176.081436 -29.621988)
			)
			(arc
				(start 177.725832 -29.621988)
				(mid 177.745355 -29.618087)
				(end 177.7619 -29.607002)
			)
			(xy 177.762154 -29.606748)
			(arc
				(start 180.039772 -29.606748)
				(mid 180.059295 -29.610649)
				(end 180.07584 -29.621734)
			)
			(arc
				(start 181.692296 -31.23819)
				(mid 181.703407 -31.254724)
				(end 181.707282 -31.274258)
			)
			(arc
				(start 181.707282 -33.47974)
				(mid 181.709692 -33.495201)
				(end 181.71668 -33.509204)
			)
			(arc
				(start 181.71668 -33.509204)
				(mid 181.794128 -33.663903)
				(end 181.82082 -33.834832)
			)
			(arc
				(start 181.82082 -34.266886)
				(mid 181.824721 -34.286409)
				(end 181.835806 -34.302954)
			)
			(arc
				(start 182.196232 -34.663126)
				(mid 182.212766 -34.674237)
				(end 182.2323 -34.678112)
			)
			(xy 187.444888 -34.678112)
		)
		(stroke
			(width 0)
			(type solid)
		)
		(fill yes)
		(layer "F.Cu")
		(net "P12V_AUX")
	)
	(gr_poly
		(pts
			(xy 219.822776 -74.799444) (xy 219.822776 -74.639424)
			(arc
				(start 219.822776 -73.23582)
				(mid 219.818875 -73.216297)
				(end 219.80779 -73.199752)
			)
			(arc
				(start 219.786962 -73.178924)
				(mid 219.770428 -73.167813)
				(end 219.750894 -73.163938)
			)
			(arc
				(start 217.456258 -73.163938)
				(mid 217.436735 -73.160037)
				(end 217.42019 -73.148952)
			)
			(xy 217.405712 -73.134474) (xy 217.394282 -73.12787)
			(arc
				(start 217.387678 -73.126092)
				(mid 217.183495 -72.989917)
				(end 217.104468 -72.757538)
			)
			(arc
				(start 217.104468 -72.757538)
				(mid 217.173274 -72.538905)
				(end 217.354912 -72.399144)
			)
			(xy 217.36558 -72.395334)
			(arc
				(start 217.36939 -72.391524)
				(mid 217.385924 -72.380413)
				(end 217.405458 -72.376538)
			)
			(xy 217.467434 -72.376538) (xy 217.485976 -72.37603) (xy 217.504518 -72.376538)
			(arc
				(start 217.861134 -72.376538)
				(mid 217.880657 -72.372637)
				(end 217.897202 -72.361552)
			)
			(arc
				(start 217.97645 -72.282304)
				(mid 217.987561 -72.26577)
				(end 217.991436 -72.246236)
			)
			(arc
				(start 217.991436 -70.8914)
				(mid 217.995337 -70.871877)
				(end 218.006422 -70.855332)
			)
			(xy 218.009216 -70.852792) (xy 218.009216 -70.839076) (xy 218.03868 -70.809612) (xy 218.052396 -70.809612)
			(arc
				(start 218.10599 -70.755764)
				(mid 218.122524 -70.744653)
				(end 218.142058 -70.740778)
			)
			(xy 219.22105 -70.740778) (xy 219.22359 -70.740524) (xy 219.26042 -70.738746) (xy 219.29725 -70.740524)
			(xy 219.29979 -70.740778)
			(arc
				(start 220.573854 -70.740778)
				(mid 220.593377 -70.744679)
				(end 220.609922 -70.755764)
			)
			(arc
				(start 220.68917 -70.835012)
				(mid 220.700281 -70.851546)
				(end 220.704156 -70.87108)
			)
			(arc
				(start 220.704156 -71.148956)
				(mid 220.708057 -71.168479)
				(end 220.719142 -71.185024)
			)
			(arc
				(start 220.76283 -71.228712)
				(mid 220.779364 -71.239823)
				(end 220.798898 -71.243698)
			)
			(arc
				(start 220.840554 -71.243698)
				(mid 220.860077 -71.239797)
				(end 220.876622 -71.228712)
			)
			(arc
				(start 220.92285 -71.182484)
				(mid 220.933961 -71.16595)
				(end 220.937836 -71.146416)
			)
			(arc
				(start 220.937836 -70.56882)
				(mid 220.933935 -70.549297)
				(end 220.92285 -70.532752)
			)
			(arc
				(start 220.912182 -70.522084)
				(mid 220.895648 -70.510973)
				(end 220.876114 -70.507098)
			)
			(arc
				(start 220.196918 -70.507098)
				(mid 220.177395 -70.503197)
				(end 220.16085 -70.492112)
			)
			(arc
				(start 219.512642 -69.843904)
				(mid 219.496108 -69.832793)
				(end 219.476574 -69.828918)
			)
			(arc
				(start 217.972386 -69.828918)
				(mid 217.952863 -69.825017)
				(end 217.936318 -69.813932)
			)
			(arc
				(start 217.828622 -69.706236)
				(mid 217.817511 -69.689702)
				(end 217.813636 -69.670168)
			)
			(arc
				(start 217.813636 -69.088)
				(mid 217.809735 -69.068477)
				(end 217.79865 -69.051932)
			)
			(arc
				(start 217.777822 -69.031104)
				(mid 217.761288 -69.019993)
				(end 217.741754 -69.016118)
			)
			(arc
				(start 216.644982 -69.016118)
				(mid 216.625459 -69.012217)
				(end 216.608914 -69.001132)
			)
			(arc
				(start 216.209626 -68.601844)
				(mid 216.198515 -68.58531)
				(end 216.19464 -68.565776)
			)
			(arc
				(start 216.19464 -67.412616)
				(mid 216.190739 -67.393093)
				(end 216.179654 -67.376548)
			)
			(arc
				(start 215.941148 -67.138042)
				(mid 215.924614 -67.126931)
				(end 215.90508 -67.123056)
			)
			(arc
				(start 214.197438 -67.123056)
				(mid 214.177915 -67.126957)
				(end 214.16137 -67.138042)
			)
			(arc
				(start 213.933786 -67.365626)
				(mid 213.922675 -67.38216)
				(end 213.9188 -67.401694)
			)
			(arc
				(start 213.9188 -70.773036)
				(mid 213.922701 -70.792559)
				(end 213.933786 -70.809104)
			)
			(arc
				(start 214.129366 -71.004684)
				(mid 214.1459 -71.015795)
				(end 214.165434 -71.01967)
			)
			(arc
				(start 215.783922 -71.01967)
				(mid 215.803445 -71.023571)
				(end 215.81999 -71.034656)
			)
			(arc
				(start 216.25179 -71.466456)
				(mid 216.262901 -71.48299)
				(end 216.266776 -71.502524)
			)
			(xy 216.266776 -73.981056) (xy 216.266776 -74.661776) (xy 216.49182 -74.88682) (xy 219.7354 -74.88682)
		)
		(stroke
			(width 0)
			(type solid)
		)
		(fill yes)
		(layer "F.Cu")
		(net "GND")
	)
	(gr_poly
		(pts
			(xy 97.042478 -60.196222) (xy 97.042478 -55.145178)
			(arc
				(start 97.042478 -53.655214)
				(mid 97.038577 -53.635691)
				(end 97.027492 -53.619146)
			)
			(arc
				(start 96.567498 -53.159152)
				(mid 96.550964 -53.148041)
				(end 96.53143 -53.144166)
			)
			(arc
				(start 93.723206 -53.144166)
				(mid 93.703683 -53.148067)
				(end 93.687138 -53.159152)
			)
			(arc
				(start 93.565218 -53.281072)
				(mid 93.554156 -53.297489)
				(end 93.550232 -53.316886)
			)
			(arc
				(start 93.550232 -53.908706)
				(mid 93.554182 -53.928093)
				(end 93.565218 -53.94452)
			)
			(arc
				(start 93.614748 -53.99405)
				(mid 93.631282 -54.005161)
				(end 93.650816 -54.009036)
			)
			(arc
				(start 94.149672 -54.009036)
				(mid 94.169195 -54.012937)
				(end 94.18574 -54.024022)
			)
			(arc
				(start 94.248986 -54.087268)
				(mid 94.260097 -54.103802)
				(end 94.263972 -54.123336)
			)
			(arc
				(start 94.263972 -54.875684)
				(mid 94.260071 -54.895207)
				(end 94.248986 -54.911752)
			)
			(xy 94.052644 -55.108094) (xy 93.842078 -55.108094) (xy 93.493336 -55.456836) (xy 93.422978 -55.52694)
			(xy 93.422978 -55.922418) (xy 93.540326 -56.039766) (xy 94.057978 -56.039766)
			(arc
				(start 95.81769 -56.039766)
				(mid 95.837213 -56.043667)
				(end 95.853758 -56.054752)
			)
			(xy 95.868236 -56.06923) (xy 95.879666 -56.075834)
			(arc
				(start 95.88627 -56.077612)
				(mid 96.090453 -56.213787)
				(end 96.16948 -56.446166)
			)
			(arc
				(start 96.16948 -56.446166)
				(mid 96.100674 -56.664799)
				(end 95.919036 -56.80456)
			)
			(xy 95.908368 -56.80837)
			(arc
				(start 95.904558 -56.81218)
				(mid 95.888024 -56.823291)
				(end 95.86849 -56.827166)
			)
			(xy 95.806514 -56.827166) (xy 95.787972 -56.827674) (xy 95.76943 -56.827166)
			(arc
				(start 95.412814 -56.827166)
				(mid 95.393291 -56.831067)
				(end 95.376746 -56.842152)
			)
			(arc
				(start 95.297498 -56.9214)
				(mid 95.286387 -56.937934)
				(end 95.282512 -56.957468)
			)
			(arc
				(start 95.282512 -58.312304)
				(mid 95.278611 -58.331827)
				(end 95.267526 -58.348372)
			)
			(xy 95.263716 -58.351928) (xy 95.263716 -58.363612) (xy 95.234252 -58.393076) (xy 95.222822 -58.393076)
			(arc
				(start 95.167958 -58.44794)
				(mid 95.151424 -58.459051)
				(end 95.13189 -58.462926)
			)
			(arc
				(start 94.302072 -58.462926)
				(mid 94.287486 -58.465065)
				(end 94.274132 -58.471308)
			)
			(arc
				(start 94.274132 -58.471308)
				(mid 94.063058 -58.535067)
				(end 93.851984 -58.471308)
			)
			(arc
				(start 93.851984 -58.471308)
				(mid 93.838628 -58.465072)
				(end 93.824044 -58.462926)
			)
			(arc
				(start 92.700094 -58.462926)
				(mid 92.680571 -58.459025)
				(end 92.664026 -58.44794)
			)
			(arc
				(start 92.584778 -58.368692)
				(mid 92.573667 -58.352158)
				(end 92.569792 -58.332624)
			)
			(arc
				(start 92.569792 -58.054748)
				(mid 92.565891 -58.035225)
				(end 92.554806 -58.01868)
			)
			(arc
				(start 92.511118 -57.974992)
				(mid 92.494584 -57.963881)
				(end 92.47505 -57.960006)
			)
			(arc
				(start 92.433394 -57.960006)
				(mid 92.413871 -57.963907)
				(end 92.397326 -57.974992)
			)
			(arc
				(start 92.351098 -58.02122)
				(mid 92.339987 -58.037754)
				(end 92.336112 -58.057288)
			)
			(arc
				(start 92.336112 -58.634884)
				(mid 92.340013 -58.654407)
				(end 92.351098 -58.670952)
			)
			(arc
				(start 92.361766 -58.68162)
				(mid 92.3783 -58.692731)
				(end 92.397834 -58.696606)
			)
			(arc
				(start 93.07703 -58.696606)
				(mid 93.096553 -58.700507)
				(end 93.113098 -58.711592)
			)
			(xy 93.75267 -59.351164) (xy 93.755972 -59.35345)
			(arc
				(start 93.768926 -59.36361)
				(mid 93.78397 -59.371934)
				(end 93.80093 -59.374786)
			)
			(arc
				(start 95.301562 -59.374786)
				(mid 95.321085 -59.378687)
				(end 95.33763 -59.389772)
			)
			(arc
				(start 95.445326 -59.497468)
				(mid 95.456437 -59.514002)
				(end 95.460312 -59.533536)
			)
			(arc
				(start 95.460312 -60.115704)
				(mid 95.464213 -60.135227)
				(end 95.475298 -60.151772)
			)
			(xy 95.496126 -60.1726) (xy 95.701866 -60.37834) (xy 96.86036 -60.37834)
		)
		(stroke
			(width 0)
			(type solid)
		)
		(fill yes)
		(layer "F.Cu")
		(net "GND")
	)
	(gr_poly
		(pts
			(xy 443.768734 -53.040026) (xy 443.883542 -52.925218) (xy 452.185024 -52.925218) (xy 455.300588 -52.925218)
			(xy 455.44486 -52.780946) (xy 455.44486 -50.790856) (xy 455.444349 -50.780954) (xy 455.436779 -50.762648)
			(xy 455.430128 -50.755296) (xy 455.42708 -50.751994) (xy 455.41968 -50.745152) (xy 455.401082 -50.737425)
			(xy 455.391012 -50.737008) (xy 454.74255 -50.737008) (xy 454.73112 -50.739802) (xy 454.356216 -50.739802)
			(xy 454.28662 -50.670206) (xy 453.43064 -50.670206) (xy 453.366886 -50.73396) (xy 451.40118 -50.73396)
			(xy 450.80174 -50.13452) (xy 450.80174 -49.021238) (xy 450.69506 -48.914558) (xy 450.69506 -47.63135)
			(xy 450.563996 -47.500286) (xy 443.866778 -47.500286) (xy 442.470032 -46.10354) (xy 431.38598 -46.10354)
			(xy 430.82464 -46.66488) (xy 430.82464 -52.989931) (xy 431.237132 -52.989931) (xy 431.237132 -52.905209)
			(xy 431.245185 -52.820872) (xy 431.261219 -52.737682) (xy 431.285087 -52.656392) (xy 431.316575 -52.57774)
			(xy 431.355397 -52.502437) (xy 431.4012 -52.431165) (xy 431.453571 -52.364569) (xy 431.512036 -52.303254)
			(xy 431.576064 -52.247773) (xy 431.645076 -52.19863) (xy 431.718446 -52.15627) (xy 431.795511 -52.121075)
			(xy 431.875573 -52.093366) (xy 431.957906 -52.073392) (xy 432.041765 -52.061335) (xy 432.12639 -52.057304)
			(xy 432.211015 -52.061335) (xy 432.294874 -52.073392) (xy 432.377207 -52.093366) (xy 432.457269 -52.121075)
			(xy 432.534334 -52.15627) (xy 432.607704 -52.19863) (xy 432.676716 -52.247773) (xy 432.740744 -52.303254)
			(xy 432.799209 -52.364569) (xy 432.85158 -52.431165) (xy 432.897383 -52.502437) (xy 432.936205 -52.57774)
			(xy 432.967693 -52.656392) (xy 432.991561 -52.737682) (xy 433.007595 -52.820872) (xy 433.015648 -52.905209)
			(xy 433.016152 -52.94757) (xy 433.015648 -52.989931) (xy 438.952382 -52.989931) (xy 438.952382 -52.905209)
			(xy 438.960435 -52.820872) (xy 438.976469 -52.737682) (xy 439.000337 -52.656392) (xy 439.031825 -52.57774)
			(xy 439.070647 -52.502437) (xy 439.11645 -52.431165) (xy 439.168821 -52.364569) (xy 439.227286 -52.303254)
			(xy 439.291314 -52.247773) (xy 439.360326 -52.19863) (xy 439.433696 -52.15627) (xy 439.510761 -52.121075)
			(xy 439.590823 -52.093366) (xy 439.673156 -52.073392) (xy 439.757015 -52.061335) (xy 439.84164 -52.057304)
			(xy 439.926265 -52.061335) (xy 440.010124 -52.073392) (xy 440.092457 -52.093366) (xy 440.172519 -52.121075)
			(xy 440.249584 -52.15627) (xy 440.322954 -52.19863) (xy 440.391966 -52.247773) (xy 440.455994 -52.303254)
			(xy 440.514459 -52.364569) (xy 440.56683 -52.431165) (xy 440.612633 -52.502437) (xy 440.651455 -52.57774)
			(xy 440.682943 -52.656392) (xy 440.706811 -52.737682) (xy 440.722845 -52.820872) (xy 440.730898 -52.905209)
			(xy 440.731402 -52.94757) (xy 440.730898 -52.989931) (xy 440.722845 -53.074268) (xy 440.706811 -53.157458)
			(xy 440.682943 -53.238748) (xy 440.651455 -53.3174) (xy 440.612633 -53.392703) (xy 440.56683 -53.463975)
			(xy 440.514459 -53.530571) (xy 440.455994 -53.591886) (xy 440.391966 -53.647367) (xy 440.322954 -53.69651)
			(xy 440.249584 -53.73887) (xy 440.172519 -53.774065) (xy 440.092457 -53.801774) (xy 440.010124 -53.821748)
			(xy 439.926265 -53.833805) (xy 439.84164 -53.837837) (xy 439.757015 -53.833805) (xy 439.673156 -53.821748)
			(xy 439.590823 -53.801774) (xy 439.510761 -53.774065) (xy 439.433696 -53.73887) (xy 439.360326 -53.69651)
			(xy 439.291314 -53.647367) (xy 439.227286 -53.591886) (xy 439.168821 -53.530571) (xy 439.11645 -53.463975)
			(xy 439.070647 -53.392703) (xy 439.031825 -53.3174) (xy 439.000337 -53.238748) (xy 438.976469 -53.157458)
			(xy 438.960435 -53.074268) (xy 438.952382 -52.989931) (xy 433.015648 -52.989931) (xy 433.007595 -53.074268)
			(xy 432.991561 -53.157458) (xy 432.967693 -53.238748) (xy 432.936205 -53.3174) (xy 432.897383 -53.392703)
			(xy 432.85158 -53.463975) (xy 432.799209 -53.530571) (xy 432.740744 -53.591886) (xy 432.676716 -53.647367)
			(xy 432.607704 -53.69651) (xy 432.534334 -53.73887) (xy 432.457269 -53.774065) (xy 432.377207 -53.801774)
			(xy 432.294874 -53.821748) (xy 432.211015 -53.833805) (xy 432.12639 -53.837837) (xy 432.041765 -53.833805)
			(xy 431.957906 -53.821748) (xy 431.875573 -53.801774) (xy 431.795511 -53.774065) (xy 431.718446 -53.73887)
			(xy 431.645076 -53.69651) (xy 431.576064 -53.647367) (xy 431.512036 -53.591886) (xy 431.453571 -53.530571)
			(xy 431.4012 -53.463975) (xy 431.355397 -53.392703) (xy 431.316575 -53.3174) (xy 431.285087 -53.238748)
			(xy 431.261219 -53.157458) (xy 431.245185 -53.074268) (xy 431.237132 -52.989931) (xy 430.82464 -52.989931)
			(xy 430.82464 -53.986684) (xy 430.827688 -53.989732) (xy 430.827688 -54.920388) (xy 431.39106 -55.48376)
			(xy 441.325 -55.48376)
		)
		(stroke
			(width 0)
			(type solid)
		)
		(fill yes)
		(layer "F.Cu")
		(net "SW_P3V3_AUX_FLT")
	)
	(gr_poly
		(pts
			(arc
				(start 453.286114 -30.026102)
				(mid 453.305637 -30.022201)
				(end 453.322182 -30.011116)
			)
			(arc
				(start 454.64603 -28.687268)
				(mid 454.657141 -28.670734)
				(end 454.661016 -28.6512)
			)
			(arc
				(start 454.661016 -26.530554)
				(mid 454.657115 -26.511031)
				(end 454.64603 -26.494486)
			)
			(arc
				(start 454.589642 -26.438098)
				(mid 454.573108 -26.426987)
				(end 454.553574 -26.423112)
			)
			(arc
				(start 452.444866 -26.423112)
				(mid 452.425343 -26.419211)
				(end 452.408798 -26.408126)
			)
			(arc
				(start 452.08317 -26.082498)
				(mid 452.072059 -26.065964)
				(end 452.068184 -26.04643)
			)
			(arc
				(start 452.068184 -25.298654)
				(mid 452.072085 -25.279131)
				(end 452.08317 -25.262586)
			)
			(arc
				(start 452.083678 -25.262078)
				(mid 452.094789 -25.245544)
				(end 452.098664 -25.22601)
			)
			(arc
				(start 452.098664 -22.756876)
				(mid 452.095911 -22.740379)
				(end 452.087996 -22.725634)
			)
			(arc
				(start 452.087996 -22.725634)
				(mid 451.980042 -22.412452)
				(end 452.087996 -22.09927)
			)
			(arc
				(start 452.087996 -22.09927)
				(mid 452.095967 -22.084544)
				(end 452.098664 -22.068028)
			)
			(arc
				(start 452.098664 -20.195794)
				(mid 452.094763 -20.176271)
				(end 452.083678 -20.159726)
			)
			(xy 452.076312 -20.15236)
			(arc
				(start 451.938898 -20.15236)
				(mid 451.919541 -20.156193)
				(end 451.903084 -20.167092)
			)
			(arc
				(start 451.88251 -20.187666)
				(mid 451.871399 -20.2042)
				(end 451.867524 -20.223734)
			)
			(arc
				(start 451.867524 -21.87575)
				(mid 451.863623 -21.895273)
				(end 451.852538 -21.911818)
			)
			(xy 451.720204 -22.044152) (xy 451.716648 -22.044152)
			(arc
				(start 451.670166 -22.090634)
				(mid 451.653749 -22.101696)
				(end 451.634352 -22.10562)
			)
			(arc
				(start 451.348856 -22.10562)
				(mid 451.329469 -22.10167)
				(end 451.313042 -22.090634)
			)
			(arc
				(start 451.281292 -22.059138)
				(mid 451.264875 -22.048076)
				(end 451.245478 -22.044152)
			)
			(arc
				(start 451.212966 -22.044152)
				(mid 451.193443 -22.040251)
				(end 451.176898 -22.029166)
			)
			(arc
				(start 451.10527 -21.957538)
				(mid 451.094159 -21.941004)
				(end 451.090284 -21.92147)
			)
			(arc
				(start 451.090284 -20.688554)
				(mid 451.086383 -20.669031)
				(end 451.075298 -20.652486)
			)
			(arc
				(start 451.06717 -20.644358)
				(mid 451.050636 -20.633247)
				(end 451.031102 -20.629372)
			)
			(arc
				(start 450.948806 -20.629372)
				(mid 450.929283 -20.633273)
				(end 450.912738 -20.644358)
			)
			(arc
				(start 450.87413 -20.682966)
				(mid 450.863019 -20.6995)
				(end 450.859144 -20.719034)
			)
			(arc
				(start 450.859144 -22.070314)
				(mid 450.862307 -22.088216)
				(end 450.87159 -22.103842)
			)
			(arc
				(start 450.87159 -22.103842)
				(mid 450.964646 -22.259597)
				(end 450.997066 -22.438106)
			)
			(arc
				(start 450.997066 -22.438106)
				(mid 450.964613 -22.616603)
				(end 450.87159 -22.77237)
			)
			(arc
				(start 450.87159 -22.77237)
				(mid 450.862331 -22.788004)
				(end 450.859144 -22.805898)
			)
			(arc
				(start 450.859144 -24.77897)
				(mid 450.855243 -24.798493)
				(end 450.844158 -24.815038)
			)
			(arc
				(start 450.42455 -25.234646)
				(mid 450.408016 -25.245757)
				(end 450.388482 -25.249632)
			)
			(arc
				(start 448.937126 -25.249632)
				(mid 448.917603 -25.253533)
				(end 448.901058 -25.264618)
			)
			(arc
				(start 448.09283 -26.072846)
				(mid 448.076296 -26.083957)
				(end 448.056762 -26.087832)
			)
			(arc
				(start 446.321688 -26.087832)
				(mid 446.302165 -26.091733)
				(end 446.28562 -26.102818)
			)
			(arc
				(start 444.916052 -27.472386)
				(mid 444.899518 -27.483497)
				(end 444.879984 -27.487372)
			)
			(arc
				(start 440.680348 -27.487372)
				(mid 440.660825 -27.491273)
				(end 440.64428 -27.502358)
			)
			(arc
				(start 440.599322 -27.547316)
				(mid 440.588211 -27.56385)
				(end 440.584336 -27.583384)
			)
			(arc
				(start 440.584336 -28.78582)
				(mid 440.588237 -28.805343)
				(end 440.599322 -28.821888)
			)
			(arc
				(start 440.64555 -28.868116)
				(mid 440.662084 -28.879227)
				(end 440.681618 -28.883102)
			)
			(arc
				(start 445.131698 -28.883102)
				(mid 445.151221 -28.887003)
				(end 445.167766 -28.898088)
			)
			(arc
				(start 446.280794 -30.011116)
				(mid 446.297328 -30.022227)
				(end 446.316862 -30.026102)
			)
		)
		(stroke
			(width 0)
			(type solid)
		)
		(fill yes)
		(layer "F.Cu")
		(net "P12V_AUX")
	)
	(gr_poly
		(pts
			(xy 425.649898 -51.24958) (xy 425.659968 -51.249157) (xy 425.678571 -51.241441) (xy 425.685966 -51.234594)
			(xy 425.907454 -51.013106) (xy 425.914306 -51.00571) (xy 425.92205 -50.987112) (xy 425.92244 -50.977038)
			(xy 425.92244 -50.097182) (xy 425.922012 -50.087115) (xy 425.914286 -50.068521) (xy 425.907454 -50.061114)
			(xy 416.193986 -40.347646) (xy 416.186589 -40.340797) (xy 416.16799 -40.33306) (xy 416.157918 -40.33266)
			(xy 413.881062 -40.33266) (xy 413.870996 -40.333092) (xy 413.852407 -40.340822) (xy 413.844994 -40.347646)
			(xy 411.28696 -42.90568) (xy 412.7881 -42.90568) (xy 412.788602 -42.873719) (xy 412.796613 -42.810301)
			(xy 412.81251 -42.748387) (xy 412.836042 -42.688954) (xy 412.866836 -42.632939) (xy 412.904409 -42.581224)
			(xy 412.948166 -42.534627) (xy 412.997419 -42.493882) (xy 413.05139 -42.459631) (xy 413.109229 -42.432414)
			(xy 413.170022 -42.412661) (xy 413.232812 -42.400683) (xy 413.296608 -42.39667) (xy 413.360404 -42.400683)
			(xy 413.423194 -42.412661) (xy 413.483987 -42.432414) (xy 413.541826 -42.459631) (xy 413.595797 -42.493882)
			(xy 413.64505 -42.534627) (xy 413.688807 -42.581224) (xy 413.72638 -42.632939) (xy 413.74797 -42.672211)
			(xy 413.881564 -42.672211) (xy 413.881564 -42.608289) (xy 413.889575 -42.544871) (xy 413.905472 -42.482957)
			(xy 413.929004 -42.423524) (xy 413.959798 -42.367509) (xy 413.997371 -42.315794) (xy 414.041128 -42.269197)
			(xy 414.090381 -42.228452) (xy 414.144352 -42.194201) (xy 414.202191 -42.166984) (xy 414.262984 -42.147231)
			(xy 414.325774 -42.135253) (xy 414.38957 -42.13124) (xy 414.453366 -42.135253) (xy 414.516156 -42.147231)
			(xy 414.576949 -42.166984) (xy 414.634788 -42.194201) (xy 414.688759 -42.228452) (xy 414.738012 -42.269197)
			(xy 414.781769 -42.315794) (xy 414.819342 -42.367509) (xy 414.850136 -42.423524) (xy 414.873668 -42.482957)
			(xy 414.889565 -42.544871) (xy 414.897576 -42.608289) (xy 414.898078 -42.64025) (xy 414.897576 -42.672211)
			(xy 414.889565 -42.735629) (xy 414.873668 -42.797543) (xy 414.850136 -42.856976) (xy 414.819342 -42.912991)
			(xy 414.781769 -42.964706) (xy 414.738012 -43.011303) (xy 414.688759 -43.052048) (xy 414.634788 -43.086299)
			(xy 414.576949 -43.113516) (xy 414.516156 -43.133269) (xy 414.453366 -43.145247) (xy 414.38957 -43.149261)
			(xy 414.325774 -43.145247) (xy 414.262984 -43.133269) (xy 414.202191 -43.113516) (xy 414.144352 -43.086299)
			(xy 414.090381 -43.052048) (xy 414.041128 -43.011303) (xy 413.997371 -42.964706) (xy 413.959798 -42.912991)
			(xy 413.929004 -42.856976) (xy 413.905472 -42.797543) (xy 413.889575 -42.735629) (xy 413.881564 -42.672211)
			(xy 413.74797 -42.672211) (xy 413.757174 -42.688954) (xy 413.780706 -42.748387) (xy 413.796603 -42.810301)
			(xy 413.804614 -42.873719) (xy 413.805116 -42.90568) (xy 413.80461 -42.936906) (xy 413.796975 -42.998888)
			(xy 413.781805 -43.059468) (xy 413.759328 -43.117734) (xy 413.729883 -43.172808) (xy 413.693914 -43.22386)
			(xy 413.67329 -43.24731) (xy 413.666686 -43.254676) (xy 413.660082 -43.272202) (xy 413.661352 -43.36161)
			(xy 413.668718 -43.378882) (xy 413.675576 -43.386248) (xy 413.694726 -43.406683) (xy 413.72819 -43.45159)
			(xy 413.755651 -43.5004) (xy 413.776658 -43.552316) (xy 413.790868 -43.606488) (xy 413.798049 -43.66203)
			(xy 413.798512 -43.690032) (xy 413.798002 -43.719915) (xy 413.789864 -43.779125) (xy 413.773739 -43.836675)
			(xy 413.749928 -43.891494) (xy 413.718874 -43.94256) (xy 413.681156 -43.988921) (xy 413.637477 -44.029715)
			(xy 413.588649 -44.064181) (xy 413.535583 -44.091678) (xy 413.479268 -44.111693) (xy 413.420751 -44.123852)
			(xy 413.361124 -44.127931) (xy 413.301497 -44.123852) (xy 413.24298 -44.111693) (xy 413.186665 -44.091678)
			(xy 413.133599 -44.064181) (xy 413.084771 -44.029715) (xy 413.041092 -43.988921) (xy 413.003374 -43.94256)
			(xy 412.97232 -43.891494) (xy 412.948509 -43.836675) (xy 412.932384 -43.779125) (xy 412.924246 -43.719915)
			(xy 412.923736 -43.690032) (xy 412.924343 -43.65699) (xy 412.934324 -43.591662) (xy 412.954004 -43.528575)
			(xy 412.982937 -43.46916) (xy 413.001206 -43.44162) (xy 413.007048 -43.433492) (xy 413.011112 -43.41495)
			(xy 412.997904 -43.326812) (xy 412.988506 -43.310302) (xy 412.980886 -43.304206) (xy 412.955511 -43.283526)
			(xy 412.909835 -43.236631) (xy 412.870555 -43.184262) (xy 412.838323 -43.127284) (xy 412.813671 -43.06664)
			(xy 412.797007 -43.003333) (xy 412.788607 -42.938412) (xy 412.7881 -42.90568) (xy 411.28696 -42.90568)
			(xy 410.740606 -43.452034) (xy 410.733764 -43.459434) (xy 410.726041 -43.478032) (xy 410.72562 -43.488102)
			(xy 410.72562 -45.457618) (xy 410.726047 -45.467686) (xy 410.733768 -45.486284) (xy 410.740606 -45.493686)
			(xy 416.481514 -51.234594) (xy 416.488913 -51.241439) (xy 416.507511 -51.249169) (xy 416.517582 -51.24958)
		)
		(stroke
			(width 0)
			(type solid)
		)
		(fill yes)
		(layer "F.Cu")
		(net "P5V_AUX")
	)
	(gr_poly
		(pts
			(arc
				(start 310.922162 -335.09331)
				(mid 310.941685 -335.089409)
				(end 310.95823 -335.078324)
			)
			(arc
				(start 311.055258 -334.981296)
				(mid 311.066369 -334.964762)
				(end 311.070244 -334.945228)
			)
			(arc
				(start 311.070244 -326.94245)
				(mid 311.074145 -326.922927)
				(end 311.08523 -326.906382)
			)
			(arc
				(start 313.125866 -324.865746)
				(mid 313.136977 -324.849212)
				(end 313.140852 -324.829678)
			)
			(arc
				(start 313.140852 -324.69836)
				(mid 313.144753 -324.678837)
				(end 313.155838 -324.662292)
			)
			(arc
				(start 314.517024 -323.301106)
				(mid 314.533558 -323.289995)
				(end 314.553092 -323.28612)
			)
			(arc
				(start 345.865704 -323.28612)
				(mid 345.885227 -323.290021)
				(end 345.901772 -323.301106)
			)
			(arc
				(start 346.19946 -323.598794)
				(mid 346.210571 -323.615328)
				(end 346.214446 -323.634862)
			)
			(arc
				(start 346.214446 -325.083678)
				(mid 346.218347 -325.103201)
				(end 346.229432 -325.119746)
			)
			(arc
				(start 346.45092 -325.341234)
				(mid 346.467454 -325.352345)
				(end 346.486988 -325.35622)
			)
			(arc
				(start 347.882464 -325.35622)
				(mid 347.901987 -325.360121)
				(end 347.918532 -325.371206)
			)
			(arc
				(start 348.886526 -326.3392)
				(mid 348.897637 -326.355734)
				(end 348.901512 -326.375268)
			)
			(arc
				(start 348.901512 -328.087228)
				(mid 348.905413 -328.106751)
				(end 348.916498 -328.123296)
			)
			(arc
				(start 349.013272 -328.22007)
				(mid 349.029689 -328.231132)
				(end 349.049086 -328.235056)
			)
			(xy 354.080826 -328.235056) (xy 354.081334 -328.23531)
			(arc
				(start 357.493824 -328.23531)
				(mid 357.513347 -328.231409)
				(end 357.529892 -328.220324)
			)
			(arc
				(start 357.77424 -327.975976)
				(mid 357.788556 -327.946866)
				(end 357.782368 -327.915016)
			)
			(arc
				(start 357.782368 -327.915016)
				(mid 357.720221 -327.763089)
				(end 357.699056 -327.60031)
			)
			(arc
				(start 357.699056 -327.60031)
				(mid 357.719575 -327.439649)
				(end 357.780082 -327.289414)
			)
			(xy 357.788464 -327.274682) (xy 357.783892 -327.2409)
			(arc
				(start 357.77043 -327.227438)
				(mid 357.753896 -327.216327)
				(end 357.734362 -327.212452)
			)
			(arc
				(start 356.006146 -327.212452)
				(mid 355.986623 -327.208551)
				(end 355.970078 -327.197466)
			)
			(arc
				(start 355.76891 -326.996298)
				(mid 355.757799 -326.979764)
				(end 355.753924 -326.96023)
			)
			(arc
				(start 355.753924 -319.59296)
				(mid 355.750023 -319.573437)
				(end 355.738938 -319.556892)
			)
			(arc
				(start 350.425512 -314.243466)
				(mid 350.408978 -314.232355)
				(end 350.389444 -314.22848)
			)
			(arc
				(start 342.798908 -314.22848)
				(mid 342.779385 -314.224579)
				(end 342.76284 -314.213494)
			)
			(arc
				(start 341.47506 -312.925714)
				(mid 341.458526 -312.914603)
				(end 341.438992 -312.910728)
			)
			(arc
				(start 314.906406 -312.910728)
				(mid 314.886883 -312.914629)
				(end 314.870338 -312.925714)
			)
			(arc
				(start 308.19471 -319.601342)
				(mid 308.178176 -319.612453)
				(end 308.158642 -319.616328)
			)
			(arc
				(start 305.198018 -319.616328)
				(mid 305.178495 -319.620229)
				(end 305.16195 -319.631314)
			)
			(arc
				(start 304.351436 -320.441828)
				(mid 304.340325 -320.458362)
				(end 304.33645 -320.477896)
			)
			(arc
				(start 304.33645 -323.442584)
				(mid 304.3404 -323.461971)
				(end 304.351436 -323.478398)
			)
			(xy 304.409602 -323.53631) (xy 304.428144 -323.544184) (xy 304.438304 -323.544184)
			(arc
				(start 306.19446 -323.544184)
				(mid 307.185314 -324.535038)
				(end 306.19446 -325.525892)
			)
			(xy 304.44186 -325.525892) (xy 304.428144 -325.525892) (xy 304.409602 -325.533766)
			(arc
				(start 304.351436 -325.591678)
				(mid 304.340374 -325.608095)
				(end 304.33645 -325.627492)
			)
			(arc
				(start 304.33645 -334.700372)
				(mid 304.340351 -334.719895)
				(end 304.351436 -334.73644)
			)
			(arc
				(start 304.69332 -335.078324)
				(mid 304.709854 -335.089435)
				(end 304.729388 -335.09331)
			)
		)
		(stroke
			(width 0)
			(type solid)
		)
		(fill yes)
		(layer "F.Cu")
		(net "PVDDCR_CPU1_P0")
	)
	(gr_poly
		(pts
			(arc
				(start 354.132896 -407.76144)
				(mid 354.152419 -407.757539)
				(end 354.168964 -407.746454)
			)
			(arc
				(start 354.490528 -407.42489)
				(mid 354.501639 -407.408356)
				(end 354.505514 -407.388822)
			)
			(arc
				(start 354.505514 -405.85771)
				(mid 354.509415 -405.838187)
				(end 354.5205 -405.821642)
			)
			(xy 355.35108 -404.991062) (xy 355.3587 -404.973028)
			(arc
				(start 355.3587 -404.962868)
				(mid 355.382252 -404.796466)
				(end 355.448616 -404.642066)
			)
			(arc
				(start 355.448616 -404.642066)
				(mid 355.453912 -404.62959)
				(end 355.455728 -404.616158)
			)
			(arc
				(start 355.455728 -404.245318)
				(mid 355.451827 -404.225795)
				(end 355.440742 -404.20925)
			)
			(arc
				(start 355.29012 -404.058628)
				(mid 355.273586 -404.047517)
				(end 355.254052 -404.043642)
			)
			(xy 355.157786 -404.043642)
			(arc
				(start 355.151944 -404.044912)
				(mid 355.11651 -404.051318)
				(end 355.08057 -404.053548)
			)
			(arc
				(start 354.837746 -404.053548)
				(mid 354.812859 -404.059919)
				(end 354.794312 -404.077678)
			)
			(arc
				(start 354.794312 -404.077678)
				(mid 354.670177 -404.224561)
				(end 354.5078 -404.327614)
			)
			(xy 354.499164 -404.331424)
			(arc
				(start 353.972876 -404.857712)
				(mid 353.956342 -404.868823)
				(end 353.936808 -404.872698)
			)
			(xy 335.363312 -404.872698)
			(arc
				(start 335.353914 -404.876508)
				(mid 335.330004 -404.88372)
				(end 335.305146 -404.88616)
			)
			(xy 335.24317 -404.88616)
			(arc
				(start 335.233772 -404.890224)
				(mid 335.175401 -404.908112)
				(end 335.114646 -404.9141)
			)
			(arc
				(start 335.114646 -404.9141)
				(mid 335.053895 -404.908092)
				(end 334.99552 -404.890224)
			)
			(xy 334.986122 -404.88616) (xy 334.953102 -404.88616) (xy 334.923638 -404.913846)
			(arc
				(start 334.922622 -404.934166)
				(mid 334.723831 -405.358646)
				(end 334.28813 -405.531574)
			)
			(arc
				(start 334.28813 -405.531574)
				(mid 333.838758 -405.345438)
				(end 333.652622 -404.896066)
			)
			(arc
				(start 333.652622 -404.896066)
				(mid 333.798692 -404.4907)
				(end 334.169766 -404.271734)
			)
			(xy 334.1878 -404.268178) (xy 334.211168 -404.240238)
			(arc
				(start 334.211168 -404.005034)
				(mid 334.207218 -403.985647)
				(end 334.196182 -403.96922)
			)
			(arc
				(start 334.171798 -403.944836)
				(mid 334.155264 -403.933725)
				(end 334.13573 -403.92985)
			)
			(arc
				(start 332.880716 -403.92985)
				(mid 332.861193 -403.933751)
				(end 332.844648 -403.944836)
			)
			(arc
				(start 332.532228 -404.257256)
				(mid 332.517214 -404.293234)
				(end 332.532228 -404.329138)
			)
			(xy 334.062832 -405.859996) (xy 334.087978 -405.867108)
			(arc
				(start 334.101186 -405.863806)
				(mid 334.174837 -405.850656)
				(end 334.249522 -405.84628)
			)
			(arc
				(start 334.249522 -405.84628)
				(mid 334.698894 -406.93116)
				(end 333.614014 -406.481788)
			)
			(arc
				(start 333.614014 -406.481788)
				(mid 333.618417 -406.407106)
				(end 333.63154 -406.333452)
			)
			(xy 333.634842 -406.320244) (xy 333.62773 -406.295098)
			(arc
				(start 332.522068 -405.18969)
				(mid 332.496077 -405.175684)
				(end 332.466696 -405.178514)
			)
			(xy 332.452472 -405.18461) (xy 332.435454 -405.209756)
			(arc
				(start 332.435454 -407.71064)
				(mid 332.450333 -407.746561)
				(end 332.486254 -407.76144)
			)
		)
		(stroke
			(width 0)
			(type solid)
		)
		(fill yes)
		(layer "F.Cu")
		(net "P1V8_CPU0_RT_1D")
	)
	(gr_poly
		(pts
			(arc
				(start 93.20022 -399.37944)
				(mid 93.219607 -399.37549)
				(end 93.236034 -399.364454)
			)
			(arc
				(start 93.625924 -398.974564)
				(mid 93.808172 -398.852726)
				(end 94.02318 -398.809972)
			)
			(arc
				(start 94.42323 -398.809972)
				(mid 94.4415 -398.806573)
				(end 94.457266 -398.796764)
			)
			(arc
				(start 94.457266 -398.796764)
				(mid 94.632892 -398.687935)
				(end 94.83598 -398.649952)
			)
			(arc
				(start 95.496634 -398.649952)
				(mid 95.516128 -398.646168)
				(end 95.532702 -398.63522)
			)
			(arc
				(start 96.475804 -397.691864)
				(mid 96.658052 -397.570026)
				(end 96.87306 -397.527272)
			)
			(arc
				(start 97.839276 -397.527272)
				(mid 97.85877 -397.523488)
				(end 97.875344 -397.51254)
			)
			(arc
				(start 98.13925 -397.24838)
				(mid 98.321498 -397.126542)
				(end 98.536506 -397.083788)
			)
			(arc
				(start 98.536506 -397.083788)
				(mid 98.658966 -397.09741)
				(end 98.77552 -397.137382)
			)
			(xy 98.790252 -397.14424) (xy 98.821748 -397.138652) (xy 99.282758 -396.677642) (xy 99.289362 -396.649956)
			(arc
				(start 99.28479 -396.635986)
				(mid 99.260837 -396.537696)
				(end 99.252786 -396.43685)
			)
			(arc
				(start 99.252786 -396.43685)
				(mid 99.301728 -396.192339)
				(end 99.441 -395.985492)
			)
			(xy 99.448112 -395.978126) (xy 99.455986 -395.959584)
			(arc
				(start 99.455986 -395.863318)
				(mid 99.452085 -395.843795)
				(end 99.441 -395.82725)
			)
			(arc
				(start 99.290378 -395.676628)
				(mid 99.273844 -395.665517)
				(end 99.25431 -395.661642)
			)
			(xy 99.158044 -395.661642)
			(arc
				(start 99.152202 -395.662912)
				(mid 99.116768 -395.669318)
				(end 99.080828 -395.671548)
			)
			(arc
				(start 98.838004 -395.671548)
				(mid 98.813117 -395.677919)
				(end 98.79457 -395.695678)
			)
			(arc
				(start 98.79457 -395.695678)
				(mid 98.563299 -395.918167)
				(end 98.252788 -395.999208)
			)
			(arc
				(start 98.252788 -395.999208)
				(mid 98.072683 -395.973142)
				(end 97.907348 -395.8971)
			)
			(arc
				(start 97.907348 -395.8971)
				(mid 97.894099 -395.890997)
				(end 97.879662 -395.888972)
			)
			(arc
				(start 87.857838 -395.888972)
				(mid 87.838315 -395.892873)
				(end 87.82177 -395.903958)
			)
			(arc
				(start 87.250016 -396.475712)
				(mid 87.233482 -396.486823)
				(end 87.213948 -396.490698)
			)
			(xy 79.36357 -396.490698)
			(arc
				(start 79.354172 -396.494508)
				(mid 79.330262 -396.50172)
				(end 79.305404 -396.50416)
			)
			(xy 79.243428 -396.50416)
			(arc
				(start 79.23403 -396.508224)
				(mid 79.175659 -396.526112)
				(end 79.114904 -396.5321)
			)
			(arc
				(start 79.114904 -396.5321)
				(mid 79.054153 -396.526092)
				(end 78.995778 -396.508224)
			)
			(xy 78.98638 -396.50416) (xy 78.95336 -396.50416) (xy 78.923896 -396.531846)
			(arc
				(start 78.92288 -396.552166)
				(mid 78.724089 -396.976646)
				(end 78.288388 -397.149574)
			)
			(arc
				(start 78.288388 -397.149574)
				(mid 77.839016 -396.963438)
				(end 77.65288 -396.514066)
			)
			(arc
				(start 77.65288 -396.514066)
				(mid 77.79895 -396.1087)
				(end 78.170024 -395.889734)
			)
			(xy 78.188058 -395.886178) (xy 78.211172 -395.858238)
			(arc
				(start 78.211172 -395.623034)
				(mid 78.207339 -395.603677)
				(end 78.19644 -395.58722)
			)
			(arc
				(start 78.172056 -395.562836)
				(mid 78.155522 -395.551725)
				(end 78.135988 -395.54785)
			)
			(arc
				(start 76.880974 -395.54785)
				(mid 76.861451 -395.551751)
				(end 76.844906 -395.562836)
			)
			(arc
				(start 76.644754 -395.763242)
				(mid 76.633643 -395.779776)
				(end 76.629768 -395.79931)
			)
			(arc
				(start 76.629768 -396.800578)
				(mid 76.633669 -396.820101)
				(end 76.644754 -396.836646)
			)
			(arc
				(start 79.172562 -399.364454)
				(mid 79.189096 -399.375565)
				(end 79.20863 -399.37944)
			)
		)
		(stroke
			(width 0)
			(type solid)
		)
		(fill yes)
		(layer "F.Cu")
		(net "P1V8_CPU1_RT_1D")
	)
	(gr_poly
		(pts
			(arc
				(start 126.42215 -31.150306)
				(mid 126.441673 -31.146405)
				(end 126.458218 -31.13532)
			)
			(arc
				(start 127.058166 -30.535372)
				(mid 127.0747 -30.524261)
				(end 127.094234 -30.520386)
			)
			(arc
				(start 128.376172 -30.520386)
				(mid 128.404359 -30.511849)
				(end 128.423162 -30.489144)
			)
			(xy 128.429004 -30.474666) (xy 128.423162 -30.444694) (xy 127.987044 -30.008576) (xy 127.9398 -29.961332)
			(xy 127.240284 -29.961332) (xy 126.90729 -29.961332) (xy 126.838456 -29.892498) (xy 126.78791 -29.841952)
			(xy 126.78791 -29.714952) (xy 126.77267 -29.699712)
			(arc
				(start 126.305056 -29.699712)
				(mid 126.269299 -29.684744)
				(end 126.254256 -29.648912)
			)
			(arc
				(start 126.254256 -29.485336)
				(mid 126.239377 -29.449415)
				(end 126.203456 -29.434536)
			)
			(xy 126.194312 -29.434536) (xy 126.194312 -29.428948) (xy 126.164848 -29.398976)
			(arc
				(start 124.521976 -29.398976)
				(mid 124.502453 -29.402877)
				(end 124.485908 -29.413962)
			)
			(arc
				(start 124.284486 -29.615384)
				(mid 124.273375 -29.631918)
				(end 124.2695 -29.651452)
			)
			(arc
				(start 124.2695 -30.287722)
				(mid 124.232228 -30.377704)
				(end 124.142246 -30.414976)
			)
			(arc
				(start 123.227846 -30.414976)
				(mid 123.137864 -30.377704)
				(end 123.100592 -30.287722)
			)
			(arc
				(start 123.100592 -29.271722)
				(mid 123.137864 -29.18174)
				(end 123.227846 -29.144468)
			)
			(arc
				(start 123.864116 -29.144468)
				(mid 123.883639 -29.140567)
				(end 123.900184 -29.129482)
			)
			(arc
				(start 124.155708 -28.873704)
				(mid 124.255595 -28.807055)
				(end 124.373386 -28.783788)
			)
			(arc
				(start 124.405898 -28.783788)
				(mid 124.430252 -28.777431)
				(end 124.44857 -28.760166)
			)
			(xy 124.501656 -28.677362) (xy 124.503434 -28.651454)
			(arc
				(start 124.4981 -28.63977)
				(mid 124.477229 -28.577008)
				(end 124.47016 -28.511246)
			)
			(arc
				(start 124.47016 -28.07081)
				(mid 124.493491 -27.953045)
				(end 124.560076 -27.853132)
			)
			(arc
				(start 124.635514 -27.777948)
				(mid 124.646625 -27.761414)
				(end 124.6505 -27.74188)
			)
			(arc
				(start 124.6505 -27.421586)
				(mid 124.687772 -27.331604)
				(end 124.777754 -27.294332)
			)
			(arc
				(start 125.692154 -27.294332)
				(mid 125.782136 -27.331604)
				(end 125.819408 -27.421586)
			)
			(arc
				(start 125.819408 -28.259532)
				(mid 125.834271 -28.295542)
				(end 125.870208 -28.310332)
			)
			(arc
				(start 125.879606 -28.310332)
				(mid 125.899129 -28.306431)
				(end 125.915674 -28.295346)
			)
			(arc
				(start 126.164848 -28.045918)
				(mid 126.202297 -28.014027)
				(end 126.24435 -27.988514)
			)
			(xy 126.257558 -27.982164) (xy 126.272544 -27.95778)
			(arc
				(start 126.272544 -27.91206)
				(mid 126.287423 -27.876139)
				(end 126.323344 -27.86126)
			)
			(arc
				(start 126.856236 -27.86126)
				(mid 126.892322 -27.876049)
				(end 126.907036 -27.91206)
			)
			(xy 126.907036 -27.926284) (xy 126.937008 -27.955748) (xy 127.076962 -27.955748) (xy 127.09144 -27.95143)
			(arc
				(start 127.09779 -27.947112)
				(mid 127.167154 -27.910316)
				(end 127.24257 -27.888438)
			)
			(xy 127.29337 -27.837638) (xy 128.056132 -27.837638) (xy 128.13538 -27.916886)
			(arc
				(start 128.177036 -27.958542)
				(mid 128.272739 -27.98767)
				(end 128.354074 -28.045918)
			)
			(arc
				(start 128.699006 -28.39085)
				(mid 128.724997 -28.404856)
				(end 128.754378 -28.402026)
			)
			(xy 128.768602 -28.39593) (xy 128.78562 -28.370784)
			(arc
				(start 128.78562 -27.587956)
				(mid 128.781719 -27.568433)
				(end 128.770634 -27.551888)
			)
			(arc
				(start 128.090168 -26.871422)
				(mid 128.073634 -26.860311)
				(end 128.0541 -26.856436)
			)
			(arc
				(start 127.60452 -26.856436)
				(mid 127.584997 -26.860337)
				(end 127.568452 -26.871422)
			)
			(arc
				(start 127.308864 -27.13101)
				(mid 127.29233 -27.142121)
				(end 127.272796 -27.145996)
			)
			(arc
				(start 126.381764 -27.145996)
				(mid 126.362241 -27.142095)
				(end 126.345696 -27.13101)
			)
			(arc
				(start 125.828298 -26.613612)
				(mid 125.811764 -26.602501)
				(end 125.79223 -26.598626)
			)
			(arc
				(start 123.40209 -26.598626)
				(mid 123.382567 -26.602527)
				(end 123.366022 -26.613612)
			)
			(arc
				(start 122.384566 -27.595068)
				(mid 122.373455 -27.611602)
				(end 122.36958 -27.631136)
			)
			(arc
				(start 122.36958 -30.204156)
				(mid 122.373481 -30.223679)
				(end 122.384566 -30.240224)
			)
			(arc
				(start 123.279662 -31.13532)
				(mid 123.296196 -31.146431)
				(end 123.31573 -31.150306)
			)
		)
		(stroke
			(width 0)
			(type solid)
		)
		(fill yes)
		(layer "F.Cu")
		(net "GND")
	)
	(gr_poly
		(pts
			(arc
				(start 458.159612 -412.75254)
				(mid 458.179135 -412.748639)
				(end 458.19568 -412.737554)
			)
			(arc
				(start 458.334872 -412.598362)
				(mid 458.345983 -412.581828)
				(end 458.349858 -412.562294)
			)
			(arc
				(start 458.349858 -397.711168)
				(mid 458.345957 -397.691645)
				(end 458.334872 -397.6751)
			)
			(arc
				(start 458.167994 -397.508222)
				(mid 458.15146 -397.497111)
				(end 458.131926 -397.493236)
			)
			(xy 454.60412 -397.493236) (xy 454.59904 -397.498316) (xy 454.59904 -399.551144) (xy 454.60539 -399.557494)
			(arc
				(start 455.99096 -399.557494)
				(mid 456.010483 -399.561395)
				(end 456.027028 -399.57248)
			)
			(arc
				(start 456.142852 -399.688304)
				(mid 456.153963 -399.704838)
				(end 456.157838 -399.724372)
			)
			(arc
				(start 456.157838 -400.646646)
				(mid 456.161603 -400.665837)
				(end 456.172316 -400.682206)
			)
			(xy 456.17257 -400.68246)
			(arc
				(start 456.456796 -400.966432)
				(mid 456.467907 -400.982966)
				(end 456.471782 -401.0025)
			)
			(xy 456.471782 -401.036028) (xy 456.47229 -401.042124)
			(arc
				(start 456.472798 -401.04695)
				(mid 456.475005 -401.056799)
				(end 456.479148 -401.066)
			)
			(xy 456.480926 -401.069048)
			(arc
				(start 456.484736 -401.076414)
				(mid 456.503084 -401.126271)
				(end 456.509374 -401.17903)
			)
			(arc
				(start 456.509374 -401.3962)
				(mid 456.505473 -401.415723)
				(end 456.494388 -401.432268)
			)
			(xy 456.479656 -401.447) (xy 456.471782 -401.447) (xy 456.471782 -401.936458) (xy 456.474322 -401.941792)
			(xy 456.474322 -401.942554)
			(arc
				(start 456.476862 -401.947634)
				(mid 456.503754 -402.026427)
				(end 456.51293 -402.109178)
			)
			(arc
				(start 456.51293 -402.109178)
				(mid 456.512195 -402.133612)
				(end 456.509882 -402.157946)
			)
			(xy 456.509374 -402.161248)
			(arc
				(start 456.509374 -402.239226)
				(mid 456.501544 -402.298276)
				(end 456.47864 -402.353272)
			)
			(xy 456.475338 -402.359114) (xy 456.471782 -402.371814)
			(arc
				(start 456.471782 -402.443188)
				(mid 456.467881 -402.462711)
				(end 456.456796 -402.479256)
			)
			(arc
				(start 456.21321 -402.722842)
				(mid 456.196676 -402.733953)
				(end 456.177142 -402.737828)
			)
			(xy 455.630788 -402.737828) (xy 455.611992 -402.745448) (xy 455.60488 -402.752814)
			(arc
				(start 455.54519 -402.812504)
				(mid 455.530562 -402.842316)
				(end 455.53757 -402.874734)
			)
			(arc
				(start 455.53757 -402.874734)
				(mid 455.58961 -402.99492)
				(end 455.60742 -403.12467)
			)
			(arc
				(start 455.60742 -403.12467)
				(mid 455.588966 -403.256847)
				(end 455.53503 -403.378924)
			)
			(xy 455.53122 -403.38502) (xy 455.52741 -403.398482) (xy 455.52741 -403.412706) (xy 455.497692 -403.442424)
			(xy 455.492866 -403.442424)
			(arc
				(start 455.492866 -403.687788)
				(mid 455.488965 -403.707311)
				(end 455.47788 -403.723856)
			)
			(arc
				(start 455.355452 -403.846284)
				(mid 455.338918 -403.857395)
				(end 455.319384 -403.86127)
			)
			(arc
				(start 455.021696 -403.86127)
				(mid 455.002339 -403.865103)
				(end 454.985882 -403.876002)
			)
			(arc
				(start 454.92035 -403.94128)
				(mid 454.903933 -403.952342)
				(end 454.884536 -403.956266)
			)
			(arc
				(start 454.502266 -403.956266)
				(mid 454.25858 -403.890223)
				(end 454.081642 -403.71014)
			)
			(xy 454.081134 -403.709378)
			(arc
				(start 454.080118 -403.7076)
				(mid 454.061548 -403.689884)
				(end 454.036684 -403.68347)
			)
			(arc
				(start 449.443348 -403.68347)
				(mid 449.423825 -403.679569)
				(end 449.40728 -403.668484)
			)
			(arc
				(start 448.903852 -403.165056)
				(mid 448.892741 -403.148522)
				(end 448.888866 -403.128988)
			)
			(arc
				(start 448.888866 -401.570952)
				(mid 448.892767 -401.551429)
				(end 448.903852 -401.534884)
			)
			(xy 449.064126 -401.37461)
			(arc
				(start 449.064634 -401.374102)
				(mid 449.075376 -401.357745)
				(end 449.079112 -401.338542)
			)
			(xy 449.079112 -397.689832) (xy 449.079112 -397.689324) (xy 449.079112 -397.679418) (xy 449.071492 -397.660622)
			(arc
				(start 448.963542 -397.552672)
				(mid 448.947008 -397.541561)
				(end 448.927474 -397.537686)
			)
			(arc
				(start 447.910458 -397.537686)
				(mid 447.890935 -397.533785)
				(end 447.87439 -397.5227)
			)
			(arc
				(start 447.86296 -397.51127)
				(mid 447.846426 -397.500159)
				(end 447.826892 -397.496284)
			)
			(arc
				(start 445.571626 -397.496284)
				(mid 445.535705 -397.511163)
				(end 445.520826 -397.547084)
			)
			(xy 445.520826 -399.558002) (xy 445.52743 -399.564606)
			(arc
				(start 446.91935 -399.564606)
				(mid 446.938873 -399.568507)
				(end 446.955418 -399.579592)
			)
			(arc
				(start 447.06413 -399.688304)
				(mid 447.075241 -399.704838)
				(end 447.079116 -399.724372)
			)
			(arc
				(start 447.079116 -400.646646)
				(mid 447.082881 -400.665837)
				(end 447.093594 -400.682206)
			)
			(xy 447.093848 -400.68246)
			(arc
				(start 447.396108 -400.98472)
				(mid 447.407219 -401.001254)
				(end 447.411094 -401.020788)
			)
			(xy 447.411094 -401.023328) (xy 447.462402 -401.074636) (xy 447.462402 -402.570442) (xy 447.401188 -402.631656)
			(arc
				(start 447.401188 -408.451558)
				(mid 447.397287 -408.471081)
				(end 447.386202 -408.487626)
			)
			(arc
				(start 446.26403 -409.609798)
				(mid 446.252919 -409.626332)
				(end 446.249044 -409.645866)
			)
			(arc
				(start 446.249044 -412.611824)
				(mid 446.252809 -412.631015)
				(end 446.263522 -412.647384)
			)
			(xy 446.263776 -412.647638)
			(arc
				(start 446.353692 -412.737554)
				(mid 446.370226 -412.748665)
				(end 446.38976 -412.75254)
			)
		)
		(stroke
			(width 0)
			(type solid)
		)
		(fill yes)
		(layer "F.Cu")
		(net "SW_P12V_AUX_P0V9_RETIMER_CPU0_FLT")
	)
	(gr_poly
		(pts
			(xy 451.301866 -435.59984) (xy 451.301365 -435.529025) (xy 451.293352 -435.387622) (xy 451.277352 -435.246898)
			(xy 451.253417 -435.107305) (xy 451.221622 -434.96929) (xy 451.18207 -434.833294) (xy 451.134887 -434.699755)
			(xy 451.080225 -434.569098) (xy 451.018259 -434.441743) (xy 450.949186 -434.318098) (xy 450.873229 -434.198559)
			(xy 450.790631 -434.083508) (xy 450.701656 -433.973315) (xy 450.60659 -433.868331) (xy 450.505736 -433.768895)
			(xy 450.399418 -433.675323) (xy 450.287977 -433.587917) (xy 450.171769 -433.506955) (xy 450.051167 -433.432697)
			(xy 449.926556 -433.365381) (xy 449.798337 -433.305223) (xy 449.66692 -433.252416) (xy 449.532726 -433.207127)
			(xy 449.396185 -433.169504) (xy 449.257733 -433.139665) (xy 449.117816 -433.117707) (xy 448.97688 -433.103701)
			(xy 448.835377 -433.09769) (xy 448.693761 -433.099694) (xy 448.552485 -433.109707) (xy 448.412002 -433.127696)
			(xy 448.272762 -433.153605) (xy 448.135211 -433.187349) (xy 447.999788 -433.228822) (xy 447.86693 -433.27789)
			(xy 447.73706 -433.334395) (xy 447.610594 -433.398158) (xy 447.487939 -433.468973) (xy 447.369486 -433.546614)
			(xy 447.255616 -433.630832) (xy 447.146693 -433.721357) (xy 447.043066 -433.8179) (xy 446.945066 -433.92015)
			(xy 446.853009 -434.027782) (xy 446.767188 -434.140449) (xy 446.687878 -434.257791) (xy 446.615335 -434.379432)
			(xy 446.549789 -434.504982) (xy 446.491451 -434.634039) (xy 446.440509 -434.766191) (xy 446.397124 -434.901012)
			(xy 446.361436 -435.038072) (xy 446.33356 -435.176932) (xy 446.313584 -435.317147) (xy 446.301573 -435.458267)
			(xy 446.297565 -435.59984) (xy 446.739528 -435.59984) (xy 446.743513 -435.471743) (xy 446.755455 -435.344142)
			(xy 446.775307 -435.21753) (xy 446.802991 -435.092397) (xy 446.838402 -434.969228) (xy 446.881401 -434.848498)
			(xy 446.931823 -434.730675) (xy 446.989472 -434.616214) (xy 447.054126 -434.505559) (xy 447.125534 -434.399138)
			(xy 447.203421 -434.297362) (xy 447.287484 -434.200625) (xy 447.377398 -434.109301) (xy 447.472816 -434.023744)
			(xy 447.573369 -433.944284) (xy 447.678667 -433.871229) (xy 447.788303 -433.804862) (xy 447.901853 -433.74544)
			(xy 448.018878 -433.693192) (xy 448.138924 -433.64832) (xy 448.261528 -433.610998) (xy 448.386215 -433.581371)
			(xy 448.512503 -433.559553) (xy 448.639903 -433.545628) (xy 448.767922 -433.539651) (xy 448.896066 -433.541644)
			(xy 449.023837 -433.5516) (xy 449.150742 -433.56948) (xy 449.276291 -433.595215) (xy 449.399996 -433.628706)
			(xy 449.52138 -433.669822) (xy 449.639973 -433.718406) (xy 449.755316 -433.774268) (xy 449.866963 -433.837193)
			(xy 449.974482 -433.906938) (xy 450.077458 -433.983232) (xy 450.17549 -434.06578) (xy 450.268201 -434.154263)
			(xy 450.355232 -434.248339) (xy 450.436246 -434.347644) (xy 450.510929 -434.451793) (xy 450.578993 -434.560384)
			(xy 450.640175 -434.672996) (xy 450.694236 -434.789194) (xy 450.74097 -434.908529) (xy 450.780194 -435.030537)
			(xy 450.811756 -435.154749) (xy 450.835536 -435.280682) (xy 450.85144 -435.40785) (xy 450.859408 -435.535761)
			(xy 450.859906 -435.59984) (xy 450.859408 -435.663919) (xy 450.85144 -435.79183) (xy 450.835536 -435.918998)
			(xy 450.811756 -436.044931) (xy 450.780194 -436.169143) (xy 450.74097 -436.291151) (xy 450.694236 -436.410486)
			(xy 450.640175 -436.526684) (xy 450.578993 -436.639296) (xy 450.510929 -436.747887) (xy 450.436246 -436.852036)
			(xy 450.355232 -436.951341) (xy 450.268201 -437.045417) (xy 450.17549 -437.1339) (xy 450.077458 -437.216448)
			(xy 449.974482 -437.292742) (xy 449.866963 -437.362487) (xy 449.755316 -437.425412) (xy 449.639973 -437.481274)
			(xy 449.52138 -437.529858) (xy 449.399996 -437.570974) (xy 449.276291 -437.604465) (xy 449.150742 -437.6302)
			(xy 449.023837 -437.64808) (xy 448.896066 -437.658036) (xy 448.767922 -437.660029) (xy 448.639903 -437.654052)
			(xy 448.512503 -437.640127) (xy 448.386215 -437.618309) (xy 448.261528 -437.588682) (xy 448.138924 -437.55136)
			(xy 448.018878 -437.506488) (xy 447.901853 -437.45424) (xy 447.788303 -437.394818) (xy 447.678667 -437.328451)
			(xy 447.573369 -437.255396) (xy 447.472816 -437.175936) (xy 447.377398 -437.090379) (xy 447.287484 -436.999055)
			(xy 447.203421 -436.902318) (xy 447.125534 -436.800542) (xy 447.054126 -436.694121) (xy 446.989472 -436.583466)
			(xy 446.931823 -436.469005) (xy 446.881401 -436.351182) (xy 446.838402 -436.230452) (xy 446.802991 -436.107283)
			(xy 446.775307 -435.98215) (xy 446.755455 -435.855538) (xy 446.743513 -435.727937) (xy 446.739528 -435.59984)
			(xy 446.297565 -435.59984) (xy 446.301573 -435.741413) (xy 446.313584 -435.882533) (xy 446.33356 -436.022748)
			(xy 446.361436 -436.161608) (xy 446.397124 -436.298668) (xy 446.440509 -436.433489) (xy 446.491451 -436.565641)
			(xy 446.549789 -436.694698) (xy 446.615335 -436.820248) (xy 446.687878 -436.941889) (xy 446.767188 -437.059231)
			(xy 446.853009 -437.171898) (xy 446.945066 -437.27953) (xy 447.043066 -437.38178) (xy 447.146693 -437.478323)
			(xy 447.255616 -437.568848) (xy 447.369486 -437.653066) (xy 447.487939 -437.730707) (xy 447.610594 -437.801522)
			(xy 447.73706 -437.865285) (xy 447.86693 -437.92179) (xy 447.999788 -437.970858) (xy 448.135211 -438.012331)
			(xy 448.272762 -438.046075) (xy 448.412002 -438.071984) (xy 448.552485 -438.089973) (xy 448.693761 -438.099986)
			(xy 448.835377 -438.10199) (xy 448.97688 -438.095979) (xy 449.117816 -438.081973) (xy 449.257733 -438.060015)
			(xy 449.396185 -438.030176) (xy 449.532726 -437.992553) (xy 449.66692 -437.947264) (xy 449.798337 -437.894457)
			(xy 449.926556 -437.834299) (xy 450.051167 -437.766983) (xy 450.171769 -437.692725) (xy 450.287977 -437.611763)
			(xy 450.399418 -437.524357) (xy 450.505736 -437.430785) (xy 450.60659 -437.331349) (xy 450.701656 -437.226365)
			(xy 450.790631 -437.116172) (xy 450.873229 -437.001121) (xy 450.949186 -436.881582) (xy 451.018259 -436.757937)
			(xy 451.080225 -436.630582) (xy 451.134887 -436.499925) (xy 451.18207 -436.366386) (xy 451.221622 -436.23039)
			(xy 451.253417 -436.092375) (xy 451.277352 -435.952782) (xy 451.293352 -435.812058) (xy 451.301365 -435.670655)
		)
		(stroke
			(width 0)
			(type solid)
		)
		(fill yes)
		(layer "F.Cu")
		(net "Net_2197")
	)
	(gr_poly
		(pts
			(arc
				(start 361.11815 -401.624038)
				(mid 361.137673 -401.620137)
				(end 361.154218 -401.609052)
			)
			(arc
				(start 361.182412 -401.580858)
				(mid 361.193523 -401.564324)
				(end 361.197398 -401.54479)
			)
			(xy 361.197398 -401.3073) (xy 361.197144 -401.30476) (xy 361.195366 -401.26793) (xy 361.197144 -401.2311)
			(xy 361.197398 -401.22856) (xy 361.197398 -400.6723) (xy 361.197144 -400.66976) (xy 361.195366 -400.63293)
			(xy 361.197144 -400.5961) (xy 361.197398 -400.59356) (xy 361.197398 -400.0373) (xy 361.197144 -400.03476)
			(xy 361.195366 -399.99793) (xy 361.197144 -399.9611) (xy 361.197398 -399.95856)
			(arc
				(start 361.197398 -399.775172)
				(mid 361.201299 -399.755649)
				(end 361.212384 -399.739104)
			)
			(arc
				(start 361.22229 -399.729198)
				(mid 361.233352 -399.712781)
				(end 361.237276 -399.693384)
			)
			(arc
				(start 361.237276 -399.646394)
				(mid 361.274548 -399.556412)
				(end 361.36453 -399.51914)
			)
			(arc
				(start 361.41152 -399.51914)
				(mid 361.430907 -399.51519)
				(end 361.447334 -399.504154)
			)
			(arc
				(start 361.45597 -399.495518)
				(mid 361.467081 -399.478984)
				(end 361.470956 -399.45945)
			)
			(arc
				(start 361.470956 -398.463516)
				(mid 361.474857 -398.443993)
				(end 361.485942 -398.427448)
			)
			(xy 361.520486 -398.392904) (xy 361.520486 -398.386808)
			(arc
				(start 361.622594 -398.2847)
				(mid 361.639128 -398.273589)
				(end 361.658662 -398.269714)
			)
			(xy 361.72902 -398.269714)
			(arc
				(start 361.73664 -398.267174)
				(mid 361.794474 -398.253473)
				(end 361.853734 -398.248886)
			)
			(arc
				(start 361.853734 -398.248886)
				(mid 361.913 -398.253438)
				(end 361.970828 -398.267174)
			)
			(xy 361.978448 -398.269714)
			(arc
				(start 363.03966 -398.269714)
				(mid 363.059183 -398.265813)
				(end 363.075728 -398.254728)
			)
			(arc
				(start 363.580426 -397.75003)
				(mid 363.591537 -397.733496)
				(end 363.595412 -397.713962)
			)
			(arc
				(start 363.595412 -396.994634)
				(mid 363.591511 -396.975111)
				(end 363.580426 -396.958566)
			)
			(arc
				(start 363.458252 -396.836392)
				(mid 363.441718 -396.825281)
				(end 363.422184 -396.821406)
			)
			(arc
				(start 361.830366 -396.821406)
				(mid 361.810843 -396.825307)
				(end 361.794298 -396.836392)
			)
			(arc
				(start 361.661202 -396.969488)
				(mid 361.644668 -396.980599)
				(end 361.625134 -396.984474)
			)
			(xy 361.100878 -396.984474)
			(arc
				(start 361.095798 -396.98549)
				(mid 361.063595 -396.99063)
				(end 361.031028 -396.992348)
			)
			(arc
				(start 360.536998 -396.992348)
				(mid 360.50443 -396.990646)
				(end 360.472228 -396.98549)
			)
			(xy 360.467148 -396.984474)
			(arc
				(start 359.780078 -396.984474)
				(mid 359.760691 -396.988424)
				(end 359.744264 -396.99946)
			)
			(arc
				(start 359.711244 -397.03248)
				(mid 359.611357 -397.099129)
				(end 359.493566 -397.122396)
			)
			(arc
				(start 358.6734 -397.122396)
				(mid 358.61332 -397.116522)
				(end 358.555544 -397.099028)
			)
			(arc
				(start 358.369108 -397.021812)
				(mid 358.341606 -397.008779)
				(end 358.315514 -396.99311)
			)
			(arc
				(start 358.315514 -396.99311)
				(mid 358.30194 -396.986634)
				(end 358.287066 -396.984474)
			)
			(arc
				(start 357.206042 -396.984474)
				(mid 357.182366 -396.990195)
				(end 357.164132 -397.006318)
			)
			(xy 357.109522 -397.085312) (xy 357.10622 -397.109696)
			(arc
				(start 357.110792 -397.121634)
				(mid 357.12526 -397.174618)
				(end 357.130096 -397.22933)
			)
			(arc
				(start 357.130096 -397.39697)
				(mid 357.133997 -397.416493)
				(end 357.145082 -397.433038)
			)
			(arc
				(start 357.535734 -397.823436)
				(mid 357.552151 -397.834498)
				(end 357.571548 -397.838422)
			)
			(arc
				(start 358.511094 -397.838422)
				(mid 358.530617 -397.834521)
				(end 358.547162 -397.823436)
			)
			(arc
				(start 358.741472 -397.629126)
				(mid 358.758006 -397.618015)
				(end 358.77754 -397.61414)
			)
			(xy 359.287572 -397.61414) (xy 359.300018 -397.610838)
			(arc
				(start 359.30586 -397.607536)
				(mid 359.378745 -397.577998)
				(end 359.456736 -397.567912)
			)
			(xy 360.292396 -397.567912)
			(arc
				(start 360.300524 -397.565118)
				(mid 360.32142 -397.559638)
				(end 360.342942 -397.557752)
			)
			(arc
				(start 360.647742 -397.557752)
				(mid 360.737814 -397.595114)
				(end 360.774996 -397.68526)
			)
			(arc
				(start 360.774996 -397.70558)
				(mid 360.778946 -397.724967)
				(end 360.789982 -397.741394)
			)
			(arc
				(start 360.802936 -397.754348)
				(mid 360.814047 -397.770882)
				(end 360.817922 -397.790416)
			)
			(arc
				(start 360.817922 -397.826484)
				(mid 360.821872 -397.845871)
				(end 360.832908 -397.862298)
			)
			(arc
				(start 360.948224 -397.977614)
				(mid 361.014873 -398.077501)
				(end 361.03814 -398.195292)
			)
			(arc
				(start 361.03814 -398.760696)
				(mid 361.014809 -398.878461)
				(end 360.948224 -398.978374)
			)
			(arc
				(start 360.751882 -399.174462)
				(mid 360.740771 -399.190996)
				(end 360.736896 -399.21053)
			)
			(arc
				(start 360.736896 -399.2245)
				(mid 360.69964 -399.314572)
				(end 360.609642 -399.352008)
			)
			(arc
				(start 360.558842 -399.352008)
				(mid 360.539485 -399.355841)
				(end 360.523028 -399.36674)
			)
			(arc
				(start 360.289602 -399.600166)
				(mid 360.278491 -399.6167)
				(end 360.274616 -399.636234)
			)
			(arc
				(start 360.274616 -401.57273)
				(mid 360.278517 -401.592253)
				(end 360.289602 -401.608798)
			)
			(arc
				(start 360.289856 -401.609052)
				(mid 360.30639 -401.620163)
				(end 360.325924 -401.624038)
			)
		)
		(stroke
			(width 0)
			(type solid)
		)
		(fill yes)
		(layer "F.Cu")
		(net "GND")
	)
	(gr_poly
		(pts
			(arc
				(start 247.613424 -53.805836)
				(mid 247.632947 -53.801935)
				(end 247.649492 -53.79085)
			)
			(arc
				(start 247.650254 -53.790088)
				(mid 247.661365 -53.773554)
				(end 247.66524 -53.75402)
			)
			(arc
				(start 247.66524 -53.32095)
				(mid 247.669141 -53.301427)
				(end 247.680226 -53.284882)
			)
			(arc
				(start 247.881902 -53.083206)
				(mid 247.898436 -53.072095)
				(end 247.91797 -53.06822)
			)
			(arc
				(start 249.198638 -53.06822)
				(mid 249.218161 -53.064319)
				(end 249.234706 -53.053234)
			)
			(arc
				(start 249.245374 -53.042566)
				(mid 249.261908 -53.031455)
				(end 249.281442 -53.02758)
			)
			(arc
				(start 251.515118 -53.02758)
				(mid 251.534641 -53.023679)
				(end 251.551186 -53.012594)
			)
			(xy 251.556774 -53.007006)
			(arc
				(start 252.767592 -53.007006)
				(mid 252.787115 -53.003105)
				(end 252.80366 -52.99202)
			)
			(arc
				(start 252.834648 -52.961032)
				(mid 252.845759 -52.944498)
				(end 252.849634 -52.924964)
			)
			(arc
				(start 252.849634 -49.347628)
				(mid 252.845733 -49.328105)
				(end 252.834648 -49.31156)
			)
			(xy 252.78588 -49.262792) (xy 252.778768 -49.255426) (xy 252.759972 -49.247806)
			(arc
				(start 250.612656 -49.247806)
				(mid 250.593133 -49.243905)
				(end 250.576588 -49.23282)
			)
			(arc
				(start 250.25223 -48.908462)
				(mid 250.235696 -48.897351)
				(end 250.216162 -48.893476)
			)
			(arc
				(start 249.960638 -48.893476)
				(mid 249.941115 -48.889575)
				(end 249.92457 -48.87849)
			)
			(arc
				(start 249.603006 -48.556926)
				(mid 249.591895 -48.540392)
				(end 249.58802 -48.520858)
			)
			(arc
				(start 249.58802 -47.915322)
				(mid 249.584119 -47.895799)
				(end 249.573034 -47.879254)
			)
			(arc
				(start 249.39244 -47.69866)
				(mid 249.375906 -47.687549)
				(end 249.356372 -47.683674)
			)
			(arc
				(start 249.04827 -47.683674)
				(mid 249.028747 -47.679773)
				(end 249.012202 -47.668688)
			)
			(arc
				(start 248.65584 -47.312072)
				(mid 248.644729 -47.295538)
				(end 248.640854 -47.276004)
			)
			(arc
				(start 248.640854 -44.276264)
				(mid 248.644755 -44.256741)
				(end 248.65584 -44.240196)
			)
			(arc
				(start 249.131836 -43.7642)
				(mid 249.14837 -43.753089)
				(end 249.167904 -43.749214)
			)
			(xy 249.184414 -43.749214) (xy 249.2121 -43.726862)
			(arc
				(start 249.21591 -43.709336)
				(mid 249.246528 -43.627311)
				(end 249.298968 -43.55719)
			)
			(arc
				(start 250.518422 -42.337736)
				(mid 250.590818 -42.284077)
				(end 250.675648 -42.253662)
			)
			(xy 250.683268 -42.252138) (xy 250.695968 -42.24528) (xy 250.696222 -42.245026) (xy 250.714764 -42.237406)
			(arc
				(start 250.916694 -42.237406)
				(mid 250.930533 -42.235557)
				(end 250.943364 -42.23004)
			)
			(arc
				(start 250.943364 -42.23004)
				(mid 251.039161 -42.18807)
				(end 251.142754 -42.173652)
			)
			(arc
				(start 251.142754 -42.173652)
				(mid 251.246352 -42.188049)
				(end 251.342144 -42.23004)
			)
			(arc
				(start 251.342144 -42.23004)
				(mid 251.354966 -42.235591)
				(end 251.368814 -42.237406)
			)
			(arc
				(start 252.382528 -42.237406)
				(mid 252.402051 -42.233505)
				(end 252.418596 -42.22242)
			)
			(arc
				(start 252.437138 -42.203878)
				(mid 252.453672 -42.192767)
				(end 252.473206 -42.188892)
			)
			(arc
				(start 253.644146 -42.188892)
				(mid 253.663669 -42.184991)
				(end 253.680214 -42.173906)
			)
			(arc
				(start 253.708408 -42.145712)
				(mid 253.719519 -42.129178)
				(end 253.723394 -42.109644)
			)
			(arc
				(start 253.723394 -42.029888)
				(mid 253.719493 -42.010365)
				(end 253.708408 -41.99382)
			)
			(xy 253.65456 -41.939972) (xy 253.647448 -41.932606) (xy 253.628652 -41.924986)
			(arc
				(start 251.877576 -41.924986)
				(mid 251.858053 -41.921085)
				(end 251.841508 -41.91)
			)
			(arc
				(start 251.72924 -41.797732)
				(mid 251.718129 -41.781198)
				(end 251.714254 -41.761664)
			)
			(xy 251.714254 -41.409366) (xy 251.71908 -41.40454) (xy 251.71908 -41.397936) (xy 251.870464 -41.246552)
			(xy 251.87529 -41.24071) (xy 251.881894 -41.232074)
			(arc
				(start 251.92863 -41.185338)
				(mid 251.945164 -41.174227)
				(end 251.964698 -41.170352)
			)
			(arc
				(start 253.106936 -41.170352)
				(mid 253.126459 -41.166451)
				(end 253.143004 -41.155366)
			)
			(arc
				(start 253.179326 -41.119044)
				(mid 253.190437 -41.10251)
				(end 253.194312 -41.082976)
			)
			(arc
				(start 253.194312 -41.02989)
				(mid 253.190411 -41.010367)
				(end 253.179326 -40.993822)
			)
			(arc
				(start 253.141226 -40.955722)
				(mid 253.124692 -40.944611)
				(end 253.105158 -40.940736)
			)
			(arc
				(start 251.694696 -40.940736)
				(mid 251.675173 -40.936835)
				(end 251.658628 -40.92575)
			)
			(xy 251.494798 -40.761666) (xy 251.487686 -40.7543) (xy 251.46889 -40.74668)
			(arc
				(start 250.55703 -40.74668)
				(mid 250.342337 -40.703917)
				(end 250.160282 -40.582342)
			)
			(arc
				(start 250.09221 -40.51427)
				(mid 250.075676 -40.503159)
				(end 250.056142 -40.499284)
			)
			(arc
				(start 247.860566 -40.499284)
				(mid 247.841043 -40.503185)
				(end 247.824498 -40.51427)
			)
			(xy 247.316752 -41.02227)
			(arc
				(start 246.256302 -42.082466)
				(mid 246.245191 -42.099)
				(end 246.241316 -42.118534)
			)
			(arc
				(start 246.241316 -44.824142)
				(mid 246.237415 -44.843665)
				(end 246.22633 -44.86021)
			)
			(arc
				(start 245.605046 -45.481494)
				(mid 245.593935 -45.498028)
				(end 245.59006 -45.517562)
			)
			(arc
				(start 245.59006 -45.833792)
				(mid 245.586159 -45.853315)
				(end 245.575074 -45.86986)
			)
			(arc
				(start 245.4021 -46.042834)
				(mid 245.390989 -46.059368)
				(end 245.387114 -46.078902)
			)
			(arc
				(start 245.387114 -49.459388)
				(mid 245.391015 -49.478911)
				(end 245.4021 -49.495456)
			)
			(arc
				(start 245.575074 -49.66843)
				(mid 245.586185 -49.684964)
				(end 245.59006 -49.704498)
			)
			(arc
				(start 245.59006 -53.595778)
				(mid 245.593961 -53.615301)
				(end 245.605046 -53.631846)
			)
			(arc
				(start 245.76405 -53.79085)
				(mid 245.780584 -53.801961)
				(end 245.800118 -53.805836)
			)
		)
		(stroke
			(width 0)
			(type solid)
		)
		(fill yes)
		(layer "F.Cu")
		(net "P12V_E1S_0")
	)
	(gr_poly
		(pts
			(xy 395.334744 -176.942242) (xy 395.664944 -176.942242) (xy 395.674949 -176.941747) (xy 395.693433 -176.934081)
			(xy 395.707582 -176.919931) (xy 395.715247 -176.901447) (xy 395.715744 -176.891442) (xy 397.392144 -176.891442)
			(xy 397.402149 -176.890947) (xy 397.420633 -176.883281) (xy 397.434782 -176.869131) (xy 397.442447 -176.850647)
			(xy 397.442944 -176.840642) (xy 397.442944 -174.916084) (xy 397.43761 -174.91075) (xy 396.020036 -174.91075)
			(xy 395.883638 -174.774352) (xy 395.883638 -173.928532) (xy 395.54658 -173.59122) (xy 395.539738 -173.583821)
			(xy 395.53202 -173.565222) (xy 395.531594 -173.555152) (xy 395.531594 -171.3865) (xy 395.851634 -171.06646)
			(xy 395.85392 -171.06646) (xy 396.3416 -170.57878) (xy 400.14906 -170.57878) (xy 400.369278 -170.358562)
			(xy 400.369278 -168.82872) (xy 400.369784 -168.81867) (xy 400.377506 -168.800109) (xy 400.384264 -168.792652)
			(xy 400.79549 -168.381426) (xy 400.802887 -168.374575) (xy 400.821485 -168.366833) (xy 400.831558 -168.36644)
			(xy 403.658324 -168.36644) (xy 403.658324 -168.364916) (xy 403.988524 -168.364916) (xy 403.99853 -168.364424)
			(xy 404.017016 -168.356761) (xy 404.031165 -168.342609) (xy 404.038826 -168.324122) (xy 404.039324 -168.314116)
			(xy 405.715724 -168.314116) (xy 405.72573 -168.313624) (xy 405.744216 -168.305961) (xy 405.758365 -168.291809)
			(xy 405.766026 -168.273322) (xy 405.766524 -168.263316) (xy 405.766524 -166.384224) (xy 405.766041 -166.374211)
			(xy 405.758386 -166.355707) (xy 405.744233 -166.341541) (xy 405.725736 -166.333869) (xy 405.715724 -166.333424)
			(xy 404.35403 -166.333424) (xy 404.207218 -166.186612) (xy 404.207218 -165.025832) (xy 403.813264 -164.631624)
			(xy 403.806423 -164.624224) (xy 403.798706 -164.605625) (xy 403.798278 -164.595556) (xy 403.798278 -163.14674)
			(xy 403.798711 -163.136674) (xy 403.806439 -163.118083) (xy 403.813264 -163.110672) (xy 404.705312 -162.218624)
			(xy 404.71271 -162.211777) (xy 404.731308 -162.204043) (xy 404.74138 -162.203638) (xy 409.095702 -162.203638)
			(xy 409.105771 -162.204062) (xy 409.124372 -162.211781) (xy 409.13177 -162.218624) (xy 409.495498 -162.582352)
			(xy 409.502337 -162.589753) (xy 409.510052 -162.608351) (xy 409.510484 -162.61842) (xy 409.510484 -163.475924)
			(xy 409.518104 -163.49472) (xy 409.52547 -163.501832) (xy 409.574492 -163.550854) (xy 409.581888 -163.557707)
			(xy 409.600486 -163.565451) (xy 409.61056 -163.56584) (xy 414.101788 -163.56584) (xy 414.120584 -163.55822)
			(xy 414.127696 -163.550854) (xy 414.133538 -163.545012) (xy 414.140904 -163.5379) (xy 414.148524 -163.519104)
			(xy 414.148524 -161.482532) (xy 414.14811 -161.472505) (xy 414.140447 -161.453973) (xy 414.126274 -161.439785)
			(xy 414.107751 -161.432101) (xy 414.097724 -161.431732) (xy 412.703518 -161.431732) (xy 412.583122 -161.311336)
			(xy 412.583122 -160.360868) (xy 412.06928 -159.847026) (xy 412.062437 -159.839627) (xy 412.054717 -159.821028)
			(xy 412.054294 -159.810958) (xy 412.054294 -158.645098) (xy 411.518608 -158.109412) (xy 401.965414 -158.109412)
			(xy 400.952208 -157.096206) (xy 400.952208 -153.137108) (xy 400.300444 -152.485344) (xy 385.590288 -152.485344)
			(xy 385.054856 -153.020776) (xy 385.054856 -154.162252) (xy 393.797026 -154.162252) (xy 393.801099 -154.106593)
			(xy 393.813234 -154.05212) (xy 393.83317 -153.999994) (xy 393.860484 -153.951326) (xy 393.894592 -153.907154)
			(xy 393.934769 -153.868419) (xy 393.980157 -153.835947) (xy 394.029789 -153.810429) (xy 394.082609 -153.79241)
			(xy 394.137488 -153.782273) (xy 394.193259 -153.780235) (xy 394.248733 -153.786338) (xy 394.302726 -153.800454)
			(xy 394.354089 -153.822281) (xy 394.401727 -153.851354) (xy 394.444623 -153.887053) (xy 394.481865 -153.928617)
			(xy 394.512659 -153.975161) (xy 394.536347 -154.025692) (xy 394.552425 -154.079134) (xy 394.560551 -154.134348)
			(xy 394.56106 -154.162252) (xy 394.560551 -154.190156) (xy 394.552425 -154.24537) (xy 394.536347 -154.298812)
			(xy 394.512659 -154.349343) (xy 394.481865 -154.395887) (xy 394.444623 -154.437451) (xy 394.401727 -154.47315)
			(xy 394.354089 -154.502223) (xy 394.302726 -154.52405) (xy 394.248733 -154.538166) (xy 394.193259 -154.544269)
			(xy 394.137488 -154.542231) (xy 394.082609 -154.532094) (xy 394.029789 -154.514075) (xy 393.980157 -154.488557)
			(xy 393.934769 -154.456085) (xy 393.894592 -154.41735) (xy 393.860484 -154.373178) (xy 393.83317 -154.32451)
			(xy 393.813234 -154.272384) (xy 393.801099 -154.217911) (xy 393.797026 -154.162252) (xy 385.054856 -154.162252)
			(xy 385.054856 -165.195193) (xy 386.31774 -165.195193) (xy 386.31774 -165.110471) (xy 386.325793 -165.026134)
			(xy 386.341827 -164.942944) (xy 386.365695 -164.861654) (xy 386.397183 -164.783002) (xy 386.436005 -164.707699)
			(xy 386.481808 -164.636427) (xy 386.534179 -164.569831) (xy 386.592644 -164.508516) (xy 386.656672 -164.453035)
			(xy 386.725684 -164.403892) (xy 386.799054 -164.361532) (xy 386.876119 -164.326337) (xy 386.956181 -164.298628)
			(xy 387.038514 -164.278654) (xy 387.122373 -164.266597) (xy 387.206998 -164.262566) (xy 387.291623 -164.266597)
			(xy 387.375482 -164.278654) (xy 387.457815 -164.298628) (xy 387.537877 -164.326337) (xy 387.614942 -164.361532)
			(xy 387.688312 -164.403892) (xy 387.757324 -164.453035) (xy 387.821352 -164.508516) (xy 387.879817 -164.569831)
			(xy 387.932188 -164.636427) (xy 387.977991 -164.707699) (xy 388.016813 -164.783002) (xy 388.048301 -164.861654)
			(xy 388.072169 -164.942944) (xy 388.088203 -165.026134) (xy 388.096256 -165.110471) (xy 388.09676 -165.152832)
			(xy 388.096256 -165.195193) (xy 388.088203 -165.27953) (xy 388.072169 -165.36272) (xy 388.048301 -165.44401)
			(xy 388.016813 -165.522662) (xy 387.977991 -165.597965) (xy 387.932188 -165.669237) (xy 387.879817 -165.735833)
			(xy 387.821352 -165.797148) (xy 387.757324 -165.852629) (xy 387.688312 -165.901772) (xy 387.614942 -165.944132)
			(xy 387.537877 -165.979327) (xy 387.457815 -166.007036) (xy 387.375482 -166.02701) (xy 387.291623 -166.039067)
			(xy 387.206998 -166.043099) (xy 387.122373 -166.039067) (xy 387.038514 -166.02701) (xy 386.956181 -166.007036)
			(xy 386.876119 -165.979327) (xy 386.799054 -165.944132) (xy 386.725684 -165.901772) (xy 386.656672 -165.852629)
			(xy 386.592644 -165.797148) (xy 386.534179 -165.735833) (xy 386.481808 -165.669237) (xy 386.436005 -165.597965)
			(xy 386.397183 -165.522662) (xy 386.365695 -165.44401) (xy 386.341827 -165.36272) (xy 386.325793 -165.27953)
			(xy 386.31774 -165.195193) (xy 385.054856 -165.195193) (xy 385.054856 -167.241728) (xy 387.35508 -169.541952)
			(xy 390.823958 -169.541952) (xy 392.855958 -171.573952) (xy 392.855958 -176.870106) (xy 392.932158 -176.946306)
			(xy 395.334744 -176.946306)
		)
		(stroke
			(width 0)
			(type solid)
		)
		(fill yes)
		(layer "F.Cu")
		(net "SW_P12V_AUX_PVDDCR_SOC_P0_FLT")
	)
	(gr_poly
		(pts
			(xy 444.46952 -27.161998) (xy 444.46952 -25.80386) (xy 444.483236 -24.978868) (xy 445.598042 -23.864062)
			(xy 445.598042 -17.435576) (xy 445.850264 -17.183354) (xy 445.850697 -17.173289) (xy 445.858431 -17.154703)
			(xy 445.86525 -17.147286) (xy 446.037208 -16.975328) (xy 446.044606 -16.96848) (xy 446.063204 -16.960744)
			(xy 446.073276 -16.960342) (xy 446.447672 -16.960342) (xy 446.452244 -16.959326) (xy 446.474952 -16.955309)
			(xy 446.520878 -16.951111) (xy 446.543938 -16.950944) (xy 447.157602 -16.950944) (xy 447.180662 -16.951115)
			(xy 447.226588 -16.955314) (xy 447.249296 -16.959326) (xy 447.253868 -16.960342) (xy 450.688964 -16.960342)
			(xy 450.688964 -16.966692) (xy 451.362318 -17.640046) (xy 451.369166 -17.647443) (xy 451.376897 -17.666042)
			(xy 451.377304 -17.676114) (xy 451.377304 -21.77415) (xy 451.377736 -21.784216) (xy 451.385464 -21.802807)
			(xy 451.39229 -21.810218) (xy 451.418198 -21.836126) (xy 451.425593 -21.842981) (xy 451.444192 -21.850728)
			(xy 451.454266 -21.851112) (xy 451.528942 -21.851112) (xy 451.539009 -21.850682) (xy 451.557604 -21.842958)
			(xy 451.56501 -21.836126) (xy 451.583298 -21.817838) (xy 451.590135 -21.810436) (xy 451.597847 -21.791838)
			(xy 451.598284 -21.78177) (xy 451.598284 -20.033234) (xy 451.598719 -20.023169) (xy 451.606448 -20.00458)
			(xy 451.61327 -19.997166) (xy 451.697598 -19.912838) (xy 451.704995 -19.905987) (xy 451.723593 -19.898246)
			(xy 451.733666 -19.897852) (xy 452.217282 -19.897852) (xy 452.227344 -19.898292) (xy 452.245922 -19.906033)
			(xy 452.25335 -19.912838) (xy 452.336662 -19.99615) (xy 452.340833 -20.000131) (xy 452.350579 -20.006287)
			(xy 452.355966 -20.008342) (xy 452.369936 -20.022312) (xy 452.376787 -20.029708) (xy 452.384527 -20.048307)
			(xy 452.384922 -20.05838) (xy 452.384922 -21.252434) (xy 452.385352 -21.262501) (xy 452.393077 -21.281094)
			(xy 452.399908 -21.288502) (xy 452.436992 -21.325586) (xy 452.444389 -21.332435) (xy 452.462987 -21.340175)
			(xy 452.47306 -21.340572) (xy 452.5137 -21.340572) (xy 452.52377 -21.340148) (xy 452.542371 -21.332431)
			(xy 452.549768 -21.325586) (xy 452.599298 -21.276056) (xy 452.606138 -21.268655) (xy 452.613856 -21.250057)
			(xy 452.614284 -21.239988) (xy 452.614284 -21.20646) (xy 452.619364 -21.20138) (xy 452.619364 -18.623534)
			(xy 452.619801 -18.613471) (xy 452.627539 -18.59489) (xy 452.63435 -18.587466) (xy 454.246488 -16.975328)
			(xy 454.253885 -16.968477) (xy 454.272483 -16.960734) (xy 454.282556 -16.960342) (xy 455.233024 -16.960342)
			(xy 455.243091 -16.959913) (xy 455.261684 -16.952186) (xy 455.269092 -16.945356) (xy 455.41819 -16.796258)
			(xy 455.425031 -16.788858) (xy 455.432752 -16.770259) (xy 455.433176 -16.76019) (xy 455.433176 -14.170406)
			(xy 455.432753 -14.160336) (xy 455.425038 -14.141732) (xy 455.41819 -14.134338) (xy 455.24039 -13.956538)
			(xy 455.233278 -13.949172) (xy 455.214482 -13.941552) (xy 453.58304 -13.941552) (xy 453.16902 -14.355572)
			(xy 448.547236 -14.355572) (xy 448.249294 -14.05763) (xy 448.24904 -14.057376) (xy 448.147948 -13.956538)
			(xy 448.140548 -13.949696) (xy 448.12195 -13.941974) (xy 448.11188 -13.941552) (xy 442.296042 -13.941552)
			(xy 442.1759 -14.061694) (xy 442.1759 -14.687715) (xy 446.518286 -14.687715) (xy 446.518286 -14.627949)
			(xy 446.526424 -14.568739) (xy 446.542549 -14.511189) (xy 446.56636 -14.45637) (xy 446.597414 -14.405304)
			(xy 446.635132 -14.358943) (xy 446.678811 -14.318149) (xy 446.727639 -14.283683) (xy 446.780705 -14.256186)
			(xy 446.83702 -14.236171) (xy 446.895537 -14.224012) (xy 446.955164 -14.219933) (xy 447.014791 -14.224012)
			(xy 447.073308 -14.236171) (xy 447.129623 -14.256186) (xy 447.182689 -14.283683) (xy 447.231517 -14.318149)
			(xy 447.275196 -14.358943) (xy 447.312914 -14.405304) (xy 447.343968 -14.45637) (xy 447.367779 -14.511189)
			(xy 447.383904 -14.568739) (xy 447.392042 -14.627949) (xy 447.392195 -14.636915) (xy 447.712086 -14.636915)
			(xy 447.712086 -14.577149) (xy 447.720224 -14.517939) (xy 447.736349 -14.460389) (xy 447.76016 -14.40557)
			(xy 447.791214 -14.354504) (xy 447.828932 -14.308143) (xy 447.872611 -14.267349) (xy 447.921439 -14.232883)
			(xy 447.974505 -14.205386) (xy 448.03082 -14.185371) (xy 448.089337 -14.173212) (xy 448.148964 -14.169133)
			(xy 448.208591 -14.173212) (xy 448.267108 -14.185371) (xy 448.323423 -14.205386) (xy 448.376489 -14.232883)
			(xy 448.425317 -14.267349) (xy 448.468996 -14.308143) (xy 448.506714 -14.354504) (xy 448.537768 -14.40557)
			(xy 448.561579 -14.460389) (xy 448.577704 -14.517939) (xy 448.585842 -14.577149) (xy 448.586352 -14.607032)
			(xy 448.585842 -14.636915) (xy 448.577704 -14.696125) (xy 448.561579 -14.753675) (xy 448.537768 -14.808494)
			(xy 448.506714 -14.85956) (xy 448.468996 -14.905921) (xy 448.425317 -14.946715) (xy 448.376489 -14.981181)
			(xy 448.323423 -15.008678) (xy 448.267108 -15.028693) (xy 448.208591 -15.040852) (xy 448.148964 -15.044931)
			(xy 448.089337 -15.040852) (xy 448.03082 -15.028693) (xy 447.974505 -15.008678) (xy 447.921439 -14.981181)
			(xy 447.872611 -14.946715) (xy 447.828932 -14.905921) (xy 447.791214 -14.85956) (xy 447.76016 -14.808494)
			(xy 447.736349 -14.753675) (xy 447.720224 -14.696125) (xy 447.712086 -14.636915) (xy 447.392195 -14.636915)
			(xy 447.392552 -14.657832) (xy 447.392042 -14.687715) (xy 447.383904 -14.746925) (xy 447.367779 -14.804475)
			(xy 447.343968 -14.859294) (xy 447.312914 -14.91036) (xy 447.275196 -14.956721) (xy 447.231517 -14.997515)
			(xy 447.182689 -15.031981) (xy 447.129623 -15.059478) (xy 447.073308 -15.079493) (xy 447.014791 -15.091652)
			(xy 446.955164 -15.095731) (xy 446.895537 -15.091652) (xy 446.83702 -15.079493) (xy 446.780705 -15.059478)
			(xy 446.727639 -15.031981) (xy 446.678811 -14.997515) (xy 446.635132 -14.956721) (xy 446.597414 -14.91036)
			(xy 446.56636 -14.859294) (xy 446.542549 -14.804475) (xy 446.526424 -14.746925) (xy 446.518286 -14.687715)
			(xy 442.1759 -14.687715) (xy 442.1759 -20.7645) (xy 442.164724 -20.775676) (xy 442.164724 -21.099272)
			(xy 442.268102 -21.20265) (xy 443.25921 -21.20265) (xy 443.394084 -21.337524) (xy 443.394084 -23.828502)
			(xy 442.980572 -24.242014) (xy 441.704984 -24.242014) (xy 441.521342 -24.058372) (xy 441.521342 -22.679914)
			(xy 441.406534 -22.565106) (xy 440.774074 -22.565106) (xy 440.713876 -22.625304) (xy 440.713876 -27.148282)
			(xy 440.71436 -27.158294) (xy 440.722016 -27.176796) (xy 440.736169 -27.19096) (xy 440.754665 -27.198631)
			(xy 440.764676 -27.199082) (xy 444.432436 -27.199082)
		)
		(stroke
			(width 0)
			(type solid)
		)
		(fill yes)
		(layer "F.Cu")
		(net "P12V_OCP_SFF")
	)
	(gr_poly
		(pts
			(arc
				(start 93.352112 -72.388476)
				(mid 93.368176 -72.385869)
				(end 93.382592 -72.378316)
			)
			(xy 93.38818 -72.37349) (xy 93.541088 -72.220582)
			(arc
				(start 93.545914 -72.214994)
				(mid 93.553467 -72.200578)
				(end 93.556074 -72.184514)
			)
			(arc
				(start 93.556074 -69.694298)
				(mid 93.559975 -69.674775)
				(end 93.57106 -69.65823)
			)
			(arc
				(start 93.876368 -69.352922)
				(mid 93.892902 -69.341811)
				(end 93.912436 -69.337936)
			)
			(arc
				(start 94.459552 -69.337936)
				(mid 94.475616 -69.335329)
				(end 94.490032 -69.327776)
			)
			(xy 94.49562 -69.32295) (xy 94.595188 -69.223382)
			(arc
				(start 94.600014 -69.217794)
				(mid 94.607567 -69.203378)
				(end 94.610174 -69.187314)
			)
			(arc
				(start 94.610174 -68.190618)
				(mid 94.614075 -68.171095)
				(end 94.62516 -68.15455)
			)
			(arc
				(start 96.175068 -66.604642)
				(mid 96.191602 -66.593531)
				(end 96.211136 -66.589656)
			)
			(arc
				(start 98.929952 -66.589656)
				(mid 98.946016 -66.587049)
				(end 98.960432 -66.579496)
			)
			(xy 98.96602 -66.57467) (xy 99.438968 -66.101722)
			(arc
				(start 99.443794 -66.096134)
				(mid 99.451347 -66.081718)
				(end 99.453954 -66.065654)
			)
			(arc
				(start 99.453954 -62.930278)
				(mid 99.451347 -62.914214)
				(end 99.443794 -62.899798)
			)
			(xy 99.438968 -62.89421) (xy 99.00666 -62.461902)
			(arc
				(start 99.001072 -62.457076)
				(mid 98.986656 -62.449523)
				(end 98.970592 -62.446916)
			)
			(arc
				(start 96.662494 -62.446916)
				(mid 96.642971 -62.443015)
				(end 96.626426 -62.43193)
			)
			(arc
				(start 96.615758 -62.421262)
				(mid 96.607347 -62.410134)
				(end 96.602296 -62.397132)
			)
			(arc
				(start 96.602296 -62.397132)
				(mid 96.597179 -62.384289)
				(end 96.588834 -62.373256)
			)
			(xy 96.587564 -62.371986) (xy 96.569022 -62.364366)
			(arc
				(start 93.142054 -62.364366)
				(mid 93.122531 -62.360465)
				(end 93.105986 -62.34938)
			)
			(arc
				(start 93.036136 -62.27953)
				(mid 93.008355 -62.265195)
				(end 92.977462 -62.269878)
			)
			(arc
				(start 92.977462 -62.269878)
				(mid 92.867273 -62.309708)
				(end 92.750894 -62.323218)
			)
			(arc
				(start 92.750894 -62.323218)
				(mid 92.391325 -62.174279)
				(end 92.242386 -61.81471)
			)
			(arc
				(start 92.242386 -61.81471)
				(mid 92.242895 -61.791954)
				(end 92.244418 -61.769244)
			)
			(xy 92.245434 -61.757814)
			(arc
				(start 92.241624 -61.7474)
				(mid 92.236784 -61.737613)
				(end 92.22994 -61.729112)
			)
			(arc
				(start 91.733624 -61.232796)
				(mid 91.667072 -61.133144)
				(end 91.643708 -61.015626)
			)
			(arc
				(start 91.643708 -60.908184)
				(mid 91.641101 -60.89212)
				(end 91.633548 -60.877704)
			)
			(xy 91.628722 -60.872116)
			(arc
				(start 91.594178 -60.837572)
				(mid 91.583067 -60.821038)
				(end 91.579192 -60.801504)
			)
			(arc
				(start 91.579192 -57.544208)
				(mid 91.576585 -57.528144)
				(end 91.569032 -57.513728)
			)
			(xy 91.564206 -57.50814) (xy 91.533218 -57.477152)
			(arc
				(start 91.52763 -57.472326)
				(mid 91.513214 -57.464773)
				(end 91.49715 -57.462166)
			)
			(arc
				(start 91.419934 -57.462166)
				(mid 91.40387 -57.464773)
				(end 91.389454 -57.472326)
			)
			(xy 91.383866 -57.477152) (xy 91.350338 -57.51068)
			(arc
				(start 91.345512 -57.516268)
				(mid 91.337959 -57.530684)
				(end 91.335352 -57.546748)
			)
			(arc
				(start 91.335352 -59.358784)
				(mid 91.331451 -59.378307)
				(end 91.320366 -59.394852)
			)
			(arc
				(start 91.167458 -59.54776)
				(mid 91.150924 -59.558871)
				(end 91.13139 -59.562746)
			)
			(arc
				(start 90.774774 -59.562746)
				(mid 90.755251 -59.558845)
				(end 90.738706 -59.54776)
			)
			(arc
				(start 90.590624 -59.399678)
				(mid 90.584339 -59.391967)
				(end 90.579702 -59.383168)
			)
			(xy 90.575892 -59.374024) (xy 90.568272 -59.365388) (xy 90.568272 -58.044334) (xy 90.505026 -57.981088)
			(xy 90.391488 -57.981088) (xy 90.333576 -58.039) (xy 90.333576 -59.597544)
			(arc
				(start 90.041984 -59.889136)
				(mid 89.857009 -60.302331)
				(end 89.443814 -60.487306)
			)
			(xy 89.07526 -60.85586) (xy 87.346536 -60.85586) (xy 86.233254 -59.742578) (xy 86.228428 -59.73699)
			(xy 85.12175 -58.630312)
			(arc
				(start 85.116162 -58.625486)
				(mid 85.101746 -58.617933)
				(end 85.085682 -58.615326)
			)
			(arc
				(start 80.563212 -58.615326)
				(mid 80.547148 -58.617933)
				(end 80.532732 -58.625486)
			)
			(xy 80.527144 -58.630312) (xy 80.354678 -58.802778)
			(arc
				(start 80.349852 -58.808366)
				(mid 80.342299 -58.822782)
				(end 80.339692 -58.838846)
			)
			(arc
				(start 80.339692 -59.668156)
				(mid 80.342299 -59.68422)
				(end 80.349852 -59.698636)
			)
			(xy 80.354678 -59.704224) (xy 80.659224 -60.00877)
			(arc
				(start 80.664812 -60.013596)
				(mid 80.679228 -60.021149)
				(end 80.695292 -60.023756)
			)
			(arc
				(start 81.689956 -60.023756)
				(mid 81.709479 -60.027657)
				(end 81.726024 -60.038742)
			)
			(arc
				(start 81.785968 -60.098686)
				(mid 81.797079 -60.11522)
				(end 81.800954 -60.134754)
			)
			(xy 81.800954 -67.348354) (xy 82.33664 -67.88404) (xy 91.675204 -67.88404) (xy 91.685872 -67.894708)
			(arc
				(start 92.555568 -68.76415)
				(mid 92.566679 -68.780684)
				(end 92.570554 -68.800218)
			)
			(arc
				(start 92.570554 -71.891906)
				(mid 92.572472 -71.905481)
				(end 92.57792 -71.918068)
			)
			(arc
				(start 92.57792 -71.918068)
				(mid 92.591608 -71.949832)
				(end 92.596208 -71.984108)
			)
			(arc
				(start 92.596208 -72.100948)
				(mid 92.598815 -72.117012)
				(end 92.606368 -72.131428)
			)
			(xy 92.611194 -72.137016) (xy 92.847668 -72.37349)
			(arc
				(start 92.853256 -72.378316)
				(mid 92.867672 -72.385869)
				(end 92.883736 -72.388476)
			)
		)
		(stroke
			(width 0)
			(type solid)
		)
		(fill yes)
		(layer "F.Cu")
		(net "P3V3_OCP_V3_2_R")
	)
	(gr_poly
		(pts
			(arc
				(start 71.257668 -386.304282)
				(mid 71.277191 -386.300381)
				(end 71.293736 -386.289296)
			)
			(arc
				(start 71.40321 -386.179822)
				(mid 71.414321 -386.163288)
				(end 71.418196 -386.143754)
			)
			(arc
				(start 71.418196 -385.88823)
				(mid 71.422097 -385.868707)
				(end 71.433182 -385.852162)
			)
			(arc
				(start 71.54926 -385.736084)
				(mid 71.560186 -385.719638)
				(end 71.563992 -385.70027)
			)
			(arc
				(start 71.563992 -385.6355)
				(mid 71.601338 -385.545338)
				(end 71.6915 -385.507992)
			)
			(xy 71.753476 -385.507992)
			(arc
				(start 71.762874 -385.504182)
				(mid 71.821236 -385.486198)
				(end 71.882 -385.480052)
			)
			(arc
				(start 71.882 -385.480052)
				(mid 71.942771 -385.486161)
				(end 72.001126 -385.504182)
			)
			(xy 72.010524 -385.507992)
			(arc
				(start 72.0725 -385.507992)
				(mid 72.149897 -385.534169)
				(end 72.195436 -385.601972)
			)
			(xy 72.200008 -385.618482) (xy 72.227186 -385.63931) (xy 72.349614 -385.63931) (xy 72.376792 -385.618482)
			(arc
				(start 72.381364 -385.601972)
				(mid 72.426953 -385.534234)
				(end 72.5043 -385.507992)
			)
			(xy 72.566276 -385.507992)
			(arc
				(start 72.575674 -385.504182)
				(mid 72.634036 -385.486198)
				(end 72.6948 -385.480052)
			)
			(arc
				(start 72.6948 -385.480052)
				(mid 72.755571 -385.486161)
				(end 72.813926 -385.504182)
			)
			(xy 72.823324 -385.507992)
			(arc
				(start 72.8853 -385.507992)
				(mid 72.962697 -385.534169)
				(end 73.008236 -385.601972)
			)
			(xy 73.012808 -385.618482) (xy 73.039986 -385.63931) (xy 73.110598 -385.63931) (xy 73.1266 -385.633976)
			(arc
				(start 73.133458 -385.628642)
				(mid 73.317051 -385.529566)
				(end 73.52284 -385.495292)
			)
			(arc
				(start 73.52284 -385.495292)
				(mid 73.753284 -385.538545)
				(end 73.952354 -385.662424)
			)
			(arc
				(start 73.952354 -385.662424)
				(mid 73.96827 -385.672195)
				(end 73.986644 -385.675632)
			)
			(xy 74.435716 -385.675632) (xy 74.454258 -385.668012) (xy 74.459592 -385.662678)
			(arc
				(start 74.459592 -385.240784)
				(mid 74.45233 -385.214609)
				(end 74.432668 -385.195826)
			)
			(arc
				(start 74.432668 -385.195826)
				(mid 74.29278 -385.09406)
				(end 74.185526 -384.958336)
			)
			(arc
				(start 74.185526 -384.958336)
				(mid 74.166867 -384.940046)
				(end 74.141584 -384.933444)
			)
			(arc
				(start 74.054208 -384.933444)
				(mid 74.028921 -384.940039)
				(end 74.010266 -384.958336)
			)
			(arc
				(start 74.010266 -384.958336)
				(mid 73.778141 -385.187488)
				(end 73.462896 -385.271264)
			)
			(arc
				(start 73.462896 -385.271264)
				(mid 72.827388 -384.635756)
				(end 73.462896 -384.000248)
			)
			(arc
				(start 73.462896 -384.000248)
				(mid 73.630639 -384.022855)
				(end 73.786492 -384.088894)
			)
			(xy 73.801732 -384.097784) (xy 73.836022 -384.093466) (xy 74.226166 -383.703322) (xy 74.233024 -383.690368)
			(arc
				(start 74.234548 -383.682748)
				(mid 74.242105 -383.652963)
				(end 74.252582 -383.624074)
			)
			(xy 74.256392 -383.614676) (xy 74.256392 -383.5527) (xy 74.257408 -383.538476) (xy 74.257662 -383.535682)
			(arc
				(start 74.257662 -383.532888)
				(mid 74.242783 -383.496967)
				(end 74.206862 -383.482088)
			)
			(xy 73.488296 -383.482088) (xy 73.462388 -383.499614)
			(arc
				(start 73.4568 -383.514346)
				(mid 73.22308 -383.80653)
				(end 72.865488 -383.916682)
			)
			(arc
				(start 72.865488 -383.916682)
				(mid 72.416116 -383.730546)
				(end 72.22998 -383.281174)
			)
			(arc
				(start 72.22998 -383.281174)
				(mid 72.234383 -383.206492)
				(end 72.247506 -383.132838)
			)
			(xy 72.250808 -383.11963) (xy 72.243696 -383.094484)
			(arc
				(start 71.804022 -382.655064)
				(mid 71.781182 -382.629464)
				(end 71.76135 -382.60147)
			)
			(arc
				(start 71.76135 -382.60147)
				(mid 71.742924 -382.584139)
				(end 71.718424 -382.577848)
			)
			(arc
				(start 71.154798 -382.577848)
				(mid 71.135304 -382.581632)
				(end 71.11873 -382.59258)
			)
			(arc
				(start 71.091044 -382.62052)
				(mid 71.079982 -382.636937)
				(end 71.076058 -382.656334)
			)
			(arc
				(start 71.076058 -383.079244)
				(mid 71.072157 -383.098767)
				(end 71.061072 -383.115312)
			)
			(arc
				(start 70.78726 -383.389124)
				(mid 70.776149 -383.405658)
				(end 70.772274 -383.425192)
			)
			(arc
				(start 70.772274 -386.200904)
				(mid 70.776175 -386.220427)
				(end 70.78726 -386.236972)
			)
			(arc
				(start 70.839584 -386.289296)
				(mid 70.856118 -386.300407)
				(end 70.875652 -386.304282)
			)
		)
		(stroke
			(width 0)
			(type solid)
		)
		(fill yes)
		(layer "F.Cu")
		(net "P1V8_CPU1_RT_1D")
	)
	(gr_poly
		(pts
			(arc
				(start 63.993268 -335.098136)
				(mid 64.029189 -335.083257)
				(end 64.044068 -335.047336)
			)
			(arc
				(start 64.044068 -327.013316)
				(mid 64.047901 -326.993959)
				(end 64.0588 -326.977502)
			)
			(arc
				(start 67.707256 -323.329046)
				(mid 67.72379 -323.317935)
				(end 67.743324 -323.31406)
			)
			(arc
				(start 73.126854 -323.31406)
				(mid 73.141878 -323.316333)
				(end 73.155556 -323.32295)
			)
			(xy 73.16216 -323.327268) (xy 73.176384 -323.33184)
			(arc
				(start 73.478644 -323.33184)
				(mid 73.498031 -323.32789)
				(end 73.514458 -323.316854)
			)
			(arc
				(start 73.529444 -323.301868)
				(mid 73.54589 -323.290942)
				(end 73.565258 -323.287136)
			)
			(arc
				(start 81.41081 -323.287136)
				(mid 81.430167 -323.290969)
				(end 81.446624 -323.301868)
			)
			(arc
				(start 81.46161 -323.316854)
				(mid 81.478144 -323.327965)
				(end 81.497678 -323.33184)
			)
			(arc
				(start 81.807304 -323.33184)
				(mid 81.826691 -323.32789)
				(end 81.843118 -323.316854)
			)
			(arc
				(start 81.863438 -323.296534)
				(mid 81.879972 -323.285423)
				(end 81.899506 -323.281548)
			)
			(arc
				(start 89.733882 -323.281548)
				(mid 89.753405 -323.285449)
				(end 89.76995 -323.296534)
			)
			(arc
				(start 89.79027 -323.316854)
				(mid 89.806804 -323.327965)
				(end 89.826338 -323.33184)
			)
			(arc
				(start 90.08745 -323.33184)
				(mid 90.106973 -323.327939)
				(end 90.123518 -323.316854)
			)
			(arc
				(start 90.124788 -323.315584)
				(mid 90.141234 -323.304658)
				(end 90.160602 -323.300852)
			)
			(arc
				(start 97.959418 -323.300852)
				(mid 97.978775 -323.304685)
				(end 97.995232 -323.315584)
			)
			(arc
				(start 98.359722 -323.680074)
				(mid 98.370833 -323.696608)
				(end 98.374708 -323.716142)
			)
			(arc
				(start 98.374708 -325.291196)
				(mid 98.378609 -325.310719)
				(end 98.389694 -325.327264)
			)
			(arc
				(start 98.549206 -325.486776)
				(mid 98.56574 -325.497887)
				(end 98.585274 -325.501762)
			)
			(arc
				(start 99.927664 -325.501762)
				(mid 99.947187 -325.505663)
				(end 99.963732 -325.516748)
			)
			(arc
				(start 100.94976 -326.502776)
				(mid 100.960871 -326.51931)
				(end 100.964746 -326.538844)
			)
			(arc
				(start 100.964746 -328.092054)
				(mid 100.968647 -328.111577)
				(end 100.979732 -328.128122)
			)
			(arc
				(start 101.07676 -328.22515)
				(mid 101.093294 -328.236261)
				(end 101.112828 -328.240136)
			)
			(arc
				(start 107.724702 -328.240136)
				(mid 107.744225 -328.236235)
				(end 107.76077 -328.22515)
			)
			(arc
				(start 107.984798 -328.001122)
				(mid 107.995909 -327.984588)
				(end 107.999784 -327.965054)
			)
			(arc
				(start 107.999784 -327.13676)
				(mid 108.003685 -327.117237)
				(end 108.01477 -327.100692)
			)
			(arc
				(start 108.149898 -326.965564)
				(mid 108.166432 -326.954453)
				(end 108.185966 -326.950578)
			)
			(arc
				(start 109.58322 -326.950578)
				(mid 109.602743 -326.946677)
				(end 109.619288 -326.935592)
			)
			(xy 109.713522 -326.841358) (xy 109.71911 -326.810878)
			(arc
				(start 109.71276 -326.7964)
				(mid 109.673286 -326.672374)
				(end 109.659928 -326.542908)
			)
			(arc
				(start 109.659928 -326.44842)
				(mid 109.645049 -326.412499)
				(end 109.609128 -326.39762)
			)
			(arc
				(start 107.551982 -326.39762)
				(mid 107.532459 -326.393719)
				(end 107.515914 -326.382634)
			)
			(arc
				(start 106.865166 -325.731886)
				(mid 106.854055 -325.715352)
				(end 106.85018 -325.695818)
			)
			(arc
				(start 106.85018 -320.309494)
				(mid 106.846279 -320.289971)
				(end 106.835194 -320.273426)
			)
			(arc
				(start 100.766626 -314.204858)
				(mid 100.750092 -314.193747)
				(end 100.730558 -314.189872)
			)
			(xy 99.243134 -314.189872) (xy 99.220274 -314.208668) (xy 99.220274 -314.974478) (xy 99.220782 -314.997084)
			(arc
				(start 99.220782 -314.997338)
				(mid 99.071769 -315.357087)
				(end 98.71202 -315.5061)
			)
			(arc
				(start 98.71202 -315.5061)
				(mid 98.547637 -315.478826)
				(end 98.40087 -315.399928)
			)
			(arc
				(start 98.40087 -315.399928)
				(mid 98.368532 -315.389375)
				(end 98.336862 -315.401706)
			)
			(arc
				(start 98.336862 -315.401706)
				(mid 98.23609 -315.461085)
				(end 98.120962 -315.481716)
			)
			(arc
				(start 98.120962 -315.481716)
				(mid 97.79 -315.150754)
				(end 98.120962 -314.819792)
			)
			(arc
				(start 98.120962 -314.819792)
				(mid 98.154409 -314.821538)
				(end 98.18751 -314.82665)
			)
			(arc
				(start 98.18751 -314.82665)
				(mid 98.201222 -314.827621)
				(end 98.214688 -314.824872)
			)
			(arc
				(start 98.214688 -314.24118)
				(mid 98.1963 -314.21373)
				(end 98.164904 -314.203334)
			)
			(arc
				(start 98.161094 -314.203334)
				(mid 98.117143 -314.2004)
				(end 98.073972 -314.19165)
			)
			(xy 98.067368 -314.189872)
			(arc
				(start 72.832214 -314.189872)
				(mid 72.812691 -314.193773)
				(end 72.796146 -314.204858)
			)
			(arc
				(start 63.315088 -323.685916)
				(mid 63.298554 -323.697027)
				(end 63.27902 -323.700902)
			)
			(arc
				(start 60.729622 -323.700902)
				(mid 60.710099 -323.704803)
				(end 60.693554 -323.715888)
			)
			(arc
				(start 58.257186 -326.152256)
				(mid 58.240652 -326.163367)
				(end 58.221118 -326.167242)
			)
			(arc
				(start 58.021728 -326.167242)
				(mid 58.002205 -326.171143)
				(end 57.98566 -326.182228)
			)
			(xy 57.638188 -326.5297) (xy 57.630822 -326.536812) (xy 57.623202 -326.555608)
			(arc
				(start 57.623202 -334.78343)
				(mid 57.627103 -334.802953)
				(end 57.638188 -334.819498)
			)
			(arc
				(start 57.90184 -335.08315)
				(mid 57.918374 -335.094261)
				(end 57.937908 -335.098136)
			)
		)
		(stroke
			(width 0)
			(type solid)
		)
		(fill yes)
		(layer "F.Cu")
		(net "PVDDCR_CPU1_P1")
	)
	(gr_poly
		(pts
			(arc
				(start 394.357606 -394.686282)
				(mid 394.377129 -394.682381)
				(end 394.393674 -394.671296)
			)
			(arc
				(start 394.503148 -394.561822)
				(mid 394.514259 -394.545288)
				(end 394.518134 -394.525754)
			)
			(arc
				(start 394.518134 -394.27023)
				(mid 394.522035 -394.250707)
				(end 394.53312 -394.234162)
			)
			(arc
				(start 394.649198 -394.118084)
				(mid 394.66026 -394.101667)
				(end 394.664184 -394.08227)
			)
			(arc
				(start 394.664184 -394.0175)
				(mid 394.70144 -393.927428)
				(end 394.791438 -393.889992)
			)
			(xy 394.853414 -393.889992)
			(arc
				(start 394.862812 -393.886182)
				(mid 394.921174 -393.868198)
				(end 394.981938 -393.862052)
			)
			(arc
				(start 394.981938 -393.862052)
				(mid 395.042709 -393.868161)
				(end 395.101064 -393.886182)
			)
			(xy 395.110462 -393.889992)
			(arc
				(start 395.172438 -393.889992)
				(mid 395.249835 -393.916169)
				(end 395.295374 -393.983972)
			)
			(xy 395.299946 -394.000482) (xy 395.327124 -394.02131) (xy 395.449552 -394.02131) (xy 395.47673 -394.000482)
			(arc
				(start 395.481302 -393.983972)
				(mid 395.526891 -393.916234)
				(end 395.604238 -393.889992)
			)
			(xy 395.666214 -393.889992)
			(arc
				(start 395.675612 -393.886182)
				(mid 395.733974 -393.868198)
				(end 395.794738 -393.862052)
			)
			(arc
				(start 395.794738 -393.862052)
				(mid 395.855509 -393.868161)
				(end 395.913864 -393.886182)
			)
			(xy 395.923262 -393.889992)
			(arc
				(start 395.985238 -393.889992)
				(mid 396.062635 -393.916169)
				(end 396.108174 -393.983972)
			)
			(xy 396.112746 -394.000482) (xy 396.139924 -394.02131) (xy 396.210536 -394.02131) (xy 396.226538 -394.015976)
			(arc
				(start 396.233396 -394.010642)
				(mid 396.416989 -393.911566)
				(end 396.622778 -393.877292)
			)
			(arc
				(start 396.622778 -393.877292)
				(mid 396.853222 -393.920545)
				(end 397.052292 -394.044424)
			)
			(arc
				(start 397.052292 -394.044424)
				(mid 397.068208 -394.054195)
				(end 397.086582 -394.057632)
			)
			(xy 397.5354 -394.057632) (xy 397.554196 -394.050012) (xy 397.55953 -394.044678)
			(arc
				(start 397.55953 -393.622784)
				(mid 397.552268 -393.596609)
				(end 397.532606 -393.577826)
			)
			(arc
				(start 397.532606 -393.577826)
				(mid 397.392718 -393.47606)
				(end 397.285464 -393.340336)
			)
			(arc
				(start 397.285464 -393.340336)
				(mid 397.266805 -393.322046)
				(end 397.241522 -393.315444)
			)
			(arc
				(start 397.154146 -393.315444)
				(mid 397.128859 -393.322039)
				(end 397.110204 -393.340336)
			)
			(arc
				(start 397.110204 -393.340336)
				(mid 396.878079 -393.569488)
				(end 396.562834 -393.653264)
			)
			(arc
				(start 396.562834 -393.653264)
				(mid 395.927326 -393.017756)
				(end 396.562834 -392.382248)
			)
			(arc
				(start 396.562834 -392.382248)
				(mid 396.730577 -392.404855)
				(end 396.88643 -392.470894)
			)
			(arc
				(start 396.88643 -392.470894)
				(mid 396.918763 -392.47759)
				(end 396.948406 -392.46302)
			)
			(xy 397.326104 -392.085322) (xy 397.332962 -392.072368)
			(arc
				(start 397.334486 -392.064748)
				(mid 397.342043 -392.034963)
				(end 397.35252 -392.006074)
			)
			(xy 397.356584 -391.996676) (xy 397.356584 -391.9347) (xy 397.357346 -391.920476) (xy 397.3576 -391.917682)
			(arc
				(start 397.3576 -391.914888)
				(mid 397.342721 -391.878967)
				(end 397.3068 -391.864088)
			)
			(xy 396.588996 -391.864088) (xy 396.563088 -391.881614)
			(arc
				(start 396.557246 -391.896092)
				(mid 396.323639 -392.187437)
				(end 395.966696 -392.297158)
			)
			(arc
				(start 395.966696 -392.297158)
				(mid 395.517324 -392.111022)
				(end 395.331188 -391.66165)
			)
			(arc
				(start 395.331188 -391.66165)
				(mid 395.335591 -391.586968)
				(end 395.348714 -391.513314)
			)
			(xy 395.352016 -391.500106) (xy 395.344904 -391.47496)
			(arc
				(start 394.903706 -391.034016)
				(mid 394.881896 -391.00958)
				(end 394.862812 -390.982962)
			)
			(arc
				(start 394.862812 -390.982962)
				(mid 394.844309 -390.96589)
				(end 394.819886 -390.959848)
			)
			(arc
				(start 394.254482 -390.959848)
				(mid 394.234988 -390.963632)
				(end 394.218414 -390.97458)
			)
			(arc
				(start 394.190982 -391.002266)
				(mid 394.17992 -391.018683)
				(end 394.175996 -391.03808)
			)
			(arc
				(start 394.175996 -391.461244)
				(mid 394.172095 -391.480767)
				(end 394.16101 -391.497312)
			)
			(arc
				(start 393.887198 -391.771124)
				(mid 393.876087 -391.787658)
				(end 393.872212 -391.807192)
			)
			(arc
				(start 393.872212 -394.582904)
				(mid 393.876113 -394.602427)
				(end 393.887198 -394.618972)
			)
			(arc
				(start 393.939522 -394.671296)
				(mid 393.956056 -394.682407)
				(end 393.97559 -394.686282)
			)
		)
		(stroke
			(width 0)
			(type solid)
		)
		(fill yes)
		(layer "F.Cu")
		(net "P1V8_CPU0_RT_1D")
	)
	(gr_poly
		(pts
			(xy 73.328022 -258.880356) (xy 73.327519 -258.796413) (xy 73.31947 -258.628721) (xy 73.30339 -258.461608)
			(xy 73.279316 -258.295458) (xy 73.247304 -258.130653) (xy 73.207427 -257.967572) (xy 73.159777 -257.806591)
			(xy 73.104464 -257.64808) (xy 73.041615 -257.492403) (xy 72.971374 -257.339918) (xy 72.893903 -257.190976)
			(xy 72.80938 -257.04592) (xy 72.717999 -256.905083) (xy 72.619971 -256.768789) (xy 72.515521 -256.637352)
			(xy 72.40489 -256.511074) (xy 72.288332 -256.390245) (xy 72.166114 -256.275144) (xy 72.038519 -256.166035)
			(xy 71.905839 -256.063169) (xy 71.768379 -255.966782) (xy 71.626457 -255.877097) (xy 71.480398 -255.794319)
			(xy 71.330538 -255.71864) (xy 71.177222 -255.650232) (xy 71.020802 -255.589254) (xy 70.861639 -255.535845)
			(xy 70.700098 -255.490129) (xy 70.536551 -255.45221) (xy 70.371374 -255.422177) (xy 70.204947 -255.400097)
			(xy 70.037653 -255.386022) (xy 69.869876 -255.379984) (xy 69.702003 -255.381997) (xy 69.53442 -255.392057)
			(xy 69.367511 -255.410139) (xy 69.201662 -255.436203) (xy 69.037252 -255.470189) (xy 68.874662 -255.512018)
			(xy 68.714263 -255.561595) (xy 68.556427 -255.618805) (xy 68.401514 -255.683517) (xy 68.249883 -255.755581)
			(xy 68.10188 -255.834832) (xy 67.957848 -255.921089) (xy 67.818117 -256.014151) (xy 67.683009 -256.113806)
			(xy 67.552833 -256.219825) (xy 67.427891 -256.331962) (xy 67.308469 -256.449961) (xy 67.194841 -256.57355)
			(xy 67.08727 -256.702444) (xy 66.986002 -256.836348) (xy 66.89127 -256.974953) (xy 66.803293 -257.117941)
			(xy 66.722273 -257.264982) (xy 66.648395 -257.415739) (xy 66.581831 -257.569864) (xy 66.522733 -257.727004)
			(xy 66.471236 -257.886796) (xy 66.427461 -258.048873) (xy 66.391506 -258.212863) (xy 66.363455 -258.378389)
			(xy 66.343372 -258.545068) (xy 66.331304 -258.712519) (xy 66.327279 -258.880356) (xy 67.312799 -258.880356)
			(xy 67.316827 -258.738064) (xy 67.328899 -258.596228) (xy 67.348976 -258.455301) (xy 67.376994 -258.315737)
			(xy 67.412863 -258.177981) (xy 67.456468 -258.042475) (xy 67.507669 -257.909653) (xy 67.566303 -257.77994)
			(xy 67.632181 -257.653753) (xy 67.705093 -257.531494) (xy 67.784805 -257.413557) (xy 67.871062 -257.300318)
			(xy 67.963586 -257.19214) (xy 68.062083 -257.08937) (xy 68.166237 -256.992337) (xy 68.275713 -256.901353)
			(xy 68.390161 -256.816707) (xy 68.509215 -256.738672) (xy 68.632493 -256.667498) (xy 68.7596 -256.603411)
			(xy 68.890129 -256.546619) (xy 69.023663 -256.497302) (xy 69.159772 -256.455619) (xy 69.298022 -256.421703)
			(xy 69.437969 -256.395663) (xy 69.579165 -256.377582) (xy 69.721158 -256.367519) (xy 69.863493 -256.365504)
			(xy 70.005714 -256.371546) (xy 70.147365 -256.385624) (xy 70.287993 -256.407693) (xy 70.427147 -256.437683)
			(xy 70.564382 -256.475498) (xy 70.699257 -256.521016) (xy 70.831341 -256.574092) (xy 70.960211 -256.634555)
			(xy 71.085454 -256.702212) (xy 71.206668 -256.776847) (xy 71.323466 -256.85822) (xy 71.435473 -256.94607)
			(xy 71.542331 -257.040117) (xy 71.643696 -257.140058) (xy 71.739245 -257.245574) (xy 71.828672 -257.356327)
			(xy 71.91169 -257.471961) (xy 71.988032 -257.592108) (xy 72.057455 -257.71638) (xy 72.119736 -257.844382)
			(xy 72.174676 -257.975702) (xy 72.222098 -258.109919) (xy 72.261851 -258.246605) (xy 72.293807 -258.385321)
			(xy 72.317864 -258.525622) (xy 72.333945 -258.66706) (xy 72.341998 -258.809181) (xy 72.342502 -258.880356)
			(xy 72.341998 -258.951531) (xy 72.333945 -259.093652) (xy 72.317864 -259.23509) (xy 72.293807 -259.375391)
			(xy 72.261851 -259.514107) (xy 72.222098 -259.650793) (xy 72.174676 -259.78501) (xy 72.119736 -259.91633)
			(xy 72.057455 -260.044332) (xy 71.988032 -260.168604) (xy 71.91169 -260.288751) (xy 71.828672 -260.404385)
			(xy 71.739245 -260.515138) (xy 71.643696 -260.620654) (xy 71.542331 -260.720595) (xy 71.435473 -260.814642)
			(xy 71.323466 -260.902492) (xy 71.206668 -260.983865) (xy 71.085454 -261.0585) (xy 70.960211 -261.126157)
			(xy 70.831341 -261.18662) (xy 70.699257 -261.239696) (xy 70.564382 -261.285214) (xy 70.427147 -261.323029)
			(xy 70.287993 -261.353019) (xy 70.147365 -261.375088) (xy 70.005714 -261.389166) (xy 69.863493 -261.395208)
			(xy 69.721158 -261.393193) (xy 69.579165 -261.38313) (xy 69.437969 -261.365049) (xy 69.298022 -261.339009)
			(xy 69.159772 -261.305093) (xy 69.023663 -261.26341) (xy 68.890129 -261.214093) (xy 68.7596 -261.157301)
			(xy 68.632493 -261.093214) (xy 68.509215 -261.02204) (xy 68.390161 -260.944005) (xy 68.275713 -260.859359)
			(xy 68.166237 -260.768375) (xy 68.062083 -260.671342) (xy 67.963586 -260.568572) (xy 67.871062 -260.460394)
			(xy 67.784805 -260.347155) (xy 67.705093 -260.229218) (xy 67.632181 -260.106959) (xy 67.566303 -259.980772)
			(xy 67.507669 -259.851059) (xy 67.456468 -259.718237) (xy 67.412863 -259.582731) (xy 67.376994 -259.444975)
			(xy 67.348976 -259.305411) (xy 67.328899 -259.164484) (xy 67.316827 -259.022648) (xy 67.312799 -258.880356)
			(xy 66.327279 -258.880356) (xy 66.331304 -259.048193) (xy 66.343372 -259.215644) (xy 66.363455 -259.382323)
			(xy 66.391506 -259.547849) (xy 66.427461 -259.711839) (xy 66.471236 -259.873916) (xy 66.522733 -260.033708)
			(xy 66.581831 -260.190848) (xy 66.648395 -260.344973) (xy 66.722273 -260.49573) (xy 66.803293 -260.642771)
			(xy 66.89127 -260.785759) (xy 66.986002 -260.924364) (xy 67.08727 -261.058268) (xy 67.194841 -261.187162)
			(xy 67.308469 -261.310751) (xy 67.427891 -261.42875) (xy 67.552833 -261.540887) (xy 67.683009 -261.646906)
			(xy 67.818117 -261.746561) (xy 67.957848 -261.839623) (xy 68.10188 -261.92588) (xy 68.249883 -262.005131)
			(xy 68.401514 -262.077195) (xy 68.556427 -262.141907) (xy 68.714263 -262.199117) (xy 68.874662 -262.248694)
			(xy 69.037252 -262.290523) (xy 69.201662 -262.324509) (xy 69.367511 -262.350573) (xy 69.53442 -262.368655)
			(xy 69.702003 -262.378715) (xy 69.869876 -262.380728) (xy 70.037653 -262.37469) (xy 70.204947 -262.360615)
			(xy 70.371374 -262.338535) (xy 70.536551 -262.308502) (xy 70.700098 -262.270583) (xy 70.861639 -262.224867)
			(xy 71.020802 -262.171458) (xy 71.177222 -262.11048) (xy 71.330538 -262.042072) (xy 71.480398 -261.966393)
			(xy 71.626457 -261.883615) (xy 71.768379 -261.79393) (xy 71.905839 -261.697543) (xy 72.038519 -261.594677)
			(xy 72.166114 -261.485568) (xy 72.288332 -261.370467) (xy 72.40489 -261.249638) (xy 72.515521 -261.12336)
			(xy 72.619971 -260.991923) (xy 72.717999 -260.855629) (xy 72.80938 -260.714792) (xy 72.893903 -260.569736)
			(xy 72.971374 -260.420794) (xy 73.041615 -260.268309) (xy 73.104464 -260.112632) (xy 73.159777 -259.954121)
			(xy 73.207427 -259.79314) (xy 73.247304 -259.630059) (xy 73.279316 -259.465254) (xy 73.30339 -259.299104)
			(xy 73.31947 -259.131991) (xy 73.327519 -258.964299)
		)
		(stroke
			(width 0)
			(type solid)
		)
		(fill yes)
		(layer "F.Cu")
		(net "Net_1979")
	)
	(gr_poly
		(pts
			(xy 84.827872 -304.780442) (xy 84.827369 -304.696506) (xy 84.81932 -304.528826) (xy 84.803242 -304.361724)
			(xy 84.77917 -304.195586) (xy 84.74716 -304.030793) (xy 84.707286 -303.867725) (xy 84.65964 -303.706755)
			(xy 84.60433 -303.548255) (xy 84.541486 -303.392589) (xy 84.47125 -303.240115) (xy 84.393784 -303.091184)
			(xy 84.309267 -302.946139) (xy 84.217893 -302.805312) (xy 84.119873 -302.669028) (xy 84.01543 -302.537601)
			(xy 83.904807 -302.411332) (xy 83.788257 -302.290512) (xy 83.666049 -302.175419) (xy 83.538462 -302.066318)
			(xy 83.405792 -301.963459) (xy 83.268343 -301.86708) (xy 83.12643 -301.777401) (xy 82.980382 -301.694629)
			(xy 82.830533 -301.618955) (xy 82.677228 -301.550552) (xy 82.520819 -301.489578) (xy 82.361668 -301.436174)
			(xy 82.200139 -301.390461) (xy 82.036603 -301.352545) (xy 81.871438 -301.322514) (xy 81.705024 -301.300436)
			(xy 81.537742 -301.286362) (xy 81.369977 -301.280324) (xy 81.202116 -301.282337) (xy 81.034545 -301.292396)
			(xy 80.867649 -301.310477) (xy 80.701811 -301.336539) (xy 80.537414 -301.370523) (xy 80.374835 -301.412349)
			(xy 80.214448 -301.461922) (xy 80.056623 -301.519128) (xy 79.901722 -301.583834) (xy 79.750101 -301.655894)
			(xy 79.60211 -301.735139) (xy 79.458088 -301.821389) (xy 79.318367 -301.914445) (xy 79.183268 -302.014093)
			(xy 79.053102 -302.120104) (xy 78.928169 -302.232233) (xy 78.808755 -302.350223) (xy 78.695136 -302.473803)
			(xy 78.587572 -302.602688) (xy 78.486312 -302.736583) (xy 78.391587 -302.875178) (xy 78.303617 -303.018155)
			(xy 78.222602 -303.165185) (xy 78.14873 -303.315931) (xy 78.082171 -303.470045) (xy 78.023077 -303.627173)
			(xy 77.971584 -303.786954) (xy 77.927811 -303.94902) (xy 77.891859 -304.112998) (xy 77.86381 -304.278511)
			(xy 77.843729 -304.445179) (xy 77.831662 -304.612617) (xy 77.827637 -304.780442) (xy 78.813157 -304.780442)
			(xy 78.817184 -304.638164) (xy 78.829255 -304.496342) (xy 78.84933 -304.35543) (xy 78.877345 -304.21588)
			(xy 78.913211 -304.078138) (xy 78.956811 -303.942646) (xy 79.008007 -303.809837) (xy 79.066635 -303.680137)
			(xy 79.132507 -303.553963) (xy 79.205411 -303.431717) (xy 79.285115 -303.313791) (xy 79.371363 -303.200563)
			(xy 79.463879 -303.092397) (xy 79.562366 -302.989637) (xy 79.666509 -302.892614) (xy 79.775974 -302.801638)
			(xy 79.89041 -302.717002) (xy 80.009452 -302.638974) (xy 80.132718 -302.567807) (xy 80.259812 -302.503727)
			(xy 80.390328 -302.446941) (xy 80.523848 -302.397629) (xy 80.659944 -302.35595) (xy 80.798179 -302.322038)
			(xy 80.938112 -302.296) (xy 81.079294 -302.277921) (xy 81.221273 -302.267858) (xy 81.363593 -302.265844)
			(xy 81.5058 -302.271885) (xy 81.647437 -302.285962) (xy 81.78805 -302.308029) (xy 81.92719 -302.338016)
			(xy 82.064411 -302.375827) (xy 82.199273 -302.42134) (xy 82.331344 -302.474411) (xy 82.460201 -302.534868)
			(xy 82.585431 -302.602518) (xy 82.706633 -302.677146) (xy 82.823419 -302.75851) (xy 82.935415 -302.846352)
			(xy 83.042261 -302.940389) (xy 83.143617 -303.04032) (xy 83.239156 -303.145825) (xy 83.328574 -303.256567)
			(xy 83.411583 -303.37219) (xy 83.487918 -303.492324) (xy 83.557334 -303.616584) (xy 83.619609 -303.744572)
			(xy 83.674543 -303.875879) (xy 83.72196 -304.010083) (xy 83.761709 -304.146755) (xy 83.793662 -304.285457)
			(xy 83.817716 -304.425744) (xy 83.833796 -304.567168) (xy 83.841848 -304.709275) (xy 83.842352 -304.780442)
			(xy 83.841848 -304.851609) (xy 83.833796 -304.993716) (xy 83.817716 -305.13514) (xy 83.793662 -305.275427)
			(xy 83.761709 -305.414129) (xy 83.72196 -305.550801) (xy 83.674543 -305.685005) (xy 83.619609 -305.816312)
			(xy 83.557334 -305.9443) (xy 83.487918 -306.06856) (xy 83.411583 -306.188694) (xy 83.328574 -306.304317)
			(xy 83.239156 -306.415059) (xy 83.143617 -306.520564) (xy 83.042261 -306.620495) (xy 82.935415 -306.714532)
			(xy 82.823419 -306.802374) (xy 82.706633 -306.883738) (xy 82.585431 -306.958366) (xy 82.460201 -307.026016)
			(xy 82.331344 -307.086473) (xy 82.199273 -307.139544) (xy 82.064411 -307.185057) (xy 81.92719 -307.222868)
			(xy 81.78805 -307.252855) (xy 81.647437 -307.274922) (xy 81.5058 -307.288999) (xy 81.363593 -307.29504)
			(xy 81.221273 -307.293026) (xy 81.079294 -307.282963) (xy 80.938112 -307.264884) (xy 80.798179 -307.238846)
			(xy 80.659944 -307.204934) (xy 80.523848 -307.163255) (xy 80.390328 -307.113943) (xy 80.259812 -307.057157)
			(xy 80.132718 -306.993077) (xy 80.009452 -306.92191) (xy 79.89041 -306.843882) (xy 79.775974 -306.759246)
			(xy 79.666509 -306.66827) (xy 79.562366 -306.571247) (xy 79.463879 -306.468487) (xy 79.371363 -306.360321)
			(xy 79.285115 -306.247093) (xy 79.205411 -306.129167) (xy 79.132507 -306.006921) (xy 79.066635 -305.880747)
			(xy 79.008007 -305.751047) (xy 78.956811 -305.618238) (xy 78.913211 -305.482746) (xy 78.877345 -305.345004)
			(xy 78.84933 -305.205454) (xy 78.829255 -305.064542) (xy 78.817184 -304.92272) (xy 78.813157 -304.780442)
			(xy 77.827637 -304.780442) (xy 77.831662 -304.948267) (xy 77.843729 -305.115705) (xy 77.86381 -305.282373)
			(xy 77.891859 -305.447886) (xy 77.927811 -305.611864) (xy 77.971584 -305.77393) (xy 78.023077 -305.933711)
			(xy 78.082171 -306.090839) (xy 78.14873 -306.244953) (xy 78.222602 -306.395699) (xy 78.303617 -306.542729)
			(xy 78.391587 -306.685706) (xy 78.486312 -306.824301) (xy 78.587572 -306.958196) (xy 78.695136 -307.087081)
			(xy 78.808755 -307.210661) (xy 78.928169 -307.328651) (xy 79.053102 -307.44078) (xy 79.183268 -307.546791)
			(xy 79.318367 -307.646439) (xy 79.458088 -307.739495) (xy 79.60211 -307.825745) (xy 79.750101 -307.90499)
			(xy 79.901722 -307.97705) (xy 80.056623 -308.041756) (xy 80.214448 -308.098962) (xy 80.374835 -308.148535)
			(xy 80.537414 -308.190361) (xy 80.701811 -308.224345) (xy 80.867649 -308.250407) (xy 81.034545 -308.268488)
			(xy 81.202116 -308.278547) (xy 81.369977 -308.28056) (xy 81.537742 -308.274522) (xy 81.705024 -308.260448)
			(xy 81.871438 -308.23837) (xy 82.036603 -308.208339) (xy 82.200139 -308.170423) (xy 82.361668 -308.12471)
			(xy 82.520819 -308.071306) (xy 82.677228 -308.010332) (xy 82.830533 -307.941929) (xy 82.980382 -307.866255)
			(xy 83.12643 -307.783483) (xy 83.268343 -307.693804) (xy 83.405792 -307.597425) (xy 83.538462 -307.494566)
			(xy 83.666049 -307.385465) (xy 83.788257 -307.270372) (xy 83.904807 -307.149552) (xy 84.01543 -307.023283)
			(xy 84.119873 -306.891856) (xy 84.217893 -306.755572) (xy 84.309267 -306.614745) (xy 84.393784 -306.4697)
			(xy 84.47125 -306.320769) (xy 84.541486 -306.168295) (xy 84.60433 -306.012629) (xy 84.65964 -305.854129)
			(xy 84.707286 -305.693159) (xy 84.74716 -305.530091) (xy 84.77917 -305.365298) (xy 84.803242 -305.19916)
			(xy 84.81932 -305.032058) (xy 84.827369 -304.864378)
		)
		(stroke
			(width 0)
			(type solid)
		)
		(fill yes)
		(layer "F.Cu")
		(net "Net_1978")
	)
	(gr_poly
		(pts
			(xy 84.827872 -212.98027) (xy 84.827369 -212.896334) (xy 84.81932 -212.728654) (xy 84.803242 -212.561552)
			(xy 84.77917 -212.395414) (xy 84.74716 -212.230621) (xy 84.707286 -212.067553) (xy 84.65964 -211.906583)
			(xy 84.60433 -211.748083) (xy 84.541486 -211.592417) (xy 84.47125 -211.439943) (xy 84.393784 -211.291012)
			(xy 84.309267 -211.145967) (xy 84.217893 -211.00514) (xy 84.119873 -210.868856) (xy 84.01543 -210.737429)
			(xy 83.904807 -210.61116) (xy 83.788257 -210.49034) (xy 83.666049 -210.375247) (xy 83.538462 -210.266146)
			(xy 83.405792 -210.163287) (xy 83.268343 -210.066908) (xy 83.12643 -209.977229) (xy 82.980382 -209.894457)
			(xy 82.830533 -209.818783) (xy 82.677228 -209.75038) (xy 82.520819 -209.689406) (xy 82.361668 -209.636002)
			(xy 82.200139 -209.590289) (xy 82.036603 -209.552373) (xy 81.871438 -209.522342) (xy 81.705024 -209.500264)
			(xy 81.537742 -209.48619) (xy 81.369977 -209.480152) (xy 81.202116 -209.482165) (xy 81.034545 -209.492224)
			(xy 80.867649 -209.510305) (xy 80.701811 -209.536367) (xy 80.537414 -209.570351) (xy 80.374835 -209.612177)
			(xy 80.214448 -209.66175) (xy 80.056623 -209.718956) (xy 79.901722 -209.783662) (xy 79.750101 -209.855722)
			(xy 79.60211 -209.934967) (xy 79.458088 -210.021217) (xy 79.318367 -210.114273) (xy 79.183268 -210.213921)
			(xy 79.053102 -210.319932) (xy 78.928169 -210.432061) (xy 78.808755 -210.550051) (xy 78.695136 -210.673631)
			(xy 78.587572 -210.802516) (xy 78.486312 -210.936411) (xy 78.391587 -211.075006) (xy 78.303617 -211.217983)
			(xy 78.222602 -211.365013) (xy 78.14873 -211.515759) (xy 78.082171 -211.669873) (xy 78.023077 -211.827001)
			(xy 77.971584 -211.986782) (xy 77.927811 -212.148848) (xy 77.891859 -212.312826) (xy 77.86381 -212.478339)
			(xy 77.843729 -212.645007) (xy 77.831662 -212.812445) (xy 77.827637 -212.98027) (xy 78.813157 -212.98027)
			(xy 78.817184 -212.837992) (xy 78.829255 -212.69617) (xy 78.84933 -212.555258) (xy 78.877345 -212.415708)
			(xy 78.913211 -212.277966) (xy 78.956811 -212.142474) (xy 79.008007 -212.009665) (xy 79.066635 -211.879965)
			(xy 79.132507 -211.753791) (xy 79.205411 -211.631545) (xy 79.285115 -211.513619) (xy 79.371363 -211.400391)
			(xy 79.463879 -211.292225) (xy 79.562366 -211.189465) (xy 79.666509 -211.092442) (xy 79.775974 -211.001466)
			(xy 79.89041 -210.91683) (xy 80.009452 -210.838802) (xy 80.132718 -210.767635) (xy 80.259812 -210.703555)
			(xy 80.390328 -210.646769) (xy 80.523848 -210.597457) (xy 80.659944 -210.555778) (xy 80.798179 -210.521866)
			(xy 80.938112 -210.495828) (xy 81.079294 -210.477749) (xy 81.221273 -210.467686) (xy 81.363593 -210.465672)
			(xy 81.5058 -210.471713) (xy 81.647437 -210.48579) (xy 81.78805 -210.507857) (xy 81.92719 -210.537844)
			(xy 82.064411 -210.575655) (xy 82.199273 -210.621168) (xy 82.331344 -210.674239) (xy 82.460201 -210.734696)
			(xy 82.585431 -210.802346) (xy 82.706633 -210.876974) (xy 82.823419 -210.958338) (xy 82.935415 -211.04618)
			(xy 83.042261 -211.140217) (xy 83.143617 -211.240148) (xy 83.239156 -211.345653) (xy 83.328574 -211.456395)
			(xy 83.411583 -211.572018) (xy 83.487918 -211.692152) (xy 83.557334 -211.816412) (xy 83.619609 -211.9444)
			(xy 83.674543 -212.075707) (xy 83.72196 -212.209911) (xy 83.761709 -212.346583) (xy 83.793662 -212.485285)
			(xy 83.817716 -212.625572) (xy 83.833796 -212.766996) (xy 83.841848 -212.909103) (xy 83.842352 -212.98027)
			(xy 83.841848 -213.051437) (xy 83.833796 -213.193544) (xy 83.817716 -213.334968) (xy 83.793662 -213.475255)
			(xy 83.761709 -213.613957) (xy 83.72196 -213.750629) (xy 83.674543 -213.884833) (xy 83.619609 -214.01614)
			(xy 83.557334 -214.144128) (xy 83.487918 -214.268388) (xy 83.411583 -214.388522) (xy 83.328574 -214.504145)
			(xy 83.239156 -214.614887) (xy 83.143617 -214.720392) (xy 83.042261 -214.820323) (xy 82.935415 -214.91436)
			(xy 82.823419 -215.002202) (xy 82.706633 -215.083566) (xy 82.585431 -215.158194) (xy 82.460201 -215.225844)
			(xy 82.331344 -215.286301) (xy 82.199273 -215.339372) (xy 82.064411 -215.384885) (xy 81.92719 -215.422696)
			(xy 81.78805 -215.452683) (xy 81.647437 -215.47475) (xy 81.5058 -215.488827) (xy 81.363593 -215.494868)
			(xy 81.221273 -215.492854) (xy 81.079294 -215.482791) (xy 80.938112 -215.464712) (xy 80.798179 -215.438674)
			(xy 80.659944 -215.404762) (xy 80.523848 -215.363083) (xy 80.390328 -215.313771) (xy 80.259812 -215.256985)
			(xy 80.132718 -215.192905) (xy 80.009452 -215.121738) (xy 79.89041 -215.04371) (xy 79.775974 -214.959074)
			(xy 79.666509 -214.868098) (xy 79.562366 -214.771075) (xy 79.463879 -214.668315) (xy 79.371363 -214.560149)
			(xy 79.285115 -214.446921) (xy 79.205411 -214.328995) (xy 79.132507 -214.206749) (xy 79.066635 -214.080575)
			(xy 79.008007 -213.950875) (xy 78.956811 -213.818066) (xy 78.913211 -213.682574) (xy 78.877345 -213.544832)
			(xy 78.84933 -213.405282) (xy 78.829255 -213.26437) (xy 78.817184 -213.122548) (xy 78.813157 -212.98027)
			(xy 77.827637 -212.98027) (xy 77.831662 -213.148095) (xy 77.843729 -213.315533) (xy 77.86381 -213.482201)
			(xy 77.891859 -213.647714) (xy 77.927811 -213.811692) (xy 77.971584 -213.973758) (xy 78.023077 -214.133539)
			(xy 78.082171 -214.290667) (xy 78.14873 -214.444781) (xy 78.222602 -214.595527) (xy 78.303617 -214.742557)
			(xy 78.391587 -214.885534) (xy 78.486312 -215.024129) (xy 78.587572 -215.158024) (xy 78.695136 -215.286909)
			(xy 78.808755 -215.410489) (xy 78.928169 -215.528479) (xy 79.053102 -215.640608) (xy 79.183268 -215.746619)
			(xy 79.318367 -215.846267) (xy 79.458088 -215.939323) (xy 79.60211 -216.025573) (xy 79.750101 -216.104818)
			(xy 79.901722 -216.176878) (xy 80.056623 -216.241584) (xy 80.214448 -216.29879) (xy 80.374835 -216.348363)
			(xy 80.537414 -216.390189) (xy 80.701811 -216.424173) (xy 80.867649 -216.450235) (xy 81.034545 -216.468316)
			(xy 81.202116 -216.478375) (xy 81.369977 -216.480388) (xy 81.537742 -216.47435) (xy 81.705024 -216.460276)
			(xy 81.871438 -216.438198) (xy 82.036603 -216.408167) (xy 82.200139 -216.370251) (xy 82.361668 -216.324538)
			(xy 82.520819 -216.271134) (xy 82.677228 -216.21016) (xy 82.830533 -216.141757) (xy 82.980382 -216.066083)
			(xy 83.12643 -215.983311) (xy 83.268343 -215.893632) (xy 83.405792 -215.797253) (xy 83.538462 -215.694394)
			(xy 83.666049 -215.585293) (xy 83.788257 -215.4702) (xy 83.904807 -215.34938) (xy 84.01543 -215.223111)
			(xy 84.119873 -215.091684) (xy 84.217893 -214.9554) (xy 84.309267 -214.814573) (xy 84.393784 -214.669528)
			(xy 84.47125 -214.520597) (xy 84.541486 -214.368123) (xy 84.60433 -214.212457) (xy 84.65964 -214.053957)
			(xy 84.707286 -213.892987) (xy 84.74716 -213.729919) (xy 84.77917 -213.565126) (xy 84.803242 -213.398988)
			(xy 84.81932 -213.231886) (xy 84.827369 -213.064206)
		)
		(stroke
			(width 0)
			(type solid)
		)
		(fill yes)
		(layer "F.Cu")
		(net "Net_1980")
	)
	(gr_poly
		(pts
			(xy 146.027902 -304.780442) (xy 146.027399 -304.696499) (xy 146.01935 -304.528807) (xy 146.00327 -304.361694)
			(xy 145.979196 -304.195544) (xy 145.947184 -304.030739) (xy 145.907307 -303.867658) (xy 145.859657 -303.706677)
			(xy 145.804344 -303.548166) (xy 145.741495 -303.392489) (xy 145.671254 -303.240004) (xy 145.593783 -303.091062)
			(xy 145.50926 -302.946006) (xy 145.417879 -302.805169) (xy 145.319851 -302.668875) (xy 145.215401 -302.537438)
			(xy 145.10477 -302.41116) (xy 144.988212 -302.290331) (xy 144.865994 -302.17523) (xy 144.738399 -302.066121)
			(xy 144.605719 -301.963255) (xy 144.468259 -301.866868) (xy 144.326337 -301.777183) (xy 144.180278 -301.694405)
			(xy 144.030418 -301.618726) (xy 143.877102 -301.550318) (xy 143.720682 -301.48934) (xy 143.561519 -301.435931)
			(xy 143.399978 -301.390215) (xy 143.236431 -301.352296) (xy 143.071254 -301.322263) (xy 142.904827 -301.300183)
			(xy 142.737533 -301.286108) (xy 142.569756 -301.28007) (xy 142.401883 -301.282083) (xy 142.2343 -301.292143)
			(xy 142.067391 -301.310225) (xy 141.901542 -301.336289) (xy 141.737132 -301.370275) (xy 141.574542 -301.412104)
			(xy 141.414143 -301.461681) (xy 141.256307 -301.518891) (xy 141.101394 -301.583603) (xy 140.949763 -301.655667)
			(xy 140.80176 -301.734918) (xy 140.657728 -301.821175) (xy 140.517997 -301.914237) (xy 140.382889 -302.013892)
			(xy 140.252713 -302.119911) (xy 140.127771 -302.232048) (xy 140.008349 -302.350047) (xy 139.894721 -302.473636)
			(xy 139.78715 -302.60253) (xy 139.685882 -302.736434) (xy 139.59115 -302.875039) (xy 139.503173 -303.018027)
			(xy 139.422153 -303.165068) (xy 139.348275 -303.315825) (xy 139.281711 -303.46995) (xy 139.222613 -303.62709)
			(xy 139.171116 -303.786882) (xy 139.127341 -303.948959) (xy 139.091386 -304.112949) (xy 139.063335 -304.278475)
			(xy 139.043252 -304.445154) (xy 139.031184 -304.612605) (xy 139.027159 -304.780442) (xy 140.012424 -304.780442)
			(xy 140.016453 -304.638135) (xy 140.028526 -304.496285) (xy 140.048605 -304.355344) (xy 140.076626 -304.215766)
			(xy 140.112498 -304.077996) (xy 140.156108 -303.942476) (xy 140.207314 -303.809641) (xy 140.265954 -303.679915)
			(xy 140.331839 -303.553715) (xy 140.404758 -303.431444) (xy 140.484478 -303.313494) (xy 140.570744 -303.200244)
			(xy 140.663278 -303.092055) (xy 140.761785 -302.989275) (xy 140.865949 -302.892232) (xy 140.975436 -302.801238)
			(xy 141.089896 -302.716584) (xy 141.208961 -302.638541) (xy 141.332252 -302.56736) (xy 141.459372 -302.503267)
			(xy 141.589914 -302.446469) (xy 141.723461 -302.397147) (xy 141.859585 -302.35546) (xy 141.997848 -302.321541)
			(xy 142.137809 -302.295498) (xy 142.27902 -302.277415) (xy 142.421027 -302.26735) (xy 142.563376 -302.265336)
			(xy 142.705612 -302.271378) (xy 142.847277 -302.285457) (xy 142.987919 -302.307529) (xy 143.127088 -302.337522)
			(xy 143.264336 -302.37534) (xy 143.399225 -302.420863) (xy 143.531323 -302.473944) (xy 143.660206 -302.534414)
			(xy 143.785461 -302.602078) (xy 143.906688 -302.67672) (xy 144.023497 -302.758101) (xy 144.135516 -302.845961)
			(xy 144.242384 -302.940017) (xy 144.34376 -303.039968) (xy 144.439319 -303.145495) (xy 144.528754 -303.256259)
			(xy 144.61178 -303.371905) (xy 144.688131 -303.492063) (xy 144.757561 -303.616349) (xy 144.819848 -303.744363)
			(xy 144.874793 -303.875696) (xy 144.92222 -304.009927) (xy 144.961977 -304.146627) (xy 144.993936 -304.285357)
			(xy 145.017996 -304.425673) (xy 145.034078 -304.567125) (xy 145.042133 -304.70926) (xy 145.042636 -304.780442)
			(xy 145.042133 -304.851624) (xy 145.034078 -304.993759) (xy 145.017996 -305.135211) (xy 144.993936 -305.275527)
			(xy 144.961977 -305.414257) (xy 144.92222 -305.550957) (xy 144.874793 -305.685188) (xy 144.819848 -305.816521)
			(xy 144.757561 -305.944535) (xy 144.688131 -306.068821) (xy 144.61178 -306.188979) (xy 144.528754 -306.304625)
			(xy 144.439319 -306.415389) (xy 144.34376 -306.520916) (xy 144.242384 -306.620867) (xy 144.135516 -306.714923)
			(xy 144.023497 -306.802783) (xy 143.906688 -306.884164) (xy 143.785461 -306.958806) (xy 143.660206 -307.02647)
			(xy 143.531323 -307.08694) (xy 143.399225 -307.140021) (xy 143.264336 -307.185544) (xy 143.127088 -307.223362)
			(xy 142.987919 -307.253355) (xy 142.847277 -307.275427) (xy 142.705612 -307.289506) (xy 142.563376 -307.295548)
			(xy 142.421027 -307.293534) (xy 142.27902 -307.283469) (xy 142.137809 -307.265386) (xy 141.997848 -307.239343)
			(xy 141.859585 -307.205424) (xy 141.723461 -307.163737) (xy 141.589914 -307.114415) (xy 141.459372 -307.057617)
			(xy 141.332252 -306.993524) (xy 141.208961 -306.922343) (xy 141.089896 -306.8443) (xy 140.975436 -306.759646)
			(xy 140.865949 -306.668652) (xy 140.761785 -306.571609) (xy 140.663278 -306.468829) (xy 140.570744 -306.36064)
			(xy 140.484478 -306.24739) (xy 140.404758 -306.12944) (xy 140.331839 -306.007169) (xy 140.265954 -305.880969)
			(xy 140.207314 -305.751243) (xy 140.156108 -305.618408) (xy 140.112498 -305.482888) (xy 140.076626 -305.345118)
			(xy 140.048605 -305.20554) (xy 140.028526 -305.064599) (xy 140.016453 -304.922749) (xy 140.012424 -304.780442)
			(xy 139.027159 -304.780442) (xy 139.031184 -304.948279) (xy 139.043252 -305.11573) (xy 139.063335 -305.282409)
			(xy 139.091386 -305.447935) (xy 139.127341 -305.611925) (xy 139.171116 -305.774002) (xy 139.222613 -305.933794)
			(xy 139.281711 -306.090934) (xy 139.348275 -306.245059) (xy 139.422153 -306.395816) (xy 139.503173 -306.542857)
			(xy 139.59115 -306.685845) (xy 139.685882 -306.82445) (xy 139.78715 -306.958354) (xy 139.894721 -307.087248)
			(xy 140.008349 -307.210837) (xy 140.127771 -307.328836) (xy 140.252713 -307.440973) (xy 140.382889 -307.546992)
			(xy 140.517997 -307.646647) (xy 140.657728 -307.739709) (xy 140.80176 -307.825966) (xy 140.949763 -307.905217)
			(xy 141.101394 -307.977281) (xy 141.256307 -308.041993) (xy 141.414143 -308.099203) (xy 141.574542 -308.14878)
			(xy 141.737132 -308.190609) (xy 141.901542 -308.224595) (xy 142.067391 -308.250659) (xy 142.2343 -308.268741)
			(xy 142.401883 -308.278801) (xy 142.569756 -308.280814) (xy 142.737533 -308.274776) (xy 142.904827 -308.260701)
			(xy 143.071254 -308.238621) (xy 143.236431 -308.208588) (xy 143.399978 -308.170669) (xy 143.561519 -308.124953)
			(xy 143.720682 -308.071544) (xy 143.877102 -308.010566) (xy 144.030418 -307.942158) (xy 144.180278 -307.866479)
			(xy 144.326337 -307.783701) (xy 144.468259 -307.694016) (xy 144.605719 -307.597629) (xy 144.738399 -307.494763)
			(xy 144.865994 -307.385654) (xy 144.988212 -307.270553) (xy 145.10477 -307.149724) (xy 145.215401 -307.023446)
			(xy 145.319851 -306.892009) (xy 145.417879 -306.755715) (xy 145.50926 -306.614878) (xy 145.593783 -306.469822)
			(xy 145.671254 -306.32088) (xy 145.741495 -306.168395) (xy 145.804344 -306.012718) (xy 145.859657 -305.854207)
			(xy 145.907307 -305.693226) (xy 145.947184 -305.530145) (xy 145.979196 -305.36534) (xy 146.00327 -305.19919)
			(xy 146.01935 -305.032077) (xy 146.027399 -304.864385)
		)
		(stroke
			(width 0)
			(type solid)
		)
		(fill yes)
		(layer "F.Cu")
		(net "Net_1983")
	)
	(gr_poly
		(pts
			(xy 146.027902 -212.98027) (xy 146.027399 -212.896327) (xy 146.01935 -212.728635) (xy 146.00327 -212.561522)
			(xy 145.979196 -212.395372) (xy 145.947184 -212.230567) (xy 145.907307 -212.067486) (xy 145.859657 -211.906505)
			(xy 145.804344 -211.747994) (xy 145.741495 -211.592317) (xy 145.671254 -211.439832) (xy 145.593783 -211.29089)
			(xy 145.50926 -211.145834) (xy 145.417879 -211.004997) (xy 145.319851 -210.868703) (xy 145.215401 -210.737266)
			(xy 145.10477 -210.610988) (xy 144.988212 -210.490159) (xy 144.865994 -210.375058) (xy 144.738399 -210.265949)
			(xy 144.605719 -210.163083) (xy 144.468259 -210.066696) (xy 144.326337 -209.977011) (xy 144.180278 -209.894233)
			(xy 144.030418 -209.818554) (xy 143.877102 -209.750146) (xy 143.720682 -209.689168) (xy 143.561519 -209.635759)
			(xy 143.399978 -209.590043) (xy 143.236431 -209.552124) (xy 143.071254 -209.522091) (xy 142.904827 -209.500011)
			(xy 142.737533 -209.485936) (xy 142.569756 -209.479898) (xy 142.401883 -209.481911) (xy 142.2343 -209.491971)
			(xy 142.067391 -209.510053) (xy 141.901542 -209.536117) (xy 141.737132 -209.570103) (xy 141.574542 -209.611932)
			(xy 141.414143 -209.661509) (xy 141.256307 -209.718719) (xy 141.101394 -209.783431) (xy 140.949763 -209.855495)
			(xy 140.80176 -209.934746) (xy 140.657728 -210.021003) (xy 140.517997 -210.114065) (xy 140.382889 -210.21372)
			(xy 140.252713 -210.319739) (xy 140.127771 -210.431876) (xy 140.008349 -210.549875) (xy 139.894721 -210.673464)
			(xy 139.78715 -210.802358) (xy 139.685882 -210.936262) (xy 139.59115 -211.074867) (xy 139.503173 -211.217855)
			(xy 139.422153 -211.364896) (xy 139.348275 -211.515653) (xy 139.281711 -211.669778) (xy 139.222613 -211.826918)
			(xy 139.171116 -211.98671) (xy 139.127341 -212.148787) (xy 139.091386 -212.312777) (xy 139.063335 -212.478303)
			(xy 139.043252 -212.644982) (xy 139.031184 -212.812433) (xy 139.027159 -212.98027) (xy 140.012424 -212.98027)
			(xy 140.016453 -212.837963) (xy 140.028526 -212.696113) (xy 140.048605 -212.555172) (xy 140.076626 -212.415594)
			(xy 140.112498 -212.277824) (xy 140.156108 -212.142304) (xy 140.207314 -212.009469) (xy 140.265954 -211.879743)
			(xy 140.331839 -211.753543) (xy 140.404758 -211.631272) (xy 140.484478 -211.513322) (xy 140.570744 -211.400072)
			(xy 140.663278 -211.291883) (xy 140.761785 -211.189103) (xy 140.865949 -211.09206) (xy 140.975436 -211.001066)
			(xy 141.089896 -210.916412) (xy 141.208961 -210.838369) (xy 141.332252 -210.767188) (xy 141.459372 -210.703095)
			(xy 141.589914 -210.646297) (xy 141.723461 -210.596975) (xy 141.859585 -210.555288) (xy 141.997848 -210.521369)
			(xy 142.137809 -210.495326) (xy 142.27902 -210.477243) (xy 142.421027 -210.467178) (xy 142.563376 -210.465164)
			(xy 142.705612 -210.471206) (xy 142.847277 -210.485285) (xy 142.987919 -210.507357) (xy 143.127088 -210.53735)
			(xy 143.264336 -210.575168) (xy 143.399225 -210.620691) (xy 143.531323 -210.673772) (xy 143.660206 -210.734242)
			(xy 143.785461 -210.801906) (xy 143.906688 -210.876548) (xy 144.023497 -210.957929) (xy 144.135516 -211.045789)
			(xy 144.242384 -211.139845) (xy 144.34376 -211.239796) (xy 144.439319 -211.345323) (xy 144.528754 -211.456087)
			(xy 144.61178 -211.571733) (xy 144.688131 -211.691891) (xy 144.757561 -211.816177) (xy 144.819848 -211.944191)
			(xy 144.874793 -212.075524) (xy 144.92222 -212.209755) (xy 144.961977 -212.346455) (xy 144.993936 -212.485185)
			(xy 145.017996 -212.625501) (xy 145.034078 -212.766953) (xy 145.042133 -212.909088) (xy 145.042636 -212.98027)
			(xy 145.042133 -213.051452) (xy 145.034078 -213.193587) (xy 145.017996 -213.335039) (xy 144.993936 -213.475355)
			(xy 144.961977 -213.614085) (xy 144.92222 -213.750785) (xy 144.874793 -213.885016) (xy 144.819848 -214.016349)
			(xy 144.757561 -214.144363) (xy 144.688131 -214.268649) (xy 144.61178 -214.388807) (xy 144.528754 -214.504453)
			(xy 144.439319 -214.615217) (xy 144.34376 -214.720744) (xy 144.242384 -214.820695) (xy 144.135516 -214.914751)
			(xy 144.023497 -215.002611) (xy 143.906688 -215.083992) (xy 143.785461 -215.158634) (xy 143.660206 -215.226298)
			(xy 143.531323 -215.286768) (xy 143.399225 -215.339849) (xy 143.264336 -215.385372) (xy 143.127088 -215.42319)
			(xy 142.987919 -215.453183) (xy 142.847277 -215.475255) (xy 142.705612 -215.489334) (xy 142.563376 -215.495376)
			(xy 142.421027 -215.493362) (xy 142.27902 -215.483297) (xy 142.137809 -215.465214) (xy 141.997848 -215.439171)
			(xy 141.859585 -215.405252) (xy 141.723461 -215.363565) (xy 141.589914 -215.314243) (xy 141.459372 -215.257445)
			(xy 141.332252 -215.193352) (xy 141.208961 -215.122171) (xy 141.089896 -215.044128) (xy 140.975436 -214.959474)
			(xy 140.865949 -214.86848) (xy 140.761785 -214.771437) (xy 140.663278 -214.668657) (xy 140.570744 -214.560468)
			(xy 140.484478 -214.447218) (xy 140.404758 -214.329268) (xy 140.331839 -214.206997) (xy 140.265954 -214.080797)
			(xy 140.207314 -213.951071) (xy 140.156108 -213.818236) (xy 140.112498 -213.682716) (xy 140.076626 -213.544946)
			(xy 140.048605 -213.405368) (xy 140.028526 -213.264427) (xy 140.016453 -213.122577) (xy 140.012424 -212.98027)
			(xy 139.027159 -212.98027) (xy 139.031184 -213.148107) (xy 139.043252 -213.315558) (xy 139.063335 -213.482237)
			(xy 139.091386 -213.647763) (xy 139.127341 -213.811753) (xy 139.171116 -213.97383) (xy 139.222613 -214.133622)
			(xy 139.281711 -214.290762) (xy 139.348275 -214.444887) (xy 139.422153 -214.595644) (xy 139.503173 -214.742685)
			(xy 139.59115 -214.885673) (xy 139.685882 -215.024278) (xy 139.78715 -215.158182) (xy 139.894721 -215.287076)
			(xy 140.008349 -215.410665) (xy 140.127771 -215.528664) (xy 140.252713 -215.640801) (xy 140.382889 -215.74682)
			(xy 140.517997 -215.846475) (xy 140.657728 -215.939537) (xy 140.80176 -216.025794) (xy 140.949763 -216.105045)
			(xy 141.101394 -216.177109) (xy 141.256307 -216.241821) (xy 141.414143 -216.299031) (xy 141.574542 -216.348608)
			(xy 141.737132 -216.390437) (xy 141.901542 -216.424423) (xy 142.067391 -216.450487) (xy 142.2343 -216.468569)
			(xy 142.401883 -216.478629) (xy 142.569756 -216.480642) (xy 142.737533 -216.474604) (xy 142.904827 -216.460529)
			(xy 143.071254 -216.438449) (xy 143.236431 -216.408416) (xy 143.399978 -216.370497) (xy 143.561519 -216.324781)
			(xy 143.720682 -216.271372) (xy 143.877102 -216.210394) (xy 144.030418 -216.141986) (xy 144.180278 -216.066307)
			(xy 144.326337 -215.983529) (xy 144.468259 -215.893844) (xy 144.605719 -215.797457) (xy 144.738399 -215.694591)
			(xy 144.865994 -215.585482) (xy 144.988212 -215.470381) (xy 145.10477 -215.349552) (xy 145.215401 -215.223274)
			(xy 145.319851 -215.091837) (xy 145.417879 -214.955543) (xy 145.50926 -214.814706) (xy 145.593783 -214.66965)
			(xy 145.671254 -214.520708) (xy 145.741495 -214.368223) (xy 145.804344 -214.212546) (xy 145.859657 -214.054035)
			(xy 145.907307 -213.893054) (xy 145.947184 -213.729973) (xy 145.979196 -213.565168) (xy 146.00327 -213.399018)
			(xy 146.01935 -213.231905) (xy 146.027399 -213.064213)
		)
		(stroke
			(width 0)
			(type solid)
		)
		(fill yes)
		(layer "F.Cu")
		(net "Net_1981")
	)
	(gr_poly
		(pts
			(xy 157.528006 -258.880356) (xy 157.527503 -258.796413) (xy 157.519454 -258.628721) (xy 157.503374 -258.461608)
			(xy 157.4793 -258.295458) (xy 157.447288 -258.130653) (xy 157.407411 -257.967572) (xy 157.359761 -257.806591)
			(xy 157.304448 -257.64808) (xy 157.241599 -257.492403) (xy 157.171358 -257.339918) (xy 157.093887 -257.190976)
			(xy 157.009364 -257.04592) (xy 156.917983 -256.905083) (xy 156.819955 -256.768789) (xy 156.715505 -256.637352)
			(xy 156.604874 -256.511074) (xy 156.488316 -256.390245) (xy 156.366098 -256.275144) (xy 156.238503 -256.166035)
			(xy 156.105823 -256.063169) (xy 155.968363 -255.966782) (xy 155.826441 -255.877097) (xy 155.680382 -255.794319)
			(xy 155.530522 -255.71864) (xy 155.377206 -255.650232) (xy 155.220786 -255.589254) (xy 155.061623 -255.535845)
			(xy 154.900082 -255.490129) (xy 154.736535 -255.45221) (xy 154.571358 -255.422177) (xy 154.404931 -255.400097)
			(xy 154.237637 -255.386022) (xy 154.06986 -255.379984) (xy 153.901987 -255.381997) (xy 153.734404 -255.392057)
			(xy 153.567495 -255.410139) (xy 153.401646 -255.436203) (xy 153.237236 -255.470189) (xy 153.074646 -255.512018)
			(xy 152.914247 -255.561595) (xy 152.756411 -255.618805) (xy 152.601498 -255.683517) (xy 152.449867 -255.755581)
			(xy 152.301864 -255.834832) (xy 152.157832 -255.921089) (xy 152.018101 -256.014151) (xy 151.882993 -256.113806)
			(xy 151.752817 -256.219825) (xy 151.627875 -256.331962) (xy 151.508453 -256.449961) (xy 151.394825 -256.57355)
			(xy 151.287254 -256.702444) (xy 151.185986 -256.836348) (xy 151.091254 -256.974953) (xy 151.003277 -257.117941)
			(xy 150.922257 -257.264982) (xy 150.848379 -257.415739) (xy 150.781815 -257.569864) (xy 150.722717 -257.727004)
			(xy 150.67122 -257.886796) (xy 150.627445 -258.048873) (xy 150.59149 -258.212863) (xy 150.563439 -258.378389)
			(xy 150.543356 -258.545068) (xy 150.531288 -258.712519) (xy 150.527263 -258.880356) (xy 151.512783 -258.880356)
			(xy 151.516811 -258.738064) (xy 151.528883 -258.596228) (xy 151.54896 -258.455301) (xy 151.576978 -258.315737)
			(xy 151.612847 -258.177981) (xy 151.656452 -258.042475) (xy 151.707653 -257.909653) (xy 151.766287 -257.77994)
			(xy 151.832165 -257.653753) (xy 151.905077 -257.531494) (xy 151.984789 -257.413557) (xy 152.071046 -257.300318)
			(xy 152.16357 -257.19214) (xy 152.262067 -257.08937) (xy 152.366221 -256.992337) (xy 152.475697 -256.901353)
			(xy 152.590145 -256.816707) (xy 152.709199 -256.738672) (xy 152.832477 -256.667498) (xy 152.959584 -256.603411)
			(xy 153.090113 -256.546619) (xy 153.223647 -256.497302) (xy 153.359756 -256.455619) (xy 153.498006 -256.421703)
			(xy 153.637953 -256.395663) (xy 153.779149 -256.377582) (xy 153.921142 -256.367519) (xy 154.063477 -256.365504)
			(xy 154.205698 -256.371546) (xy 154.347349 -256.385624) (xy 154.487977 -256.407693) (xy 154.627131 -256.437683)
			(xy 154.764366 -256.475498) (xy 154.899241 -256.521016) (xy 155.031325 -256.574092) (xy 155.160195 -256.634555)
			(xy 155.285438 -256.702212) (xy 155.406652 -256.776847) (xy 155.52345 -256.85822) (xy 155.635457 -256.94607)
			(xy 155.742315 -257.040117) (xy 155.84368 -257.140058) (xy 155.939229 -257.245574) (xy 156.028656 -257.356327)
			(xy 156.111674 -257.471961) (xy 156.188016 -257.592108) (xy 156.257439 -257.71638) (xy 156.31972 -257.844382)
			(xy 156.37466 -257.975702) (xy 156.422082 -258.109919) (xy 156.461835 -258.246605) (xy 156.493791 -258.385321)
			(xy 156.517848 -258.525622) (xy 156.533929 -258.66706) (xy 156.541982 -258.809181) (xy 156.542486 -258.880356)
			(xy 156.541982 -258.951531) (xy 156.533929 -259.093652) (xy 156.517848 -259.23509) (xy 156.493791 -259.375391)
			(xy 156.461835 -259.514107) (xy 156.422082 -259.650793) (xy 156.37466 -259.78501) (xy 156.31972 -259.91633)
			(xy 156.257439 -260.044332) (xy 156.188016 -260.168604) (xy 156.111674 -260.288751) (xy 156.028656 -260.404385)
			(xy 155.939229 -260.515138) (xy 155.84368 -260.620654) (xy 155.742315 -260.720595) (xy 155.635457 -260.814642)
			(xy 155.52345 -260.902492) (xy 155.406652 -260.983865) (xy 155.285438 -261.0585) (xy 155.160195 -261.126157)
			(xy 155.031325 -261.18662) (xy 154.899241 -261.239696) (xy 154.764366 -261.285214) (xy 154.627131 -261.323029)
			(xy 154.487977 -261.353019) (xy 154.347349 -261.375088) (xy 154.205698 -261.389166) (xy 154.063477 -261.395208)
			(xy 153.921142 -261.393193) (xy 153.779149 -261.38313) (xy 153.637953 -261.365049) (xy 153.498006 -261.339009)
			(xy 153.359756 -261.305093) (xy 153.223647 -261.26341) (xy 153.090113 -261.214093) (xy 152.959584 -261.157301)
			(xy 152.832477 -261.093214) (xy 152.709199 -261.02204) (xy 152.590145 -260.944005) (xy 152.475697 -260.859359)
			(xy 152.366221 -260.768375) (xy 152.262067 -260.671342) (xy 152.16357 -260.568572) (xy 152.071046 -260.460394)
			(xy 151.984789 -260.347155) (xy 151.905077 -260.229218) (xy 151.832165 -260.106959) (xy 151.766287 -259.980772)
			(xy 151.707653 -259.851059) (xy 151.656452 -259.718237) (xy 151.612847 -259.582731) (xy 151.576978 -259.444975)
			(xy 151.54896 -259.305411) (xy 151.528883 -259.164484) (xy 151.516811 -259.022648) (xy 151.512783 -258.880356)
			(xy 150.527263 -258.880356) (xy 150.531288 -259.048193) (xy 150.543356 -259.215644) (xy 150.563439 -259.382323)
			(xy 150.59149 -259.547849) (xy 150.627445 -259.711839) (xy 150.67122 -259.873916) (xy 150.722717 -260.033708)
			(xy 150.781815 -260.190848) (xy 150.848379 -260.344973) (xy 150.922257 -260.49573) (xy 151.003277 -260.642771)
			(xy 151.091254 -260.785759) (xy 151.185986 -260.924364) (xy 151.287254 -261.058268) (xy 151.394825 -261.187162)
			(xy 151.508453 -261.310751) (xy 151.627875 -261.42875) (xy 151.752817 -261.540887) (xy 151.882993 -261.646906)
			(xy 152.018101 -261.746561) (xy 152.157832 -261.839623) (xy 152.301864 -261.92588) (xy 152.449867 -262.005131)
			(xy 152.601498 -262.077195) (xy 152.756411 -262.141907) (xy 152.914247 -262.199117) (xy 153.074646 -262.248694)
			(xy 153.237236 -262.290523) (xy 153.401646 -262.324509) (xy 153.567495 -262.350573) (xy 153.734404 -262.368655)
			(xy 153.901987 -262.378715) (xy 154.06986 -262.380728) (xy 154.237637 -262.37469) (xy 154.404931 -262.360615)
			(xy 154.571358 -262.338535) (xy 154.736535 -262.308502) (xy 154.900082 -262.270583) (xy 155.061623 -262.224867)
			(xy 155.220786 -262.171458) (xy 155.377206 -262.11048) (xy 155.530522 -262.042072) (xy 155.680382 -261.966393)
			(xy 155.826441 -261.883615) (xy 155.968363 -261.79393) (xy 156.105823 -261.697543) (xy 156.238503 -261.594677)
			(xy 156.366098 -261.485568) (xy 156.488316 -261.370467) (xy 156.604874 -261.249638) (xy 156.715505 -261.12336)
			(xy 156.819955 -260.991923) (xy 156.917983 -260.855629) (xy 157.009364 -260.714792) (xy 157.093887 -260.569736)
			(xy 157.171358 -260.420794) (xy 157.241599 -260.268309) (xy 157.304448 -260.112632) (xy 157.359761 -259.954121)
			(xy 157.407411 -259.79314) (xy 157.447288 -259.630059) (xy 157.4793 -259.465254) (xy 157.503374 -259.299104)
			(xy 157.519454 -259.131991) (xy 157.527503 -258.964299)
		)
		(stroke
			(width 0)
			(type solid)
		)
		(fill yes)
		(layer "F.Cu")
		(net "Net_1982")
	)
	(gr_poly
		(pts
			(xy 321.26809 -258.880102) (xy 321.267587 -258.796159) (xy 321.259538 -258.628467) (xy 321.243458 -258.461354)
			(xy 321.219384 -258.295204) (xy 321.187372 -258.130399) (xy 321.147495 -257.967318) (xy 321.099845 -257.806337)
			(xy 321.044532 -257.647826) (xy 320.981683 -257.492149) (xy 320.911442 -257.339664) (xy 320.833971 -257.190722)
			(xy 320.749448 -257.045666) (xy 320.658067 -256.904829) (xy 320.560039 -256.768535) (xy 320.455589 -256.637098)
			(xy 320.344958 -256.51082) (xy 320.2284 -256.389991) (xy 320.106182 -256.27489) (xy 319.978587 -256.165781)
			(xy 319.845907 -256.062915) (xy 319.708447 -255.966528) (xy 319.566525 -255.876843) (xy 319.420466 -255.794065)
			(xy 319.270606 -255.718386) (xy 319.11729 -255.649978) (xy 318.96087 -255.589) (xy 318.801707 -255.535591)
			(xy 318.640166 -255.489875) (xy 318.476619 -255.451956) (xy 318.311442 -255.421923) (xy 318.145015 -255.399843)
			(xy 317.977721 -255.385768) (xy 317.809944 -255.37973) (xy 317.642071 -255.381743) (xy 317.474488 -255.391803)
			(xy 317.307579 -255.409885) (xy 317.14173 -255.435949) (xy 316.97732 -255.469935) (xy 316.81473 -255.511764)
			(xy 316.654331 -255.561341) (xy 316.496495 -255.618551) (xy 316.341582 -255.683263) (xy 316.189951 -255.755327)
			(xy 316.041948 -255.834578) (xy 315.897916 -255.920835) (xy 315.758185 -256.013897) (xy 315.623077 -256.113552)
			(xy 315.492901 -256.219571) (xy 315.367959 -256.331708) (xy 315.248537 -256.449707) (xy 315.134909 -256.573296)
			(xy 315.027338 -256.70219) (xy 314.92607 -256.836094) (xy 314.831338 -256.974699) (xy 314.743361 -257.117687)
			(xy 314.662341 -257.264728) (xy 314.588463 -257.415485) (xy 314.521899 -257.56961) (xy 314.462801 -257.72675)
			(xy 314.411304 -257.886542) (xy 314.367529 -258.048619) (xy 314.331574 -258.212609) (xy 314.303523 -258.378135)
			(xy 314.28344 -258.544814) (xy 314.271372 -258.712265) (xy 314.267347 -258.880102) (xy 315.252867 -258.880102)
			(xy 315.256895 -258.73781) (xy 315.268967 -258.595974) (xy 315.289044 -258.455047) (xy 315.317062 -258.315483)
			(xy 315.352931 -258.177727) (xy 315.396536 -258.042221) (xy 315.447737 -257.909399) (xy 315.506371 -257.779686)
			(xy 315.572249 -257.653499) (xy 315.645161 -257.53124) (xy 315.724873 -257.413303) (xy 315.81113 -257.300064)
			(xy 315.903654 -257.191886) (xy 316.002151 -257.089116) (xy 316.106305 -256.992083) (xy 316.215781 -256.901099)
			(xy 316.330229 -256.816453) (xy 316.449283 -256.738418) (xy 316.572561 -256.667244) (xy 316.699668 -256.603157)
			(xy 316.830197 -256.546365) (xy 316.963731 -256.497048) (xy 317.09984 -256.455365) (xy 317.23809 -256.421449)
			(xy 317.378037 -256.395409) (xy 317.519233 -256.377328) (xy 317.661226 -256.367265) (xy 317.803561 -256.36525)
			(xy 317.945782 -256.371292) (xy 318.087433 -256.38537) (xy 318.228061 -256.407439) (xy 318.367215 -256.437429)
			(xy 318.50445 -256.475244) (xy 318.639325 -256.520762) (xy 318.771409 -256.573838) (xy 318.900279 -256.634301)
			(xy 319.025522 -256.701958) (xy 319.146736 -256.776593) (xy 319.263534 -256.857966) (xy 319.375541 -256.945816)
			(xy 319.482399 -257.039863) (xy 319.583764 -257.139804) (xy 319.679313 -257.24532) (xy 319.76874 -257.356073)
			(xy 319.851758 -257.471707) (xy 319.9281 -257.591854) (xy 319.997523 -257.716126) (xy 320.059804 -257.844128)
			(xy 320.114744 -257.975448) (xy 320.162166 -258.109665) (xy 320.201919 -258.246351) (xy 320.233875 -258.385067)
			(xy 320.257932 -258.525368) (xy 320.274013 -258.666806) (xy 320.282066 -258.808927) (xy 320.28257 -258.880102)
			(xy 320.282066 -258.951277) (xy 320.274013 -259.093398) (xy 320.257932 -259.234836) (xy 320.233875 -259.375137)
			(xy 320.201919 -259.513853) (xy 320.162166 -259.650539) (xy 320.114744 -259.784756) (xy 320.059804 -259.916076)
			(xy 319.997523 -260.044078) (xy 319.9281 -260.16835) (xy 319.851758 -260.288497) (xy 319.76874 -260.404131)
			(xy 319.679313 -260.514884) (xy 319.583764 -260.6204) (xy 319.482399 -260.720341) (xy 319.375541 -260.814388)
			(xy 319.263534 -260.902238) (xy 319.146736 -260.983611) (xy 319.025522 -261.058246) (xy 318.900279 -261.125903)
			(xy 318.771409 -261.186366) (xy 318.639325 -261.239442) (xy 318.50445 -261.28496) (xy 318.367215 -261.322775)
			(xy 318.228061 -261.352765) (xy 318.087433 -261.374834) (xy 317.945782 -261.388912) (xy 317.803561 -261.394954)
			(xy 317.661226 -261.392939) (xy 317.519233 -261.382876) (xy 317.378037 -261.364795) (xy 317.23809 -261.338755)
			(xy 317.09984 -261.304839) (xy 316.963731 -261.263156) (xy 316.830197 -261.213839) (xy 316.699668 -261.157047)
			(xy 316.572561 -261.09296) (xy 316.449283 -261.021786) (xy 316.330229 -260.943751) (xy 316.215781 -260.859105)
			(xy 316.106305 -260.768121) (xy 316.002151 -260.671088) (xy 315.903654 -260.568318) (xy 315.81113 -260.46014)
			(xy 315.724873 -260.346901) (xy 315.645161 -260.228964) (xy 315.572249 -260.106705) (xy 315.506371 -259.980518)
			(xy 315.447737 -259.850805) (xy 315.396536 -259.717983) (xy 315.352931 -259.582477) (xy 315.317062 -259.444721)
			(xy 315.289044 -259.305157) (xy 315.268967 -259.16423) (xy 315.256895 -259.022394) (xy 315.252867 -258.880102)
			(xy 314.267347 -258.880102) (xy 314.271372 -259.047939) (xy 314.28344 -259.21539) (xy 314.303523 -259.382069)
			(xy 314.331574 -259.547595) (xy 314.367529 -259.711585) (xy 314.411304 -259.873662) (xy 314.462801 -260.033454)
			(xy 314.521899 -260.190594) (xy 314.588463 -260.344719) (xy 314.662341 -260.495476) (xy 314.743361 -260.642517)
			(xy 314.831338 -260.785505) (xy 314.92607 -260.92411) (xy 315.027338 -261.058014) (xy 315.134909 -261.186908)
			(xy 315.248537 -261.310497) (xy 315.367959 -261.428496) (xy 315.492901 -261.540633) (xy 315.623077 -261.646652)
			(xy 315.758185 -261.746307) (xy 315.897916 -261.839369) (xy 316.041948 -261.925626) (xy 316.189951 -262.004877)
			(xy 316.341582 -262.076941) (xy 316.496495 -262.141653) (xy 316.654331 -262.198863) (xy 316.81473 -262.24844)
			(xy 316.97732 -262.290269) (xy 317.14173 -262.324255) (xy 317.307579 -262.350319) (xy 317.474488 -262.368401)
			(xy 317.642071 -262.378461) (xy 317.809944 -262.380474) (xy 317.977721 -262.374436) (xy 318.145015 -262.360361)
			(xy 318.311442 -262.338281) (xy 318.476619 -262.308248) (xy 318.640166 -262.270329) (xy 318.801707 -262.224613)
			(xy 318.96087 -262.171204) (xy 319.11729 -262.110226) (xy 319.270606 -262.041818) (xy 319.420466 -261.966139)
			(xy 319.566525 -261.883361) (xy 319.708447 -261.793676) (xy 319.845907 -261.697289) (xy 319.978587 -261.594423)
			(xy 320.106182 -261.485314) (xy 320.2284 -261.370213) (xy 320.344958 -261.249384) (xy 320.455589 -261.123106)
			(xy 320.560039 -260.991669) (xy 320.658067 -260.855375) (xy 320.749448 -260.714538) (xy 320.833971 -260.569482)
			(xy 320.911442 -260.42054) (xy 320.981683 -260.268055) (xy 321.044532 -260.112378) (xy 321.099845 -259.953867)
			(xy 321.147495 -259.792886) (xy 321.187372 -259.629805) (xy 321.219384 -259.465) (xy 321.243458 -259.29885)
			(xy 321.259538 -259.131737) (xy 321.267587 -258.964045)
		)
		(stroke
			(width 0)
			(type solid)
		)
		(fill yes)
		(layer "F.Cu")
		(net "Net_1776")
	)
	(gr_poly
		(pts
			(arc
				(start 327.25741 -394.686282)
				(mid 327.276933 -394.682381)
				(end 327.293478 -394.671296)
			)
			(arc
				(start 327.402952 -394.561822)
				(mid 327.414063 -394.545288)
				(end 327.417938 -394.525754)
			)
			(arc
				(start 327.417938 -394.27023)
				(mid 327.421839 -394.250707)
				(end 327.432924 -394.234162)
			)
			(arc
				(start 327.549002 -394.118084)
				(mid 327.560064 -394.101667)
				(end 327.563988 -394.08227)
			)
			(arc
				(start 327.563988 -394.0175)
				(mid 327.601244 -393.927428)
				(end 327.691242 -393.889992)
			)
			(xy 327.753218 -393.889992)
			(arc
				(start 327.762616 -393.886182)
				(mid 327.820978 -393.868198)
				(end 327.881742 -393.862052)
			)
			(arc
				(start 327.881742 -393.862052)
				(mid 327.942513 -393.868161)
				(end 328.000868 -393.886182)
			)
			(xy 328.010266 -393.889992)
			(arc
				(start 328.072242 -393.889992)
				(mid 328.149639 -393.916169)
				(end 328.195178 -393.983972)
			)
			(xy 328.19975 -394.000482) (xy 328.226928 -394.02131) (xy 328.349356 -394.02131) (xy 328.376534 -394.000482)
			(arc
				(start 328.381106 -393.983972)
				(mid 328.426695 -393.916234)
				(end 328.504042 -393.889992)
			)
			(xy 328.566018 -393.889992)
			(arc
				(start 328.575416 -393.886182)
				(mid 328.633778 -393.868198)
				(end 328.694542 -393.862052)
			)
			(arc
				(start 328.694542 -393.862052)
				(mid 328.755313 -393.868161)
				(end 328.813668 -393.886182)
			)
			(xy 328.823066 -393.889992)
			(arc
				(start 328.885042 -393.889992)
				(mid 328.962439 -393.916169)
				(end 329.007978 -393.983972)
			)
			(xy 329.01255 -394.000482) (xy 329.039728 -394.02131) (xy 329.11034 -394.02131) (xy 329.126342 -394.015976)
			(arc
				(start 329.1332 -394.010642)
				(mid 329.316793 -393.911566)
				(end 329.522582 -393.877292)
			)
			(arc
				(start 329.522582 -393.877292)
				(mid 329.690756 -393.899878)
				(end 329.84694 -393.966192)
			)
			(arc
				(start 329.84694 -393.966192)
				(mid 329.859416 -393.971488)
				(end 329.872848 -393.973304)
			)
			(arc
				(start 330.408534 -393.973304)
				(mid 330.444455 -393.958425)
				(end 330.459334 -393.922504)
			)
			(arc
				(start 330.459334 -393.622784)
				(mid 330.452072 -393.596609)
				(end 330.43241 -393.577826)
			)
			(arc
				(start 330.43241 -393.577826)
				(mid 330.292522 -393.47606)
				(end 330.185268 -393.340336)
			)
			(arc
				(start 330.185268 -393.340336)
				(mid 330.166609 -393.322046)
				(end 330.141326 -393.315444)
			)
			(arc
				(start 330.05395 -393.315444)
				(mid 330.028663 -393.322039)
				(end 330.010008 -393.340336)
			)
			(arc
				(start 330.010008 -393.340336)
				(mid 329.777883 -393.569488)
				(end 329.462638 -393.653264)
			)
			(arc
				(start 329.462638 -393.653264)
				(mid 328.82713 -393.017756)
				(end 329.462638 -392.382248)
			)
			(arc
				(start 329.462638 -392.382248)
				(mid 329.630381 -392.404855)
				(end 329.786234 -392.470894)
			)
			(arc
				(start 329.786234 -392.470894)
				(mid 329.818567 -392.47759)
				(end 329.84821 -392.46302)
			)
			(xy 330.225908 -392.085322) (xy 330.232766 -392.072368)
			(arc
				(start 330.23429 -392.064748)
				(mid 330.241847 -392.034963)
				(end 330.252324 -392.006074)
			)
			(xy 330.256388 -391.996676) (xy 330.256388 -391.9347) (xy 330.25715 -391.920476) (xy 330.257404 -391.917682)
			(arc
				(start 330.257404 -391.914888)
				(mid 330.242525 -391.878967)
				(end 330.206604 -391.864088)
			)
			(xy 329.488038 -391.864088) (xy 329.46213 -391.881614)
			(arc
				(start 329.456542 -391.896346)
				(mid 329.222822 -392.18853)
				(end 328.86523 -392.298682)
			)
			(arc
				(start 328.86523 -392.298682)
				(mid 328.415858 -392.112546)
				(end 328.229722 -391.663174)
			)
			(arc
				(start 328.229722 -391.663174)
				(mid 328.234125 -391.588492)
				(end 328.247248 -391.514838)
			)
			(xy 328.25055 -391.50163) (xy 328.243438 -391.476484)
			(arc
				(start 327.803764 -391.037064)
				(mid 327.780924 -391.011464)
				(end 327.761092 -390.98347)
			)
			(arc
				(start 327.761092 -390.98347)
				(mid 327.742666 -390.966139)
				(end 327.718166 -390.959848)
			)
			(arc
				(start 327.15454 -390.959848)
				(mid 327.135046 -390.963632)
				(end 327.118472 -390.97458)
			)
			(arc
				(start 327.090786 -391.00252)
				(mid 327.079724 -391.018937)
				(end 327.0758 -391.038334)
			)
			(arc
				(start 327.0758 -391.461244)
				(mid 327.071899 -391.480767)
				(end 327.060814 -391.497312)
			)
			(arc
				(start 326.787002 -391.771124)
				(mid 326.775891 -391.787658)
				(end 326.772016 -391.807192)
			)
			(arc
				(start 326.772016 -394.582904)
				(mid 326.775917 -394.602427)
				(end 326.787002 -394.618972)
			)
			(arc
				(start 326.839326 -394.671296)
				(mid 326.85586 -394.682407)
				(end 326.875394 -394.686282)
			)
		)
		(stroke
			(width 0)
			(type solid)
		)
		(fill yes)
		(layer "F.Cu")
		(net "P1V8_CPU0_RT_1D")
	)
	(gr_poly
		(pts
			(xy 332.76794 -304.780188) (xy 332.767437 -304.696252) (xy 332.759388 -304.528572) (xy 332.74331 -304.36147)
			(xy 332.719238 -304.195332) (xy 332.687228 -304.030539) (xy 332.647354 -303.867471) (xy 332.599708 -303.706501)
			(xy 332.544398 -303.548001) (xy 332.481554 -303.392335) (xy 332.411318 -303.239861) (xy 332.333852 -303.09093)
			(xy 332.249335 -302.945885) (xy 332.157961 -302.805058) (xy 332.059941 -302.668774) (xy 331.955498 -302.537347)
			(xy 331.844875 -302.411078) (xy 331.728325 -302.290258) (xy 331.606117 -302.175165) (xy 331.47853 -302.066064)
			(xy 331.34586 -301.963205) (xy 331.208411 -301.866826) (xy 331.066498 -301.777147) (xy 330.92045 -301.694375)
			(xy 330.770601 -301.618701) (xy 330.617296 -301.550298) (xy 330.460887 -301.489324) (xy 330.301736 -301.43592)
			(xy 330.140207 -301.390207) (xy 329.976671 -301.352291) (xy 329.811506 -301.32226) (xy 329.645092 -301.300182)
			(xy 329.47781 -301.286108) (xy 329.310045 -301.28007) (xy 329.142184 -301.282083) (xy 328.974613 -301.292142)
			(xy 328.807717 -301.310223) (xy 328.641879 -301.336285) (xy 328.477482 -301.370269) (xy 328.314903 -301.412095)
			(xy 328.154516 -301.461668) (xy 327.996691 -301.518874) (xy 327.84179 -301.58358) (xy 327.690169 -301.65564)
			(xy 327.542178 -301.734885) (xy 327.398156 -301.821135) (xy 327.258435 -301.914191) (xy 327.123336 -302.013839)
			(xy 326.99317 -302.11985) (xy 326.868237 -302.231979) (xy 326.748823 -302.349969) (xy 326.635204 -302.473549)
			(xy 326.52764 -302.602434) (xy 326.42638 -302.736329) (xy 326.331655 -302.874924) (xy 326.243685 -303.017901)
			(xy 326.16267 -303.164931) (xy 326.088798 -303.315677) (xy 326.022239 -303.469791) (xy 325.963145 -303.626919)
			(xy 325.911652 -303.7867) (xy 325.867879 -303.948766) (xy 325.831927 -304.112744) (xy 325.803878 -304.278257)
			(xy 325.783797 -304.444925) (xy 325.77173 -304.612363) (xy 325.767705 -304.780188) (xy 326.753225 -304.780188)
			(xy 326.757252 -304.63791) (xy 326.769323 -304.496088) (xy 326.789398 -304.355176) (xy 326.817413 -304.215626)
			(xy 326.853279 -304.077884) (xy 326.896879 -303.942392) (xy 326.948075 -303.809583) (xy 327.006703 -303.679883)
			(xy 327.072575 -303.553709) (xy 327.145479 -303.431463) (xy 327.225183 -303.313537) (xy 327.311431 -303.200309)
			(xy 327.403947 -303.092143) (xy 327.502434 -302.989383) (xy 327.606577 -302.89236) (xy 327.716042 -302.801384)
			(xy 327.830478 -302.716748) (xy 327.94952 -302.63872) (xy 328.072786 -302.567553) (xy 328.19988 -302.503473)
			(xy 328.330396 -302.446687) (xy 328.463916 -302.397375) (xy 328.600012 -302.355696) (xy 328.738247 -302.321784)
			(xy 328.87818 -302.295746) (xy 329.019362 -302.277667) (xy 329.161341 -302.267604) (xy 329.303661 -302.26559)
			(xy 329.445868 -302.271631) (xy 329.587505 -302.285708) (xy 329.728118 -302.307775) (xy 329.867258 -302.337762)
			(xy 330.004479 -302.375573) (xy 330.139341 -302.421086) (xy 330.271412 -302.474157) (xy 330.400269 -302.534614)
			(xy 330.525499 -302.602264) (xy 330.646701 -302.676892) (xy 330.763487 -302.758256) (xy 330.875483 -302.846098)
			(xy 330.982329 -302.940135) (xy 331.083685 -303.040066) (xy 331.179224 -303.145571) (xy 331.268642 -303.256313)
			(xy 331.351651 -303.371936) (xy 331.427986 -303.49207) (xy 331.497402 -303.61633) (xy 331.559677 -303.744318)
			(xy 331.614611 -303.875625) (xy 331.662028 -304.009829) (xy 331.701777 -304.146501) (xy 331.73373 -304.285203)
			(xy 331.757784 -304.42549) (xy 331.773864 -304.566914) (xy 331.781916 -304.709021) (xy 331.78242 -304.780188)
			(xy 331.781916 -304.851355) (xy 331.773864 -304.993462) (xy 331.757784 -305.134886) (xy 331.73373 -305.275173)
			(xy 331.701777 -305.413875) (xy 331.662028 -305.550547) (xy 331.614611 -305.684751) (xy 331.559677 -305.816058)
			(xy 331.497402 -305.944046) (xy 331.427986 -306.068306) (xy 331.351651 -306.18844) (xy 331.268642 -306.304063)
			(xy 331.179224 -306.414805) (xy 331.083685 -306.52031) (xy 330.982329 -306.620241) (xy 330.875483 -306.714278)
			(xy 330.763487 -306.80212) (xy 330.646701 -306.883484) (xy 330.525499 -306.958112) (xy 330.400269 -307.025762)
			(xy 330.271412 -307.086219) (xy 330.139341 -307.13929) (xy 330.004479 -307.184803) (xy 329.867258 -307.222614)
			(xy 329.728118 -307.252601) (xy 329.587505 -307.274668) (xy 329.445868 -307.288745) (xy 329.303661 -307.294786)
			(xy 329.161341 -307.292772) (xy 329.019362 -307.282709) (xy 328.87818 -307.26463) (xy 328.738247 -307.238592)
			(xy 328.600012 -307.20468) (xy 328.463916 -307.163001) (xy 328.330396 -307.113689) (xy 328.19988 -307.056903)
			(xy 328.072786 -306.992823) (xy 327.94952 -306.921656) (xy 327.830478 -306.843628) (xy 327.716042 -306.758992)
			(xy 327.606577 -306.668016) (xy 327.502434 -306.570993) (xy 327.403947 -306.468233) (xy 327.311431 -306.360067)
			(xy 327.225183 -306.246839) (xy 327.145479 -306.128913) (xy 327.072575 -306.006667) (xy 327.006703 -305.880493)
			(xy 326.948075 -305.750793) (xy 326.896879 -305.617984) (xy 326.853279 -305.482492) (xy 326.817413 -305.34475)
			(xy 326.789398 -305.2052) (xy 326.769323 -305.064288) (xy 326.757252 -304.922466) (xy 326.753225 -304.780188)
			(xy 325.767705 -304.780188) (xy 325.77173 -304.948013) (xy 325.783797 -305.115451) (xy 325.803878 -305.282119)
			(xy 325.831927 -305.447632) (xy 325.867879 -305.61161) (xy 325.911652 -305.773676) (xy 325.963145 -305.933457)
			(xy 326.022239 -306.090585) (xy 326.088798 -306.244699) (xy 326.16267 -306.395445) (xy 326.243685 -306.542475)
			(xy 326.331655 -306.685452) (xy 326.42638 -306.824047) (xy 326.52764 -306.957942) (xy 326.635204 -307.086827)
			(xy 326.748823 -307.210407) (xy 326.868237 -307.328397) (xy 326.99317 -307.440526) (xy 327.123336 -307.546537)
			(xy 327.258435 -307.646185) (xy 327.398156 -307.739241) (xy 327.542178 -307.825491) (xy 327.690169 -307.904736)
			(xy 327.84179 -307.976796) (xy 327.996691 -308.041502) (xy 328.154516 -308.098708) (xy 328.314903 -308.148281)
			(xy 328.477482 -308.190107) (xy 328.641879 -308.224091) (xy 328.807717 -308.250153) (xy 328.974613 -308.268234)
			(xy 329.142184 -308.278293) (xy 329.310045 -308.280306) (xy 329.47781 -308.274268) (xy 329.645092 -308.260194)
			(xy 329.811506 -308.238116) (xy 329.976671 -308.208085) (xy 330.140207 -308.170169) (xy 330.301736 -308.124456)
			(xy 330.460887 -308.071052) (xy 330.617296 -308.010078) (xy 330.770601 -307.941675) (xy 330.92045 -307.866001)
			(xy 331.066498 -307.783229) (xy 331.208411 -307.69355) (xy 331.34586 -307.597171) (xy 331.47853 -307.494312)
			(xy 331.606117 -307.385211) (xy 331.728325 -307.270118) (xy 331.844875 -307.149298) (xy 331.955498 -307.023029)
			(xy 332.059941 -306.891602) (xy 332.157961 -306.755318) (xy 332.249335 -306.614491) (xy 332.333852 -306.469446)
			(xy 332.411318 -306.320515) (xy 332.481554 -306.168041) (xy 332.544398 -306.012375) (xy 332.599708 -305.853875)
			(xy 332.647354 -305.692905) (xy 332.687228 -305.529837) (xy 332.719238 -305.365044) (xy 332.74331 -305.198906)
			(xy 332.759388 -305.031804) (xy 332.767437 -304.864124)
		)
		(stroke
			(width 0)
			(type solid)
		)
		(fill yes)
		(layer "F.Cu")
		(net "Net_1775")
	)
	(gr_poly
		(pts
			(xy 332.76794 -212.980016) (xy 332.767437 -212.89608) (xy 332.759388 -212.7284) (xy 332.74331 -212.561298)
			(xy 332.719238 -212.39516) (xy 332.687228 -212.230367) (xy 332.647354 -212.067299) (xy 332.599708 -211.906329)
			(xy 332.544398 -211.747829) (xy 332.481554 -211.592163) (xy 332.411318 -211.439689) (xy 332.333852 -211.290758)
			(xy 332.249335 -211.145713) (xy 332.157961 -211.004886) (xy 332.059941 -210.868602) (xy 331.955498 -210.737175)
			(xy 331.844875 -210.610906) (xy 331.728325 -210.490086) (xy 331.606117 -210.374993) (xy 331.47853 -210.265892)
			(xy 331.34586 -210.163033) (xy 331.208411 -210.066654) (xy 331.066498 -209.976975) (xy 330.92045 -209.894203)
			(xy 330.770601 -209.818529) (xy 330.617296 -209.750126) (xy 330.460887 -209.689152) (xy 330.301736 -209.635748)
			(xy 330.140207 -209.590035) (xy 329.976671 -209.552119) (xy 329.811506 -209.522088) (xy 329.645092 -209.50001)
			(xy 329.47781 -209.485936) (xy 329.310045 -209.479898) (xy 329.142184 -209.481911) (xy 328.974613 -209.49197)
			(xy 328.807717 -209.510051) (xy 328.641879 -209.536113) (xy 328.477482 -209.570097) (xy 328.314903 -209.611923)
			(xy 328.154516 -209.661496) (xy 327.996691 -209.718702) (xy 327.84179 -209.783408) (xy 327.690169 -209.855468)
			(xy 327.542178 -209.934713) (xy 327.398156 -210.020963) (xy 327.258435 -210.114019) (xy 327.123336 -210.213667)
			(xy 326.99317 -210.319678) (xy 326.868237 -210.431807) (xy 326.748823 -210.549797) (xy 326.635204 -210.673377)
			(xy 326.52764 -210.802262) (xy 326.42638 -210.936157) (xy 326.331655 -211.074752) (xy 326.243685 -211.217729)
			(xy 326.16267 -211.364759) (xy 326.088798 -211.515505) (xy 326.022239 -211.669619) (xy 325.963145 -211.826747)
			(xy 325.911652 -211.986528) (xy 325.867879 -212.148594) (xy 325.831927 -212.312572) (xy 325.803878 -212.478085)
			(xy 325.783797 -212.644753) (xy 325.77173 -212.812191) (xy 325.767705 -212.980016) (xy 326.753225 -212.980016)
			(xy 326.757252 -212.837738) (xy 326.769323 -212.695916) (xy 326.789398 -212.555004) (xy 326.817413 -212.415454)
			(xy 326.853279 -212.277712) (xy 326.896879 -212.14222) (xy 326.948075 -212.009411) (xy 327.006703 -211.879711)
			(xy 327.072575 -211.753537) (xy 327.145479 -211.631291) (xy 327.225183 -211.513365) (xy 327.311431 -211.400137)
			(xy 327.403947 -211.291971) (xy 327.502434 -211.189211) (xy 327.606577 -211.092188) (xy 327.716042 -211.001212)
			(xy 327.830478 -210.916576) (xy 327.94952 -210.838548) (xy 328.072786 -210.767381) (xy 328.19988 -210.703301)
			(xy 328.330396 -210.646515) (xy 328.463916 -210.597203) (xy 328.600012 -210.555524) (xy 328.738247 -210.521612)
			(xy 328.87818 -210.495574) (xy 329.019362 -210.477495) (xy 329.161341 -210.467432) (xy 329.303661 -210.465418)
			(xy 329.445868 -210.471459) (xy 329.587505 -210.485536) (xy 329.728118 -210.507603) (xy 329.867258 -210.53759)
			(xy 330.004479 -210.575401) (xy 330.139341 -210.620914) (xy 330.271412 -210.673985) (xy 330.400269 -210.734442)
			(xy 330.525499 -210.802092) (xy 330.646701 -210.87672) (xy 330.763487 -210.958084) (xy 330.875483 -211.045926)
			(xy 330.982329 -211.139963) (xy 331.083685 -211.239894) (xy 331.179224 -211.345399) (xy 331.268642 -211.456141)
			(xy 331.351651 -211.571764) (xy 331.427986 -211.691898) (xy 331.497402 -211.816158) (xy 331.559677 -211.944146)
			(xy 331.614611 -212.075453) (xy 331.662028 -212.209657) (xy 331.701777 -212.346329) (xy 331.73373 -212.485031)
			(xy 331.757784 -212.625318) (xy 331.773864 -212.766742) (xy 331.781916 -212.908849) (xy 331.78242 -212.980016)
			(xy 331.781916 -213.051183) (xy 331.773864 -213.19329) (xy 331.757784 -213.334714) (xy 331.73373 -213.475001)
			(xy 331.701777 -213.613703) (xy 331.662028 -213.750375) (xy 331.614611 -213.884579) (xy 331.559677 -214.015886)
			(xy 331.497402 -214.143874) (xy 331.427986 -214.268134) (xy 331.351651 -214.388268) (xy 331.268642 -214.503891)
			(xy 331.179224 -214.614633) (xy 331.083685 -214.720138) (xy 330.982329 -214.820069) (xy 330.875483 -214.914106)
			(xy 330.763487 -215.001948) (xy 330.646701 -215.083312) (xy 330.525499 -215.15794) (xy 330.400269 -215.22559)
			(xy 330.271412 -215.286047) (xy 330.139341 -215.339118) (xy 330.004479 -215.384631) (xy 329.867258 -215.422442)
			(xy 329.728118 -215.452429) (xy 329.587505 -215.474496) (xy 329.445868 -215.488573) (xy 329.303661 -215.494614)
			(xy 329.161341 -215.4926) (xy 329.019362 -215.482537) (xy 328.87818 -215.464458) (xy 328.738247 -215.43842)
			(xy 328.600012 -215.404508) (xy 328.463916 -215.362829) (xy 328.330396 -215.313517) (xy 328.19988 -215.256731)
			(xy 328.072786 -215.192651) (xy 327.94952 -215.121484) (xy 327.830478 -215.043456) (xy 327.716042 -214.95882)
			(xy 327.606577 -214.867844) (xy 327.502434 -214.770821) (xy 327.403947 -214.668061) (xy 327.311431 -214.559895)
			(xy 327.225183 -214.446667) (xy 327.145479 -214.328741) (xy 327.072575 -214.206495) (xy 327.006703 -214.080321)
			(xy 326.948075 -213.950621) (xy 326.896879 -213.817812) (xy 326.853279 -213.68232) (xy 326.817413 -213.544578)
			(xy 326.789398 -213.405028) (xy 326.769323 -213.264116) (xy 326.757252 -213.122294) (xy 326.753225 -212.980016)
			(xy 325.767705 -212.980016) (xy 325.77173 -213.147841) (xy 325.783797 -213.315279) (xy 325.803878 -213.481947)
			(xy 325.831927 -213.64746) (xy 325.867879 -213.811438) (xy 325.911652 -213.973504) (xy 325.963145 -214.133285)
			(xy 326.022239 -214.290413) (xy 326.088798 -214.444527) (xy 326.16267 -214.595273) (xy 326.243685 -214.742303)
			(xy 326.331655 -214.88528) (xy 326.42638 -215.023875) (xy 326.52764 -215.15777) (xy 326.635204 -215.286655)
			(xy 326.748823 -215.410235) (xy 326.868237 -215.528225) (xy 326.99317 -215.640354) (xy 327.123336 -215.746365)
			(xy 327.258435 -215.846013) (xy 327.398156 -215.939069) (xy 327.542178 -216.025319) (xy 327.690169 -216.104564)
			(xy 327.84179 -216.176624) (xy 327.996691 -216.24133) (xy 328.154516 -216.298536) (xy 328.314903 -216.348109)
			(xy 328.477482 -216.389935) (xy 328.641879 -216.423919) (xy 328.807717 -216.449981) (xy 328.974613 -216.468062)
			(xy 329.142184 -216.478121) (xy 329.310045 -216.480134) (xy 329.47781 -216.474096) (xy 329.645092 -216.460022)
			(xy 329.811506 -216.437944) (xy 329.976671 -216.407913) (xy 330.140207 -216.369997) (xy 330.301736 -216.324284)
			(xy 330.460887 -216.27088) (xy 330.617296 -216.209906) (xy 330.770601 -216.141503) (xy 330.92045 -216.065829)
			(xy 331.066498 -215.983057) (xy 331.208411 -215.893378) (xy 331.34586 -215.796999) (xy 331.47853 -215.69414)
			(xy 331.606117 -215.585039) (xy 331.728325 -215.469946) (xy 331.844875 -215.349126) (xy 331.955498 -215.222857)
			(xy 332.059941 -215.09143) (xy 332.157961 -214.955146) (xy 332.249335 -214.814319) (xy 332.333852 -214.669274)
			(xy 332.411318 -214.520343) (xy 332.481554 -214.367869) (xy 332.544398 -214.212203) (xy 332.599708 -214.053703)
			(xy 332.647354 -213.892733) (xy 332.687228 -213.729665) (xy 332.719238 -213.564872) (xy 332.74331 -213.398734)
			(xy 332.759388 -213.231632) (xy 332.767437 -213.063952)
		)
		(stroke
			(width 0)
			(type solid)
		)
		(fill yes)
		(layer "F.Cu")
		(net "Net_1777")
	)
	(gr_poly
		(pts
			(xy 393.96797 -304.780188) (xy 393.967467 -304.696245) (xy 393.959418 -304.528553) (xy 393.943338 -304.36144)
			(xy 393.919264 -304.19529) (xy 393.887252 -304.030485) (xy 393.847375 -303.867404) (xy 393.799725 -303.706423)
			(xy 393.744412 -303.547912) (xy 393.681563 -303.392235) (xy 393.611322 -303.23975) (xy 393.533851 -303.090808)
			(xy 393.449328 -302.945752) (xy 393.357947 -302.804915) (xy 393.259919 -302.668621) (xy 393.155469 -302.537184)
			(xy 393.044838 -302.410906) (xy 392.92828 -302.290077) (xy 392.806062 -302.174976) (xy 392.678467 -302.065867)
			(xy 392.545787 -301.963001) (xy 392.408327 -301.866614) (xy 392.266405 -301.776929) (xy 392.120346 -301.694151)
			(xy 391.970486 -301.618472) (xy 391.81717 -301.550064) (xy 391.66075 -301.489086) (xy 391.501587 -301.435677)
			(xy 391.340046 -301.389961) (xy 391.176499 -301.352042) (xy 391.011322 -301.322009) (xy 390.844895 -301.299929)
			(xy 390.677601 -301.285854) (xy 390.509824 -301.279816) (xy 390.341951 -301.281829) (xy 390.174368 -301.291889)
			(xy 390.007459 -301.309971) (xy 389.84161 -301.336035) (xy 389.6772 -301.370021) (xy 389.51461 -301.41185)
			(xy 389.354211 -301.461427) (xy 389.196375 -301.518637) (xy 389.041462 -301.583349) (xy 388.889831 -301.655413)
			(xy 388.741828 -301.734664) (xy 388.597796 -301.820921) (xy 388.458065 -301.913983) (xy 388.322957 -302.013638)
			(xy 388.192781 -302.119657) (xy 388.067839 -302.231794) (xy 387.948417 -302.349793) (xy 387.834789 -302.473382)
			(xy 387.727218 -302.602276) (xy 387.62595 -302.73618) (xy 387.531218 -302.874785) (xy 387.443241 -303.017773)
			(xy 387.362221 -303.164814) (xy 387.288343 -303.315571) (xy 387.221779 -303.469696) (xy 387.162681 -303.626836)
			(xy 387.111184 -303.786628) (xy 387.067409 -303.948705) (xy 387.031454 -304.112695) (xy 387.003403 -304.278221)
			(xy 386.98332 -304.4449) (xy 386.971252 -304.612351) (xy 386.967227 -304.780188) (xy 387.952492 -304.780188)
			(xy 387.956521 -304.637881) (xy 387.968594 -304.496031) (xy 387.988673 -304.35509) (xy 388.016694 -304.215512)
			(xy 388.052566 -304.077742) (xy 388.096176 -303.942222) (xy 388.147382 -303.809387) (xy 388.206022 -303.679661)
			(xy 388.271907 -303.553461) (xy 388.344826 -303.43119) (xy 388.424546 -303.31324) (xy 388.510812 -303.19999)
			(xy 388.603346 -303.091801) (xy 388.701853 -302.989021) (xy 388.806017 -302.891978) (xy 388.915504 -302.800984)
			(xy 389.029964 -302.71633) (xy 389.149029 -302.638287) (xy 389.27232 -302.567106) (xy 389.39944 -302.503013)
			(xy 389.529982 -302.446215) (xy 389.663529 -302.396893) (xy 389.799653 -302.355206) (xy 389.937916 -302.321287)
			(xy 390.077877 -302.295244) (xy 390.219088 -302.277161) (xy 390.361095 -302.267096) (xy 390.503444 -302.265082)
			(xy 390.64568 -302.271124) (xy 390.787345 -302.285203) (xy 390.927987 -302.307275) (xy 391.067156 -302.337268)
			(xy 391.204404 -302.375086) (xy 391.339293 -302.420609) (xy 391.471391 -302.47369) (xy 391.600274 -302.53416)
			(xy 391.725529 -302.601824) (xy 391.846756 -302.676466) (xy 391.963565 -302.757847) (xy 392.075584 -302.845707)
			(xy 392.182452 -302.939763) (xy 392.283828 -303.039714) (xy 392.379387 -303.145241) (xy 392.468822 -303.256005)
			(xy 392.551848 -303.371651) (xy 392.628199 -303.491809) (xy 392.697629 -303.616095) (xy 392.759916 -303.744109)
			(xy 392.814861 -303.875442) (xy 392.862288 -304.009673) (xy 392.902045 -304.146373) (xy 392.934004 -304.285103)
			(xy 392.958064 -304.425419) (xy 392.974146 -304.566871) (xy 392.982201 -304.709006) (xy 392.982704 -304.780188)
			(xy 392.982201 -304.85137) (xy 392.974146 -304.993505) (xy 392.958064 -305.134957) (xy 392.934004 -305.275273)
			(xy 392.902045 -305.414003) (xy 392.862288 -305.550703) (xy 392.814861 -305.684934) (xy 392.759916 -305.816267)
			(xy 392.697629 -305.944281) (xy 392.628199 -306.068567) (xy 392.551848 -306.188725) (xy 392.468822 -306.304371)
			(xy 392.379387 -306.415135) (xy 392.283828 -306.520662) (xy 392.182452 -306.620613) (xy 392.075584 -306.714669)
			(xy 391.963565 -306.802529) (xy 391.846756 -306.88391) (xy 391.725529 -306.958552) (xy 391.600274 -307.026216)
			(xy 391.471391 -307.086686) (xy 391.339293 -307.139767) (xy 391.204404 -307.18529) (xy 391.067156 -307.223108)
			(xy 390.927987 -307.253101) (xy 390.787345 -307.275173) (xy 390.64568 -307.289252) (xy 390.503444 -307.295294)
			(xy 390.361095 -307.29328) (xy 390.219088 -307.283215) (xy 390.077877 -307.265132) (xy 389.937916 -307.239089)
			(xy 389.799653 -307.20517) (xy 389.663529 -307.163483) (xy 389.529982 -307.114161) (xy 389.39944 -307.057363)
			(xy 389.27232 -306.99327) (xy 389.149029 -306.922089) (xy 389.029964 -306.844046) (xy 388.915504 -306.759392)
			(xy 388.806017 -306.668398) (xy 388.701853 -306.571355) (xy 388.603346 -306.468575) (xy 388.510812 -306.360386)
			(xy 388.424546 -306.247136) (xy 388.344826 -306.129186) (xy 388.271907 -306.006915) (xy 388.206022 -305.880715)
			(xy 388.147382 -305.750989) (xy 388.096176 -305.618154) (xy 388.052566 -305.482634) (xy 388.016694 -305.344864)
			(xy 387.988673 -305.205286) (xy 387.968594 -305.064345) (xy 387.956521 -304.922495) (xy 387.952492 -304.780188)
			(xy 386.967227 -304.780188) (xy 386.971252 -304.948025) (xy 386.98332 -305.115476) (xy 387.003403 -305.282155)
			(xy 387.031454 -305.447681) (xy 387.067409 -305.611671) (xy 387.111184 -305.773748) (xy 387.162681 -305.93354)
			(xy 387.221779 -306.09068) (xy 387.288343 -306.244805) (xy 387.362221 -306.395562) (xy 387.443241 -306.542603)
			(xy 387.531218 -306.685591) (xy 387.62595 -306.824196) (xy 387.727218 -306.9581) (xy 387.834789 -307.086994)
			(xy 387.948417 -307.210583) (xy 388.067839 -307.328582) (xy 388.192781 -307.440719) (xy 388.322957 -307.546738)
			(xy 388.458065 -307.646393) (xy 388.597796 -307.739455) (xy 388.741828 -307.825712) (xy 388.889831 -307.904963)
			(xy 389.041462 -307.977027) (xy 389.196375 -308.041739) (xy 389.354211 -308.098949) (xy 389.51461 -308.148526)
			(xy 389.6772 -308.190355) (xy 389.84161 -308.224341) (xy 390.007459 -308.250405) (xy 390.174368 -308.268487)
			(xy 390.341951 -308.278547) (xy 390.509824 -308.28056) (xy 390.677601 -308.274522) (xy 390.844895 -308.260447)
			(xy 391.011322 -308.238367) (xy 391.176499 -308.208334) (xy 391.340046 -308.170415) (xy 391.501587 -308.124699)
			(xy 391.66075 -308.07129) (xy 391.81717 -308.010312) (xy 391.970486 -307.941904) (xy 392.120346 -307.866225)
			(xy 392.266405 -307.783447) (xy 392.408327 -307.693762) (xy 392.545787 -307.597375) (xy 392.678467 -307.494509)
			(xy 392.806062 -307.3854) (xy 392.92828 -307.270299) (xy 393.044838 -307.14947) (xy 393.155469 -307.023192)
			(xy 393.259919 -306.891755) (xy 393.357947 -306.755461) (xy 393.449328 -306.614624) (xy 393.533851 -306.469568)
			(xy 393.611322 -306.320626) (xy 393.681563 -306.168141) (xy 393.744412 -306.012464) (xy 393.799725 -305.853953)
			(xy 393.847375 -305.692972) (xy 393.887252 -305.529891) (xy 393.919264 -305.365086) (xy 393.943338 -305.198936)
			(xy 393.959418 -305.031823) (xy 393.967467 -304.864131)
		)
		(stroke
			(width 0)
			(type solid)
		)
		(fill yes)
		(layer "F.Cu")
		(net "Net_1780")
	)
	(gr_poly
		(pts
			(xy 393.96797 -212.980016) (xy 393.967467 -212.896073) (xy 393.959418 -212.728381) (xy 393.943338 -212.561268)
			(xy 393.919264 -212.395118) (xy 393.887252 -212.230313) (xy 393.847375 -212.067232) (xy 393.799725 -211.906251)
			(xy 393.744412 -211.74774) (xy 393.681563 -211.592063) (xy 393.611322 -211.439578) (xy 393.533851 -211.290636)
			(xy 393.449328 -211.14558) (xy 393.357947 -211.004743) (xy 393.259919 -210.868449) (xy 393.155469 -210.737012)
			(xy 393.044838 -210.610734) (xy 392.92828 -210.489905) (xy 392.806062 -210.374804) (xy 392.678467 -210.265695)
			(xy 392.545787 -210.162829) (xy 392.408327 -210.066442) (xy 392.266405 -209.976757) (xy 392.120346 -209.893979)
			(xy 391.970486 -209.8183) (xy 391.81717 -209.749892) (xy 391.66075 -209.688914) (xy 391.501587 -209.635505)
			(xy 391.340046 -209.589789) (xy 391.176499 -209.55187) (xy 391.011322 -209.521837) (xy 390.844895 -209.499757)
			(xy 390.677601 -209.485682) (xy 390.509824 -209.479644) (xy 390.341951 -209.481657) (xy 390.174368 -209.491717)
			(xy 390.007459 -209.509799) (xy 389.84161 -209.535863) (xy 389.6772 -209.569849) (xy 389.51461 -209.611678)
			(xy 389.354211 -209.661255) (xy 389.196375 -209.718465) (xy 389.041462 -209.783177) (xy 388.889831 -209.855241)
			(xy 388.741828 -209.934492) (xy 388.597796 -210.020749) (xy 388.458065 -210.113811) (xy 388.322957 -210.213466)
			(xy 388.192781 -210.319485) (xy 388.067839 -210.431622) (xy 387.948417 -210.549621) (xy 387.834789 -210.67321)
			(xy 387.727218 -210.802104) (xy 387.62595 -210.936008) (xy 387.531218 -211.074613) (xy 387.443241 -211.217601)
			(xy 387.362221 -211.364642) (xy 387.288343 -211.515399) (xy 387.221779 -211.669524) (xy 387.162681 -211.826664)
			(xy 387.111184 -211.986456) (xy 387.067409 -212.148533) (xy 387.031454 -212.312523) (xy 387.003403 -212.478049)
			(xy 386.98332 -212.644728) (xy 386.971252 -212.812179) (xy 386.967227 -212.980016) (xy 387.952492 -212.980016)
			(xy 387.956521 -212.837709) (xy 387.968594 -212.695859) (xy 387.988673 -212.554918) (xy 388.016694 -212.41534)
			(xy 388.052566 -212.27757) (xy 388.096176 -212.14205) (xy 388.147382 -212.009215) (xy 388.206022 -211.879489)
			(xy 388.271907 -211.753289) (xy 388.344826 -211.631018) (xy 388.424546 -211.513068) (xy 388.510812 -211.399818)
			(xy 388.603346 -211.291629) (xy 388.701853 -211.188849) (xy 388.806017 -211.091806) (xy 388.915504 -211.000812)
			(xy 389.029964 -210.916158) (xy 389.149029 -210.838115) (xy 389.27232 -210.766934) (xy 389.39944 -210.702841)
			(xy 389.529982 -210.646043) (xy 389.663529 -210.596721) (xy 389.799653 -210.555034) (xy 389.937916 -210.521115)
			(xy 390.077877 -210.495072) (xy 390.219088 -210.476989) (xy 390.361095 -210.466924) (xy 390.503444 -210.46491)
			(xy 390.64568 -210.470952) (xy 390.787345 -210.485031) (xy 390.927987 -210.507103) (xy 391.067156 -210.537096)
			(xy 391.204404 -210.574914) (xy 391.339293 -210.620437) (xy 391.471391 -210.673518) (xy 391.600274 -210.733988)
			(xy 391.725529 -210.801652) (xy 391.846756 -210.876294) (xy 391.963565 -210.957675) (xy 392.075584 -211.045535)
			(xy 392.182452 -211.139591) (xy 392.283828 -211.239542) (xy 392.379387 -211.345069) (xy 392.468822 -211.455833)
			(xy 392.551848 -211.571479) (xy 392.628199 -211.691637) (xy 392.697629 -211.815923) (xy 392.759916 -211.943937)
			(xy 392.814861 -212.07527) (xy 392.862288 -212.209501) (xy 392.902045 -212.346201) (xy 392.934004 -212.484931)
			(xy 392.958064 -212.625247) (xy 392.974146 -212.766699) (xy 392.982201 -212.908834) (xy 392.982704 -212.980016)
			(xy 392.982201 -213.051198) (xy 392.974146 -213.193333) (xy 392.958064 -213.334785) (xy 392.934004 -213.475101)
			(xy 392.902045 -213.613831) (xy 392.862288 -213.750531) (xy 392.814861 -213.884762) (xy 392.759916 -214.016095)
			(xy 392.697629 -214.144109) (xy 392.628199 -214.268395) (xy 392.551848 -214.388553) (xy 392.468822 -214.504199)
			(xy 392.379387 -214.614963) (xy 392.283828 -214.72049) (xy 392.182452 -214.820441) (xy 392.075584 -214.914497)
			(xy 391.963565 -215.002357) (xy 391.846756 -215.083738) (xy 391.725529 -215.15838) (xy 391.600274 -215.226044)
			(xy 391.471391 -215.286514) (xy 391.339293 -215.339595) (xy 391.204404 -215.385118) (xy 391.067156 -215.422936)
			(xy 390.927987 -215.452929) (xy 390.787345 -215.475001) (xy 390.64568 -215.48908) (xy 390.503444 -215.495122)
			(xy 390.361095 -215.493108) (xy 390.219088 -215.483043) (xy 390.077877 -215.46496) (xy 389.937916 -215.438917)
			(xy 389.799653 -215.404998) (xy 389.663529 -215.363311) (xy 389.529982 -215.313989) (xy 389.39944 -215.257191)
			(xy 389.27232 -215.193098) (xy 389.149029 -215.121917) (xy 389.029964 -215.043874) (xy 388.915504 -214.95922)
			(xy 388.806017 -214.868226) (xy 388.701853 -214.771183) (xy 388.603346 -214.668403) (xy 388.510812 -214.560214)
			(xy 388.424546 -214.446964) (xy 388.344826 -214.329014) (xy 388.271907 -214.206743) (xy 388.206022 -214.080543)
			(xy 388.147382 -213.950817) (xy 388.096176 -213.817982) (xy 388.052566 -213.682462) (xy 388.016694 -213.544692)
			(xy 387.988673 -213.405114) (xy 387.968594 -213.264173) (xy 387.956521 -213.122323) (xy 387.952492 -212.980016)
			(xy 386.967227 -212.980016) (xy 386.971252 -213.147853) (xy 386.98332 -213.315304) (xy 387.003403 -213.481983)
			(xy 387.031454 -213.647509) (xy 387.067409 -213.811499) (xy 387.111184 -213.973576) (xy 387.162681 -214.133368)
			(xy 387.221779 -214.290508) (xy 387.288343 -214.444633) (xy 387.362221 -214.59539) (xy 387.443241 -214.742431)
			(xy 387.531218 -214.885419) (xy 387.62595 -215.024024) (xy 387.727218 -215.157928) (xy 387.834789 -215.286822)
			(xy 387.948417 -215.410411) (xy 388.067839 -215.52841) (xy 388.192781 -215.640547) (xy 388.322957 -215.746566)
			(xy 388.458065 -215.846221) (xy 388.597796 -215.939283) (xy 388.741828 -216.02554) (xy 388.889831 -216.104791)
			(xy 389.041462 -216.176855) (xy 389.196375 -216.241567) (xy 389.354211 -216.298777) (xy 389.51461 -216.348354)
			(xy 389.6772 -216.390183) (xy 389.84161 -216.424169) (xy 390.007459 -216.450233) (xy 390.174368 -216.468315)
			(xy 390.341951 -216.478375) (xy 390.509824 -216.480388) (xy 390.677601 -216.47435) (xy 390.844895 -216.460275)
			(xy 391.011322 -216.438195) (xy 391.176499 -216.408162) (xy 391.340046 -216.370243) (xy 391.501587 -216.324527)
			(xy 391.66075 -216.271118) (xy 391.81717 -216.21014) (xy 391.970486 -216.141732) (xy 392.120346 -216.066053)
			(xy 392.266405 -215.983275) (xy 392.408327 -215.89359) (xy 392.545787 -215.797203) (xy 392.678467 -215.694337)
			(xy 392.806062 -215.585228) (xy 392.92828 -215.470127) (xy 393.044838 -215.349298) (xy 393.155469 -215.22302)
			(xy 393.259919 -215.091583) (xy 393.357947 -214.955289) (xy 393.449328 -214.814452) (xy 393.533851 -214.669396)
			(xy 393.611322 -214.520454) (xy 393.681563 -214.367969) (xy 393.744412 -214.212292) (xy 393.799725 -214.053781)
			(xy 393.847375 -213.8928) (xy 393.887252 -213.729719) (xy 393.919264 -213.564914) (xy 393.943338 -213.398764)
			(xy 393.959418 -213.231651) (xy 393.967467 -213.063959)
		)
		(stroke
			(width 0)
			(type solid)
		)
		(fill yes)
		(layer "F.Cu")
		(net "Net_1778")
	)
	(gr_poly
		(pts
			(xy 405.468074 -258.880102) (xy 405.467571 -258.796159) (xy 405.459522 -258.628467) (xy 405.443442 -258.461354)
			(xy 405.419368 -258.295204) (xy 405.387356 -258.130399) (xy 405.347479 -257.967318) (xy 405.299829 -257.806337)
			(xy 405.244516 -257.647826) (xy 405.181667 -257.492149) (xy 405.111426 -257.339664) (xy 405.033955 -257.190722)
			(xy 404.949432 -257.045666) (xy 404.858051 -256.904829) (xy 404.760023 -256.768535) (xy 404.655573 -256.637098)
			(xy 404.544942 -256.51082) (xy 404.428384 -256.389991) (xy 404.306166 -256.27489) (xy 404.178571 -256.165781)
			(xy 404.045891 -256.062915) (xy 403.908431 -255.966528) (xy 403.766509 -255.876843) (xy 403.62045 -255.794065)
			(xy 403.47059 -255.718386) (xy 403.317274 -255.649978) (xy 403.160854 -255.589) (xy 403.001691 -255.535591)
			(xy 402.84015 -255.489875) (xy 402.676603 -255.451956) (xy 402.511426 -255.421923) (xy 402.344999 -255.399843)
			(xy 402.177705 -255.385768) (xy 402.009928 -255.37973) (xy 401.842055 -255.381743) (xy 401.674472 -255.391803)
			(xy 401.507563 -255.409885) (xy 401.341714 -255.435949) (xy 401.177304 -255.469935) (xy 401.014714 -255.511764)
			(xy 400.854315 -255.561341) (xy 400.696479 -255.618551) (xy 400.541566 -255.683263) (xy 400.389935 -255.755327)
			(xy 400.241932 -255.834578) (xy 400.0979 -255.920835) (xy 399.958169 -256.013897) (xy 399.823061 -256.113552)
			(xy 399.692885 -256.219571) (xy 399.567943 -256.331708) (xy 399.448521 -256.449707) (xy 399.334893 -256.573296)
			(xy 399.227322 -256.70219) (xy 399.126054 -256.836094) (xy 399.031322 -256.974699) (xy 398.943345 -257.117687)
			(xy 398.862325 -257.264728) (xy 398.788447 -257.415485) (xy 398.721883 -257.56961) (xy 398.662785 -257.72675)
			(xy 398.611288 -257.886542) (xy 398.567513 -258.048619) (xy 398.531558 -258.212609) (xy 398.503507 -258.378135)
			(xy 398.483424 -258.544814) (xy 398.471356 -258.712265) (xy 398.467331 -258.880102) (xy 399.452851 -258.880102)
			(xy 399.456879 -258.73781) (xy 399.468951 -258.595974) (xy 399.489028 -258.455047) (xy 399.517046 -258.315483)
			(xy 399.552915 -258.177727) (xy 399.59652 -258.042221) (xy 399.647721 -257.909399) (xy 399.706355 -257.779686)
			(xy 399.772233 -257.653499) (xy 399.845145 -257.53124) (xy 399.924857 -257.413303) (xy 400.011114 -257.300064)
			(xy 400.103638 -257.191886) (xy 400.202135 -257.089116) (xy 400.306289 -256.992083) (xy 400.415765 -256.901099)
			(xy 400.530213 -256.816453) (xy 400.649267 -256.738418) (xy 400.772545 -256.667244) (xy 400.899652 -256.603157)
			(xy 401.030181 -256.546365) (xy 401.163715 -256.497048) (xy 401.299824 -256.455365) (xy 401.438074 -256.421449)
			(xy 401.578021 -256.395409) (xy 401.719217 -256.377328) (xy 401.86121 -256.367265) (xy 402.003545 -256.36525)
			(xy 402.145766 -256.371292) (xy 402.287417 -256.38537) (xy 402.428045 -256.407439) (xy 402.567199 -256.437429)
			(xy 402.704434 -256.475244) (xy 402.839309 -256.520762) (xy 402.971393 -256.573838) (xy 403.100263 -256.634301)
			(xy 403.225506 -256.701958) (xy 403.34672 -256.776593) (xy 403.463518 -256.857966) (xy 403.575525 -256.945816)
			(xy 403.682383 -257.039863) (xy 403.783748 -257.139804) (xy 403.879297 -257.24532) (xy 403.968724 -257.356073)
			(xy 404.051742 -257.471707) (xy 404.128084 -257.591854) (xy 404.197507 -257.716126) (xy 404.259788 -257.844128)
			(xy 404.314728 -257.975448) (xy 404.36215 -258.109665) (xy 404.401903 -258.246351) (xy 404.433859 -258.385067)
			(xy 404.457916 -258.525368) (xy 404.473997 -258.666806) (xy 404.48205 -258.808927) (xy 404.482554 -258.880102)
			(xy 404.48205 -258.951277) (xy 404.473997 -259.093398) (xy 404.457916 -259.234836) (xy 404.433859 -259.375137)
			(xy 404.401903 -259.513853) (xy 404.36215 -259.650539) (xy 404.314728 -259.784756) (xy 404.259788 -259.916076)
			(xy 404.197507 -260.044078) (xy 404.128084 -260.16835) (xy 404.051742 -260.288497) (xy 403.968724 -260.404131)
			(xy 403.879297 -260.514884) (xy 403.783748 -260.6204) (xy 403.682383 -260.720341) (xy 403.575525 -260.814388)
			(xy 403.463518 -260.902238) (xy 403.34672 -260.983611) (xy 403.225506 -261.058246) (xy 403.100263 -261.125903)
			(xy 402.971393 -261.186366) (xy 402.839309 -261.239442) (xy 402.704434 -261.28496) (xy 402.567199 -261.322775)
			(xy 402.428045 -261.352765) (xy 402.287417 -261.374834) (xy 402.145766 -261.388912) (xy 402.003545 -261.394954)
			(xy 401.86121 -261.392939) (xy 401.719217 -261.382876) (xy 401.578021 -261.364795) (xy 401.438074 -261.338755)
			(xy 401.299824 -261.304839) (xy 401.163715 -261.263156) (xy 401.030181 -261.213839) (xy 400.899652 -261.157047)
			(xy 400.772545 -261.09296) (xy 400.649267 -261.021786) (xy 400.530213 -260.943751) (xy 400.415765 -260.859105)
			(xy 400.306289 -260.768121) (xy 400.202135 -260.671088) (xy 400.103638 -260.568318) (xy 400.011114 -260.46014)
			(xy 399.924857 -260.346901) (xy 399.845145 -260.228964) (xy 399.772233 -260.106705) (xy 399.706355 -259.980518)
			(xy 399.647721 -259.850805) (xy 399.59652 -259.717983) (xy 399.552915 -259.582477) (xy 399.517046 -259.444721)
			(xy 399.489028 -259.305157) (xy 399.468951 -259.16423) (xy 399.456879 -259.022394) (xy 399.452851 -258.880102)
			(xy 398.467331 -258.880102) (xy 398.471356 -259.047939) (xy 398.483424 -259.21539) (xy 398.503507 -259.382069)
			(xy 398.531558 -259.547595) (xy 398.567513 -259.711585) (xy 398.611288 -259.873662) (xy 398.662785 -260.033454)
			(xy 398.721883 -260.190594) (xy 398.788447 -260.344719) (xy 398.862325 -260.495476) (xy 398.943345 -260.642517)
			(xy 399.031322 -260.785505) (xy 399.126054 -260.92411) (xy 399.227322 -261.058014) (xy 399.334893 -261.186908)
			(xy 399.448521 -261.310497) (xy 399.567943 -261.428496) (xy 399.692885 -261.540633) (xy 399.823061 -261.646652)
			(xy 399.958169 -261.746307) (xy 400.0979 -261.839369) (xy 400.241932 -261.925626) (xy 400.389935 -262.004877)
			(xy 400.541566 -262.076941) (xy 400.696479 -262.141653) (xy 400.854315 -262.198863) (xy 401.014714 -262.24844)
			(xy 401.177304 -262.290269) (xy 401.341714 -262.324255) (xy 401.507563 -262.350319) (xy 401.674472 -262.368401)
			(xy 401.842055 -262.378461) (xy 402.009928 -262.380474) (xy 402.177705 -262.374436) (xy 402.344999 -262.360361)
			(xy 402.511426 -262.338281) (xy 402.676603 -262.308248) (xy 402.84015 -262.270329) (xy 403.001691 -262.224613)
			(xy 403.160854 -262.171204) (xy 403.317274 -262.110226) (xy 403.47059 -262.041818) (xy 403.62045 -261.966139)
			(xy 403.766509 -261.883361) (xy 403.908431 -261.793676) (xy 404.045891 -261.697289) (xy 404.178571 -261.594423)
			(xy 404.306166 -261.485314) (xy 404.428384 -261.370213) (xy 404.544942 -261.249384) (xy 404.655573 -261.123106)
			(xy 404.760023 -260.991669) (xy 404.858051 -260.855375) (xy 404.949432 -260.714538) (xy 405.033955 -260.569482)
			(xy 405.111426 -260.42054) (xy 405.181667 -260.268055) (xy 405.244516 -260.112378) (xy 405.299829 -259.953867)
			(xy 405.347479 -259.792886) (xy 405.387356 -259.629805) (xy 405.419368 -259.465) (xy 405.443442 -259.29885)
			(xy 405.459522 -259.131737) (xy 405.467571 -258.964045)
		)
		(stroke
			(width 0)
			(type solid)
		)
		(fill yes)
		(layer "F.Cu")
		(net "Net_1779")
	)
	(gr_poly
		(pts
			(arc
				(start 105.116122 -394.053822)
				(mid 105.135645 -394.049921)
				(end 105.15219 -394.038836)
			)
			(arc
				(start 105.18267 -394.008356)
				(mid 105.193781 -393.991822)
				(end 105.197656 -393.972288)
			)
			(xy 105.197656 -393.56284)
			(arc
				(start 105.197402 -393.560046)
				(mid 105.195881 -393.540514)
				(end 105.19537 -393.52093)
			)
			(arc
				(start 105.19537 -393.52093)
				(mid 105.195886 -393.501346)
				(end 105.197402 -393.481814)
			)
			(xy 105.197656 -393.47902) (xy 105.197656 -392.92784)
			(arc
				(start 105.197402 -392.925046)
				(mid 105.195881 -392.905514)
				(end 105.19537 -392.88593)
			)
			(arc
				(start 105.19537 -392.88593)
				(mid 105.195886 -392.866346)
				(end 105.197402 -392.846814)
			)
			(xy 105.197656 -392.84402) (xy 105.197656 -392.29284)
			(arc
				(start 105.197402 -392.290046)
				(mid 105.195881 -392.270514)
				(end 105.19537 -392.25093)
			)
			(arc
				(start 105.19537 -392.25093)
				(mid 105.195886 -392.231346)
				(end 105.197402 -392.211814)
			)
			(xy 105.197656 -392.20902) (xy 105.197656 -391.65784)
			(arc
				(start 105.197402 -391.655046)
				(mid 105.195881 -391.635514)
				(end 105.19537 -391.61593)
			)
			(arc
				(start 105.19537 -391.61593)
				(mid 105.195886 -391.596346)
				(end 105.197402 -391.576814)
			)
			(xy 105.197656 -391.57402)
			(arc
				(start 105.197656 -391.393172)
				(mid 105.201557 -391.373649)
				(end 105.212642 -391.357104)
			)
			(arc
				(start 105.222294 -391.347452)
				(mid 105.233356 -391.331035)
				(end 105.23728 -391.311638)
			)
			(arc
				(start 105.23728 -391.264394)
				(mid 105.274552 -391.174412)
				(end 105.364534 -391.13714)
			)
			(arc
				(start 105.411778 -391.13714)
				(mid 105.431165 -391.13319)
				(end 105.447592 -391.122154)
			)
			(arc
				(start 105.505758 -391.063988)
				(mid 105.516869 -391.047454)
				(end 105.520744 -391.02792)
			)
			(arc
				(start 105.520744 -390.02589)
				(mid 105.524645 -390.006367)
				(end 105.53573 -389.989822)
			)
			(arc
				(start 105.622852 -389.9027)
				(mid 105.639386 -389.891589)
				(end 105.65892 -389.887714)
			)
			(xy 105.818178 -389.887714)
			(arc
				(start 105.825798 -389.885174)
				(mid 105.883632 -389.871473)
				(end 105.942892 -389.866886)
			)
			(arc
				(start 105.942892 -389.866886)
				(mid 106.002158 -389.871438)
				(end 106.059986 -389.885174)
			)
			(xy 106.067606 -389.887714)
			(arc
				(start 107.039918 -389.887714)
				(mid 107.059441 -389.883813)
				(end 107.075986 -389.872728)
			)
			(arc
				(start 107.580684 -389.36803)
				(mid 107.591795 -389.351496)
				(end 107.59567 -389.331962)
			)
			(arc
				(start 107.59567 -388.606538)
				(mid 107.59172 -388.587151)
				(end 107.580684 -388.570724)
			)
			(xy 107.376976 -388.366762) (xy 107.35564 -388.359142)
			(arc
				(start 107.344464 -388.360158)
				(mid 107.321754 -388.361685)
				(end 107.298998 -388.36219)
			)
			(arc
				(start 107.298998 -388.36219)
				(mid 107.200889 -388.352641)
				(end 107.106466 -388.324344)
			)
			(xy 107.097068 -388.320534)
			(arc
				(start 105.949496 -388.320534)
				(mid 105.929973 -388.324435)
				(end 105.913428 -388.33552)
			)
			(arc
				(start 105.66146 -388.587488)
				(mid 105.644926 -388.598599)
				(end 105.625392 -388.602474)
			)
			(xy 105.101136 -388.602474)
			(arc
				(start 105.096056 -388.60349)
				(mid 105.063853 -388.60863)
				(end 105.031286 -388.610348)
			)
			(arc
				(start 104.537256 -388.610348)
				(mid 104.504688 -388.608646)
				(end 104.472486 -388.60349)
			)
			(xy 104.467406 -388.602474)
			(arc
				(start 103.780336 -388.602474)
				(mid 103.760949 -388.606424)
				(end 103.744522 -388.61746)
			)
			(arc
				(start 103.711502 -388.65048)
				(mid 103.611615 -388.717129)
				(end 103.493824 -388.740396)
			)
			(arc
				(start 102.673658 -388.740396)
				(mid 102.613578 -388.734522)
				(end 102.555802 -388.717028)
			)
			(arc
				(start 102.369366 -388.639812)
				(mid 102.341864 -388.626779)
				(end 102.315772 -388.61111)
			)
			(arc
				(start 102.315772 -388.61111)
				(mid 102.302198 -388.604634)
				(end 102.287324 -388.602474)
			)
			(arc
				(start 101.2063 -388.602474)
				(mid 101.182624 -388.608195)
				(end 101.16439 -388.624318)
			)
			(xy 101.10978 -388.703312) (xy 101.106478 -388.727696)
			(arc
				(start 101.11105 -388.739634)
				(mid 101.125649 -388.792606)
				(end 101.130608 -388.84733)
			)
			(arc
				(start 101.130608 -389.01497)
				(mid 101.134392 -389.034464)
				(end 101.14534 -389.051038)
			)
			(arc
				(start 101.535992 -389.441436)
				(mid 101.552409 -389.452498)
				(end 101.571806 -389.456422)
			)
			(arc
				(start 102.511352 -389.456422)
				(mid 102.530875 -389.452521)
				(end 102.54742 -389.441436)
			)
			(arc
				(start 102.74173 -389.247126)
				(mid 102.758264 -389.236015)
				(end 102.777798 -389.23214)
			)
			(xy 103.28783 -389.23214) (xy 103.300276 -389.228838)
			(arc
				(start 103.306118 -389.225536)
				(mid 103.379003 -389.195998)
				(end 103.456994 -389.185912)
			)
			(xy 104.292654 -389.185912)
			(arc
				(start 104.300782 -389.183118)
				(mid 104.321678 -389.177638)
				(end 104.3432 -389.175752)
			)
			(arc
				(start 104.648 -389.175752)
				(mid 104.738162 -389.213098)
				(end 104.775508 -389.30326)
			)
			(arc
				(start 104.775508 -389.32358)
				(mid 104.779341 -389.342937)
				(end 104.79024 -389.359394)
			)
			(arc
				(start 104.803194 -389.372348)
				(mid 104.814305 -389.388882)
				(end 104.81818 -389.408416)
			)
			(arc
				(start 104.81818 -389.444484)
				(mid 104.82213 -389.463871)
				(end 104.833166 -389.480298)
			)
			(arc
				(start 104.94645 -389.593582)
				(mid 105.013182 -389.693454)
				(end 105.03662 -389.81126)
			)
			(arc
				(start 105.03662 -390.380728)
				(mid 105.013186 -390.498536)
				(end 104.94645 -390.598406)
			)
			(arc
				(start 104.75214 -390.792462)
				(mid 104.741166 -390.809025)
				(end 104.737408 -390.82853)
			)
			(arc
				(start 104.737408 -390.8425)
				(mid 104.700062 -390.932662)
				(end 104.6099 -390.970008)
			)
			(arc
				(start 104.5591 -390.970008)
				(mid 104.539743 -390.973841)
				(end 104.523286 -390.98474)
			)
			(arc
				(start 104.28986 -391.218166)
				(mid 104.278749 -391.2347)
				(end 104.274874 -391.254234)
			)
			(arc
				(start 104.274874 -393.937744)
				(mid 104.278775 -393.957267)
				(end 104.28986 -393.973812)
			)
			(arc
				(start 104.354884 -394.038836)
				(mid 104.371418 -394.049947)
				(end 104.390952 -394.053822)
			)
		)
		(stroke
			(width 0)
			(type solid)
		)
		(fill yes)
		(layer "F.Cu")
		(net "GND")
	)
	(gr_poly
		(pts
			(arc
				(start 435.543198 -112.001808)
				(mid 435.562721 -111.997907)
				(end 435.579266 -111.986822)
			)
			(arc
				(start 435.815994 -111.750094)
				(mid 435.827105 -111.73356)
				(end 435.83098 -111.714026)
			)
			(xy 435.83098 -110.75543) (xy 435.8386 -110.736888) (xy 435.84368 -110.731808) (xy 435.84368 -108.119672)
			(xy 435.843172 -108.119418)
			(arc
				(start 435.843172 -107.450382)
				(mid 435.839339 -107.431025)
				(end 435.82844 -107.414568)
			)
			(arc
				(start 435.755288 -107.341416)
				(mid 435.738754 -107.330305)
				(end 435.71922 -107.32643)
			)
			(arc
				(start 434.194458 -107.32643)
				(mid 434.174935 -107.330331)
				(end 434.15839 -107.341416)
			)
			(arc
				(start 434.137562 -107.362244)
				(mid 434.126451 -107.378778)
				(end 434.122576 -107.398312)
			)
			(arc
				(start 434.122576 -109.692948)
				(mid 434.118675 -109.712471)
				(end 434.10759 -109.729016)
			)
			(xy 434.093112 -109.743494) (xy 434.086508 -109.754924)
			(arc
				(start 434.08473 -109.761528)
				(mid 433.948555 -109.965711)
				(end 433.716176 -110.044738)
			)
			(arc
				(start 433.716176 -110.044738)
				(mid 433.497543 -109.975932)
				(end 433.357782 -109.794294)
			)
			(xy 433.353972 -109.783626)
			(arc
				(start 433.350162 -109.779816)
				(mid 433.339051 -109.763282)
				(end 433.335176 -109.743748)
			)
			(xy 433.335176 -109.681772) (xy 433.334668 -109.66323) (xy 433.335176 -109.644688)
			(arc
				(start 433.335176 -109.288072)
				(mid 433.331275 -109.268549)
				(end 433.32019 -109.252004)
			)
			(arc
				(start 433.240942 -109.172756)
				(mid 433.224408 -109.161645)
				(end 433.204874 -109.15777)
			)
			(arc
				(start 431.850038 -109.15777)
				(mid 431.830515 -109.153869)
				(end 431.81397 -109.142784)
			)
			(xy 431.811176 -109.139736) (xy 431.797968 -109.139736) (xy 431.767996 -109.110272) (xy 431.767996 -109.097064)
			(arc
				(start 431.714402 -109.043216)
				(mid 431.703291 -109.026682)
				(end 431.699416 -109.007148)
			)
			(arc
				(start 431.699416 -106.575352)
				(mid 431.703317 -106.555829)
				(end 431.714402 -106.539284)
			)
			(arc
				(start 431.79365 -106.460036)
				(mid 431.810184 -106.448925)
				(end 431.829718 -106.44505)
			)
			(arc
				(start 432.107594 -106.44505)
				(mid 432.127117 -106.441149)
				(end 432.143662 -106.430064)
			)
			(arc
				(start 432.18735 -106.386376)
				(mid 432.198461 -106.369842)
				(end 432.202336 -106.350308)
			)
			(arc
				(start 432.202336 -106.308652)
				(mid 432.198435 -106.289129)
				(end 432.18735 -106.272584)
			)
			(arc
				(start 432.141122 -106.226356)
				(mid 432.124588 -106.215245)
				(end 432.105054 -106.21137)
			)
			(arc
				(start 431.527458 -106.21137)
				(mid 431.507935 -106.215271)
				(end 431.49139 -106.226356)
			)
			(arc
				(start 431.480722 -106.237024)
				(mid 431.469611 -106.253558)
				(end 431.465736 -106.273092)
			)
			(arc
				(start 431.465736 -106.952288)
				(mid 431.461835 -106.971811)
				(end 431.45075 -106.988356)
			)
			(xy 430.957736 -107.48137)
			(arc
				(start 430.952656 -107.487212)
				(mid 430.91531 -107.530638)
				(end 430.871884 -107.567984)
			)
			(xy 430.868836 -107.57027)
			(arc
				(start 430.802542 -107.636564)
				(mid 430.791431 -107.653098)
				(end 430.787556 -107.672632)
			)
			(arc
				(start 430.787556 -109.17682)
				(mid 430.783655 -109.196343)
				(end 430.77257 -109.212888)
			)
			(arc
				(start 430.664874 -109.320584)
				(mid 430.64834 -109.331695)
				(end 430.628806 -109.33557)
			)
			(arc
				(start 430.046638 -109.33557)
				(mid 430.027115 -109.339471)
				(end 430.01057 -109.350556)
			)
			(arc
				(start 429.989742 -109.371384)
				(mid 429.978631 -109.387918)
				(end 429.974756 -109.407452)
			)
			(xy 429.974756 -110.54842) (xy 429.993552 -110.574836)
			(arc
				(start 430.008792 -110.58017)
				(mid 430.193586 -110.719538)
				(end 430.263808 -110.940088)
			)
			(arc
				(start 430.263808 -110.940088)
				(mid 429.8823 -111.321596)
				(end 429.500792 -110.940088)
			)
			(xy 429.501554 -110.915958) (xy 429.502316 -110.905544) (xy 429.495204 -110.885732)
			(arc
				(start 429.437292 -110.82401)
				(mid 429.420413 -110.81214)
				(end 429.400208 -110.808008)
			)
			(arc
				(start 428.752762 -110.808008)
				(mid 428.733239 -110.804107)
				(end 428.716694 -110.793022)
			)
			(arc
				(start 428.670466 -110.746794)
				(mid 428.659355 -110.73026)
				(end 428.65548 -110.710726)
			)
			(arc
				(start 428.65548 -109.73689)
				(mid 428.651579 -109.717367)
				(end 428.640494 -109.700822)
			)
			(arc
				(start 428.467266 -109.527594)
				(mid 428.450732 -109.516483)
				(end 428.431198 -109.512608)
			)
			(arc
				(start 425.704762 -109.512608)
				(mid 425.685239 -109.508707)
				(end 425.668694 -109.497622)
			)
			(arc
				(start 425.495466 -109.324394)
				(mid 425.478932 -109.313283)
				(end 425.459398 -109.309408)
			)
			(arc
				(start 424.764962 -109.309408)
				(mid 424.745439 -109.305507)
				(end 424.728894 -109.294422)
			)
			(arc
				(start 424.352466 -108.917994)
				(mid 424.341355 -108.90146)
				(end 424.33748 -108.881926)
			)
			(arc
				(start 424.33748 -108.78566)
				(mid 424.33353 -108.766273)
				(end 424.322494 -108.749846)
			)
			(arc
				(start 424.277282 -108.70438)
				(mid 424.26622 -108.687963)
				(end 424.262296 -108.668566)
			)
			(arc
				(start 424.262296 -106.740706)
				(mid 424.258463 -106.721349)
				(end 424.247564 -106.704892)
			)
			(arc
				(start 424.123866 -106.581194)
				(mid 424.107332 -106.570083)
				(end 424.087798 -106.566208)
			)
			(arc
				(start 423.113962 -106.566208)
				(mid 423.094439 -106.570109)
				(end 423.077894 -106.581194)
			)
			(arc
				(start 422.980866 -106.678222)
				(mid 422.969755 -106.694756)
				(end 422.96588 -106.71429)
			)
			(arc
				(start 422.96588 -111.599726)
				(mid 422.969781 -111.619249)
				(end 422.980866 -111.635794)
			)
			(arc
				(start 423.331894 -111.986822)
				(mid 423.348428 -111.997933)
				(end 423.367962 -112.001808)
			)
		)
		(stroke
			(width 0)
			(type solid)
		)
		(fill yes)
		(layer "F.Cu")
		(net "GND")
	)
	(gr_poly
		(pts
			(xy 179.760118 -27.918664) (xy 179.770186 -27.918237) (xy 179.788782 -27.910514) (xy 179.796186 -27.903678)
			(xy 179.84089 -27.858974) (xy 179.847733 -27.851574) (xy 179.85546 -27.832976) (xy 179.855876 -27.822906)
			(xy 179.855876 -25.740106) (xy 179.855758 -25.735151) (xy 179.853843 -25.725428) (xy 179.852066 -25.720802)
			(xy 179.85613 -25.700228) (xy 180.17744 -25.378918) (xy 180.18484 -25.372076) (xy 180.203438 -25.364353)
			(xy 180.213508 -25.363932) (xy 182.387494 -25.363932) (xy 182.397565 -25.363511) (xy 182.416174 -25.355802)
			(xy 182.423562 -25.348946) (xy 183.0832 -24.689308) (xy 183.090048 -24.68191) (xy 183.097785 -24.663312)
			(xy 183.098186 -24.65324) (xy 183.098186 -22.555962) (xy 183.097659 -22.540643) (xy 183.088569 -22.511386)
			(xy 183.071217 -22.486136) (xy 183.047162 -22.467162) (xy 183.018565 -22.456169) (xy 182.987994 -22.454144)
			(xy 182.972964 -22.457156) (xy 182.951066 -22.46205) (xy 182.9065 -22.467267) (xy 182.884064 -22.46757)
			(xy 182.857047 -22.467099) (xy 182.803554 -22.459477) (xy 182.751669 -22.444391) (xy 182.702429 -22.422141)
			(xy 182.656817 -22.393173) (xy 182.615744 -22.358064) (xy 182.58003 -22.317516) (xy 182.550388 -22.272338)
			(xy 182.527411 -22.223433) (xy 182.511558 -22.171778) (xy 182.503144 -22.118403) (xy 182.502302 -22.091396)
			(xy 182.502302 -22.085554) (xy 182.50279 -22.058352) (xy 182.510513 -22.004498) (xy 182.525784 -21.95228)
			(xy 182.536592 -21.927312) (xy 182.540661 -21.917156) (xy 182.540673 -21.895298) (xy 182.536592 -21.885148)
			(xy 182.525853 -21.860298) (xy 182.510705 -21.808326) (xy 182.50305 -21.754735) (xy 182.502556 -21.727668)
			(xy 182.502556 -21.727414) (xy 182.503041 -21.700161) (xy 182.510795 -21.64621) (xy 182.526149 -21.593912)
			(xy 182.548789 -21.54433) (xy 182.578254 -21.498475) (xy 182.613945 -21.457281) (xy 182.655135 -21.421584)
			(xy 182.700986 -21.392113) (xy 182.750565 -21.369467) (xy 182.802861 -21.354106) (xy 182.856811 -21.346344)
			(xy 182.884064 -21.345906) (xy 182.884826 -21.345906) (xy 182.907069 -21.346263) (xy 182.95125 -21.351484)
			(xy 182.972964 -21.35632) (xy 182.984394 -21.359114) (xy 183.006746 -21.354034) (xy 183.078882 -21.297392)
			(xy 183.087598 -21.289816) (xy 183.097646 -21.26905) (xy 183.098186 -21.257514) (xy 183.098186 -19.90471)
			(xy 183.097764 -19.894639) (xy 183.090051 -19.876034) (xy 183.0832 -19.868642) (xy 182.552086 -19.337528)
			(xy 182.541418 -19.333718) (xy 182.512489 -19.322853) (xy 182.456992 -19.295667) (xy 182.404809 -19.262562)
			(xy 182.35657 -19.223936) (xy 182.334408 -19.2024) (xy 182.32247 -19.190462) (xy 182.315073 -19.183614)
			(xy 182.296474 -19.17588) (xy 182.286402 -19.175476) (xy 181.719474 -19.175476) (xy 181.711982 -19.175777)
			(xy 181.697649 -19.180157) (xy 181.69128 -19.184112) (xy 181.663575 -19.201972) (xy 181.604791 -19.231804)
			(xy 181.542919 -19.254546) (xy 181.478809 -19.269887) (xy 181.413344 -19.277616) (xy 181.380384 -19.278092)
			(xy 181.347426 -19.277602) (xy 181.281965 -19.269858) (xy 181.217859 -19.254513) (xy 181.155987 -19.231777)
			(xy 181.097197 -19.201964) (xy 181.069488 -19.184112) (xy 181.063126 -19.18014) (xy 181.04879 -19.17576)
			(xy 181.041294 -19.175476) (xy 176.110392 -19.175476) (xy 176.100322 -19.1759) (xy 176.081717 -19.183614)
			(xy 176.074324 -19.190462) (xy 175.973994 -19.290792) (xy 175.966628 -19.297904) (xy 175.959008 -19.3167)
			(xy 175.959008 -20.105116) (xy 175.959434 -20.115185) (xy 175.967154 -20.133784) (xy 175.973994 -20.141184)
			(xy 175.97755 -20.14474) (xy 175.526446 -20.595844) (xy 175.519047 -20.602688) (xy 175.500448 -20.610412)
			(xy 175.490378 -20.61083) (xy 175.320198 -20.61083) (xy 175.310179 -20.611251) (xy 175.291668 -20.618922)
			(xy 175.277504 -20.633095) (xy 175.269844 -20.651611) (xy 175.269398 -20.66163) (xy 175.269398 -21.517356)
			(xy 180.650132 -21.517356) (xy 180.654203 -21.461734) (xy 180.666329 -21.407297) (xy 180.686252 -21.355206)
			(xy 180.713548 -21.306571) (xy 180.747634 -21.262428) (xy 180.787783 -21.223719) (xy 180.833141 -21.191268)
			(xy 180.882741 -21.165767) (xy 180.935525 -21.14776) (xy 180.990368 -21.13763) (xy 181.046102 -21.135593)
			(xy 181.101539 -21.141693) (xy 181.155496 -21.155799) (xy 181.206825 -21.177611) (xy 181.254431 -21.206665)
			(xy 181.297299 -21.24234) (xy 181.334516 -21.283877) (xy 181.365289 -21.33039) (xy 181.388961 -21.380887)
			(xy 181.405029 -21.434294) (xy 181.413149 -21.48947) (xy 181.413658 -21.517356) (xy 181.413149 -21.545242)
			(xy 181.405029 -21.600418) (xy 181.388961 -21.653825) (xy 181.365289 -21.704322) (xy 181.334516 -21.750835)
			(xy 181.297299 -21.792372) (xy 181.254431 -21.828047) (xy 181.206825 -21.857101) (xy 181.155496 -21.878913)
			(xy 181.101539 -21.893019) (xy 181.046102 -21.899119) (xy 180.990368 -21.897082) (xy 180.935525 -21.886952)
			(xy 180.882741 -21.868945) (xy 180.833141 -21.843444) (xy 180.787783 -21.810993) (xy 180.747634 -21.772284)
			(xy 180.713548 -21.728141) (xy 180.686252 -21.679506) (xy 180.666329 -21.627415) (xy 180.654203 -21.572978)
			(xy 180.650132 -21.517356) (xy 175.269398 -21.517356) (xy 175.269398 -21.689568) (xy 175.269834 -21.699633)
			(xy 175.277565 -21.718219) (xy 175.284384 -21.725636) (xy 175.478948 -21.9202) (xy 181.416958 -21.9202)
			(xy 181.421031 -21.864541) (xy 181.433166 -21.810068) (xy 181.453102 -21.757942) (xy 181.480416 -21.709274)
			(xy 181.514524 -21.665102) (xy 181.554701 -21.626367) (xy 181.600089 -21.593895) (xy 181.649721 -21.568377)
			(xy 181.702541 -21.550358) (xy 181.75742 -21.540221) (xy 181.813191 -21.538183) (xy 181.868665 -21.544286)
			(xy 181.922658 -21.558402) (xy 181.974021 -21.580229) (xy 182.021659 -21.609302) (xy 182.064555 -21.645001)
			(xy 182.101797 -21.686565) (xy 182.132591 -21.733109) (xy 182.156279 -21.78364) (xy 182.172357 -21.837082)
			(xy 182.180483 -21.892296) (xy 182.180992 -21.9202) (xy 182.180483 -21.948104) (xy 182.172357 -22.003318)
			(xy 182.156279 -22.05676) (xy 182.132591 -22.107291) (xy 182.101797 -22.153835) (xy 182.064555 -22.195399)
			(xy 182.021659 -22.231098) (xy 181.974021 -22.260171) (xy 181.922658 -22.281998) (xy 181.868665 -22.296114)
			(xy 181.813191 -22.302217) (xy 181.75742 -22.300179) (xy 181.702541 -22.290042) (xy 181.649721 -22.272023)
			(xy 181.600089 -22.246505) (xy 181.554701 -22.214033) (xy 181.514524 -22.175298) (xy 181.480416 -22.131126)
			(xy 181.453102 -22.082458) (xy 181.433166 -22.030332) (xy 181.421031 -21.975859) (xy 181.416958 -21.9202)
			(xy 175.478948 -21.9202) (xy 175.971962 -22.413214) (xy 175.97881 -22.420611) (xy 175.986546 -22.43921)
			(xy 175.986948 -22.449282) (xy 175.986948 -22.800564) (xy 175.987435 -22.810525) (xy 175.995028 -22.828946)
			(xy 176.00168 -22.836378) (xy 176.061878 -22.89683) (xy 176.068686 -22.904176) (xy 176.076411 -22.922639)
			(xy 176.076864 -22.932644) (xy 176.076864 -27.867864) (xy 176.077345 -27.877879) (xy 176.084997 -27.896389)
			(xy 176.09915 -27.910562) (xy 176.11765 -27.918241) (xy 176.127664 -27.918664)
		)
		(stroke
			(width 0)
			(type solid)
		)
		(fill yes)
		(layer "F.Cu")
		(net "P12V_SCM_R")
	)
	(gr_poly
		(pts
			(xy 217.68816 -360.764074) (xy 217.687662 -360.674653) (xy 217.679695 -360.495989) (xy 217.663777 -360.317856)
			(xy 217.63994 -360.14061) (xy 217.60823 -359.964602) (xy 217.568712 -359.79018) (xy 217.521463 -359.617693)
			(xy 217.466576 -359.447481) (xy 217.404162 -359.279884) (xy 217.334344 -359.115233) (xy 217.257261 -358.953856)
			(xy 217.173065 -358.796072) (xy 217.081925 -358.642196) (xy 216.984019 -358.492533) (xy 216.879545 -358.34738)
			(xy 216.768707 -358.207025) (xy 216.651728 -358.071747) (xy 216.528838 -357.941814) (xy 216.400282 -357.817484)
			(xy 216.266315 -357.699005) (xy 216.127204 -357.586611) (xy 215.983223 -357.480525) (xy 215.83466 -357.380959)
			(xy 215.681809 -357.28811) (xy 215.524974 -357.202161) (xy 215.364465 -357.123285) (xy 215.200602 -357.051637)
			(xy 215.03371 -356.98736) (xy 214.864121 -356.930581) (xy 214.69217 -356.881413) (xy 214.5182 -356.839954)
			(xy 214.342556 -356.806286) (xy 214.165586 -356.780475) (xy 213.987642 -356.762574) (xy 213.809078 -356.752617)
			(xy 213.630247 -356.750625) (xy 213.451505 -356.756601) (xy 213.273206 -356.770534) (xy 213.095705 -356.792395)
			(xy 212.919355 -356.822141) (xy 212.744504 -356.859714) (xy 212.571501 -356.905039) (xy 212.400688 -356.958026)
			(xy 212.232406 -357.018569) (xy 212.066987 -357.086548) (xy 211.904761 -357.161829) (xy 211.74605 -357.244262)
			(xy 211.591168 -357.333683) (xy 211.440424 -357.429915) (xy 211.294116 -357.532766) (xy 211.152535 -357.642033)
			(xy 211.015961 -357.757498) (xy 210.884668 -357.878933) (xy 210.758914 -358.006096) (xy 210.638949 -358.138734)
			(xy 210.525012 -358.276585) (xy 210.417329 -358.419375) (xy 210.316114 -358.566819) (xy 210.221568 -358.718627)
			(xy 210.133878 -358.874495) (xy 210.053218 -359.034115) (xy 209.979749 -359.197169) (xy 209.913617 -359.363335)
			(xy 209.854952 -359.532281) (xy 209.803872 -359.703673) (xy 209.760477 -359.877171) (xy 209.724855 -360.052429)
			(xy 209.697074 -360.2291) (xy 209.677192 -360.406834) (xy 209.665246 -360.585276) (xy 209.661262 -360.764074)
			(xy 211.159857 -360.764074) (xy 211.163885 -360.621782) (xy 211.175957 -360.479946) (xy 211.196034 -360.339019)
			(xy 211.224052 -360.199455) (xy 211.259921 -360.061699) (xy 211.303526 -359.926193) (xy 211.354727 -359.793371)
			(xy 211.413361 -359.663658) (xy 211.479239 -359.537471) (xy 211.552151 -359.415212) (xy 211.631863 -359.297275)
			(xy 211.71812 -359.184036) (xy 211.810644 -359.075858) (xy 211.909141 -358.973088) (xy 212.013295 -358.876055)
			(xy 212.122771 -358.785071) (xy 212.237219 -358.700425) (xy 212.356273 -358.62239) (xy 212.479551 -358.551216)
			(xy 212.606658 -358.487129) (xy 212.737187 -358.430337) (xy 212.870721 -358.38102) (xy 213.00683 -358.339337)
			(xy 213.14508 -358.305421) (xy 213.285027 -358.279381) (xy 213.426223 -358.2613) (xy 213.568216 -358.251237)
			(xy 213.710551 -358.249222) (xy 213.852772 -358.255264) (xy 213.994423 -358.269342) (xy 214.135051 -358.291411)
			(xy 214.274205 -358.321401) (xy 214.41144 -358.359216) (xy 214.546315 -358.404734) (xy 214.678399 -358.45781)
			(xy 214.807269 -358.518273) (xy 214.932512 -358.58593) (xy 215.053726 -358.660565) (xy 215.170524 -358.741938)
			(xy 215.282531 -358.829788) (xy 215.389389 -358.923835) (xy 215.490754 -359.023776) (xy 215.586303 -359.129292)
			(xy 215.67573 -359.240045) (xy 215.758748 -359.355679) (xy 215.83509 -359.475826) (xy 215.904513 -359.600098)
			(xy 215.966794 -359.7281) (xy 216.021734 -359.85942) (xy 216.069156 -359.993637) (xy 216.108909 -360.130323)
			(xy 216.140865 -360.269039) (xy 216.164922 -360.40934) (xy 216.181003 -360.550778) (xy 216.189056 -360.692899)
			(xy 216.18956 -360.764074) (xy 216.189056 -360.835249) (xy 216.181003 -360.97737) (xy 216.164922 -361.118808)
			(xy 216.140865 -361.259109) (xy 216.108909 -361.397825) (xy 216.069156 -361.534511) (xy 216.021734 -361.668728)
			(xy 215.966794 -361.800048) (xy 215.904513 -361.92805) (xy 215.83509 -362.052322) (xy 215.758748 -362.172469)
			(xy 215.67573 -362.288103) (xy 215.586303 -362.398856) (xy 215.490754 -362.504372) (xy 215.389389 -362.604313)
			(xy 215.282531 -362.69836) (xy 215.170524 -362.78621) (xy 215.053726 -362.867583) (xy 214.932512 -362.942218)
			(xy 214.807269 -363.009875) (xy 214.678399 -363.070338) (xy 214.546315 -363.123414) (xy 214.41144 -363.168932)
			(xy 214.274205 -363.206747) (xy 214.135051 -363.236737) (xy 213.994423 -363.258806) (xy 213.852772 -363.272884)
			(xy 213.710551 -363.278926) (xy 213.568216 -363.276911) (xy 213.426223 -363.266848) (xy 213.285027 -363.248767)
			(xy 213.14508 -363.222727) (xy 213.00683 -363.188811) (xy 212.870721 -363.147128) (xy 212.737187 -363.097811)
			(xy 212.606658 -363.041019) (xy 212.479551 -362.976932) (xy 212.356273 -362.905758) (xy 212.237219 -362.827723)
			(xy 212.122771 -362.743077) (xy 212.013295 -362.652093) (xy 211.909141 -362.55506) (xy 211.810644 -362.45229)
			(xy 211.71812 -362.344112) (xy 211.631863 -362.230873) (xy 211.552151 -362.112936) (xy 211.479239 -361.990677)
			(xy 211.413361 -361.86449) (xy 211.354727 -361.734777) (xy 211.303526 -361.601955) (xy 211.259921 -361.466449)
			(xy 211.224052 -361.328693) (xy 211.196034 -361.189129) (xy 211.175957 -361.048202) (xy 211.163885 -360.906366)
			(xy 211.159857 -360.764074) (xy 209.661262 -360.764074) (xy 209.665246 -360.942872) (xy 209.677192 -361.121314)
			(xy 209.697074 -361.299048) (xy 209.724855 -361.475719) (xy 209.760477 -361.650977) (xy 209.803872 -361.824475)
			(xy 209.854952 -361.995867) (xy 209.913617 -362.164813) (xy 209.979749 -362.330979) (xy 210.053218 -362.494033)
			(xy 210.133878 -362.653653) (xy 210.221568 -362.809521) (xy 210.316114 -362.961329) (xy 210.417329 -363.108773)
			(xy 210.525012 -363.251563) (xy 210.638949 -363.389414) (xy 210.758914 -363.522052) (xy 210.884668 -363.649215)
			(xy 211.015961 -363.77065) (xy 211.152535 -363.886115) (xy 211.294116 -363.995382) (xy 211.440424 -364.098233)
			(xy 211.591168 -364.194465) (xy 211.74605 -364.283886) (xy 211.904761 -364.366319) (xy 212.066987 -364.4416)
			(xy 212.232406 -364.509579) (xy 212.400688 -364.570122) (xy 212.571501 -364.623109) (xy 212.744504 -364.668434)
			(xy 212.919355 -364.706007) (xy 213.095705 -364.735753) (xy 213.273206 -364.757614) (xy 213.451505 -364.771547)
			(xy 213.630247 -364.777523) (xy 213.809078 -364.775531) (xy 213.987642 -364.765574) (xy 214.165586 -364.747673)
			(xy 214.342556 -364.721862) (xy 214.5182 -364.688194) (xy 214.69217 -364.646735) (xy 214.864121 -364.597567)
			(xy 215.03371 -364.540788) (xy 215.200602 -364.476511) (xy 215.364465 -364.404863) (xy 215.524974 -364.325987)
			(xy 215.681809 -364.240038) (xy 215.83466 -364.147189) (xy 215.983223 -364.047623) (xy 216.127204 -363.941537)
			(xy 216.266315 -363.829143) (xy 216.400282 -363.710664) (xy 216.528838 -363.586334) (xy 216.651728 -363.456401)
			(xy 216.768707 -363.321123) (xy 216.879545 -363.180768) (xy 216.984019 -363.035615) (xy 217.081925 -362.885952)
			(xy 217.173065 -362.732076) (xy 217.257261 -362.574292) (xy 217.334344 -362.412915) (xy 217.404162 -362.248264)
			(xy 217.466576 -362.080667) (xy 217.521463 -361.910455) (xy 217.568712 -361.737968) (xy 217.60823 -361.563546)
			(xy 217.63994 -361.387538) (xy 217.663777 -361.210292) (xy 217.679695 -361.032159) (xy 217.687662 -360.853495)
		)
		(stroke
			(width 0)
			(type solid)
		)
		(fill yes)
		(layer "F.Cu")
		(net "GND")
	)
	(gr_poly
		(pts
			(xy 262.13816 -360.764074) (xy 262.137662 -360.674653) (xy 262.129695 -360.495989) (xy 262.113777 -360.317856)
			(xy 262.08994 -360.14061) (xy 262.05823 -359.964602) (xy 262.018712 -359.79018) (xy 261.971463 -359.617693)
			(xy 261.916576 -359.447481) (xy 261.854162 -359.279884) (xy 261.784344 -359.115233) (xy 261.707261 -358.953856)
			(xy 261.623065 -358.796072) (xy 261.531925 -358.642196) (xy 261.434019 -358.492533) (xy 261.329545 -358.34738)
			(xy 261.218707 -358.207025) (xy 261.101728 -358.071747) (xy 260.978838 -357.941814) (xy 260.850282 -357.817484)
			(xy 260.716315 -357.699005) (xy 260.577204 -357.586611) (xy 260.433223 -357.480525) (xy 260.28466 -357.380959)
			(xy 260.131809 -357.28811) (xy 259.974974 -357.202161) (xy 259.814465 -357.123285) (xy 259.650602 -357.051637)
			(xy 259.48371 -356.98736) (xy 259.314121 -356.930581) (xy 259.14217 -356.881413) (xy 258.9682 -356.839954)
			(xy 258.792556 -356.806286) (xy 258.615586 -356.780475) (xy 258.437642 -356.762574) (xy 258.259078 -356.752617)
			(xy 258.080247 -356.750625) (xy 257.901505 -356.756601) (xy 257.723206 -356.770534) (xy 257.545705 -356.792395)
			(xy 257.369355 -356.822141) (xy 257.194504 -356.859714) (xy 257.021501 -356.905039) (xy 256.850688 -356.958026)
			(xy 256.682406 -357.018569) (xy 256.516987 -357.086548) (xy 256.354761 -357.161829) (xy 256.19605 -357.244262)
			(xy 256.041168 -357.333683) (xy 255.890424 -357.429915) (xy 255.744116 -357.532766) (xy 255.602535 -357.642033)
			(xy 255.465961 -357.757498) (xy 255.334668 -357.878933) (xy 255.208914 -358.006096) (xy 255.088949 -358.138734)
			(xy 254.975012 -358.276585) (xy 254.867329 -358.419375) (xy 254.766114 -358.566819) (xy 254.671568 -358.718627)
			(xy 254.583878 -358.874495) (xy 254.503218 -359.034115) (xy 254.429749 -359.197169) (xy 254.363617 -359.363335)
			(xy 254.304952 -359.532281) (xy 254.253872 -359.703673) (xy 254.210477 -359.877171) (xy 254.174855 -360.052429)
			(xy 254.147074 -360.2291) (xy 254.127192 -360.406834) (xy 254.115246 -360.585276) (xy 254.111262 -360.764074)
			(xy 255.609857 -360.764074) (xy 255.613885 -360.621782) (xy 255.625957 -360.479946) (xy 255.646034 -360.339019)
			(xy 255.674052 -360.199455) (xy 255.709921 -360.061699) (xy 255.753526 -359.926193) (xy 255.804727 -359.793371)
			(xy 255.863361 -359.663658) (xy 255.929239 -359.537471) (xy 256.002151 -359.415212) (xy 256.081863 -359.297275)
			(xy 256.16812 -359.184036) (xy 256.260644 -359.075858) (xy 256.359141 -358.973088) (xy 256.463295 -358.876055)
			(xy 256.572771 -358.785071) (xy 256.687219 -358.700425) (xy 256.806273 -358.62239) (xy 256.929551 -358.551216)
			(xy 257.056658 -358.487129) (xy 257.187187 -358.430337) (xy 257.320721 -358.38102) (xy 257.45683 -358.339337)
			(xy 257.59508 -358.305421) (xy 257.735027 -358.279381) (xy 257.876223 -358.2613) (xy 258.018216 -358.251237)
			(xy 258.160551 -358.249222) (xy 258.302772 -358.255264) (xy 258.444423 -358.269342) (xy 258.585051 -358.291411)
			(xy 258.724205 -358.321401) (xy 258.86144 -358.359216) (xy 258.996315 -358.404734) (xy 259.128399 -358.45781)
			(xy 259.257269 -358.518273) (xy 259.382512 -358.58593) (xy 259.503726 -358.660565) (xy 259.620524 -358.741938)
			(xy 259.732531 -358.829788) (xy 259.839389 -358.923835) (xy 259.940754 -359.023776) (xy 260.036303 -359.129292)
			(xy 260.12573 -359.240045) (xy 260.208748 -359.355679) (xy 260.28509 -359.475826) (xy 260.354513 -359.600098)
			(xy 260.416794 -359.7281) (xy 260.471734 -359.85942) (xy 260.519156 -359.993637) (xy 260.558909 -360.130323)
			(xy 260.590865 -360.269039) (xy 260.614922 -360.40934) (xy 260.631003 -360.550778) (xy 260.639056 -360.692899)
			(xy 260.63956 -360.764074) (xy 260.639056 -360.835249) (xy 260.631003 -360.97737) (xy 260.614922 -361.118808)
			(xy 260.590865 -361.259109) (xy 260.558909 -361.397825) (xy 260.519156 -361.534511) (xy 260.471734 -361.668728)
			(xy 260.416794 -361.800048) (xy 260.354513 -361.92805) (xy 260.28509 -362.052322) (xy 260.208748 -362.172469)
			(xy 260.12573 -362.288103) (xy 260.036303 -362.398856) (xy 259.940754 -362.504372) (xy 259.839389 -362.604313)
			(xy 259.732531 -362.69836) (xy 259.620524 -362.78621) (xy 259.503726 -362.867583) (xy 259.382512 -362.942218)
			(xy 259.257269 -363.009875) (xy 259.128399 -363.070338) (xy 258.996315 -363.123414) (xy 258.86144 -363.168932)
			(xy 258.724205 -363.206747) (xy 258.585051 -363.236737) (xy 258.444423 -363.258806) (xy 258.302772 -363.272884)
			(xy 258.160551 -363.278926) (xy 258.018216 -363.276911) (xy 257.876223 -363.266848) (xy 257.735027 -363.248767)
			(xy 257.59508 -363.222727) (xy 257.45683 -363.188811) (xy 257.320721 -363.147128) (xy 257.187187 -363.097811)
			(xy 257.056658 -363.041019) (xy 256.929551 -362.976932) (xy 256.806273 -362.905758) (xy 256.687219 -362.827723)
			(xy 256.572771 -362.743077) (xy 256.463295 -362.652093) (xy 256.359141 -362.55506) (xy 256.260644 -362.45229)
			(xy 256.16812 -362.344112) (xy 256.081863 -362.230873) (xy 256.002151 -362.112936) (xy 255.929239 -361.990677)
			(xy 255.863361 -361.86449) (xy 255.804727 -361.734777) (xy 255.753526 -361.601955) (xy 255.709921 -361.466449)
			(xy 255.674052 -361.328693) (xy 255.646034 -361.189129) (xy 255.625957 -361.048202) (xy 255.613885 -360.906366)
			(xy 255.609857 -360.764074) (xy 254.111262 -360.764074) (xy 254.115246 -360.942872) (xy 254.127192 -361.121314)
			(xy 254.147074 -361.299048) (xy 254.174855 -361.475719) (xy 254.210477 -361.650977) (xy 254.253872 -361.824475)
			(xy 254.304952 -361.995867) (xy 254.363617 -362.164813) (xy 254.429749 -362.330979) (xy 254.503218 -362.494033)
			(xy 254.583878 -362.653653) (xy 254.671568 -362.809521) (xy 254.766114 -362.961329) (xy 254.867329 -363.108773)
			(xy 254.975012 -363.251563) (xy 255.088949 -363.389414) (xy 255.208914 -363.522052) (xy 255.334668 -363.649215)
			(xy 255.465961 -363.77065) (xy 255.602535 -363.886115) (xy 255.744116 -363.995382) (xy 255.890424 -364.098233)
			(xy 256.041168 -364.194465) (xy 256.19605 -364.283886) (xy 256.354761 -364.366319) (xy 256.516987 -364.4416)
			(xy 256.682406 -364.509579) (xy 256.850688 -364.570122) (xy 257.021501 -364.623109) (xy 257.194504 -364.668434)
			(xy 257.369355 -364.706007) (xy 257.545705 -364.735753) (xy 257.723206 -364.757614) (xy 257.901505 -364.771547)
			(xy 258.080247 -364.777523) (xy 258.259078 -364.775531) (xy 258.437642 -364.765574) (xy 258.615586 -364.747673)
			(xy 258.792556 -364.721862) (xy 258.9682 -364.688194) (xy 259.14217 -364.646735) (xy 259.314121 -364.597567)
			(xy 259.48371 -364.540788) (xy 259.650602 -364.476511) (xy 259.814465 -364.404863) (xy 259.974974 -364.325987)
			(xy 260.131809 -364.240038) (xy 260.28466 -364.147189) (xy 260.433223 -364.047623) (xy 260.577204 -363.941537)
			(xy 260.716315 -363.829143) (xy 260.850282 -363.710664) (xy 260.978838 -363.586334) (xy 261.101728 -363.456401)
			(xy 261.218707 -363.321123) (xy 261.329545 -363.180768) (xy 261.434019 -363.035615) (xy 261.531925 -362.885952)
			(xy 261.623065 -362.732076) (xy 261.707261 -362.574292) (xy 261.784344 -362.412915) (xy 261.854162 -362.248264)
			(xy 261.916576 -362.080667) (xy 261.971463 -361.910455) (xy 262.018712 -361.737968) (xy 262.05823 -361.563546)
			(xy 262.08994 -361.387538) (xy 262.113777 -361.210292) (xy 262.129695 -361.032159) (xy 262.137662 -360.853495)
		)
		(stroke
			(width 0)
			(type solid)
		)
		(fill yes)
		(layer "F.Cu")
		(net "GND")
	)
	(gr_poly
		(pts
			(xy 43.481752 -360.4006) (xy 43.503088 -360.4006) (xy 45.155612 -358.748076)
			(arc
				(start 45.572426 -358.331262)
				(mid 45.58896 -358.320151)
				(end 45.608494 -358.316276)
			)
			(xy 55.959248 -358.316276)
			(arc
				(start 55.966868 -358.313736)
				(mid 56.0247 -358.300006)
				(end 56.083962 -358.295448)
			)
			(arc
				(start 56.083962 -358.295448)
				(mid 56.14322 -358.300035)
				(end 56.201056 -358.313736)
			)
			(xy 56.208676 -358.316276) (xy 57.571894 -356.953058)
			(arc
				(start 57.571894 -347.086682)
				(mid 57.567993 -347.067159)
				(end 57.556908 -347.050614)
			)
			(arc
				(start 57.514998 -347.008704)
				(mid 57.498464 -346.997593)
				(end 57.47893 -346.993718)
			)
			(arc
				(start 53.966364 -346.993718)
				(mid 53.946841 -346.997619)
				(end 53.930296 -347.008704)
			)
			(xy 53.926994 -347.012006)
			(arc
				(start 53.926994 -348.96679)
				(mid 53.930895 -348.986313)
				(end 53.94198 -349.002858)
			)
			(arc
				(start 53.994304 -349.055182)
				(mid 54.010838 -349.066293)
				(end 54.030372 -349.070168)
			)
			(arc
				(start 55.33898 -349.070168)
				(mid 55.358474 -349.073952)
				(end 55.375048 -349.0849)
			)
			(arc
				(start 55.475632 -349.185484)
				(mid 55.486743 -349.202018)
				(end 55.490618 -349.221552)
			)
			(arc
				(start 55.490618 -349.958914)
				(mid 55.494519 -349.978437)
				(end 55.505604 -349.994982)
			)
			(arc
				(start 55.858664 -350.348042)
				(mid 55.869775 -350.364576)
				(end 55.87365 -350.38411)
			)
			(arc
				(start 55.87365 -352.166936)
				(mid 55.869749 -352.186459)
				(end 55.858664 -352.203004)
			)
			(arc
				(start 55.730902 -352.330766)
				(mid 55.714368 -352.341877)
				(end 55.694834 -352.345752)
			)
			(arc
				(start 53.28031 -352.345752)
				(mid 53.260787 -352.349653)
				(end 53.244242 -352.360738)
			)
			(arc
				(start 52.963826 -352.641154)
				(mid 52.947292 -352.652265)
				(end 52.927758 -352.65614)
			)
			(arc
				(start 49.959006 -352.65614)
				(mid 49.939483 -352.652239)
				(end 49.922938 -352.641154)
			)
			(arc
				(start 49.23028 -351.948496)
				(mid 49.219169 -351.931962)
				(end 49.215294 -351.912428)
			)
			(arc
				(start 49.215294 -347.213682)
				(mid 49.211393 -347.194159)
				(end 49.200308 -347.177614)
			)
			(arc
				(start 49.00676 -346.984066)
				(mid 48.990226 -346.972955)
				(end 48.970692 -346.96908)
			)
			(arc
				(start 45.66158 -346.96908)
				(mid 45.642057 -346.972981)
				(end 45.625512 -346.984066)
			)
			(arc
				(start 45.58538 -347.024198)
				(mid 45.574269 -347.040732)
				(end 45.570394 -347.060266)
			)
			(arc
				(start 45.570394 -348.96679)
				(mid 45.574295 -348.986313)
				(end 45.58538 -349.002858)
			)
			(arc
				(start 45.637704 -349.055182)
				(mid 45.654238 -349.066293)
				(end 45.673772 -349.070168)
			)
			(arc
				(start 46.98238 -349.070168)
				(mid 47.001874 -349.073952)
				(end 47.018448 -349.0849)
			)
			(arc
				(start 47.136812 -349.20301)
				(mid 47.147923 -349.219544)
				(end 47.151798 -349.239078)
			)
			(arc
				(start 47.151798 -349.976694)
				(mid 47.155699 -349.996217)
				(end 47.166784 -350.012762)
			)
			(arc
				(start 47.502064 -350.348042)
				(mid 47.513175 -350.364576)
				(end 47.51705 -350.38411)
			)
			(xy 47.51705 -351.812098) (xy 47.513494 -351.815654)
			(arc
				(start 47.513494 -352.039936)
				(mid 47.509593 -352.059459)
				(end 47.498508 -352.076004)
			)
			(arc
				(start 46.902878 -352.671634)
				(mid 46.886344 -352.682745)
				(end 46.86681 -352.68662)
			)
			(arc
				(start 41.677082 -352.68662)
				(mid 41.657559 -352.682719)
				(end 41.641014 -352.671634)
			)
			(arc
				(start 40.89908 -351.9297)
				(mid 40.887969 -351.913166)
				(end 40.884094 -351.893632)
			)
			(arc
				(start 40.884094 -347.137482)
				(mid 40.880193 -347.117959)
				(end 40.869108 -347.101414)
			)
			(arc
				(start 40.72128 -346.953586)
				(mid 40.704746 -346.942475)
				(end 40.685212 -346.9386)
			)
			(arc
				(start 37.374322 -346.9386)
				(mid 37.354799 -346.942501)
				(end 37.338254 -346.953586)
			)
			(arc
				(start 37.27958 -347.01226)
				(mid 37.268469 -347.028794)
				(end 37.264594 -347.048328)
			)
			(arc
				(start 37.264594 -348.96679)
				(mid 37.268495 -348.986313)
				(end 37.27958 -349.002858)
			)
			(arc
				(start 37.331904 -349.055182)
				(mid 37.348438 -349.066293)
				(end 37.367972 -349.070168)
			)
			(arc
				(start 38.67658 -349.070168)
				(mid 38.696074 -349.073952)
				(end 38.712648 -349.0849)
			)
			(arc
				(start 38.816788 -349.18904)
				(mid 38.827899 -349.205574)
				(end 38.831774 -349.225108)
			)
			(arc
				(start 38.831774 -349.96247)
				(mid 38.835675 -349.981993)
				(end 38.84676 -349.998538)
			)
			(arc
				(start 39.196264 -350.348042)
				(mid 39.207375 -350.364576)
				(end 39.21125 -350.38411)
			)
			(xy 39.21125 -351.761298) (xy 39.207694 -351.764854)
			(arc
				(start 39.207694 -352.166936)
				(mid 39.203793 -352.186459)
				(end 39.192708 -352.203004)
			)
			(arc
				(start 38.772338 -352.623374)
				(mid 38.755804 -352.634485)
				(end 38.73627 -352.63836)
			)
			(arc
				(start 33.345882 -352.63836)
				(mid 33.326359 -352.634459)
				(end 33.309814 -352.623374)
			)
			(arc
				(start 32.61868 -351.93224)
				(mid 32.607569 -351.915706)
				(end 32.603694 -351.896172)
			)
			(arc
				(start 32.603694 -347.086682)
				(mid 32.599793 -347.067159)
				(end 32.588708 -347.050614)
			)
			(arc
				(start 32.55137 -347.013276)
				(mid 32.534836 -347.002165)
				(end 32.515302 -346.99829)
			)
			(arc
				(start 31.745428 -346.99829)
				(mid 31.725905 -346.994389)
				(end 31.70936 -346.983304)
			)
			(arc
				(start 31.700724 -346.974668)
				(mid 31.68419 -346.963557)
				(end 31.664656 -346.959682)
			)
			(arc
				(start 29.028644 -346.959682)
				(mid 29.009121 -346.963583)
				(end 28.992576 -346.974668)
			)
			(xy 28.989782 -346.977462) (xy 28.982162 -346.996004)
			(arc
				(start 28.982162 -348.996)
				(mid 28.986063 -349.015523)
				(end 28.997148 -349.032068)
			)
			(xy 28.999942 -349.034862) (xy 29.018484 -349.042482)
			(arc
				(start 30.368494 -349.042482)
				(mid 30.387988 -349.046266)
				(end 30.404562 -349.057214)
			)
			(arc
				(start 30.540706 -349.193358)
				(mid 30.551817 -349.209892)
				(end 30.555692 -349.229426)
			)
			(arc
				(start 30.555692 -349.966788)
				(mid 30.559593 -349.986311)
				(end 30.570678 -350.002856)
			)
			(arc
				(start 30.915864 -350.348042)
				(mid 30.926975 -350.364576)
				(end 30.93085 -350.38411)
			)
			(xy 30.93085 -351.507298) (xy 30.927294 -351.510854)
			(arc
				(start 30.927294 -353.546918)
				(mid 30.931195 -353.566441)
				(end 30.94228 -353.582986)
			)
			(arc
				(start 31.475934 -354.11664)
				(mid 31.492468 -354.127751)
				(end 31.512002 -354.131626)
			)
			(arc
				(start 35.567366 -354.131626)
				(mid 35.586889 -354.135527)
				(end 35.603434 -354.146612)
			)
			(xy 39.412418 -357.955596) (xy 39.412418 -357.995728) (xy 41.804336 -360.387646) (xy 41.804336 -360.408474)
			(xy 43.474132 -360.408474)
		)
		(stroke
			(width 0)
			(type solid)
		)
		(fill yes)
		(layer "F.Cu")
		(net "SW_P12V_AUX_PVDDIO_P1_FLT")
	)
	(gr_poly
		(pts
			(arc
				(start 138.35761 -386.304282)
				(mid 138.377133 -386.300381)
				(end 138.393678 -386.289296)
			)
			(arc
				(start 138.503152 -386.179822)
				(mid 138.514263 -386.163288)
				(end 138.518138 -386.143754)
			)
			(arc
				(start 138.518138 -385.88823)
				(mid 138.522039 -385.868707)
				(end 138.533124 -385.852162)
			)
			(arc
				(start 138.649202 -385.736084)
				(mid 138.660264 -385.719667)
				(end 138.664188 -385.70027)
			)
			(arc
				(start 138.664188 -385.6355)
				(mid 138.701444 -385.545428)
				(end 138.791442 -385.507992)
			)
			(xy 138.853418 -385.507992)
			(arc
				(start 138.862816 -385.504182)
				(mid 138.921178 -385.486198)
				(end 138.981942 -385.480052)
			)
			(arc
				(start 138.981942 -385.480052)
				(mid 139.042713 -385.486161)
				(end 139.101068 -385.504182)
			)
			(xy 139.110466 -385.507992)
			(arc
				(start 139.172442 -385.507992)
				(mid 139.249839 -385.534169)
				(end 139.295378 -385.601972)
			)
			(xy 139.29995 -385.618482) (xy 139.327128 -385.63931) (xy 139.449556 -385.63931) (xy 139.476734 -385.618482)
			(arc
				(start 139.481306 -385.601972)
				(mid 139.526895 -385.534234)
				(end 139.604242 -385.507992)
			)
			(xy 139.666218 -385.507992)
			(arc
				(start 139.675616 -385.504182)
				(mid 139.733978 -385.486198)
				(end 139.794742 -385.480052)
			)
			(arc
				(start 139.794742 -385.480052)
				(mid 139.855513 -385.486161)
				(end 139.913868 -385.504182)
			)
			(xy 139.923266 -385.507992)
			(arc
				(start 139.985242 -385.507992)
				(mid 140.062639 -385.534169)
				(end 140.108178 -385.601972)
			)
			(xy 140.11275 -385.618482) (xy 140.139928 -385.63931) (xy 140.21054 -385.63931) (xy 140.226542 -385.633976)
			(arc
				(start 140.2334 -385.628642)
				(mid 140.416993 -385.529566)
				(end 140.622782 -385.495292)
			)
			(arc
				(start 140.622782 -385.495292)
				(mid 140.853226 -385.538545)
				(end 141.052296 -385.662424)
			)
			(arc
				(start 141.052296 -385.662424)
				(mid 141.068212 -385.672195)
				(end 141.086586 -385.675632)
			)
			(xy 141.535404 -385.675632) (xy 141.5542 -385.668012) (xy 141.559534 -385.662678)
			(arc
				(start 141.559534 -385.240784)
				(mid 141.552272 -385.214609)
				(end 141.53261 -385.195826)
			)
			(arc
				(start 141.53261 -385.195826)
				(mid 141.392722 -385.09406)
				(end 141.285468 -384.958336)
			)
			(arc
				(start 141.285468 -384.958336)
				(mid 141.266809 -384.940046)
				(end 141.241526 -384.933444)
			)
			(arc
				(start 141.15415 -384.933444)
				(mid 141.128863 -384.940039)
				(end 141.110208 -384.958336)
			)
			(arc
				(start 141.110208 -384.958336)
				(mid 140.878083 -385.187488)
				(end 140.562838 -385.271264)
			)
			(arc
				(start 140.562838 -385.271264)
				(mid 139.92733 -384.635756)
				(end 140.562838 -384.000248)
			)
			(arc
				(start 140.562838 -384.000248)
				(mid 140.737462 -384.02472)
				(end 140.898626 -384.09626)
			)
			(arc
				(start 140.898626 -384.09626)
				(mid 140.931262 -384.103481)
				(end 140.961364 -384.088894)
			)
			(xy 141.322552 -383.72796) (xy 141.329918 -383.71272)
			(arc
				(start 141.330934 -383.704338)
				(mid 141.339011 -383.663475)
				(end 141.352524 -383.624074)
			)
			(xy 141.356588 -383.614676) (xy 141.356588 -383.5527) (xy 141.35735 -383.538476) (xy 141.357604 -383.535682)
			(arc
				(start 141.357604 -383.532888)
				(mid 141.342725 -383.496967)
				(end 141.306804 -383.482088)
			)
			(xy 139.850114 -383.482088) (xy 139.844018 -383.475992) (xy 139.720828 -383.502408) (xy 139.70127 -383.519426)
			(arc
				(start 139.696698 -383.531618)
				(mid 139.463482 -383.830192)
				(end 139.10183 -383.943098)
			)
			(arc
				(start 139.10183 -383.943098)
				(mid 138.652458 -383.756962)
				(end 138.466322 -383.30759)
			)
			(arc
				(start 138.466322 -383.30759)
				(mid 138.547602 -382.996688)
				(end 138.770614 -382.7653)
			)
			(arc
				(start 138.770614 -382.7653)
				(mid 138.787529 -382.748289)
				(end 138.794744 -382.725422)
			)
			(arc
				(start 138.794744 -382.725422)
				(mid 138.800219 -382.684879)
				(end 138.811 -382.645412)
			)
			(xy 138.814048 -382.637284)
			(arc
				(start 138.814048 -382.618996)
				(mid 138.799169 -382.583075)
				(end 138.763248 -382.568196)
			)
			(xy 138.757152 -382.568196)
			(arc
				(start 138.751564 -382.569466)
				(mid 138.716501 -382.575705)
				(end 138.680952 -382.577848)
			)
			(arc
				(start 138.25474 -382.577848)
				(mid 138.235246 -382.581632)
				(end 138.218672 -382.59258)
			)
			(arc
				(start 138.190986 -382.62052)
				(mid 138.179924 -382.636937)
				(end 138.176 -382.656334)
			)
			(arc
				(start 138.176 -383.079244)
				(mid 138.172099 -383.098767)
				(end 138.161014 -383.115312)
			)
			(arc
				(start 137.887202 -383.389124)
				(mid 137.876091 -383.405658)
				(end 137.872216 -383.425192)
			)
			(arc
				(start 137.872216 -386.200904)
				(mid 137.876117 -386.220427)
				(end 137.887202 -386.236972)
			)
			(arc
				(start 137.939526 -386.289296)
				(mid 137.95606 -386.300407)
				(end 137.975594 -386.304282)
			)
		)
		(stroke
			(width 0)
			(type solid)
		)
		(fill yes)
		(layer "F.Cu")
		(net "P1V8_CPU1_RT_1D")
	)
	(gr_poly
		(pts
			(xy 380.696724 -180.526182) (xy 379.26391 -180.526182) (xy 379.132338 -180.39461) (xy 379.132338 -179.410868)
			(xy 378.754894 -179.033424) (xy 378.754894 -177.331116) (xy 379.578362 -176.507648) (xy 384.353308 -176.507648)
			(xy 385.308094 -177.462434) (xy 385.308094 -182.363364) (xy 385.435094 -182.490364) (xy 389.016494 -182.490364)
			(xy 389.027924 -182.478934) (xy 389.027924 -180.526182) (xy 387.648958 -180.526182) (xy 387.46303 -180.340254)
			(xy 387.46303 -179.33416) (xy 387.161278 -179.032408) (xy 387.161278 -175.777652) (xy 386.155438 -174.771812)
			(xy 386.155438 -170.080432) (xy 384.092958 -168.017952) (xy 384.02768 -167.952674) (xy 384.02768 -159.951674)
			(xy 383.711958 -159.635952) (xy 365.421418 -159.635952) (xy 364.534958 -158.749492) (xy 364.534958 -150.042372)
			(xy 363.531658 -149.039072) (xy 352.823018 -149.039072) (xy 350.326452 -151.535638) (xy 341.92083 -151.535638)
			(xy 341.549228 -151.90724) (xy 341.549228 -152.754781) (xy 361.196124 -152.754781) (xy 361.196124 -152.670059)
			(xy 361.204177 -152.585722) (xy 361.220211 -152.502532) (xy 361.244079 -152.421242) (xy 361.275567 -152.34259)
			(xy 361.314389 -152.267287) (xy 361.360192 -152.196015) (xy 361.412563 -152.129419) (xy 361.471028 -152.068104)
			(xy 361.535056 -152.012623) (xy 361.604068 -151.96348) (xy 361.677438 -151.92112) (xy 361.754503 -151.885925)
			(xy 361.834565 -151.858216) (xy 361.916898 -151.838242) (xy 362.000757 -151.826185) (xy 362.085382 -151.822154)
			(xy 362.170007 -151.826185) (xy 362.253866 -151.838242) (xy 362.336199 -151.858216) (xy 362.416261 -151.885925)
			(xy 362.493326 -151.92112) (xy 362.566696 -151.96348) (xy 362.635708 -152.012623) (xy 362.699736 -152.068104)
			(xy 362.758201 -152.129419) (xy 362.810572 -152.196015) (xy 362.856375 -152.267287) (xy 362.895197 -152.34259)
			(xy 362.926685 -152.421242) (xy 362.950553 -152.502532) (xy 362.966587 -152.585722) (xy 362.97464 -152.670059)
			(xy 362.975144 -152.71242) (xy 362.97464 -152.754781) (xy 362.966587 -152.839118) (xy 362.950553 -152.922308)
			(xy 362.926685 -153.003598) (xy 362.895197 -153.08225) (xy 362.856375 -153.157553) (xy 362.810572 -153.228825)
			(xy 362.758201 -153.295421) (xy 362.699736 -153.356736) (xy 362.635708 -153.412217) (xy 362.566696 -153.46136)
			(xy 362.493326 -153.50372) (xy 362.416261 -153.538915) (xy 362.336199 -153.566624) (xy 362.253866 -153.586598)
			(xy 362.170007 -153.598655) (xy 362.085382 -153.602687) (xy 362.000757 -153.598655) (xy 361.916898 -153.586598)
			(xy 361.834565 -153.566624) (xy 361.754503 -153.538915) (xy 361.677438 -153.50372) (xy 361.604068 -153.46136)
			(xy 361.535056 -153.412217) (xy 361.471028 -153.356736) (xy 361.412563 -153.295421) (xy 361.360192 -153.228825)
			(xy 361.314389 -153.157553) (xy 361.275567 -153.08225) (xy 361.244079 -153.003598) (xy 361.220211 -152.922308)
			(xy 361.204177 -152.839118) (xy 361.196124 -152.754781) (xy 341.549228 -152.754781) (xy 341.549228 -160.675828)
			(xy 341.783924 -160.910524) (xy 345.568524 -160.910524) (xy 345.619324 -160.859724) (xy 347.346524 -160.859724)
			(xy 347.346524 -158.894018) (xy 347.331538 -158.879032) (xy 345.924378 -158.879032) (xy 345.808554 -158.763208)
			(xy 345.808554 -157.716474) (xy 345.478354 -157.386274) (xy 345.478354 -155.262834) (xy 345.863164 -154.878024)
			(xy 351.54743 -154.878024) (xy 352.034094 -155.364688) (xy 352.034094 -162.635946) (xy 352.564192 -163.166044)
			(xy 352.564192 -164.6809) (xy 352.232468 -165.012624) (xy 352.231198 -165.012624) (xy 352.034094 -165.209728)
			(xy 352.034094 -169.14876) (xy 352.152458 -169.267124) (xy 353.874324 -169.267124) (xy 353.925124 -169.216324)
			(xy 355.652324 -169.216324) (xy 355.652324 -167.235632) (xy 354.237798 -167.235632) (xy 354.127054 -167.124888)
			(xy 354.127054 -166.271448) (xy 353.608894 -165.753288) (xy 353.608894 -163.879022) (xy 353.756722 -163.731194)
			(xy 354.903278 -163.731194) (xy 355.030278 -163.604194) (xy 355.030278 -163.00831) (xy 355.354636 -162.683952)
			(xy 358.8512 -162.683952) (xy 360.364278 -164.19703) (xy 360.364278 -165.139313) (xy 376.9807 -165.139313)
			(xy 376.9807 -165.054591) (xy 376.988753 -164.970254) (xy 377.004787 -164.887064) (xy 377.028655 -164.805774)
			(xy 377.060143 -164.727122) (xy 377.098965 -164.651819) (xy 377.144768 -164.580547) (xy 377.197139 -164.513951)
			(xy 377.255604 -164.452636) (xy 377.319632 -164.397155) (xy 377.388644 -164.348012) (xy 377.462014 -164.305652)
			(xy 377.539079 -164.270457) (xy 377.619141 -164.242748) (xy 377.701474 -164.222774) (xy 377.785333 -164.210717)
			(xy 377.869958 -164.206686) (xy 377.954583 -164.210717) (xy 378.038442 -164.222774) (xy 378.120775 -164.242748)
			(xy 378.200837 -164.270457) (xy 378.277902 -164.305652) (xy 378.351272 -164.348012) (xy 378.420284 -164.397155)
			(xy 378.484312 -164.452636) (xy 378.542777 -164.513951) (xy 378.595148 -164.580547) (xy 378.640951 -164.651819)
			(xy 378.679773 -164.727122) (xy 378.711261 -164.805774) (xy 378.735129 -164.887064) (xy 378.751163 -164.970254)
			(xy 378.759216 -165.054591) (xy 378.75972 -165.096952) (xy 378.759216 -165.139313) (xy 378.751163 -165.22365)
			(xy 378.735129 -165.30684) (xy 378.711261 -165.38813) (xy 378.679773 -165.466782) (xy 378.640951 -165.542085)
			(xy 378.595148 -165.613357) (xy 378.542777 -165.679953) (xy 378.484312 -165.741268) (xy 378.420284 -165.796749)
			(xy 378.351272 -165.845892) (xy 378.277902 -165.888252) (xy 378.200837 -165.923447) (xy 378.120775 -165.951156)
			(xy 378.038442 -165.97113) (xy 377.954583 -165.983187) (xy 377.869958 -165.987219) (xy 377.785333 -165.983187)
			(xy 377.701474 -165.97113) (xy 377.619141 -165.951156) (xy 377.539079 -165.923447) (xy 377.462014 -165.888252)
			(xy 377.388644 -165.845892) (xy 377.319632 -165.796749) (xy 377.255604 -165.741268) (xy 377.197139 -165.679953)
			(xy 377.144768 -165.613357) (xy 377.098965 -165.542085) (xy 377.060143 -165.466782) (xy 377.028655 -165.38813)
			(xy 377.004787 -165.30684) (xy 376.988753 -165.22365) (xy 376.9807 -165.139313) (xy 360.364278 -165.139313)
			(xy 360.364278 -171.01693) (xy 360.869992 -171.522644) (xy 360.869992 -173.0375) (xy 360.538268 -173.369224)
			(xy 360.536998 -173.369224) (xy 360.364278 -173.541944) (xy 360.364278 -177.35931) (xy 360.542078 -177.53711)
			(xy 362.205524 -177.53711) (xy 362.205524 -177.491644) (xy 363.932724 -177.491644) (xy 363.932724 -175.510952)
			(xy 362.52658 -175.510952) (xy 362.407454 -175.391826) (xy 362.407454 -174.406814) (xy 362.015278 -174.014638)
			(xy 362.015278 -172.27931) (xy 362.269278 -172.02531) (xy 363.666278 -172.02531) (xy 363.708442 -171.983146)
			(xy 363.708442 -171.221146) (xy 363.793278 -171.13631) (xy 367.417858 -171.13631) (xy 368.569494 -172.287946)
			(xy 368.569494 -179.217066) (xy 369.150392 -179.797964) (xy 369.150392 -181.31282) (xy 368.818668 -181.644544)
			(xy 368.817398 -181.644544) (xy 368.746278 -181.715664) (xy 368.746278 -182.367174) (xy 368.848894 -182.46979)
			(xy 370.566696 -182.46979) (xy 370.566696 -182.464202) (xy 372.293896 -182.464202) (xy 372.293896 -180.48351)
			(xy 370.935758 -180.48351) (xy 370.730018 -180.27777) (xy 370.730018 -179.380642) (xy 370.394738 -179.045362)
			(xy 370.394738 -177.23231) (xy 370.521738 -177.10531) (xy 371.413278 -177.10531) (xy 371.679978 -176.83861)
			(xy 371.679978 -176.35601) (xy 371.946932 -176.08931) (xy 375.782078 -176.08931) (xy 377.014994 -177.322226)
			(xy 377.014994 -182.376064) (xy 377.129294 -182.490364) (xy 380.696724 -182.490364)
		)
		(stroke
			(width 0)
			(type solid)
		)
		(fill yes)
		(layer "F.Cu")
		(net "SW_P12V_AUX_PVDDCR_CPU0_P0_FLT")
	)
	(gr_poly
		(pts
			(xy 462.395824 -322.088256) (xy 462.395824 -198.588884) (xy 465.7471 -195.237354) (xy 465.753793 -195.229947)
			(xy 465.761394 -195.211511) (xy 465.761832 -195.20154) (xy 465.761832 -172.130466) (xy 465.761398 -172.120431)
			(xy 465.753833 -172.101848) (xy 465.7471 -172.094398) (xy 463.329782 -169.67708) (xy 463.322356 -169.670307)
			(xy 463.303759 -169.662723) (xy 463.293714 -169.662348) (xy 457.662534 -169.662348) (xy 457.626998 -169.661773)
			(xy 457.556501 -169.652751) (xy 457.487704 -169.634911) (xy 457.454508 -169.622216) (xy 457.445364 -169.61866)
			(xy 457.091542 -169.61866) (xy 457.081477 -169.618225) (xy 457.062892 -169.610491) (xy 457.055474 -169.603674)
			(xy 452.117206 -164.665406) (xy 452.110358 -164.658008) (xy 452.10262 -164.63941) (xy 452.10222 -164.629338)
			(xy 452.10222 -146.4818) (xy 446.659 -141.03858) (xy 445.57442 -139.954) (xy 433.62245 -139.954)
			(xy 429.640746 -139.954) (xy 429.259746 -140.335) (xy 429.259746 -143.115538) (xy 429.260177 -143.125604)
			(xy 429.267907 -143.144194) (xy 429.274732 -143.151606) (xy 429.319436 -143.196564) (xy 429.319436 -145.423636)
			(xy 434.2638 -150.368) (xy 434.2638 -153.774394) (xy 436.382169 -153.774394) (xy 436.386165 -153.564508)
			(xy 436.39815 -153.354926) (xy 436.418104 -153.145952) (xy 436.446 -152.93789) (xy 436.481797 -152.73104)
			(xy 436.525442 -152.525703) (xy 436.576874 -152.322177) (xy 436.636016 -152.120756) (xy 436.702784 -151.921733)
			(xy 436.77708 -151.725396) (xy 436.858798 -151.53203) (xy 436.947817 -151.341915) (xy 437.04401 -151.155327)
			(xy 437.147237 -150.972536) (xy 437.257348 -150.793808) (xy 437.374183 -150.619401) (xy 437.497573 -150.449569)
			(xy 437.62734 -150.284557) (xy 437.763294 -150.124606) (xy 437.90524 -149.969946) (xy 438.05297 -149.820802)
			(xy 438.206272 -149.677391) (xy 438.364922 -149.53992) (xy 438.528691 -149.408588) (xy 438.697341 -149.283587)
			(xy 438.870627 -149.165096) (xy 439.048299 -149.053289) (xy 439.230099 -148.948327) (xy 439.415763 -148.850362)
			(xy 439.605021 -148.759537) (xy 439.797601 -148.675983) (xy 439.993222 -148.59982) (xy 440.1916 -148.531161)
			(xy 440.392449 -148.470104) (xy 440.595476 -148.416737) (xy 440.800389 -148.371139) (xy 441.006888 -148.333374)
			(xy 441.214675 -148.303499) (xy 441.42345 -148.281556) (xy 441.632908 -148.267577) (xy 441.842747 -148.261582)
			(xy 442.052661 -148.263581) (xy 442.262348 -148.273569) (xy 442.471502 -148.291534) (xy 442.67982 -148.317448)
			(xy 442.887001 -148.351273) (xy 443.092745 -148.392962) (xy 443.296751 -148.442454) (xy 443.498726 -148.499676)
			(xy 443.698376 -148.564546) (xy 443.895411 -148.63697) (xy 444.089547 -148.716843) (xy 444.2805 -148.804049)
			(xy 444.467996 -148.898461) (xy 444.651761 -148.999943) (xy 444.831529 -149.108347) (xy 445.00704 -149.223517)
			(xy 445.178039 -149.345285) (xy 445.344279 -149.473474) (xy 445.505518 -149.6079) (xy 445.661522 -149.748367)
			(xy 445.812065 -149.894671) (xy 445.956929 -150.0466) (xy 446.095904 -150.203934) (xy 446.228789 -150.366445)
			(xy 446.35539 -150.533898) (xy 446.475525 -150.706048) (xy 446.589019 -150.882648) (xy 446.695707 -151.06344)
			(xy 446.795434 -151.248163) (xy 446.888057 -151.436549) (xy 446.973441 -151.628324) (xy 447.051462 -151.823211)
			(xy 447.122007 -152.020927) (xy 447.184974 -152.221185) (xy 447.240271 -152.423695) (xy 447.287818 -152.628164)
			(xy 447.327546 -152.834295) (xy 447.359398 -153.041788) (xy 447.383328 -153.250344) (xy 447.3993 -153.45966)
			(xy 447.407292 -153.669432) (xy 447.407792 -153.774394) (xy 447.407292 -153.879356) (xy 447.3993 -154.089128)
			(xy 447.383328 -154.298444) (xy 447.359398 -154.507) (xy 447.327546 -154.714493) (xy 447.287818 -154.920624)
			(xy 447.240271 -155.125093) (xy 447.184974 -155.327603) (xy 447.122007 -155.527861) (xy 447.051462 -155.725577)
			(xy 446.973441 -155.920464) (xy 446.888057 -156.112239) (xy 446.795434 -156.300625) (xy 446.695707 -156.485348)
			(xy 446.589019 -156.66614) (xy 446.475525 -156.84274) (xy 446.35539 -157.01489) (xy 446.228789 -157.182343)
			(xy 446.095904 -157.344854) (xy 445.956929 -157.502188) (xy 445.812065 -157.654117) (xy 445.661522 -157.800421)
			(xy 445.505518 -157.940888) (xy 445.344279 -158.075314) (xy 445.178039 -158.203503) (xy 445.00704 -158.325271)
			(xy 444.831529 -158.440441) (xy 444.651761 -158.548845) (xy 444.467996 -158.650327) (xy 444.2805 -158.744739)
			(xy 444.089547 -158.831945) (xy 443.895411 -158.911818) (xy 443.698376 -158.984242) (xy 443.498726 -159.049112)
			(xy 443.296751 -159.106334) (xy 443.092745 -159.155826) (xy 442.887001 -159.197515) (xy 442.67982 -159.23134)
			(xy 442.471502 -159.257254) (xy 442.262348 -159.275219) (xy 442.052661 -159.285207) (xy 441.842747 -159.287206)
			(xy 441.632908 -159.281211) (xy 441.42345 -159.267232) (xy 441.214675 -159.245289) (xy 441.006888 -159.215414)
			(xy 440.800389 -159.177649) (xy 440.595476 -159.132051) (xy 440.392449 -159.078684) (xy 440.1916 -159.017627)
			(xy 439.993222 -158.948968) (xy 439.797601 -158.872805) (xy 439.605021 -158.789251) (xy 439.415763 -158.698426)
			(xy 439.230099 -158.600461) (xy 439.048299 -158.495499) (xy 438.870627 -158.383692) (xy 438.697341 -158.265201)
			(xy 438.528691 -158.1402) (xy 438.364922 -158.008868) (xy 438.206272 -157.871397) (xy 438.05297 -157.727986)
			(xy 437.90524 -157.578842) (xy 437.763294 -157.424182) (xy 437.62734 -157.264231) (xy 437.497573 -157.099219)
			(xy 437.374183 -156.929387) (xy 437.257348 -156.75498) (xy 437.147237 -156.576252) (xy 437.04401 -156.393461)
			(xy 436.947817 -156.206873) (xy 436.858798 -156.016758) (xy 436.77708 -155.823392) (xy 436.702784 -155.627055)
			(xy 436.636016 -155.428032) (xy 436.576874 -155.226611) (xy 436.525442 -155.023085) (xy 436.481797 -154.817748)
			(xy 436.446 -154.610898) (xy 436.418104 -154.402836) (xy 436.39815 -154.193862) (xy 436.386165 -153.98428)
			(xy 436.382169 -153.774394) (xy 434.2638 -153.774394) (xy 434.2638 -161.053018) (xy 434.264227 -161.063087)
			(xy 434.271946 -161.081686) (xy 434.278786 -161.089086) (xy 436.453534 -163.263834) (xy 436.460931 -163.270682)
			(xy 436.47953 -163.278415) (xy 436.489602 -163.27882) (xy 441.750196 -163.27882) (xy 441.760266 -163.279243)
			(xy 441.77887 -163.286958) (xy 441.786264 -163.293806) (xy 451.179692 -172.687234) (xy 451.187087 -172.694089)
			(xy 451.205686 -172.701837) (xy 451.21576 -172.70222) (xy 455.78522 -172.70222) (xy 458.72654 -175.64354)
			(xy 460.98968 -175.64354) (xy 462.730088 -177.383948) (xy 462.736928 -177.391348) (xy 462.744647 -177.409947)
			(xy 462.745074 -177.420016) (xy 462.745074 -192.766696) (xy 462.744651 -192.776766) (xy 462.736935 -192.795369)
			(xy 462.730088 -192.802764) (xy 461.868774 -193.664078) (xy 461.86852 -193.664332) (xy 461.692752 -193.8401)
			(xy 456.23861 -193.8401) (xy 455.97699 -194.10172) (xy 455.970278 -194.108958) (xy 455.962686 -194.127163)
			(xy 455.962258 -194.137026) (xy 455.962258 -318.362838) (xy 455.96173 -318.372679) (xy 455.954157 -318.390854)
			(xy 455.947526 -318.398144) (xy 454.94829 -319.39738) (xy 454.941054 -319.404097) (xy 454.922848 -319.411697)
			(xy 454.912984 -319.412112) (xy 413.153606 -319.412112) (xy 413.143536 -319.412534) (xy 413.124931 -319.420249)
			(xy 413.117538 -319.427098) (xy 412.849314 -319.695322) (xy 412.84247 -319.702721) (xy 412.834741 -319.721319)
			(xy 412.834328 -319.73139) (xy 412.834328 -323.017388) (xy 413.14624 -323.3293) (xy 461.15478 -323.3293)
		)
		(stroke
			(width 0)
			(type solid)
		)
		(fill yes)
		(layer "F.Cu")
		(net "PVDD18_S5_P0")
	)
	(gr_poly
		(pts
			(xy 221.860364 -71.71182) (xy 221.870238 -71.711352) (xy 221.888527 -71.7039) (xy 221.895924 -71.697342)
			(xy 221.909386 -71.68388) (xy 221.909894 -71.683372) (xy 221.916476 -71.67599) (xy 221.923929 -71.657692)
			(xy 221.924372 -71.647812) (xy 221.924372 -69.88048) (xy 221.924798 -69.870411) (xy 221.932514 -69.851809)
			(xy 221.939358 -69.844412) (xy 222.00616 -69.77761) (xy 222.013561 -69.770772) (xy 222.03216 -69.763058)
			(xy 222.042228 -69.762624) (xy 222.474028 -69.762624) (xy 222.484095 -69.763053) (xy 222.50269 -69.770777)
			(xy 222.510096 -69.77761) (xy 222.666052 -69.933566) (xy 222.667068 -69.933312) (xy 222.69323 -69.959474)
			(xy 222.700072 -69.966873) (xy 222.707791 -69.985472) (xy 222.708216 -69.995542) (xy 222.708216 -71.148194)
			(xy 222.708638 -71.158264) (xy 222.716353 -71.176869) (xy 222.723202 -71.184262) (xy 222.758508 -71.219568)
			(xy 222.765905 -71.226417) (xy 222.784504 -71.234153) (xy 222.794576 -71.234554) (xy 222.847662 -71.234554)
			(xy 222.857726 -71.234118) (xy 222.87631 -71.226383) (xy 222.88373 -71.219568) (xy 222.922084 -71.181214)
			(xy 222.928919 -71.173812) (xy 222.936624 -71.155213) (xy 222.93707 -71.145146) (xy 222.93707 -69.731382)
			(xy 222.937496 -69.721313) (xy 222.945211 -69.70271) (xy 222.952056 -69.695314) (xy 222.964756 -69.682614)
			(xy 222.965264 -69.682106) (xy 222.971839 -69.674722) (xy 222.979273 -69.656423) (xy 222.979742 -69.646546)
			(xy 222.979742 -66.65595) (xy 222.980176 -66.645885) (xy 222.987907 -66.627298) (xy 222.994728 -66.619882)
			(xy 223.220534 -66.394076) (xy 223.227931 -66.387227) (xy 223.24653 -66.379493) (xy 223.256602 -66.37909)
			(xy 226.80549 -66.37909) (xy 226.815361 -66.378617) (xy 226.83364 -66.371154) (xy 226.84105 -66.364612)
			(xy 227.05441 -66.151252) (xy 227.054918 -66.150744) (xy 227.061503 -66.143364) (xy 227.068958 -66.125065)
			(xy 227.069396 -66.115184) (xy 227.069396 -59.594496) (xy 227.068972 -59.584426) (xy 227.061256 -59.565823)
			(xy 227.05441 -59.558428) (xy 226.193858 -58.697876) (xy 225.119946 -57.624218) (xy 225.112834 -57.616852)
			(xy 225.094038 -57.609232) (xy 220.452442 -57.609232) (xy 220.442377 -57.609666) (xy 220.423791 -57.617399)
			(xy 220.416374 -57.624218) (xy 220.293946 -57.746646) (xy 220.28658 -57.753758) (xy 220.27896 -57.772554)
			(xy 220.27896 -58.32475) (xy 220.278526 -58.334815) (xy 220.270795 -58.353403) (xy 220.263974 -58.360818)
			(xy 219.906342 -58.71845) (xy 219.898943 -58.725293) (xy 219.880344 -58.733014) (xy 219.870274 -58.733436)
			(xy 218.630246 -58.733436) (xy 218.620181 -58.73387) (xy 218.601594 -58.741602) (xy 218.594178 -58.748422)
			(xy 218.480386 -58.862214) (xy 218.473532 -58.869609) (xy 218.46579 -58.888208) (xy 218.4654 -58.898282)
			(xy 218.4654 -62.14491) (xy 218.464975 -62.154979) (xy 218.457258 -62.173581) (xy 218.450414 -62.180978)
			(xy 218.061286 -62.570106) (xy 218.061286 -62.583568) (xy 198.105776 -62.583568) (xy 198.095707 -62.583995)
			(xy 198.077106 -62.591712) (xy 198.069708 -62.598554) (xy 197.999858 -62.668404) (xy 197.993006 -62.6758)
			(xy 197.985264 -62.694399) (xy 197.984872 -62.704472) (xy 197.984872 -65.281556) (xy 197.984438 -65.291621)
			(xy 197.976706 -65.310208) (xy 197.969886 -65.317624) (xy 197.705472 -65.582038) (xy 195.684648 -65.582038)
			(xy 195.561458 -65.705228) (xy 195.561458 -66.158364) (xy 198.426576 -66.158364) (xy 198.430649 -66.102705)
			(xy 198.442784 -66.048232) (xy 198.46272 -65.996106) (xy 198.490034 -65.947438) (xy 198.524142 -65.903266)
			(xy 198.564319 -65.864531) (xy 198.609707 -65.832059) (xy 198.659339 -65.806541) (xy 198.712159 -65.788522)
			(xy 198.767038 -65.778385) (xy 198.822809 -65.776347) (xy 198.878283 -65.78245) (xy 198.932276 -65.796566)
			(xy 198.983639 -65.818393) (xy 199.031277 -65.847466) (xy 199.074173 -65.883165) (xy 199.111415 -65.924729)
			(xy 199.142209 -65.971273) (xy 199.165897 -66.021804) (xy 199.181975 -66.075246) (xy 199.190101 -66.13046)
			(xy 199.19061 -66.158364) (xy 199.190101 -66.186268) (xy 199.181975 -66.241482) (xy 199.165897 -66.294924)
			(xy 199.142209 -66.345455) (xy 199.111415 -66.391999) (xy 199.074173 -66.433563) (xy 199.031277 -66.469262)
			(xy 198.983639 -66.498335) (xy 198.932276 -66.520162) (xy 198.878283 -66.534278) (xy 198.822809 -66.540381)
			(xy 198.767038 -66.538343) (xy 198.712159 -66.528206) (xy 198.659339 -66.510187) (xy 198.609707 -66.484669)
			(xy 198.564319 -66.452197) (xy 198.524142 -66.413462) (xy 198.490034 -66.36929) (xy 198.46272 -66.320622)
			(xy 198.442784 -66.268496) (xy 198.430649 -66.214023) (xy 198.426576 -66.158364) (xy 195.561458 -66.158364)
			(xy 195.561458 -67.579748) (xy 196.171058 -68.189348) (xy 196.171058 -69.230748) (xy 196.831458 -69.230748)
			(xy 196.907658 -69.154548) (xy 196.907658 -68.417948) (xy 197.960234 -67.365372) (xy 199.979788 -67.365372)
			(xy 200.605898 -66.739262) (xy 203.572364 -66.739262) (xy 203.760578 -66.551048) (xy 216.44483 -66.551048)
			(xy 216.453911 -66.550673) (xy 216.47093 -66.544333) (xy 216.484672 -66.53246) (xy 216.493416 -66.516541)
			(xy 216.495122 -66.507614) (xy 216.499516 -66.480752) (xy 216.514923 -66.428548) (xy 216.537595 -66.379065)
			(xy 216.567071 -66.333308) (xy 216.602753 -66.292206) (xy 216.643916 -66.256594) (xy 216.689723 -66.227196)
			(xy 216.739245 -66.204608) (xy 216.791474 -66.189289) (xy 216.845351 -66.181551) (xy 216.899781 -66.181551)
			(xy 216.953658 -66.189289) (xy 217.005887 -66.204608) (xy 217.055409 -66.227196) (xy 217.101216 -66.256594)
			(xy 217.142379 -66.292206) (xy 217.178061 -66.333308) (xy 217.207537 -66.379065) (xy 217.230209 -66.428548)
			(xy 217.245616 -66.480752) (xy 217.25001 -66.507614) (xy 217.25169 -66.516549) (xy 217.260428 -66.532479)
			(xy 217.274182 -66.544349) (xy 217.291217 -66.550665) (xy 217.300302 -66.551048) (xy 217.675206 -66.551048)
			(xy 217.701368 -66.532506) (xy 217.706702 -66.517266) (xy 217.716405 -66.491429) (xy 217.742191 -66.442635)
			(xy 217.77474 -66.398066) (xy 217.813372 -66.358653) (xy 217.857281 -66.325219) (xy 217.90555 -66.298462)
			(xy 217.957172 -66.278941) (xy 218.011067 -66.267062) (xy 218.066112 -66.263075) (xy 218.121157 -66.267062)
			(xy 218.175052 -66.278941) (xy 218.226674 -66.298462) (xy 218.274943 -66.325219) (xy 218.318852 -66.358653)
			(xy 218.357484 -66.398066) (xy 218.390033 -66.442635) (xy 218.415819 -66.491429) (xy 218.425522 -66.517266)
			(xy 218.430856 -66.532506) (xy 218.457018 -66.551048) (xy 220.290136 -66.551048) (xy 220.293879 -66.55097)
			(xy 220.301278 -66.549825) (xy 220.304868 -66.548762) (xy 220.325188 -66.542666) (xy 220.33103 -66.538856)
			(xy 220.355552 -66.523748) (xy 220.407348 -66.498551) (xy 220.46166 -66.479371) (xy 220.517793 -66.466455)
			(xy 220.575026 -66.459968) (xy 220.603826 -66.459608) (xy 220.604334 -66.459608) (xy 220.63377 -66.460031)
			(xy 220.692249 -66.466834) (xy 220.74955 -66.480345) (xy 220.804907 -66.500383) (xy 220.85758 -66.52668)
			(xy 220.882464 -66.542412) (xy 220.882718 -66.542666) (xy 220.889068 -66.54673) (xy 220.903038 -66.551048)
			(xy 220.915992 -66.551048) (xy 221.510352 -67.145408) (xy 221.515178 -67.145408) (xy 221.629478 -67.259708)
			(xy 221.636325 -67.267106) (xy 221.64406 -67.285704) (xy 221.644464 -67.295776) (xy 221.644464 -71.626222)
			(xy 221.644924 -71.6361) (xy 221.652364 -71.6544) (xy 221.658942 -71.661782) (xy 221.693994 -71.696834)
			(xy 221.694502 -71.697342) (xy 221.701885 -71.703918) (xy 221.720185 -71.711352) (xy 221.730062 -71.71182)
		)
		(stroke
			(width 0)
			(type solid)
		)
		(fill yes)
		(layer "F.Cu")
		(net "P3V3_E1S_0_R")
	)
	(gr_poly
		(pts
			(xy 240.89995 -81.700116) (xy 240.899449 -81.600062) (xy 240.891443 -81.400115) (xy 240.875444 -81.200648)
			(xy 240.851476 -81.00198) (xy 240.819579 -80.804431) (xy 240.779804 -80.608316) (xy 240.732214 -80.41395)
			(xy 240.676886 -80.221643) (xy 240.613908 -80.031704) (xy 240.543381 -79.844437) (xy 240.465418 -79.660141)
			(xy 240.380144 -79.479112) (xy 240.287695 -79.30164) (xy 240.18822 -79.128009) (xy 240.081877 -78.958497)
			(xy 239.968838 -78.793376) (xy 239.849282 -78.632909) (xy 239.723402 -78.477354) (xy 239.591399 -78.32696)
			(xy 239.453485 -78.181968) (xy 239.30988 -78.04261) (xy 239.160814 -77.909109) (xy 239.006526 -77.781679)
			(xy 238.847264 -77.660524) (xy 238.683281 -77.545838) (xy 238.514842 -77.437805) (xy 238.342215 -77.336597)
			(xy 238.165676 -77.242377) (xy 237.98551 -77.155296) (xy 237.802003 -77.075493) (xy 237.615451 -77.003096)
			(xy 237.426152 -76.938221) (xy 237.234408 -76.880971) (xy 237.040527 -76.831439) (xy 236.84482 -76.789704)
			(xy 236.6476 -76.755832) (xy 236.449183 -76.729879) (xy 236.249886 -76.711884) (xy 236.050028 -76.701878)
			(xy 235.849931 -76.699876) (xy 235.649913 -76.705881) (xy 235.450296 -76.719884) (xy 235.251399 -76.741863)
			(xy 235.05354 -76.771782) (xy 234.857037 -76.809593) (xy 234.662204 -76.855236) (xy 234.469354 -76.908637)
			(xy 234.278794 -76.969712) (xy 234.090831 -77.038361) (xy 233.905764 -77.114477) (xy 233.723891 -77.197935)
			(xy 233.545503 -77.288604) (xy 233.370886 -77.386337) (xy 233.200318 -77.490978) (xy 233.034074 -77.60236)
			(xy 232.872419 -77.720304) (xy 232.715612 -77.844622) (xy 232.563905 -77.975113) (xy 232.417541 -78.11157)
			(xy 232.276753 -78.253774) (xy 232.141767 -78.401497) (xy 232.0128 -78.554502) (xy 231.890057 -78.712544)
			(xy 231.773737 -78.875371) (xy 231.664024 -79.042721) (xy 231.561094 -79.214327) (xy 231.465113 -79.389914)
			(xy 231.376233 -79.5692) (xy 231.294598 -79.751899) (xy 231.220339 -79.937718) (xy 231.153573 -80.126359)
			(xy 231.094408 -80.31752) (xy 231.042938 -80.510895) (xy 230.999247 -80.706175) (xy 230.963404 -80.903046)
			(xy 230.935466 -81.101194) (xy 230.915479 -81.300301) (xy 230.903473 -81.500048) (xy 230.899643 -81.691489)
			(xy 232.138767 -81.691489) (xy 232.143191 -81.51754) (xy 232.155655 -81.343981) (xy 232.176134 -81.171185)
			(xy 232.204582 -80.999521) (xy 232.24094 -80.829356) (xy 232.285129 -80.661055) (xy 232.337055 -80.494978)
			(xy 232.396606 -80.331481) (xy 232.463656 -80.170912) (xy 232.53806 -80.013617) (xy 232.61966 -79.859931)
			(xy 232.708281 -79.710183) (xy 232.803732 -79.564695) (xy 232.905811 -79.423777) (xy 233.014297 -79.287731)
			(xy 233.12896 -79.156848) (xy 233.249554 -79.031409) (xy 233.37582 -78.911681) (xy 233.507489 -78.797922)
			(xy 233.644278 -78.690374) (xy 233.714798 -78.639416) (xy 238.085122 -78.639416) (xy 238.155642 -78.690374)
			(xy 238.292431 -78.797922) (xy 238.4241 -78.911681) (xy 238.550366 -79.031409) (xy 238.67096 -79.156848)
			(xy 238.785623 -79.287731) (xy 238.894109 -79.423777) (xy 238.996188 -79.564695) (xy 239.091639 -79.710183)
			(xy 239.18026 -79.859931) (xy 239.26186 -80.013617) (xy 239.336264 -80.170912) (xy 239.403314 -80.331481)
			(xy 239.462865 -80.494978) (xy 239.514791 -80.661055) (xy 239.55898 -80.829356) (xy 239.595338 -80.999521)
			(xy 239.623786 -81.171185) (xy 239.644265 -81.343981) (xy 239.656729 -81.51754) (xy 239.661153 -81.691489)
			(xy 239.657527 -81.865456) (xy 239.645859 -82.03907) (xy 239.626174 -82.211958) (xy 239.598513 -82.383751)
			(xy 239.562936 -82.554081) (xy 239.51952 -82.722583) (xy 239.468356 -82.888896) (xy 239.409555 -83.052665)
			(xy 239.343243 -83.21354) (xy 239.269561 -83.371175) (xy 239.188667 -83.525234) (xy 239.100735 -83.675386)
			(xy 239.005951 -83.821311) (xy 238.904521 -83.962695) (xy 238.796659 -84.099238) (xy 238.682598 -84.230645)
			(xy 238.562581 -84.356636) (xy 238.436865 -84.476942) (xy 238.30572 -84.591304) (xy 238.169425 -84.699479)
			(xy 238.028273 -84.801234) (xy 237.882567 -84.896351) (xy 237.732616 -84.984628) (xy 237.578744 -85.065875)
			(xy 237.421278 -85.139919) (xy 237.260556 -85.2066) (xy 237.096922 -85.265776) (xy 236.930726 -85.317321)
			(xy 236.762325 -85.361124) (xy 236.592077 -85.397091) (xy 236.420348 -85.425146) (xy 236.247505 -85.445228)
			(xy 236.073919 -85.457294) (xy 235.89996 -85.461319) (xy 235.726001 -85.457294) (xy 235.552415 -85.445228)
			(xy 235.379572 -85.425146) (xy 235.207843 -85.397091) (xy 235.037595 -85.361124) (xy 234.869194 -85.317321)
			(xy 234.702998 -85.265776) (xy 234.539364 -85.2066) (xy 234.378642 -85.139919) (xy 234.221176 -85.065875)
			(xy 234.067304 -84.984628) (xy 233.917353 -84.896351) (xy 233.771647 -84.801234) (xy 233.630495 -84.699479)
			(xy 233.4942 -84.591304) (xy 233.363055 -84.476942) (xy 233.237339 -84.356636) (xy 233.117322 -84.230645)
			(xy 233.003261 -84.099238) (xy 232.895399 -83.962695) (xy 232.793969 -83.821311) (xy 232.699185 -83.675386)
			(xy 232.611253 -83.525234) (xy 232.530359 -83.371175) (xy 232.456677 -83.21354) (xy 232.390365 -83.052665)
			(xy 232.331564 -82.888896) (xy 232.2804 -82.722583) (xy 232.236984 -82.554081) (xy 232.201407 -82.383751)
			(xy 232.173746 -82.211958) (xy 232.154061 -82.03907) (xy 232.142393 -81.865456) (xy 232.138767 -81.691489)
			(xy 230.899643 -81.691489) (xy 230.89947 -81.700116) (xy 230.903473 -81.900184) (xy 230.915479 -82.099931)
			(xy 230.935466 -82.299038) (xy 230.963404 -82.497186) (xy 230.999247 -82.694057) (xy 231.042938 -82.889337)
			(xy 231.094408 -83.082712) (xy 231.153573 -83.273873) (xy 231.220339 -83.462514) (xy 231.294598 -83.648333)
			(xy 231.376233 -83.831032) (xy 231.465113 -84.010318) (xy 231.561094 -84.185905) (xy 231.664024 -84.357511)
			(xy 231.773737 -84.524861) (xy 231.890057 -84.687688) (xy 232.0128 -84.84573) (xy 232.141767 -84.998735)
			(xy 232.276753 -85.146458) (xy 232.417541 -85.288662) (xy 232.563905 -85.425119) (xy 232.715612 -85.55561)
			(xy 232.872419 -85.679928) (xy 233.034074 -85.797872) (xy 233.200318 -85.909254) (xy 233.370886 -86.013895)
			(xy 233.545503 -86.111628) (xy 233.723891 -86.202297) (xy 233.905764 -86.285755) (xy 234.090831 -86.361871)
			(xy 234.278794 -86.43052) (xy 234.469354 -86.491595) (xy 234.662204 -86.544996) (xy 234.857037 -86.590639)
			(xy 235.05354 -86.62845) (xy 235.251399 -86.658369) (xy 235.450296 -86.680348) (xy 235.649913 -86.694351)
			(xy 235.849931 -86.700356) (xy 236.050028 -86.698354) (xy 236.249886 -86.688348) (xy 236.449183 -86.670353)
			(xy 236.6476 -86.6444) (xy 236.84482 -86.610528) (xy 237.040527 -86.568793) (xy 237.234408 -86.519261)
			(xy 237.426152 -86.462011) (xy 237.615451 -86.397136) (xy 237.802003 -86.324739) (xy 237.98551 -86.244936)
			(xy 238.165676 -86.157855) (xy 238.342215 -86.063635) (xy 238.514842 -85.962427) (xy 238.683281 -85.854394)
			(xy 238.847264 -85.739708) (xy 239.006526 -85.618553) (xy 239.160814 -85.491123) (xy 239.30988 -85.357622)
			(xy 239.453485 -85.218264) (xy 239.591399 -85.073272) (xy 239.723402 -84.922878) (xy 239.849282 -84.767323)
			(xy 239.968838 -84.606856) (xy 240.081877 -84.441735) (xy 240.18822 -84.272223) (xy 240.287695 -84.098592)
			(xy 240.380144 -83.92112) (xy 240.465418 -83.740091) (xy 240.543381 -83.555795) (xy 240.613908 -83.368528)
			(xy 240.676886 -83.178589) (xy 240.732214 -82.986282) (xy 240.779804 -82.791916) (xy 240.819579 -82.595801)
			(xy 240.851476 -82.398252) (xy 240.875444 -82.199584) (xy 240.891443 -82.000117) (xy 240.899449 -81.80017)
		)
		(stroke
			(width 0)
			(type solid)
		)
		(fill yes)
		(layer "F.Cu")
		(net "GND")
	)
	(gr_poly
		(pts
			(arc
				(start 237.763304 -37.135308)
				(mid 237.799225 -37.120429)
				(end 237.814104 -37.084508)
			)
			(xy 237.814104 -36.864036) (xy 237.887002 -36.791138) (xy 242.211098 -36.791138) (xy 242.28552 -36.86556)
			(arc
				(start 242.28552 -37.084508)
				(mid 242.300399 -37.120429)
				(end 242.33632 -37.135308)
			)
			(arc
				(start 256.800604 -37.135308)
				(mid 258.932532 -36.252077)
				(end 259.815584 -34.120074)
			)
			(arc
				(start 259.815584 -27.794458)
				(mid 259.811974 -27.775902)
				(end 259.801868 -27.759914)
			)
			(arc
				(start 259.801868 -27.759914)
				(mid 259.642242 -27.583685)
				(end 259.487924 -27.40279)
			)
			(arc
				(start 259.487924 -27.40279)
				(mid 259.462136 -27.386216)
				(end 259.431536 -27.38755)
			)
			(arc
				(start 259.34162 -27.419808)
				(mid 259.317325 -27.438392)
				(end 259.308092 -27.46756)
			)
			(arc
				(start 259.308092 -34.120074)
				(mid 258.573517 -35.893495)
				(end 256.800096 -36.62807)
			)
			(arc
				(start 225.300032 -36.62807)
				(mid 223.526611 -35.893495)
				(end 222.792036 -34.120074)
			)
			(arc
				(start 222.792036 -13.780008)
				(mid 222.35504 -12.725008)
				(end 221.30004 -12.288012)
			)
			(arc
				(start 196.701918 -12.288012)
				(mid 194.928497 -11.553437)
				(end 194.193922 -9.780016)
			)
			(arc
				(start 194.193922 -8.918448)
				(mid 194.182875 -8.887073)
				(end 194.154806 -8.869172)
			)
			(xy 194.041522 -8.842248) (xy 194.009518 -8.857234)
			(arc
				(start 194.001644 -8.872982)
				(mid 193.875648 -9.062025)
				(end 193.70802 -9.215374)
			)
			(arc
				(start 193.70802 -9.215374)
				(mid 193.69232 -9.233484)
				(end 193.686684 -9.256776)
			)
			(arc
				(start 193.686684 -9.780524)
				(mid 194.569915 -11.912452)
				(end 196.701918 -12.795504)
			)
			(arc
				(start 221.30004 -12.795504)
				(mid 221.996189 -13.083859)
				(end 222.284544 -13.780008)
			)
			(arc
				(start 222.284544 -34.120074)
				(mid 223.16785 -36.252182)
				(end 225.300032 -37.135308)
			)
		)
		(stroke
			(width 0)
			(type solid)
		)
		(fill yes)
		(layer "F.Cu")
		(net "GND")
	)
	(gr_poly
		(pts
			(xy 209.64525 -51.999896) (xy 209.644749 -51.899842) (xy 209.636743 -51.699895) (xy 209.620744 -51.500428)
			(xy 209.596776 -51.30176) (xy 209.564879 -51.104211) (xy 209.525104 -50.908096) (xy 209.477514 -50.71373)
			(xy 209.422186 -50.521423) (xy 209.359208 -50.331484) (xy 209.288681 -50.144217) (xy 209.210718 -49.959921)
			(xy 209.125444 -49.778892) (xy 209.032995 -49.60142) (xy 208.93352 -49.427789) (xy 208.827177 -49.258277)
			(xy 208.714138 -49.093156) (xy 208.594582 -48.932689) (xy 208.468702 -48.777134) (xy 208.336699 -48.62674)
			(xy 208.198785 -48.481748) (xy 208.05518 -48.34239) (xy 207.906114 -48.208889) (xy 207.751826 -48.081459)
			(xy 207.592564 -47.960304) (xy 207.428581 -47.845618) (xy 207.260142 -47.737585) (xy 207.087515 -47.636377)
			(xy 206.910976 -47.542157) (xy 206.73081 -47.455076) (xy 206.547303 -47.375273) (xy 206.360751 -47.302876)
			(xy 206.171452 -47.238001) (xy 205.979708 -47.180751) (xy 205.785827 -47.131219) (xy 205.59012 -47.089484)
			(xy 205.3929 -47.055612) (xy 205.194483 -47.029659) (xy 204.995186 -47.011664) (xy 204.795328 -47.001658)
			(xy 204.595231 -46.999656) (xy 204.395213 -47.005661) (xy 204.195596 -47.019664) (xy 203.996699 -47.041643)
			(xy 203.79884 -47.071562) (xy 203.602337 -47.109373) (xy 203.407504 -47.155016) (xy 203.214654 -47.208417)
			(xy 203.024094 -47.269492) (xy 202.836131 -47.338141) (xy 202.651064 -47.414257) (xy 202.469191 -47.497715)
			(xy 202.290803 -47.588384) (xy 202.116186 -47.686117) (xy 201.945618 -47.790758) (xy 201.779374 -47.90214)
			(xy 201.617719 -48.020084) (xy 201.460912 -48.144402) (xy 201.309205 -48.274893) (xy 201.162841 -48.41135)
			(xy 201.022053 -48.553554) (xy 200.887067 -48.701277) (xy 200.7581 -48.854282) (xy 200.635357 -49.012324)
			(xy 200.519037 -49.175151) (xy 200.409324 -49.342501) (xy 200.306394 -49.514107) (xy 200.210413 -49.689694)
			(xy 200.121533 -49.86898) (xy 200.039898 -50.051679) (xy 199.965639 -50.237498) (xy 199.898873 -50.426139)
			(xy 199.839708 -50.6173) (xy 199.788238 -50.810675) (xy 199.744547 -51.005955) (xy 199.708704 -51.202826)
			(xy 199.680766 -51.400974) (xy 199.660779 -51.600081) (xy 199.648773 -51.799828) (xy 199.64477 -51.999896)
			(xy 201.365618 -51.999896) (xy 201.369631 -51.837706) (xy 201.38166 -51.675912) (xy 201.401675 -51.514911)
			(xy 201.429628 -51.355097) (xy 201.465451 -51.196861) (xy 201.509055 -51.04059) (xy 201.560333 -50.886667)
			(xy 201.619161 -50.735468) (xy 201.685395 -50.587364) (xy 201.758871 -50.442716) (xy 201.839411 -50.301878)
			(xy 201.926818 -50.165196) (xy 202.020877 -50.033004) (xy 202.121358 -49.905625) (xy 202.228016 -49.783371)
			(xy 202.340589 -49.666542) (xy 202.458802 -49.555422) (xy 202.582365 -49.450285) (xy 202.710977 -49.351387)
			(xy 202.844323 -49.25897) (xy 202.982075 -49.173261) (xy 203.123898 -49.094468) (xy 203.269444 -49.022786)
			(xy 203.418356 -48.95839) (xy 203.570271 -48.901437) (xy 203.724817 -48.852066) (xy 203.881615 -48.810398)
			(xy 204.040282 -48.776535) (xy 204.200429 -48.750561) (xy 204.361665 -48.732538) (xy 204.523595 -48.722511)
			(xy 204.685823 -48.720505) (xy 204.847952 -48.726523) (xy 205.009584 -48.740553) (xy 205.170325 -48.762558)
			(xy 205.329781 -48.792485) (xy 205.487562 -48.830262) (xy 205.643281 -48.875795) (xy 205.796558 -48.928974)
			(xy 205.947018 -48.989667) (xy 206.094293 -49.057727) (xy 206.238021 -49.132987) (xy 206.377851 -49.215263)
			(xy 206.513442 -49.304354) (xy 206.64446 -49.40004) (xy 206.770587 -49.502089) (xy 206.891512 -49.610251)
			(xy 207.00694 -49.72426) (xy 207.116589 -49.843839) (xy 207.22019 -49.968693) (xy 207.31749 -50.098518)
			(xy 207.408251 -50.232997) (xy 207.49225 -50.371799) (xy 207.569282 -50.514585) (xy 207.639158 -50.661006)
			(xy 207.701708 -50.810704) (xy 207.756778 -50.963312) (xy 207.804234 -51.118456) (xy 207.843959 -51.275758)
			(xy 207.875856 -51.434831) (xy 207.899848 -51.595288) (xy 207.915875 -51.756734) (xy 207.923899 -51.918776)
			(xy 207.9244 -51.999896) (xy 207.923899 -52.081016) (xy 207.915875 -52.243058) (xy 207.899848 -52.404504)
			(xy 207.875856 -52.564961) (xy 207.843959 -52.724034) (xy 207.804234 -52.881336) (xy 207.756778 -53.03648)
			(xy 207.701708 -53.189088) (xy 207.639158 -53.338786) (xy 207.569282 -53.485207) (xy 207.49225 -53.627993)
			(xy 207.408251 -53.766795) (xy 207.31749 -53.901274) (xy 207.22019 -54.031099) (xy 207.116589 -54.155953)
			(xy 207.00694 -54.275532) (xy 206.891512 -54.389541) (xy 206.770587 -54.497703) (xy 206.64446 -54.599752)
			(xy 206.513442 -54.695438) (xy 206.377851 -54.784529) (xy 206.238021 -54.866805) (xy 206.094293 -54.942065)
			(xy 205.947018 -55.010125) (xy 205.796558 -55.070818) (xy 205.643281 -55.123997) (xy 205.487562 -55.16953)
			(xy 205.329781 -55.207307) (xy 205.170325 -55.237234) (xy 205.009584 -55.259239) (xy 204.847952 -55.273269)
			(xy 204.685823 -55.279287) (xy 204.523595 -55.277281) (xy 204.361665 -55.267254) (xy 204.200429 -55.249231)
			(xy 204.040282 -55.223257) (xy 203.881615 -55.189394) (xy 203.724817 -55.147726) (xy 203.570271 -55.098355)
			(xy 203.418356 -55.041402) (xy 203.269444 -54.977006) (xy 203.123898 -54.905324) (xy 202.982075 -54.826531)
			(xy 202.844323 -54.740822) (xy 202.710977 -54.648405) (xy 202.582365 -54.549507) (xy 202.458802 -54.44437)
			(xy 202.340589 -54.33325) (xy 202.228016 -54.216421) (xy 202.121358 -54.094167) (xy 202.020877 -53.966788)
			(xy 201.926818 -53.834596) (xy 201.839411 -53.697914) (xy 201.758871 -53.557076) (xy 201.685395 -53.412428)
			(xy 201.619161 -53.264324) (xy 201.560333 -53.113125) (xy 201.509055 -52.959202) (xy 201.465451 -52.802931)
			(xy 201.429628 -52.644695) (xy 201.401675 -52.484881) (xy 201.38166 -52.32388) (xy 201.369631 -52.162086)
			(xy 201.365618 -51.999896) (xy 199.64477 -51.999896) (xy 199.648773 -52.199964) (xy 199.660779 -52.399711)
			(xy 199.680766 -52.598818) (xy 199.708704 -52.796966) (xy 199.744547 -52.993837) (xy 199.788238 -53.189117)
			(xy 199.839708 -53.382492) (xy 199.898873 -53.573653) (xy 199.965639 -53.762294) (xy 200.039898 -53.948113)
			(xy 200.121533 -54.130812) (xy 200.210413 -54.310098) (xy 200.306394 -54.485685) (xy 200.409324 -54.657291)
			(xy 200.519037 -54.824641) (xy 200.635357 -54.987468) (xy 200.7581 -55.14551) (xy 200.887067 -55.298515)
			(xy 201.022053 -55.446238) (xy 201.162841 -55.588442) (xy 201.309205 -55.724899) (xy 201.460912 -55.85539)
			(xy 201.617719 -55.979708) (xy 201.779374 -56.097652) (xy 201.945618 -56.209034) (xy 202.116186 -56.313675)
			(xy 202.290803 -56.411408) (xy 202.469191 -56.502077) (xy 202.651064 -56.585535) (xy 202.836131 -56.661651)
			(xy 203.024094 -56.7303) (xy 203.214654 -56.791375) (xy 203.407504 -56.844776) (xy 203.602337 -56.890419)
			(xy 203.79884 -56.92823) (xy 203.996699 -56.958149) (xy 204.195596 -56.980128) (xy 204.395213 -56.994131)
			(xy 204.595231 -57.000136) (xy 204.795328 -56.998134) (xy 204.995186 -56.988128) (xy 205.194483 -56.970133)
			(xy 205.3929 -56.94418) (xy 205.59012 -56.910308) (xy 205.785827 -56.868573) (xy 205.979708 -56.819041)
			(xy 206.171452 -56.761791) (xy 206.360751 -56.696916) (xy 206.547303 -56.624519) (xy 206.73081 -56.544716)
			(xy 206.910976 -56.457635) (xy 207.087515 -56.363415) (xy 207.260142 -56.262207) (xy 207.428581 -56.154174)
			(xy 207.592564 -56.039488) (xy 207.751826 -55.918333) (xy 207.906114 -55.790903) (xy 208.05518 -55.657402)
			(xy 208.198785 -55.518044) (xy 208.336699 -55.373052) (xy 208.468702 -55.222658) (xy 208.594582 -55.067103)
			(xy 208.714138 -54.906636) (xy 208.827177 -54.741515) (xy 208.93352 -54.572003) (xy 209.032995 -54.398372)
			(xy 209.125444 -54.2209) (xy 209.210718 -54.039871) (xy 209.288681 -53.855575) (xy 209.359208 -53.668308)
			(xy 209.422186 -53.478369) (xy 209.477514 -53.286062) (xy 209.525104 -53.091696) (xy 209.564879 -52.895581)
			(xy 209.596776 -52.698032) (xy 209.620744 -52.499364) (xy 209.636743 -52.299897) (xy 209.644749 -52.09995)
		)
		(stroke
			(width 0)
			(type solid)
		)
		(fill yes)
		(layer "F.Cu")
		(net "GND")
	)
	(gr_poly
		(pts
			(xy 273.645376 -51.999896) (xy 273.644875 -51.899842) (xy 273.636869 -51.699895) (xy 273.62087 -51.500428)
			(xy 273.596902 -51.30176) (xy 273.565005 -51.104211) (xy 273.52523 -50.908096) (xy 273.47764 -50.71373)
			(xy 273.422312 -50.521423) (xy 273.359334 -50.331484) (xy 273.288807 -50.144217) (xy 273.210844 -49.959921)
			(xy 273.12557 -49.778892) (xy 273.033121 -49.60142) (xy 272.933646 -49.427789) (xy 272.827303 -49.258277)
			(xy 272.714264 -49.093156) (xy 272.594708 -48.932689) (xy 272.468828 -48.777134) (xy 272.336825 -48.62674)
			(xy 272.198911 -48.481748) (xy 272.055306 -48.34239) (xy 271.90624 -48.208889) (xy 271.751952 -48.081459)
			(xy 271.59269 -47.960304) (xy 271.428707 -47.845618) (xy 271.260268 -47.737585) (xy 271.087641 -47.636377)
			(xy 270.911102 -47.542157) (xy 270.730936 -47.455076) (xy 270.547429 -47.375273) (xy 270.360877 -47.302876)
			(xy 270.171578 -47.238001) (xy 269.979834 -47.180751) (xy 269.785953 -47.131219) (xy 269.590246 -47.089484)
			(xy 269.393026 -47.055612) (xy 269.194609 -47.029659) (xy 268.995312 -47.011664) (xy 268.795454 -47.001658)
			(xy 268.595357 -46.999656) (xy 268.395339 -47.005661) (xy 268.195722 -47.019664) (xy 267.996825 -47.041643)
			(xy 267.798966 -47.071562) (xy 267.602463 -47.109373) (xy 267.40763 -47.155016) (xy 267.21478 -47.208417)
			(xy 267.02422 -47.269492) (xy 266.836257 -47.338141) (xy 266.65119 -47.414257) (xy 266.469317 -47.497715)
			(xy 266.290929 -47.588384) (xy 266.116312 -47.686117) (xy 265.945744 -47.790758) (xy 265.7795 -47.90214)
			(xy 265.617845 -48.020084) (xy 265.461038 -48.144402) (xy 265.309331 -48.274893) (xy 265.162967 -48.41135)
			(xy 265.022179 -48.553554) (xy 264.887193 -48.701277) (xy 264.758226 -48.854282) (xy 264.635483 -49.012324)
			(xy 264.519163 -49.175151) (xy 264.40945 -49.342501) (xy 264.30652 -49.514107) (xy 264.210539 -49.689694)
			(xy 264.121659 -49.86898) (xy 264.040024 -50.051679) (xy 263.965765 -50.237498) (xy 263.898999 -50.426139)
			(xy 263.839834 -50.6173) (xy 263.788364 -50.810675) (xy 263.744673 -51.005955) (xy 263.70883 -51.202826)
			(xy 263.680892 -51.400974) (xy 263.660905 -51.600081) (xy 263.648899 -51.799828) (xy 263.644896 -51.999896)
			(xy 265.365744 -51.999896) (xy 265.369757 -51.837706) (xy 265.381786 -51.675912) (xy 265.401801 -51.514911)
			(xy 265.429754 -51.355097) (xy 265.465577 -51.196861) (xy 265.509181 -51.04059) (xy 265.560459 -50.886667)
			(xy 265.619287 -50.735468) (xy 265.685521 -50.587364) (xy 265.758997 -50.442716) (xy 265.839537 -50.301878)
			(xy 265.926944 -50.165196) (xy 266.021003 -50.033004) (xy 266.121484 -49.905625) (xy 266.228142 -49.783371)
			(xy 266.340715 -49.666542) (xy 266.458928 -49.555422) (xy 266.582491 -49.450285) (xy 266.711103 -49.351387)
			(xy 266.844449 -49.25897) (xy 266.982201 -49.173261) (xy 267.124024 -49.094468) (xy 267.26957 -49.022786)
			(xy 267.418482 -48.95839) (xy 267.570397 -48.901437) (xy 267.724943 -48.852066) (xy 267.881741 -48.810398)
			(xy 268.040408 -48.776535) (xy 268.200555 -48.750561) (xy 268.361791 -48.732538) (xy 268.523721 -48.722511)
			(xy 268.685949 -48.720505) (xy 268.848078 -48.726523) (xy 269.00971 -48.740553) (xy 269.170451 -48.762558)
			(xy 269.329907 -48.792485) (xy 269.487688 -48.830262) (xy 269.643407 -48.875795) (xy 269.796684 -48.928974)
			(xy 269.947144 -48.989667) (xy 270.094419 -49.057727) (xy 270.238147 -49.132987) (xy 270.377977 -49.215263)
			(xy 270.513568 -49.304354) (xy 270.644586 -49.40004) (xy 270.770713 -49.502089) (xy 270.891638 -49.610251)
			(xy 271.007066 -49.72426) (xy 271.116715 -49.843839) (xy 271.220316 -49.968693) (xy 271.317616 -50.098518)
			(xy 271.408377 -50.232997) (xy 271.492376 -50.371799) (xy 271.569408 -50.514585) (xy 271.639284 -50.661006)
			(xy 271.701834 -50.810704) (xy 271.756904 -50.963312) (xy 271.80436 -51.118456) (xy 271.844085 -51.275758)
			(xy 271.875982 -51.434831) (xy 271.899974 -51.595288) (xy 271.916001 -51.756734) (xy 271.924025 -51.918776)
			(xy 271.924526 -51.999896) (xy 271.924025 -52.081016) (xy 271.916001 -52.243058) (xy 271.899974 -52.404504)
			(xy 271.875982 -52.564961) (xy 271.844085 -52.724034) (xy 271.80436 -52.881336) (xy 271.756904 -53.03648)
			(xy 271.701834 -53.189088) (xy 271.639284 -53.338786) (xy 271.569408 -53.485207) (xy 271.492376 -53.627993)
			(xy 271.408377 -53.766795) (xy 271.317616 -53.901274) (xy 271.220316 -54.031099) (xy 271.116715 -54.155953)
			(xy 271.007066 -54.275532) (xy 270.891638 -54.389541) (xy 270.770713 -54.497703) (xy 270.644586 -54.599752)
			(xy 270.513568 -54.695438) (xy 270.377977 -54.784529) (xy 270.238147 -54.866805) (xy 270.094419 -54.942065)
			(xy 269.947144 -55.010125) (xy 269.796684 -55.070818) (xy 269.643407 -55.123997) (xy 269.487688 -55.16953)
			(xy 269.329907 -55.207307) (xy 269.170451 -55.237234) (xy 269.00971 -55.259239) (xy 268.848078 -55.273269)
			(xy 268.685949 -55.279287) (xy 268.523721 -55.277281) (xy 268.361791 -55.267254) (xy 268.200555 -55.249231)
			(xy 268.040408 -55.223257) (xy 267.881741 -55.189394) (xy 267.724943 -55.147726) (xy 267.570397 -55.098355)
			(xy 267.418482 -55.041402) (xy 267.26957 -54.977006) (xy 267.124024 -54.905324) (xy 266.982201 -54.826531)
			(xy 266.844449 -54.740822) (xy 266.711103 -54.648405) (xy 266.582491 -54.549507) (xy 266.458928 -54.44437)
			(xy 266.340715 -54.33325) (xy 266.228142 -54.216421) (xy 266.121484 -54.094167) (xy 266.021003 -53.966788)
			(xy 265.926944 -53.834596) (xy 265.839537 -53.697914) (xy 265.758997 -53.557076) (xy 265.685521 -53.412428)
			(xy 265.619287 -53.264324) (xy 265.560459 -53.113125) (xy 265.509181 -52.959202) (xy 265.465577 -52.802931)
			(xy 265.429754 -52.644695) (xy 265.401801 -52.484881) (xy 265.381786 -52.32388) (xy 265.369757 -52.162086)
			(xy 265.365744 -51.999896) (xy 263.644896 -51.999896) (xy 263.648899 -52.199964) (xy 263.660905 -52.399711)
			(xy 263.680892 -52.598818) (xy 263.70883 -52.796966) (xy 263.744673 -52.993837) (xy 263.788364 -53.189117)
			(xy 263.839834 -53.382492) (xy 263.898999 -53.573653) (xy 263.965765 -53.762294) (xy 264.040024 -53.948113)
			(xy 264.121659 -54.130812) (xy 264.210539 -54.310098) (xy 264.30652 -54.485685) (xy 264.40945 -54.657291)
			(xy 264.519163 -54.824641) (xy 264.635483 -54.987468) (xy 264.758226 -55.14551) (xy 264.887193 -55.298515)
			(xy 265.022179 -55.446238) (xy 265.162967 -55.588442) (xy 265.309331 -55.724899) (xy 265.461038 -55.85539)
			(xy 265.617845 -55.979708) (xy 265.7795 -56.097652) (xy 265.945744 -56.209034) (xy 266.116312 -56.313675)
			(xy 266.290929 -56.411408) (xy 266.469317 -56.502077) (xy 266.65119 -56.585535) (xy 266.836257 -56.661651)
			(xy 267.02422 -56.7303) (xy 267.21478 -56.791375) (xy 267.40763 -56.844776) (xy 267.602463 -56.890419)
			(xy 267.798966 -56.92823) (xy 267.996825 -56.958149) (xy 268.195722 -56.980128) (xy 268.395339 -56.994131)
			(xy 268.595357 -57.000136) (xy 268.795454 -56.998134) (xy 268.995312 -56.988128) (xy 269.194609 -56.970133)
			(xy 269.393026 -56.94418) (xy 269.590246 -56.910308) (xy 269.785953 -56.868573) (xy 269.979834 -56.819041)
			(xy 270.171578 -56.761791) (xy 270.360877 -56.696916) (xy 270.547429 -56.624519) (xy 270.730936 -56.544716)
			(xy 270.911102 -56.457635) (xy 271.087641 -56.363415) (xy 271.260268 -56.262207) (xy 271.428707 -56.154174)
			(xy 271.59269 -56.039488) (xy 271.751952 -55.918333) (xy 271.90624 -55.790903) (xy 272.055306 -55.657402)
			(xy 272.198911 -55.518044) (xy 272.336825 -55.373052) (xy 272.468828 -55.222658) (xy 272.594708 -55.067103)
			(xy 272.714264 -54.906636) (xy 272.827303 -54.741515) (xy 272.933646 -54.572003) (xy 273.033121 -54.398372)
			(xy 273.12557 -54.2209) (xy 273.210844 -54.039871) (xy 273.288807 -53.855575) (xy 273.359334 -53.668308)
			(xy 273.422312 -53.478369) (xy 273.47764 -53.286062) (xy 273.52523 -53.091696) (xy 273.565005 -52.895581)
			(xy 273.596902 -52.698032) (xy 273.62087 -52.499364) (xy 273.636869 -52.299897) (xy 273.644875 -52.09995)
		)
		(stroke
			(width 0)
			(type solid)
		)
		(fill yes)
		(layer "F.Cu")
		(net "GND")
	)
	(gr_poly
		(pts
			(arc
				(start 359.785158 -394.686282)
				(mid 359.804681 -394.682381)
				(end 359.821226 -394.671296)
			)
			(arc
				(start 359.9307 -394.561822)
				(mid 359.941811 -394.545288)
				(end 359.945686 -394.525754)
			)
			(arc
				(start 359.945686 -394.27023)
				(mid 359.949587 -394.250707)
				(end 359.960672 -394.234162)
			)
			(arc
				(start 360.07675 -394.118084)
				(mid 360.087812 -394.101667)
				(end 360.091736 -394.08227)
			)
			(arc
				(start 360.091736 -394.0175)
				(mid 360.128992 -393.927428)
				(end 360.21899 -393.889992)
			)
			(xy 360.280966 -393.889992)
			(arc
				(start 360.290364 -393.886182)
				(mid 360.348726 -393.868198)
				(end 360.40949 -393.862052)
			)
			(arc
				(start 360.40949 -393.862052)
				(mid 360.470261 -393.868161)
				(end 360.528616 -393.886182)
			)
			(xy 360.538014 -393.889992)
			(arc
				(start 360.59999 -393.889992)
				(mid 360.677387 -393.916169)
				(end 360.722926 -393.983972)
			)
			(xy 360.727498 -394.000482) (xy 360.754676 -394.02131) (xy 360.877104 -394.02131) (xy 360.904282 -394.000482)
			(arc
				(start 360.908854 -393.983972)
				(mid 360.954443 -393.916234)
				(end 361.03179 -393.889992)
			)
			(xy 361.093766 -393.889992)
			(arc
				(start 361.103164 -393.886182)
				(mid 361.161526 -393.868198)
				(end 361.22229 -393.862052)
			)
			(arc
				(start 361.22229 -393.862052)
				(mid 361.283061 -393.868161)
				(end 361.341416 -393.886182)
			)
			(xy 361.350814 -393.889992) (xy 361.41279 -393.889992) (xy 361.421172 -393.8905) (xy 361.44708 -393.8905)
			(xy 361.452668 -393.896088)
			(arc
				(start 361.461812 -393.899898)
				(mid 361.502883 -393.927407)
				(end 361.530392 -393.968478)
			)
			(xy 361.534202 -393.977622)
			(arc
				(start 361.780074 -394.223494)
				(mid 361.796608 -394.234605)
				(end 361.816142 -394.23848)
			)
			(arc
				(start 362.293662 -394.23848)
				(mid 362.310327 -394.235669)
				(end 362.325158 -394.227558)
			)
			(arc
				(start 362.325158 -394.227558)
				(mid 362.473023 -394.146964)
				(end 362.639102 -394.1191)
			)
			(arc
				(start 362.639102 -394.1191)
				(mid 362.790199 -394.142146)
				(end 362.927646 -394.209016)
			)
			(arc
				(start 362.927646 -394.209016)
				(mid 362.956602 -394.218046)
				(end 362.985558 -394.209016)
			)
			(arc
				(start 362.985558 -394.209016)
				(mid 363.122993 -394.142106)
				(end 363.274102 -394.1191)
			)
			(arc
				(start 363.274102 -394.1191)
				(mid 363.440174 -394.146983)
				(end 363.588046 -394.227558)
			)
			(arc
				(start 363.588046 -394.227558)
				(mid 363.602871 -394.235684)
				(end 363.619542 -394.23848)
			)
			(arc
				(start 363.913166 -394.23848)
				(mid 363.932553 -394.23453)
				(end 363.94898 -394.223494)
			)
			(arc
				(start 364.065312 -394.107162)
				(mid 364.165184 -394.04043)
				(end 364.28299 -394.016992)
			)
			(arc
				(start 364.93958 -394.016992)
				(mid 364.975501 -394.002113)
				(end 364.99038 -393.966192)
			)
			(arc
				(start 364.99038 -393.598654)
				(mid 364.984083 -393.574157)
				(end 364.966758 -393.555728)
			)
			(arc
				(start 364.966758 -393.555728)
				(mid 364.849339 -393.46055)
				(end 364.757716 -393.340336)
			)
			(arc
				(start 364.757716 -393.340336)
				(mid 364.739057 -393.322046)
				(end 364.713774 -393.315444)
			)
			(arc
				(start 364.626398 -393.315444)
				(mid 364.601111 -393.322039)
				(end 364.582456 -393.340336)
			)
			(arc
				(start 364.582456 -393.340336)
				(mid 364.350331 -393.569488)
				(end 364.035086 -393.653264)
			)
			(arc
				(start 364.035086 -393.653264)
				(mid 363.399578 -393.017756)
				(end 364.035086 -392.382248)
			)
			(arc
				(start 364.035086 -392.382248)
				(mid 364.202829 -392.404855)
				(end 364.358682 -392.470894)
			)
			(arc
				(start 364.358682 -392.470894)
				(mid 364.391015 -392.47759)
				(end 364.420658 -392.46302)
			)
			(xy 364.798356 -392.085322) (xy 364.805214 -392.072368)
			(arc
				(start 364.806738 -392.064748)
				(mid 364.814295 -392.034963)
				(end 364.824772 -392.006074)
			)
			(xy 364.828836 -391.996676)
			(arc
				(start 364.828836 -391.93851)
				(mid 364.813957 -391.902589)
				(end 364.778036 -391.88771)
			)
			(arc
				(start 363.291628 -391.88771)
				(mid 363.263817 -391.895999)
				(end 363.245146 -391.91819)
			)
			(arc
				(start 363.245146 -391.91819)
				(mid 362.662978 -392.298747)
				(end 362.08081 -391.91819)
			)
			(arc
				(start 362.08081 -391.91819)
				(mid 362.062101 -391.896058)
				(end 362.034328 -391.88771)
			)
			(arc
				(start 362.021628 -391.88771)
				(mid 361.993817 -391.895999)
				(end 361.975146 -391.91819)
			)
			(arc
				(start 361.975146 -391.91819)
				(mid 361.740736 -392.195167)
				(end 361.392978 -392.298682)
			)
			(arc
				(start 361.392978 -392.298682)
				(mid 360.943606 -392.112546)
				(end 360.75747 -391.663174)
			)
			(arc
				(start 360.75747 -391.663174)
				(mid 360.761873 -391.588492)
				(end 360.774996 -391.514838)
			)
			(xy 360.778298 -391.50163) (xy 360.771186 -391.476484)
			(arc
				(start 360.331512 -391.037064)
				(mid 360.308672 -391.011464)
				(end 360.28884 -390.98347)
			)
			(arc
				(start 360.28884 -390.98347)
				(mid 360.270414 -390.966139)
				(end 360.245914 -390.959848)
			)
			(arc
				(start 359.682288 -390.959848)
				(mid 359.662794 -390.963632)
				(end 359.64622 -390.97458)
			)
			(arc
				(start 359.618534 -391.00252)
				(mid 359.607472 -391.018937)
				(end 359.603548 -391.038334)
			)
			(arc
				(start 359.603548 -391.461244)
				(mid 359.599647 -391.480767)
				(end 359.588562 -391.497312)
			)
			(arc
				(start 359.31475 -391.771124)
				(mid 359.303639 -391.787658)
				(end 359.299764 -391.807192)
			)
			(arc
				(start 359.299764 -394.582904)
				(mid 359.303665 -394.602427)
				(end 359.31475 -394.618972)
			)
			(arc
				(start 359.367074 -394.671296)
				(mid 359.383608 -394.682407)
				(end 359.403142 -394.686282)
			)
		)
		(stroke
			(width 0)
			(type solid)
		)
		(fill yes)
		(layer "F.Cu")
		(net "P1V8_CPU0_RT_1D")
	)
	(gr_poly
		(pts
			(xy 229.6795 -435.74208) (xy 229.6795 -422.049194)
			(arc
				(start 237.719616 -414.009078)
				(mid 237.723517 -413.989555)
				(end 237.734602 -413.97301)
			)
			(xy 241.352832 -410.35478) (xy 279.44318 -410.35478) (xy 280.05024 -409.74772)
			(arc
				(start 280.05024 -394.963396)
				(mid 280.046339 -394.943873)
				(end 280.035254 -394.927328)
			)
			(arc
				(start 279.651206 -394.54328)
				(mid 279.634672 -394.532169)
				(end 279.615138 -394.528294)
			)
			(arc
				(start 277.939246 -394.528294)
				(mid 277.919723 -394.532195)
				(end 277.903178 -394.54328)
			)
			(arc
				(start 277.80742 -394.639038)
				(mid 277.796309 -394.655572)
				(end 277.792434 -394.675106)
			)
			(xy 277.792434 -396.22222) (xy 277.55342 -396.461234) (xy 276.894798 -396.461234) (xy 276.71268 -396.279116)
			(arc
				(start 276.71268 -394.651738)
				(mid 276.708779 -394.632215)
				(end 276.697694 -394.61567)
			)
			(arc
				(start 276.625304 -394.54328)
				(mid 276.60877 -394.532169)
				(end 276.589236 -394.528294)
			)
			(xy 269.076678 -394.528294) (xy 268.526768 -395.078204) (xy 267.8684 -395.078204) (xy 267.31849 -394.528294)
			(xy 261.050278 -394.528294) (xy 260.500368 -395.078204) (xy 259.842 -395.078204) (xy 259.29209 -394.528294)
			(xy 253.023878 -394.528294) (xy 252.473968 -395.078204) (xy 251.8156 -395.078204) (xy 251.26569 -394.528294)
			(xy 244.990366 -394.528294) (xy 244.44452 -395.07414) (xy 243.786152 -395.07414) (xy 243.240306 -394.528294)
			(xy 240.234978 -394.528294) (xy 239.933988 -394.829284) (xy 239.933988 -405.043894) (xy 239.933988 -405.438864)
			(xy 239.487202 -405.88565) (xy 234.366562 -405.88565) (xy 233.479086 -404.998174)
			(arc
				(start 233.479086 -404.727664)
				(mid 233.467975 -404.71113)
				(end 233.4641 -404.691596)
			)
			(arc
				(start 233.4641 -404.044658)
				(mid 233.460199 -404.025135)
				(end 233.449114 -404.00859)
			)
			(arc
				(start 233.257852 -403.817328)
				(mid 233.246741 -403.800794)
				(end 233.242866 -403.78126)
			)
			(arc
				(start 233.242866 -400.25574)
				(mid 233.238965 -400.236217)
				(end 233.22788 -400.219672)
			)
			(xy 233.226102 -400.217894) (xy 229.85857 -400.217894) (xy 229.840028 -400.225514) (xy 229.838504 -400.227038)
			(arc
				(start 229.838504 -403.745192)
				(mid 229.834603 -403.764715)
				(end 229.823518 -403.78126)
			)
			(arc
				(start 229.669086 -403.935692)
				(mid 229.657975 -403.952226)
				(end 229.6541 -403.97176)
			)
			(arc
				(start 229.6541 -406.3111)
				(mid 229.650199 -406.330623)
				(end 229.639114 -406.347168)
			)
			(arc
				(start 227.357686 -408.628596)
				(mid 227.341152 -408.639707)
				(end 227.321618 -408.643582)
			)
			(arc
				(start 224.887028 -408.643582)
				(mid 224.867505 -408.639681)
				(end 224.85096 -408.628596)
			)
			(arc
				(start 222.783146 -406.560782)
				(mid 222.772035 -406.544248)
				(end 222.76816 -406.524714)
			)
			(arc
				(start 222.76816 -403.989286)
				(mid 222.759553 -403.961247)
				(end 222.736918 -403.94255)
			)
			(arc
				(start 222.718884 -403.935184)
				(mid 222.710101 -403.930524)
				(end 222.702374 -403.924262)
			)
			(arc
				(start 222.591376 -403.813264)
				(mid 222.580402 -403.796701)
				(end 222.576644 -403.777196)
			)
			(xy 222.576644 -401.18284) (xy 222.575374 -401.181316)
			(arc
				(start 222.575374 -400.254724)
				(mid 222.571473 -400.235201)
				(end 222.560388 -400.218656)
			)
			(xy 222.557086 -400.215354)
			(arc
				(start 219.202 -400.215354)
				(mid 219.182477 -400.219255)
				(end 219.165932 -400.23034)
			)
			(xy 219.162122 -400.23415)
			(arc
				(start 219.162122 -403.734524)
				(mid 219.158221 -403.754047)
				(end 219.147136 -403.770592)
			)
			(arc
				(start 219.003626 -403.914102)
				(mid 218.992515 -403.930636)
				(end 218.98864 -403.95017)
			)
			(arc
				(start 218.98864 -406.33396)
				(mid 218.984739 -406.353483)
				(end 218.973654 -406.370028)
			)
			(arc
				(start 216.689686 -408.653996)
				(mid 216.673152 -408.665107)
				(end 216.653618 -408.668982)
			)
			(arc
				(start 214.237824 -408.668982)
				(mid 214.218301 -408.665081)
				(end 214.201756 -408.653996)
			)
			(arc
				(start 212.104986 -406.557226)
				(mid 212.093875 -406.540692)
				(end 212.09 -406.521158)
			)
			(arc
				(start 212.09 -403.965156)
				(mid 212.086099 -403.945633)
				(end 212.075014 -403.929088)
			)
			(arc
				(start 211.927186 -403.78126)
				(mid 211.916075 -403.764726)
				(end 211.9122 -403.745192)
			)
			(arc
				(start 211.9122 -400.279108)
				(mid 211.908299 -400.259585)
				(end 211.897214 -400.24304)
			)
			(arc
				(start 211.878672 -400.224498)
				(mid 211.862138 -400.213387)
				(end 211.842604 -400.209512)
			)
			(arc
				(start 208.562956 -400.209512)
				(mid 208.543433 -400.213413)
				(end 208.526888 -400.224498)
			)
			(arc
				(start 208.51622 -400.235166)
				(mid 208.505109 -400.2517)
				(end 208.501234 -400.271234)
			)
			(arc
				(start 208.501234 -403.743922)
				(mid 208.497333 -403.763445)
				(end 208.486248 -403.77999)
			)
			(arc
				(start 208.328006 -403.938232)
				(mid 208.316895 -403.954766)
				(end 208.31302 -403.9743)
			)
			(arc
				(start 208.31302 -406.39238)
				(mid 208.309119 -406.411903)
				(end 208.298034 -406.428448)
			)
			(arc
				(start 206.097886 -408.628596)
				(mid 206.081352 -408.639707)
				(end 206.061818 -408.643582)
			)
			(arc
				(start 203.335382 -408.643582)
				(mid 203.315859 -408.639681)
				(end 203.299314 -408.628596)
			)
			(arc
				(start 201.500486 -406.829768)
				(mid 201.489375 -406.813234)
				(end 201.4855 -406.7937)
			)
			(arc
				(start 201.4855 -403.99843)
				(mid 201.481599 -403.978907)
				(end 201.470514 -403.962362)
			)
			(arc
				(start 201.252836 -403.744684)
				(mid 201.241725 -403.72815)
				(end 201.23785 -403.708616)
			)
			(xy 201.23785 -400.23669) (xy 201.23023 -400.218148) (xy 201.224388 -400.212306)
			(arc
				(start 197.887336 -400.212306)
				(mid 197.867813 -400.216207)
				(end 197.851268 -400.227292)
			)
			(arc
				(start 197.849236 -400.229324)
				(mid 197.838125 -400.245858)
				(end 197.83425 -400.265392)
			)
			(arc
				(start 197.83425 -403.693884)
				(mid 197.830349 -403.713407)
				(end 197.819264 -403.729952)
			)
			(arc
				(start 195.562982 -405.986234)
				(mid 195.546448 -405.997345)
				(end 195.526914 -406.00122)
			)
			(arc
				(start 190.876682 -406.00122)
				(mid 190.857159 -405.997319)
				(end 190.840614 -405.986234)
			)
			(xy 189.57163 -404.71725)
			(arc
				(start 189.56274 -404.71344)
				(mid 189.406076 -404.606706)
				(end 189.299342 -404.450042)
			)
			(xy 189.295532 -404.441152)
			(arc
				(start 188.736986 -403.882606)
				(mid 188.725875 -403.866072)
				(end 188.722 -403.846538)
			)
			(arc
				(start 188.722 -403.423882)
				(mid 188.718099 -403.404359)
				(end 188.707014 -403.387814)
			)
			(xy 188.70422 -403.38502) (xy 188.685678 -403.3774)
			(arc
				(start 188.108082 -403.3774)
				(mid 188.088559 -403.373499)
				(end 188.072014 -403.362414)
			)
			(arc
				(start 187.995306 -403.285706)
				(mid 187.984195 -403.269172)
				(end 187.98032 -403.249638)
			)
			(arc
				(start 187.98032 -400.256502)
				(mid 187.976419 -400.236979)
				(end 187.965334 -400.220434)
			)
			(xy 187.96254 -400.21764) (xy 184.600342 -400.21764) (xy 184.5818 -400.22526) (xy 184.57672 -400.23034)
			(arc
				(start 184.57672 -403.615398)
				(mid 184.580621 -403.634921)
				(end 184.591706 -403.651466)
			)
			(arc
				(start 184.691274 -403.751034)
				(mid 184.702385 -403.767568)
				(end 184.70626 -403.787102)
			)
			(arc
				(start 184.70626 -404.357078)
				(mid 184.710161 -404.376601)
				(end 184.721246 -404.393146)
			)
			(arc
				(start 184.871614 -404.543514)
				(mid 184.882725 -404.560048)
				(end 184.8866 -404.579582)
			)
			(arc
				(start 184.8866 -405.431498)
				(mid 184.890501 -405.451021)
				(end 184.901586 -405.467566)
			)
			(arc
				(start 185.323734 -405.889714)
				(mid 185.334845 -405.906248)
				(end 185.33872 -405.925782)
			)
			(arc
				(start 185.33872 -406.904698)
				(mid 185.334819 -406.924221)
				(end 185.323734 -406.940766)
			)
			(arc
				(start 184.718706 -407.545794)
				(mid 184.707595 -407.562328)
				(end 184.70372 -407.581862)
			)
			(xy 184.70372 -409.57754) (xy 184.70372 -410.697426) (xy 184.94502 -410.938726) (xy 186.043824 -410.938726)
			(xy 187.297314 -410.938726) (xy 188.09589 -410.938726) (xy 188.849 -411.691836) (xy 195.399914 -411.691836)
			(xy 196.750432 -413.042354) (xy 196.750432 -421.568118) (xy 206.039974 -430.85766)
			(arc
				(start 206.039974 -431.536856)
				(mid 206.051085 -431.55339)
				(end 206.05496 -431.572924)
			)
			(xy 206.05496 -435.09946) (xy 207.43418 -436.47868) (xy 228.9429 -436.47868)
		)
		(stroke
			(width 0)
			(type solid)
		)
		(fill yes)
		(layer "F.Cu")
		(net "P12V_PSU")
	)
	(gr_poly
		(pts
			(arc
				(start 79.053944 -354.006658)
				(mid 79.073467 -354.002757)
				(end 79.090012 -353.991672)
			)
			(arc
				(start 81.582514 -351.49917)
				(mid 81.599048 -351.488059)
				(end 81.618582 -351.484184)
			)
			(arc
				(start 84.269326 -351.484184)
				(mid 84.288849 -351.480283)
				(end 84.305394 -351.469198)
			)
			(arc
				(start 86.763606 -349.010986)
				(mid 86.78014 -348.999875)
				(end 86.799674 -348.996)
			)
			(xy 103.490522 -348.996) (xy 103.859076 -348.627446) (xy 104.257856 -348.228412) (xy 104.41686 -348.069408)
			(xy 106.844592 -348.069408)
			(arc
				(start 108.694474 -346.219526)
				(mid 108.705585 -346.202992)
				(end 108.70946 -346.183458)
			)
			(arc
				(start 108.70946 -340.254336)
				(mid 108.694581 -340.218415)
				(end 108.65866 -340.203536)
			)
			(xy 104.224836 -340.203536) (xy 104.20604 -340.211156) (xy 104.198928 -340.218522)
			(arc
				(start 104.126284 -340.291166)
				(mid 104.115173 -340.3077)
				(end 104.111298 -340.327234)
			)
			(arc
				(start 104.111298 -342.213692)
				(mid 104.126177 -342.249613)
				(end 104.162098 -342.264492)
			)
			(arc
				(start 105.494582 -342.264492)
				(mid 105.514105 -342.268393)
				(end 105.53065 -342.279478)
			)
			(arc
				(start 105.659936 -342.408764)
				(mid 105.671047 -342.425298)
				(end 105.674922 -342.444832)
			)
			(arc
				(start 105.674922 -343.586816)
				(mid 105.678687 -343.606007)
				(end 105.6894 -343.622376)
			)
			(xy 105.689654 -343.62263)
			(arc
				(start 105.932986 -343.865962)
				(mid 105.944097 -343.882496)
				(end 105.947972 -343.90203)
			)
			(arc
				(start 105.947972 -345.268296)
				(mid 105.944071 -345.287819)
				(end 105.932986 -345.304364)
			)
			(arc
				(start 105.343198 -345.894152)
				(mid 105.326664 -345.905263)
				(end 105.30713 -345.909138)
			)
			(arc
				(start 100.062284 -345.909138)
				(mid 100.042761 -345.905237)
				(end 100.026216 -345.894152)
			)
			(arc
				(start 99.496372 -345.364308)
				(mid 99.485261 -345.347774)
				(end 99.481386 -345.32824)
			)
			(xy 99.481386 -339.012276) (xy 99.473766 -338.99348) (xy 99.4664 -338.986368)
			(arc
				(start 98.907854 -338.427822)
				(mid 98.896743 -338.411288)
				(end 98.892868 -338.391754)
			)
			(arc
				(start 98.892868 -336.425794)
				(mid 98.896769 -336.406271)
				(end 98.907854 -336.389726)
			)
			(arc
				(start 99.365308 -335.932272)
				(mid 99.376419 -335.915738)
				(end 99.380294 -335.896204)
			)
			(xy 99.380294 -335.348326) (xy 99.372674 -335.32953) (xy 99.365308 -335.322418) (xy 99.352608 -335.309718)
			(xy 99.352608 -335.30921)
			(arc
				(start 99.333558 -335.29016)
				(mid 99.317024 -335.279049)
				(end 99.29749 -335.275174)
			)
			(xy 95.90405 -335.275174) (xy 95.885254 -335.282794) (xy 95.878142 -335.29016)
			(arc
				(start 95.850456 -335.317846)
				(mid 95.839345 -335.33438)
				(end 95.83547 -335.353914)
			)
			(arc
				(start 95.83547 -337.245198)
				(mid 95.850534 -337.275509)
				(end 95.881444 -337.28914)
			)
			(arc
				(start 97.115122 -337.28914)
				(mid 97.134645 -337.293041)
				(end 97.15119 -337.304126)
			)
			(arc
				(start 97.390712 -337.543648)
				(mid 97.401823 -337.560182)
				(end 97.405698 -337.579716)
			)
			(arc
				(start 97.405698 -338.311998)
				(mid 97.409463 -338.331189)
				(end 97.420176 -338.347558)
			)
			(xy 97.42043 -338.347812)
			(arc
				(start 97.790508 -338.71789)
				(mid 97.801619 -338.734424)
				(end 97.805494 -338.753958)
			)
			(arc
				(start 97.805494 -340.444582)
				(mid 97.801593 -340.464105)
				(end 97.790508 -340.48065)
			)
			(arc
				(start 97.331784 -340.939374)
				(mid 97.31525 -340.950485)
				(end 97.295716 -340.95436)
			)
			(arc
				(start 91.773502 -340.95436)
				(mid 91.753979 -340.950459)
				(end 91.737434 -340.939374)
			)
			(arc
				(start 91.101672 -340.303612)
				(mid 91.090561 -340.287078)
				(end 91.086686 -340.267544)
			)
			(xy 91.086686 -335.335118) (xy 91.079066 -335.316322) (xy 91.0717 -335.30921)
			(arc
				(start 91.004136 -335.241646)
				(mid 90.987602 -335.230535)
				(end 90.968068 -335.22666)
			)
			(xy 87.573104 -335.22666) (xy 87.554308 -335.23428) (xy 87.547196 -335.241646)
			(arc
				(start 87.519256 -335.269586)
				(mid 87.508145 -335.28612)
				(end 87.50427 -335.305654)
			)
			(arc
				(start 87.50427 -337.194398)
				(mid 87.519334 -337.224709)
				(end 87.550244 -337.23834)
			)
			(arc
				(start 88.824816 -337.23834)
				(mid 88.844339 -337.242241)
				(end 88.860884 -337.253326)
			)
			(arc
				(start 89.063322 -337.455764)
				(mid 89.074433 -337.472298)
				(end 89.078308 -337.491832)
			)
			(arc
				(start 89.078308 -338.265008)
				(mid 89.082073 -338.284199)
				(end 89.092786 -338.300568)
			)
			(xy 89.09304 -338.300822)
			(arc
				(start 89.39911 -338.606892)
				(mid 89.410016 -338.623075)
				(end 89.413842 -338.642198)
			)
			(arc
				(start 89.413842 -340.429596)
				(mid 89.409941 -340.449119)
				(end 89.398856 -340.465664)
			)
			(arc
				(start 88.978486 -340.886034)
				(mid 88.961952 -340.897145)
				(end 88.942418 -340.90102)
			)
			(arc
				(start 83.571842 -340.90102)
				(mid 83.552319 -340.897119)
				(end 83.535774 -340.886034)
			)
			(arc
				(start 82.745072 -340.095332)
				(mid 82.733961 -340.078798)
				(end 82.730086 -340.059264)
			)
			(xy 82.730086 -335.365344) (xy 82.722466 -335.346548) (xy 82.7151 -335.339436)
			(arc
				(start 82.638138 -335.262474)
				(mid 82.621604 -335.251363)
				(end 82.60207 -335.247488)
			)
			(xy 79.203804 -335.247488) (xy 79.185008 -335.255108) (xy 79.177896 -335.262474) (xy 79.15275 -335.28762)
			(xy 79.15275 -335.287874) (xy 79.146654 -335.29397)
			(arc
				(start 79.146654 -337.20913)
				(mid 79.160872 -337.238399)
				(end 79.190088 -337.252564)
			)
			(arc
				(start 80.45958 -337.252564)
				(mid 80.479103 -337.256465)
				(end 80.495648 -337.26755)
			)
			(arc
				(start 80.698086 -337.469988)
				(mid 80.709197 -337.486522)
				(end 80.713072 -337.506056)
			)
			(arc
				(start 80.713072 -338.271866)
				(mid 80.716837 -338.291057)
				(end 80.72755 -338.307426)
			)
			(xy 80.727804 -338.30768)
			(arc
				(start 81.041494 -338.62137)
				(mid 81.0524 -338.637553)
				(end 81.056226 -338.656676)
			)
			(arc
				(start 81.056226 -340.461092)
				(mid 81.052325 -340.480615)
				(end 81.04124 -340.49716)
			)
			(arc
				(start 80.581246 -340.957154)
				(mid 80.564712 -340.968265)
				(end 80.545178 -340.97214)
			)
			(arc
				(start 75.288902 -340.97214)
				(mid 75.269379 -340.968239)
				(end 75.252834 -340.957154)
			)
			(arc
				(start 74.48296 -340.18728)
				(mid 74.471849 -340.170746)
				(end 74.467974 -340.151212)
			)
			(xy 74.467974 -335.404714) (xy 74.460354 -335.385918) (xy 74.452988 -335.378806)
			(arc
				(start 74.319892 -335.24571)
				(mid 74.303358 -335.234599)
				(end 74.283824 -335.230724)
			)
			(xy 70.883272 -335.230724) (xy 70.864476 -335.238344) (xy 70.857364 -335.24571)
			(arc
				(start 70.806056 -335.297018)
				(mid 70.794945 -335.313552)
				(end 70.79107 -335.333086)
			)
			(arc
				(start 70.79107 -337.216242)
				(mid 70.805288 -337.245511)
				(end 70.834504 -337.259676)
			)
			(arc
				(start 72.227186 -337.259676)
				(mid 72.246709 -337.263577)
				(end 72.263254 -337.274662)
			)
			(arc
				(start 72.340978 -337.352386)
				(mid 72.352089 -337.36892)
				(end 72.355964 -337.388454)
			)
			(arc
				(start 72.355964 -338.34578)
				(mid 72.359729 -338.364971)
				(end 72.370442 -338.38134)
			)
			(xy 72.370696 -338.381594)
			(arc
				(start 72.720962 -338.73186)
				(mid 72.731868 -338.748043)
				(end 72.735694 -338.767166)
			)
			(arc
				(start 72.735694 -342.504268)
				(mid 72.739459 -342.523459)
				(end 72.750172 -342.539828)
			)
			(xy 72.750426 -342.540082)
			(arc
				(start 73.589896 -343.379552)
				(mid 73.601007 -343.396086)
				(end 73.604882 -343.41562)
			)
			(arc
				(start 73.604882 -346.240862)
				(mid 73.600981 -346.260385)
				(end 73.589896 -346.27693)
			)
			(arc
				(start 71.719694 -348.147132)
				(mid 71.70316 -348.158243)
				(end 71.683626 -348.162118)
			)
			(arc
				(start 68.331842 -348.162118)
				(mid 68.312319 -348.158217)
				(end 68.295774 -348.147132)
			)
			(arc
				(start 67.161664 -347.013022)
				(mid 67.14513 -347.001911)
				(end 67.125596 -346.998036)
			)
			(xy 62.332616 -346.998036) (xy 62.31382 -347.005656) (xy 62.306708 -347.013022)
			(arc
				(start 62.271656 -347.048074)
				(mid 62.260545 -347.064608)
				(end 62.25667 -347.084142)
			)
			(arc
				(start 62.25667 -348.909894)
				(mid 62.260435 -348.929085)
				(end 62.271148 -348.945454)
			)
			(xy 62.271402 -348.945708) (xy 62.310264 -348.98457)
			(arc
				(start 62.310772 -348.985078)
				(mid 62.327129 -348.99582)
				(end 62.346332 -348.999556)
			)
			(arc
				(start 63.606172 -348.999556)
				(mid 63.625695 -349.003457)
				(end 63.64224 -349.014542)
			)
			(xy 63.746126 -349.118428) (xy 63.746126 -349.129858)
			(arc
				(start 63.816738 -349.20047)
				(mid 63.827849 -349.217004)
				(end 63.831724 -349.236538)
			)
			(arc
				(start 63.831724 -350.286574)
				(mid 63.835489 -350.305765)
				(end 63.846202 -350.322134)
			)
			(xy 63.846456 -350.322388)
			(arc
				(start 64.328548 -350.80448)
				(mid 64.345082 -350.815591)
				(end 64.364616 -350.819466)
			)
			(arc
				(start 64.379094 -350.819466)
				(mid 64.398617 -350.823367)
				(end 64.415162 -350.834452)
			)
			(arc
				(start 67.572382 -353.991672)
				(mid 67.588916 -354.002783)
				(end 67.60845 -354.006658)
			)
		)
		(stroke
			(width 0)
			(type solid)
		)
		(fill yes)
		(layer "F.Cu")
		(net "SW_P12V_AUX_PVDDCR_CPU1_P1_FLT")
	)
	(gr_poly
		(pts
			(arc
				(start 102.686104 -386.718048)
				(mid 102.73927 -386.70645)
				(end 102.793546 -386.702554)
			)
			(arc
				(start 102.793546 -386.702554)
				(mid 102.847819 -386.706471)
				(end 102.900988 -386.718048)
			)
			(xy 102.9081 -386.72008)
			(arc
				(start 102.950518 -386.72008)
				(mid 102.970041 -386.716179)
				(end 102.986586 -386.705094)
			)
			(arc
				(start 103.188262 -386.503418)
				(mid 103.199324 -386.487001)
				(end 103.203248 -386.467604)
			)
			(xy 103.232458 -386.43814) (xy 103.242364 -386.43814) (xy 103.26116 -386.43052)
			(arc
				(start 103.372412 -386.319268)
				(mid 103.388946 -386.308157)
				(end 103.40848 -386.304282)
			)
			(arc
				(start 103.785416 -386.304282)
				(mid 103.804939 -386.300381)
				(end 103.821484 -386.289296)
			)
			(arc
				(start 103.930958 -386.179822)
				(mid 103.942069 -386.163288)
				(end 103.945944 -386.143754)
			)
			(arc
				(start 103.945944 -385.88823)
				(mid 103.949845 -385.868707)
				(end 103.96093 -385.852162)
			)
			(arc
				(start 104.077008 -385.736084)
				(mid 104.087934 -385.719638)
				(end 104.09174 -385.70027)
			)
			(arc
				(start 104.09174 -385.6355)
				(mid 104.129086 -385.545338)
				(end 104.219248 -385.507992)
			)
			(xy 104.281224 -385.507992)
			(arc
				(start 104.290622 -385.504182)
				(mid 104.348984 -385.486198)
				(end 104.409748 -385.480052)
			)
			(arc
				(start 104.409748 -385.480052)
				(mid 104.470519 -385.486161)
				(end 104.528874 -385.504182)
			)
			(xy 104.538272 -385.507992)
			(arc
				(start 104.600248 -385.507992)
				(mid 104.677645 -385.534169)
				(end 104.723184 -385.601972)
			)
			(xy 104.727756 -385.618482) (xy 104.754934 -385.63931) (xy 104.877362 -385.63931) (xy 104.90454 -385.618482)
			(arc
				(start 104.909112 -385.601972)
				(mid 104.954701 -385.534234)
				(end 105.032048 -385.507992)
			)
			(xy 105.094024 -385.507992)
			(arc
				(start 105.103422 -385.504182)
				(mid 105.161784 -385.486198)
				(end 105.222548 -385.480052)
			)
			(arc
				(start 105.222548 -385.480052)
				(mid 105.283319 -385.486161)
				(end 105.341674 -385.504182)
			)
			(xy 105.351072 -385.507992)
			(arc
				(start 105.413048 -385.507992)
				(mid 105.501855 -385.544104)
				(end 105.540302 -385.631944)
			)
			(xy 105.540556 -385.64185) (xy 105.54843 -385.65963)
			(arc
				(start 105.730294 -385.841494)
				(mid 105.746828 -385.852605)
				(end 105.766362 -385.85648)
			)
			(arc
				(start 107.490514 -385.85648)
				(mid 107.516687 -385.849371)
				(end 107.535472 -385.82981)
			)
			(arc
				(start 107.535472 -385.82981)
				(mid 107.769068 -385.585295)
				(end 108.095034 -385.495292)
			)
			(arc
				(start 108.095034 -385.495292)
				(mid 108.325478 -385.538545)
				(end 108.524548 -385.662424)
			)
			(xy 108.53166 -385.668774) (xy 108.549186 -385.675632)
			(arc
				(start 108.72089 -385.675632)
				(mid 108.730858 -385.674695)
				(end 108.740448 -385.671822)
			)
			(arc
				(start 108.959142 -385.581398)
				(mid 108.981928 -385.562649)
				(end 108.990384 -385.534408)
			)
			(arc
				(start 108.990384 -385.216654)
				(mid 108.984087 -385.192157)
				(end 108.966762 -385.173728)
			)
			(arc
				(start 108.966762 -385.173728)
				(mid 108.809892 -385.034075)
				(end 108.707174 -384.850894)
			)
			(xy 108.703364 -384.840226) (xy 108.687362 -384.824224) (xy 108.592366 -384.789934) (xy 108.570014 -384.791966)
			(arc
				(start 108.560108 -384.797808)
				(mid 108.517511 -384.818604)
				(end 108.472224 -384.832606)
			)
			(arc
				(start 108.472224 -384.832606)
				(mid 108.453538 -384.84107)
				(end 108.439712 -384.856228)
			)
			(arc
				(start 108.439712 -384.856228)
				(mid 108.207581 -385.084539)
				(end 107.89285 -385.167886)
			)
			(arc
				(start 107.89285 -385.167886)
				(mid 107.257342 -384.532378)
				(end 107.89285 -383.89687)
			)
			(arc
				(start 107.89285 -383.89687)
				(mid 108.12828 -383.941986)
				(end 108.330238 -384.071114)
			)
			(arc
				(start 108.330238 -384.071114)
				(mid 108.346297 -384.081447)
				(end 108.365036 -384.085084)
			)
			(arc
				(start 108.395262 -384.085338)
				(mid 108.414785 -384.081437)
				(end 108.43133 -384.070352)
			)
			(xy 108.79836 -383.703322) (xy 108.805218 -383.690368)
			(arc
				(start 108.806742 -383.682748)
				(mid 108.814299 -383.652963)
				(end 108.824776 -383.624074)
			)
			(xy 108.82884 -383.614676)
			(arc
				(start 108.82884 -383.55651)
				(mid 108.813961 -383.520589)
				(end 108.77804 -383.50571)
			)
			(xy 107.273598 -383.50571) (xy 107.26928 -383.510028) (xy 107.257088 -383.510028)
			(arc
				(start 107.243626 -383.54)
				(mid 107.009186 -383.814242)
				(end 106.663236 -383.916682)
			)
			(arc
				(start 106.663236 -383.916682)
				(mid 106.317331 -383.814346)
				(end 106.082846 -383.540254)
			)
			(arc
				(start 106.082846 -383.540254)
				(mid 106.064095 -383.518227)
				(end 106.036364 -383.510028)
			)
			(arc
				(start 106.020108 -383.510028)
				(mid 105.992394 -383.518254)
				(end 105.973626 -383.540254)
			)
			(arc
				(start 105.973626 -383.540254)
				(mid 105.739104 -383.814288)
				(end 105.393236 -383.916682)
			)
			(arc
				(start 105.393236 -383.916682)
				(mid 104.943864 -383.730546)
				(end 104.757728 -383.281174)
			)
			(arc
				(start 104.757728 -383.281174)
				(mid 104.762131 -383.206492)
				(end 104.775254 -383.132838)
			)
			(xy 104.778556 -383.11963) (xy 104.771444 -383.094484)
			(arc
				(start 104.33177 -382.655064)
				(mid 104.30893 -382.629464)
				(end 104.289098 -382.60147)
			)
			(arc
				(start 104.289098 -382.60147)
				(mid 104.270672 -382.584139)
				(end 104.246172 -382.577848)
			)
			(arc
				(start 103.682546 -382.577848)
				(mid 103.663052 -382.581632)
				(end 103.646478 -382.59258)
			)
			(arc
				(start 103.618792 -382.62052)
				(mid 103.60773 -382.636937)
				(end 103.603806 -382.656334)
			)
			(arc
				(start 103.603806 -383.079244)
				(mid 103.599905 -383.098767)
				(end 103.58882 -383.115312)
			)
			(arc
				(start 103.315008 -383.389124)
				(mid 103.303897 -383.405658)
				(end 103.300022 -383.425192)
			)
			(arc
				(start 103.300022 -385.403598)
				(mid 103.296121 -385.423121)
				(end 103.285036 -385.439666)
			)
			(arc
				(start 103.210868 -385.513834)
				(mid 103.194334 -385.524945)
				(end 103.1748 -385.52882)
			)
			(xy 103.06177 -385.52882) (xy 103.04907 -385.532122)
			(arc
				(start 103.043228 -385.535678)
				(mid 102.921139 -385.585867)
				(end 102.790244 -385.602988)
			)
			(arc
				(start 102.790244 -385.602988)
				(mid 102.676068 -385.590004)
				(end 102.56774 -385.55168)
			)
			(xy 102.553008 -385.544568) (xy 102.521258 -385.549902)
			(arc
				(start 102.450646 -385.620514)
				(mid 102.439535 -385.637048)
				(end 102.43566 -385.656582)
			)
			(xy 102.43566 -385.737608) (xy 102.439978 -385.751578)
			(arc
				(start 102.444296 -385.758182)
				(mid 102.5299 -386.04063)
				(end 102.444296 -386.323078)
			)
			(arc
				(start 102.444296 -386.323078)
				(mid 102.437857 -386.33653)
				(end 102.43566 -386.351272)
			)
			(arc
				(start 102.43566 -386.615178)
				(mid 102.439561 -386.634701)
				(end 102.450646 -386.651246)
			)
			(arc
				(start 102.504494 -386.705094)
				(mid 102.521028 -386.716205)
				(end 102.540562 -386.72008)
			)
			(xy 102.678992 -386.72008)
		)
		(stroke
			(width 0)
			(type solid)
		)
		(fill yes)
		(layer "F.Cu")
		(net "P1V8_CPU1_RT_1D")
	)
	(gr_poly
		(pts
			(xy 40.413178 -393.279376) (xy 40.423241 -393.278938) (xy 40.441823 -393.271201) (xy 40.449246 -393.26439)
			(xy 40.630602 -393.083034) (xy 40.637438 -393.075632) (xy 40.645148 -393.057034) (xy 40.645588 -393.046966)
			(xy 40.645588 -391.861548) (xy 40.645177 -391.851521) (xy 40.637515 -391.83299) (xy 40.62334 -391.818805)
			(xy 40.604814 -391.81113) (xy 40.594788 -391.810748) (xy 40.386 -391.810748) (xy 40.355385 -391.809993)
			(xy 40.295373 -391.797831) (xy 40.266874 -391.786618) (xy 40.257476 -391.782808) (xy 40.1955 -391.782808)
			(xy 40.178785 -391.782262) (xy 40.146494 -391.77361) (xy 40.117543 -391.756895) (xy 40.093905 -391.733257)
			(xy 40.07719 -391.704306) (xy 40.068538 -391.672015) (xy 40.067992 -391.6553) (xy 40.067992 -391.3505)
			(xy 40.068538 -391.333785) (xy 40.07719 -391.301494) (xy 40.093905 -391.272543) (xy 40.117543 -391.248905)
			(xy 40.146494 -391.23219) (xy 40.178785 -391.223538) (xy 40.1955 -391.222992) (xy 40.257476 -391.222992)
			(xy 40.266874 -391.219182) (xy 40.295376 -391.207985) (xy 40.355387 -391.195836) (xy 40.386 -391.195052)
			(xy 40.594788 -391.195052) (xy 40.604807 -391.194634) (xy 40.62332 -391.186964) (xy 40.637484 -391.17279)
			(xy 40.645141 -391.154272) (xy 40.645588 -391.144252) (xy 40.645588 -391.023348) (xy 40.645177 -391.013321)
			(xy 40.637515 -390.99479) (xy 40.62334 -390.980605) (xy 40.604814 -390.97293) (xy 40.594788 -390.972548)
			(xy 40.386 -390.972548) (xy 40.355385 -390.971793) (xy 40.295373 -390.959631) (xy 40.266874 -390.948418)
			(xy 40.257476 -390.944608) (xy 40.1955 -390.944608) (xy 40.178785 -390.944062) (xy 40.146494 -390.93541)
			(xy 40.117543 -390.918695) (xy 40.093905 -390.895057) (xy 40.07719 -390.866106) (xy 40.068538 -390.833815)
			(xy 40.067992 -390.8171) (xy 40.067992 -390.5123) (xy 40.068538 -390.495585) (xy 40.07719 -390.463294)
			(xy 40.093905 -390.434343) (xy 40.117543 -390.410705) (xy 40.146494 -390.39399) (xy 40.178785 -390.385338)
			(xy 40.1955 -390.384792) (xy 40.257476 -390.384792) (xy 40.266874 -390.380982) (xy 40.295376 -390.369785)
			(xy 40.355387 -390.357636) (xy 40.386 -390.356852) (xy 40.594788 -390.356852) (xy 40.604807 -390.356434)
			(xy 40.62332 -390.348764) (xy 40.637484 -390.33459) (xy 40.645141 -390.316072) (xy 40.645588 -390.306052)
			(xy 40.645588 -389.12292) (xy 40.645054 -389.112931) (xy 40.637344 -389.094495) (xy 40.630602 -389.087106)
			(xy 40.62603 -389.08228) (xy 40.618606 -389.0755) (xy 40.60001 -389.067898) (xy 40.589962 -389.067548)
			(xy 40.386 -389.067548) (xy 40.355385 -389.066793) (xy 40.295373 -389.054631) (xy 40.266874 -389.043418)
			(xy 40.257476 -389.039608) (xy 40.1955 -389.039608) (xy 40.178785 -389.039062) (xy 40.146494 -389.03041)
			(xy 40.117543 -389.013695) (xy 40.093905 -388.990057) (xy 40.07719 -388.961106) (xy 40.068538 -388.928815)
			(xy 40.067992 -388.9121) (xy 40.067992 -388.6073) (xy 40.068228 -388.596477) (xy 40.07193 -388.57515)
			(xy 40.075358 -388.564882) (xy 40.078152 -388.556754) (xy 40.078152 -387.90118) (xy 40.077593 -387.890071)
			(xy 40.068243 -387.869915) (xy 40.060118 -387.862318) (xy 40.036018 -387.841562) (xy 39.992653 -387.795033)
			(xy 39.95543 -387.743458) (xy 39.924932 -387.687642) (xy 39.901634 -387.628459) (xy 39.8859 -387.566831)
			(xy 39.877976 -387.503722) (xy 39.877492 -387.47192) (xy 39.878007 -387.43906) (xy 39.886473 -387.373888)
			(xy 39.903266 -387.31035) (xy 39.928107 -387.249505) (xy 39.960581 -387.192369) (xy 40.000147 -387.139894)
			(xy 40.02278 -387.116066) (xy 40.032432 -387.10616) (xy 40.039036 -387.079236) (xy 40.00627 -386.96773)
			(xy 39.986204 -386.948934) (xy 39.972488 -386.945886) (xy 39.93775 -386.937531) (xy 39.870267 -386.914051)
			(xy 39.805842 -386.883155) (xy 39.745286 -386.845231) (xy 39.689364 -386.800759) (xy 39.638779 -386.750297)
			(xy 39.594169 -386.694483) (xy 39.556098 -386.63402) (xy 39.525044 -386.569671) (xy 39.501399 -386.502246)
			(xy 39.485462 -386.432595) (xy 39.477434 -386.361597) (xy 39.476934 -386.325872) (xy 39.477417 -386.290212)
			(xy 39.485406 -386.219339) (xy 39.501279 -386.149807) (xy 39.524839 -386.08249) (xy 39.555787 -386.018234)
			(xy 39.593735 -385.957846) (xy 39.638206 -385.902088) (xy 39.68864 -385.851659) (xy 39.744404 -385.807194)
			(xy 39.804795 -385.769253) (xy 39.869055 -385.738312) (xy 39.936375 -385.71476) (xy 40.005909 -385.698894)
			(xy 40.076782 -385.690913) (xy 40.112442 -385.690364) (xy 40.148499 -385.690871) (xy 40.220148 -385.699041)
			(xy 40.290411 -385.715271) (xy 40.358384 -385.739353) (xy 40.423194 -385.770976) (xy 40.484006 -385.809734)
			(xy 40.540039 -385.855129) (xy 40.590571 -385.906577) (xy 40.634953 -385.963415) (xy 40.654224 -385.993894)
			(xy 40.659084 -386.001086) (xy 40.67261 -386.011948) (xy 40.688983 -386.01768) (xy 40.697658 -386.018024)
			(xy 40.900096 -386.018024) (xy 40.905114 -386.017927) (xy 40.914963 -386.016) (xy 40.919654 -386.014214)
			(xy 41.627298 -385.721098) (xy 41.655508 -385.710081) (xy 41.714878 -385.698173) (xy 41.745154 -385.697476)
			(xy 41.952418 -385.697476) (xy 41.954704 -385.69519) (xy 41.954704 -385.58216) (xy 41.955454 -385.551543)
			(xy 41.967607 -385.491528) (xy 41.978834 -385.463034) (xy 41.982644 -385.453636) (xy 41.982644 -385.39166)
			(xy 41.98286 -385.382575) (xy 41.985537 -385.3646) (xy 41.987978 -385.355846) (xy 41.990518 -385.346702)
			(xy 41.989502 -385.329176) (xy 41.955212 -385.252214) (xy 41.942766 -385.239514) (xy 41.934384 -385.23545)
			(xy 41.905066 -385.220888) (xy 41.849295 -385.186608) (xy 41.797343 -385.146776) (xy 41.74976 -385.101816)
			(xy 41.70705 -385.052202) (xy 41.669666 -384.998462) (xy 41.65346 -384.97002) (xy 41.646856 -384.958082)
			(xy 41.623996 -384.944112) (xy 41.50868 -384.941826) (xy 41.485058 -384.95478) (xy 41.477946 -384.966464)
			(xy 41.45869 -384.997062) (xy 41.414287 -385.054119) (xy 41.363699 -385.105771) (xy 41.307578 -385.151352)
			(xy 41.24665 -385.190272) (xy 41.181699 -385.22203) (xy 41.113566 -385.246216) (xy 41.043129 -385.262517)
			(xy 40.971297 -385.270723) (xy 40.935148 -385.271264) (xy 40.899487 -385.270764) (xy 40.828614 -385.262778)
			(xy 40.75908 -385.246907) (xy 40.69176 -385.223351) (xy 40.627501 -385.192405) (xy 40.567111 -385.15446)
			(xy 40.51135 -385.109991) (xy 40.460918 -385.059559) (xy 40.416449 -385.003797) (xy 40.378504 -384.943407)
			(xy 40.347558 -384.879148) (xy 40.324002 -384.811828) (xy 40.308132 -384.742295) (xy 40.300146 -384.671421)
			(xy 40.300146 -384.600099) (xy 40.308132 -384.529225) (xy 40.324002 -384.459692) (xy 40.347558 -384.392372)
			(xy 40.378504 -384.328113) (xy 40.416449 -384.267723) (xy 40.460918 -384.211961) (xy 40.51135 -384.161529)
			(xy 40.567111 -384.11706) (xy 40.627501 -384.079115) (xy 40.69176 -384.048169) (xy 40.75908 -384.024613)
			(xy 40.828614 -384.008742) (xy 40.899487 -384.000756) (xy 40.935148 -384.000248) (xy 40.96911 -384.000706)
			(xy 41.036644 -384.007979) (xy 41.103019 -384.022404) (xy 41.167479 -384.043818) (xy 41.229292 -384.071977)
			(xy 41.258744 -384.088894) (xy 41.273984 -384.097784) (xy 41.308274 -384.093466) (xy 41.698418 -383.703322)
			(xy 41.705276 -383.690368) (xy 41.7068 -383.682748) (xy 41.709302 -383.670915) (xy 41.715914 -383.647647)
			(xy 41.720008 -383.636266) (xy 41.72331 -383.62763) (xy 41.72331 -383.618486) (xy 41.722819 -383.60848)
			(xy 41.715158 -383.589991) (xy 41.701006 -383.57584) (xy 41.682517 -383.56818) (xy 41.67251 -383.567686)
			(xy 39.033704 -383.567686) (xy 39.023633 -383.568108) (xy 39.005026 -383.57582) (xy 38.997636 -383.582672)
			(xy 38.38575 -384.194558) (xy 38.378907 -384.201957) (xy 38.371186 -384.220556) (xy 38.370764 -384.230626)
			(xy 38.370764 -392.107377) (xy 38.880028 -392.107377) (xy 38.880028 -392.043455) (xy 38.888039 -391.980037)
			(xy 38.903936 -391.918123) (xy 38.927468 -391.85869) (xy 38.958262 -391.802675) (xy 38.995835 -391.75096)
			(xy 39.039592 -391.704363) (xy 39.088845 -391.663618) (xy 39.142816 -391.629367) (xy 39.200655 -391.60215)
			(xy 39.261448 -391.582397) (xy 39.324238 -391.570419) (xy 39.388034 -391.566406) (xy 39.45183 -391.570419)
			(xy 39.51462 -391.582397) (xy 39.575413 -391.60215) (xy 39.633252 -391.629367) (xy 39.687223 -391.663618)
			(xy 39.736476 -391.704363) (xy 39.780233 -391.75096) (xy 39.817806 -391.802675) (xy 39.8486 -391.85869)
			(xy 39.872132 -391.918123) (xy 39.888029 -391.980037) (xy 39.89604 -392.043455) (xy 39.896542 -392.075416)
			(xy 39.89604 -392.107377) (xy 39.888029 -392.170795) (xy 39.872132 -392.232709) (xy 39.8486 -392.292142)
			(xy 39.817806 -392.348157) (xy 39.780233 -392.399872) (xy 39.736476 -392.446469) (xy 39.687223 -392.487214)
			(xy 39.633252 -392.521465) (xy 39.575413 -392.548682) (xy 39.51462 -392.568435) (xy 39.45183 -392.580413)
			(xy 39.388034 -392.584427) (xy 39.324238 -392.580413) (xy 39.261448 -392.568435) (xy 39.200655 -392.548682)
			(xy 39.142816 -392.521465) (xy 39.088845 -392.487214) (xy 39.039592 -392.446469) (xy 38.995835 -392.399872)
			(xy 38.958262 -392.348157) (xy 38.927468 -392.292142) (xy 38.903936 -392.232709) (xy 38.888039 -392.170795)
			(xy 38.880028 -392.107377) (xy 38.370764 -392.107377) (xy 38.370764 -392.538712) (xy 38.371191 -392.54878)
			(xy 38.378916 -392.567375) (xy 38.38575 -392.57478) (xy 39.003224 -393.192254) (xy 39.010866 -393.199168)
			(xy 39.030004 -393.206765) (xy 39.040308 -393.206986) (xy 39.124382 -393.204954) (xy 39.143178 -393.196318)
			(xy 39.15029 -393.188444) (xy 39.170976 -393.166288) (xy 39.216749 -393.126547) (xy 39.266922 -393.092531)
			(xy 39.320783 -393.064721) (xy 39.37757 -393.043514) (xy 39.436475 -393.029209) (xy 39.496663 -393.02201)
			(xy 39.526972 -393.021566) (xy 39.558809 -393.022065) (xy 39.621984 -393.030025) (xy 39.683671 -393.045811)
			(xy 39.742904 -393.069176) (xy 39.798755 -393.099755) (xy 39.850351 -393.137068) (xy 39.896884 -393.180532)
			(xy 39.937626 -393.229466) (xy 39.955216 -393.256008) (xy 39.960097 -393.263002) (xy 39.973505 -393.273529)
			(xy 39.989619 -393.279091) (xy 39.998142 -393.279376)
		)
		(stroke
			(width 0)
			(type solid)
		)
		(fill yes)
		(layer "F.Cu")
		(net "P1V8_CPU1_RT_1D")
	)
	(gr_poly
		(pts
			(xy 363.955584 -342.264492) (xy 363.955584 -339.201252) (xy 363.955584 -333.325978) (xy 363.397038 -332.767432)
			(xy 361.225084 -332.767432) (xy 349.01886 -332.767432) (xy 348.766892 -332.515464) (xy 348.766892 -330.85024)
			(xy 348.583504 -330.666852) (xy 347.817186 -330.666852) (xy 347.118686 -329.968352) (xy 347.118686 -328.596752)
			(xy 346.32646 -327.804526) (xy 316.140338 -327.804526) (xy 315.459872 -327.804526) (xy 314.346844 -328.917554)
			(xy 314.346844 -329.59802) (xy 314.34024 -329.60437) (xy 314.34024 -330.916788) (xy 314.524136 -331.100684)
			(xy 315.63056 -331.100684) (xy 315.889132 -330.842112) (xy 315.889132 -328.63155) (xy 316.093094 -328.427588)
			(xy 320.837814 -328.427588) (xy 321.017646 -328.60742) (xy 321.017646 -332.585314) (xy 320.817494 -332.785466)
			(xy 315.651388 -332.785466) (xy 315.595508 -332.841346) (xy 322.119752 -332.841346) (xy 322.119752 -331.537818)
			(xy 322.302378 -331.355192) (xy 323.796152 -331.355192) (xy 324.253352 -330.897992) (xy 324.253352 -328.575924)
			(xy 324.423278 -328.405998) (xy 329.193398 -328.405998) (xy 329.37323 -328.58583) (xy 329.37323 -332.60411)
			(xy 329.198986 -332.778354) (xy 323.996304 -332.778354) (xy 323.933312 -332.841346) (xy 330.477368 -332.841346)
			(xy 330.477368 -331.537818) (xy 330.658216 -331.357224) (xy 330.660248 -331.355192) (xy 332.153768 -331.355192)
			(xy 332.610968 -330.897992) (xy 332.610968 -328.553064) (xy 332.758034 -328.405998) (xy 337.551014 -328.405998)
			(xy 337.730846 -328.58583) (xy 337.730846 -332.58887) (xy 337.55584 -332.763876) (xy 332.329536 -332.763876)
			(xy 332.201266 -332.892146) (xy 338.808568 -332.892146) (xy 338.808568 -331.588618) (xy 338.815172 -331.582014)
			(xy 338.815172 -331.51953) (xy 338.975446 -331.359256) (xy 340.419182 -331.359256) (xy 340.96452 -330.813918)
			(xy 340.96452 -328.60361) (xy 341.111332 -328.456798) (xy 345.882214 -328.456798) (xy 346.062046 -328.63663)
			(xy 346.062046 -332.613762) (xy 345.861132 -332.814676) (xy 340.660736 -332.814676) (xy 340.061042 -333.41437)
			(xy 339.330792 -333.41437) (xy 338.808568 -332.892146) (xy 332.201266 -332.892146) (xy 331.729842 -333.36357)
			(xy 330.999592 -333.36357) (xy 330.477368 -332.841346) (xy 323.933312 -332.841346) (xy 323.395594 -333.379064)
			(xy 322.65747 -333.379064) (xy 322.119752 -332.841346) (xy 315.595508 -332.841346) (xy 315.051694 -333.38516)
			(xy 314.34024 -333.38516) (xy 314.34024 -334.614774) (xy 314.41644 -334.690974) (xy 315.39434 -334.690974)
			(xy 315.877702 -334.207612) (xy 317.432944 -334.207612) (xy 317.432944 -334.913478) (xy 317.099442 -335.24698)
			(xy 316.592712 -335.24698) (xy 316.535308 -335.304384) (xy 316.535308 -335.30794) (xy 316.487048 -335.3562)
			(xy 315.737748 -335.3562) (xy 315.686948 -335.407) (xy 315.686948 -335.5594) (xy 315.712348 -335.5848)
			(xy 316.248288 -335.5848) (xy 316.250828 -335.58226) (xy 316.538864 -335.58226) (xy 316.597284 -335.64068)
			(xy 316.597284 -335.76006) (xy 316.599316 -335.76514) (xy 316.599316 -336.607912) (xy 316.597284 -336.613246)
			(xy 316.597284 -336.65414) (xy 316.565788 -336.685636) (xy 316.565788 -336.68716) (xy 316.545722 -336.707226)
			(xy 315.710062 -336.707226) (xy 315.697108 -336.72018) (xy 315.697108 -336.90306) (xy 315.727334 -336.933286)
			(xy 316.55893 -336.933286) (xy 316.597284 -336.97164) (xy 316.597284 -337.03006) (xy 316.599316 -337.03514)
			(xy 316.599316 -337.221576) (xy 316.614302 -337.257644) (xy 316.63513 -337.278472) (xy 316.663578 -337.290156)
			(xy 316.675262 -337.286854) (xy 316.691448 -337.282087) (xy 316.724232 -337.274079) (xy 316.740794 -337.270852)
			(xy 316.769417 -337.265746) (xy 316.827293 -337.260147) (xy 316.856364 -337.259676) (xy 316.862714 -337.259676)
			(xy 316.895398 -337.260301) (xy 316.960384 -337.267423) (xy 317.024295 -337.281179) (xy 317.0555 -337.290918)
			(xy 317.06312 -337.293458) (xy 318.322706 -337.293458) (xy 318.370966 -337.245198) (xy 318.370966 -335.24698)
			(xy 318.688466 -334.92948) (xy 320.913506 -334.92948) (xy 320.95567 -334.971644) (xy 322.334382 -334.971644)
			(xy 322.445634 -334.860392) (xy 323.565774 -334.860392) (xy 324.223634 -334.202532) (xy 325.789544 -334.202532)
			(xy 325.789544 -334.902302) (xy 325.452486 -335.23936) (xy 324.948804 -335.23936) (xy 324.890892 -335.297272)
			(xy 324.890892 -335.300828) (xy 324.842632 -335.349088) (xy 324.093332 -335.349088) (xy 324.042532 -335.399888)
			(xy 324.042532 -335.552288) (xy 324.067424 -335.57718) (xy 324.60438 -335.57718) (xy 324.606412 -335.575148)
			(xy 324.894448 -335.575148) (xy 324.952868 -335.633568) (xy 324.952868 -335.752948) (xy 324.9549 -335.758028)
			(xy 324.9549 -336.6008) (xy 324.952868 -336.606134) (xy 324.952868 -336.647028) (xy 324.921372 -336.678524)
			(xy 324.921372 -336.680048) (xy 324.898766 -336.702654) (xy 324.063106 -336.702654) (xy 324.052692 -336.713068)
			(xy 324.052692 -336.895948) (xy 324.082664 -336.92592) (xy 324.91426 -336.92592) (xy 324.952868 -336.964528)
			(xy 324.952868 -337.022948) (xy 324.9549 -337.028028) (xy 324.9549 -337.214464) (xy 324.969886 -337.250532)
			(xy 324.990714 -337.27136) (xy 325.019162 -337.283044) (xy 325.030846 -337.279742) (xy 325.047033 -337.274977)
			(xy 325.079817 -337.266974) (xy 325.096378 -337.26374) (xy 325.125001 -337.258633) (xy 325.182877 -337.253033)
			(xy 325.211948 -337.252564) (xy 325.218298 -337.252564) (xy 325.250981 -337.253193) (xy 325.315965 -337.260323)
			(xy 325.379873 -337.274087) (xy 325.411084 -337.283806) (xy 325.418704 -337.286346) (xy 326.66686 -337.286346)
			(xy 326.735186 -337.21802) (xy 326.735186 -335.18856) (xy 327.027794 -334.895952) (xy 327.103232 -334.895952)
			(xy 330.751434 -334.895952) (xy 330.797154 -334.850232) (xy 331.924914 -334.850232) (xy 332.589124 -334.186022)
			(xy 334.144874 -334.186022) (xy 334.144874 -334.819498) (xy 334.144874 -334.885792) (xy 333.797148 -335.233518)
			(xy 333.297784 -335.233518) (xy 333.248508 -335.282794) (xy 333.248508 -335.28635) (xy 333.200248 -335.33461)
			(xy 332.450948 -335.33461) (xy 332.400148 -335.38541) (xy 332.400148 -335.53781) (xy 332.425548 -335.56321)
			(xy 332.961488 -335.56321) (xy 332.964028 -335.56067) (xy 333.252064 -335.56067) (xy 333.310484 -335.61909)
			(xy 333.310484 -335.73847) (xy 333.312516 -335.74355) (xy 333.312516 -336.586322) (xy 333.310484 -336.591656)
			(xy 333.310484 -336.63255) (xy 333.278988 -336.664046) (xy 333.278988 -336.66557) (xy 333.257144 -336.687414)
			(xy 332.421484 -336.687414) (xy 332.410308 -336.69859) (xy 332.410308 -336.88147) (xy 332.435454 -336.906616)
			(xy 333.26705 -336.906616) (xy 333.310484 -336.95005) (xy 333.310484 -337.00847) (xy 333.312516 -337.01355)
			(xy 333.312516 -337.199986) (xy 333.327502 -337.236054) (xy 333.34833 -337.256882) (xy 333.376778 -337.268566)
			(xy 333.388462 -337.265264) (xy 333.404648 -337.260497) (xy 333.437432 -337.252489) (xy 333.453994 -337.249262)
			(xy 333.482617 -337.244156) (xy 333.540493 -337.238557) (xy 333.569564 -337.238086) (xy 333.575914 -337.238086)
			(xy 333.608598 -337.238711) (xy 333.673584 -337.245833) (xy 333.737495 -337.259589) (xy 333.7687 -337.269328)
			(xy 333.77632 -337.271868) (xy 335.030318 -337.271868) (xy 335.084166 -337.21802) (xy 335.084166 -335.21142)
			(xy 335.399634 -334.895952) (xy 335.421224 -334.895952) (xy 339.057234 -334.895952) (xy 339.062314 -334.890872)
			(xy 340.221824 -334.890872) (xy 340.877144 -334.235552) (xy 342.476074 -334.235552) (xy 342.476074 -334.92313)
			(xy 342.476074 -334.944212) (xy 342.139778 -335.280508) (xy 342.11133 -335.280508) (xy 341.632794 -335.280508)
			(xy 341.579708 -335.333594) (xy 341.579708 -335.33715) (xy 341.531448 -335.38541) (xy 340.782148 -335.38541)
			(xy 340.731348 -335.43621) (xy 340.731348 -335.58861) (xy 340.75624 -335.613502) (xy 341.293196 -335.613502)
			(xy 341.295228 -335.61147) (xy 341.583264 -335.61147) (xy 341.641684 -335.66989) (xy 341.641684 -335.78927)
			(xy 341.643716 -335.79435) (xy 341.643716 -336.637122) (xy 341.641684 -336.642456) (xy 341.641684 -336.68335)
			(xy 341.610188 -336.714846) (xy 341.610188 -336.71637) (xy 341.587328 -336.73923) (xy 340.751668 -336.73923)
			(xy 340.741508 -336.74939) (xy 340.741508 -336.93227) (xy 340.768432 -336.959194) (xy 341.600028 -336.959194)
			(xy 341.641684 -337.00085) (xy 341.641684 -337.05927) (xy 341.643716 -337.06435) (xy 341.643716 -337.250786)
			(xy 341.658702 -337.286854) (xy 341.67953 -337.307682) (xy 341.707978 -337.319366) (xy 341.719662 -337.316064)
			(xy 341.735848 -337.311297) (xy 341.768632 -337.303289) (xy 341.785194 -337.300062) (xy 341.813817 -337.294956)
			(xy 341.871693 -337.289357) (xy 341.900764 -337.288886) (xy 341.907114 -337.288886) (xy 341.939798 -337.289511)
			(xy 342.004784 -337.296633) (xy 342.068695 -337.310389) (xy 342.0999 -337.320128) (xy 342.10752 -337.322668)
			(xy 343.379806 -337.322668) (xy 343.428066 -337.274408) (xy 343.428066 -335.26222) (xy 343.720674 -334.969612)
			(xy 343.770204 -334.969612) (xy 348.781624 -334.969612) (xy 348.923864 -334.827372) (xy 348.923864 -333.544672)
			(xy 349.208344 -333.260192) (xy 354.232464 -333.260192) (xy 354.369624 -333.397352) (xy 354.369624 -337.483958)
			(xy 354.14331 -337.710272) (xy 348.979744 -337.710272) (xy 348.365064 -338.324952) (xy 347.745304 -338.324952)
			(xy 347.689424 -338.380832) (xy 347.689424 -339.777832) (xy 347.735144 -339.823552) (xy 348.288864 -339.823552)
			(xy 348.967044 -339.145372) (xy 350.765364 -339.145372) (xy 350.765364 -339.851492) (xy 350.397064 -340.219792)
			(xy 349.669862 -340.219792) (xy 349.594424 -340.29523) (xy 348.86265 -340.29523) (xy 348.809564 -340.348316)
			(xy 348.809564 -340.473284) (xy 348.86011 -340.52383) (xy 349.649542 -340.52383) (xy 349.784416 -340.52383)
			(xy 349.884746 -340.62416) (xy 349.884746 -341.61222) (xy 349.849948 -341.647018) (xy 349.663258 -341.647018)
			(xy 348.919038 -341.647018) (xy 348.890844 -341.675212) (xy 348.890844 -341.842852) (xy 348.918022 -341.87003)
			(xy 349.690182 -341.87003) (xy 349.858076 -341.87003) (xy 349.887286 -341.89924) (xy 349.887286 -342.203532)
			(xy 349.915226 -342.231472) (xy 351.639124 -342.231472) (xy 351.679764 -342.190832) (xy 351.679764 -340.257892)
			(xy 351.679764 -340.228682) (xy 352.041714 -339.866732) (xy 352.070924 -339.866732) (xy 356.797864 -339.866732)
			(xy 357.402384 -340.471252) (xy 357.402384 -343.222072) (xy 357.730044 -343.549732) (xy 362.670344 -343.549732)
		)
		(stroke
			(width 0)
			(type solid)
		)
		(fill yes)
		(layer "F.Cu")
		(net "GND")
	)
	(gr_poly
		(pts
			(xy 22.350222 -351.339658) (xy 22.350222 -350.034098) (xy 23.31466 -349.06966) (xy 23.31466 -346.64396)
			(xy 23.545292 -346.413328) (xy 23.91283 -346.413328) (xy 25.532588 -346.413328) (xy 26.01214 -345.933776)
			(xy 27.673554 -345.933776) (xy 27.687778 -345.948) (xy 27.687778 -346.634054) (xy 27.316176 -347.005656)
			(xy 26.744168 -347.005656) (xy 26.667968 -347.081856) (xy 25.908508 -347.081856) (xy 25.895808 -347.094556)
			(xy 25.895808 -347.297756) (xy 25.908508 -347.310456) (xy 26.667968 -347.310456) (xy 26.849324 -347.491812)
			(xy 26.849324 -348.25051) (xy 26.667968 -348.431866) (xy 25.908508 -348.431866) (xy 25.908254 -348.43212)
			(xy 25.852882 -348.43212) (xy 25.824942 -348.46006) (xy 25.824942 -348.621096) (xy 25.857962 -348.654116)
			(xy 25.902158 -348.654116) (xy 25.908508 -348.660466) (xy 26.667714 -348.660466) (xy 26.836624 -348.829376)
			(xy 26.836624 -348.961456) (xy 26.862024 -348.986856) (xy 28.589224 -348.986856) (xy 28.614624 -348.961456)
			(xy 28.614624 -346.980256) (xy 28.96108 -346.6338) (xy 31.737046 -346.6338) (xy 31.847536 -346.74429)
			(xy 32.579818 -346.74429) (xy 32.72155 -346.602558) (xy 33.67278 -346.602558) (xy 34.34842 -345.926918)
			(xy 35.95116 -345.926918) (xy 35.95116 -346.653104) (xy 35.614864 -346.9894) (xy 35.052 -346.9894)
			(xy 34.957766 -347.083634) (xy 34.136584 -347.083634) (xy 34.095182 -347.125036) (xy 34.095182 -347.277436)
			(xy 34.126932 -347.309186) (xy 34.990786 -347.309186) (xy 35.1028 -347.4212) (xy 35.1028 -348.3864)
			(xy 35.054286 -348.434914) (xy 34.136076 -348.434914) (xy 34.105342 -348.465648) (xy 34.105342 -348.621096)
			(xy 34.138362 -348.654116) (xy 35.040316 -348.654116) (xy 35.10534 -348.71914) (xy 35.10534 -348.976442)
			(xy 35.12312 -348.994222) (xy 35.149028 -348.988888) (xy 35.177651 -348.983783) (xy 35.235527 -348.978187)
			(xy 35.264598 -348.977712) (xy 35.270948 -348.977712) (xy 35.303632 -348.978339) (xy 35.368616 -348.985465)
			(xy 35.432526 -348.999224) (xy 35.463734 -349.008954) (xy 35.471354 -349.011494) (xy 36.764468 -349.011494)
			(xy 36.800536 -348.996508) (xy 36.857432 -348.939612) (xy 36.857432 -347.529912) (xy 36.856162 -347.528642)
			(xy 36.856162 -347.055186) (xy 37.24275 -346.668598) (xy 40.796718 -346.668598) (xy 41.050718 -346.414598)
			(xy 42.193718 -346.414598) (xy 42.683938 -345.924378) (xy 44.24934 -345.924378) (xy 44.24934 -346.64396)
			(xy 43.9039 -346.9894) (xy 43.282362 -346.9894) (xy 43.249342 -347.02242) (xy 43.249342 -347.025976)
			(xy 43.192954 -347.082364) (xy 42.443654 -347.082364) (xy 42.400982 -347.125036) (xy 42.400982 -347.277436)
			(xy 42.4307 -347.307154) (xy 43.259502 -347.307154) (xy 43.342814 -347.307154) (xy 43.41114 -347.37548)
			(xy 43.41114 -348.3737) (xy 43.35145 -348.43339) (xy 43.251628 -348.43339) (xy 42.458132 -348.43339)
			(xy 42.411142 -348.48038) (xy 42.411142 -348.621096) (xy 42.444162 -348.654116) (xy 43.275758 -348.654116)
			(xy 43.320716 -348.654116) (xy 43.4086 -348.742) (xy 43.4086 -348.968314) (xy 43.433492 -348.993206)
			(xy 43.454828 -348.988888) (xy 43.483451 -348.983783) (xy 43.541327 -348.978187) (xy 43.570398 -348.977712)
			(xy 43.576748 -348.977712) (xy 43.609432 -348.978339) (xy 43.674416 -348.985465) (xy 43.738326 -348.999224)
			(xy 43.769534 -349.008954) (xy 43.777154 -349.011494) (xy 45.070268 -349.011494) (xy 45.106336 -348.996508)
			(xy 45.136054 -348.96679) (xy 45.136054 -346.935298) (xy 45.372274 -346.699078) (xy 45.437552 -346.6338)
			(xy 47.9298 -346.6338) (xy 47.995078 -346.699078) (xy 49.06899 -346.699078) (xy 49.16297 -346.605098)
			(xy 50.282094 -346.605098) (xy 50.962814 -345.924378) (xy 52.62118 -345.924378) (xy 52.62118 -346.64142)
			(xy 52.2732 -346.9894) (xy 51.638962 -346.9894) (xy 51.605942 -347.02242) (xy 51.605942 -347.025976)
			(xy 51.548538 -347.08338) (xy 50.799238 -347.08338) (xy 50.757582 -347.125036) (xy 50.757582 -347.277436)
			(xy 50.786792 -347.306646) (xy 51.615848 -347.306646) (xy 51.686206 -347.306646) (xy 51.77028 -347.39072)
			(xy 51.77028 -348.37878) (xy 51.713384 -348.435676) (xy 51.605942 -348.435676) (xy 50.816764 -348.435676)
			(xy 50.767742 -348.484698) (xy 50.767742 -348.621096) (xy 50.800762 -348.654116) (xy 51.632358 -348.654116)
			(xy 51.702716 -348.654116) (xy 51.7652 -348.7166) (xy 51.7652 -348.94266) (xy 51.811428 -348.988888)
			(xy 51.840051 -348.983783) (xy 51.897927 -348.978187) (xy 51.926998 -348.977712) (xy 51.933348 -348.977712)
			(xy 51.966032 -348.978339) (xy 52.031016 -348.985465) (xy 52.094926 -348.999224) (xy 52.126134 -349.008954)
			(xy 52.133754 -349.011494) (xy 53.426868 -349.011494) (xy 53.462936 -348.996508) (xy 53.519832 -348.939612)
			(xy 53.519832 -346.987622) (xy 53.815996 -346.691458) (xy 53.873654 -346.6338) (xy 56.228742 -346.6338)
			(xy 56.2864 -346.691458) (xy 57.712102 -346.691458) (xy 57.813194 -346.590366) (xy 58.58129 -346.590366)
			(xy 59.247278 -345.924378) (xy 60.96 -345.924378) (xy 60.96 -346.6592) (xy 60.6298 -346.9894) (xy 59.950096 -346.9894)
			(xy 59.853576 -347.08592) (xy 59.154568 -347.08592) (xy 59.125358 -347.11513) (xy 59.125358 -347.285818)
			(xy 59.147202 -347.307662) (xy 59.982862 -347.307662) (xy 60.0964 -347.4212) (xy 60.0964 -348.3102)
			(xy 60.0964 -348.3991) (xy 60.062364 -348.433136) (xy 60.049156 -348.433136) (xy 60.036202 -348.433136)
			(xy 60.024264 -348.433136) (xy 59.137042 -348.433136) (xy 59.098942 -348.471236) (xy 59.098942 -348.621096)
			(xy 59.131962 -348.654116) (xy 59.963558 -348.654116) (xy 60.059316 -348.654116) (xy 60.0964 -348.6912)
			(xy 60.0964 -348.968314) (xy 60.121292 -348.993206) (xy 60.142628 -348.988888) (xy 60.171251 -348.983783)
			(xy 60.229127 -348.978187) (xy 60.258198 -348.977712) (xy 60.264548 -348.977712) (xy 60.297232 -348.978339)
			(xy 60.362216 -348.985465) (xy 60.426126 -348.999224) (xy 60.457334 -349.008954) (xy 60.464954 -349.011494)
			(xy 61.758068 -349.011494) (xy 61.794136 -348.996508) (xy 61.851032 -348.939612) (xy 61.851032 -346.970858)
			(xy 62.090554 -346.731336) (xy 62.18809 -346.6338) (xy 65.0494 -346.6338) (xy 65.146936 -346.731336)
			(xy 67.72402 -346.731336) (xy 68.725542 -347.732858) (xy 71.463662 -347.732858) (xy 73.147682 -346.048838)
			(xy 73.147682 -343.534238) (xy 72.322182 -342.708738) (xy 72.322182 -342.464898) (xy 70.813422 -340.956138)
			(xy 66.845942 -340.956138) (xy 66.556382 -340.666578) (xy 66.556382 -339.77453) (xy 66.439542 -339.65769)
			(xy 59.628278 -339.65769) (xy 59.282838 -339.31225) (xy 59.282838 -337.326478) (xy 59.529218 -337.080098)
			(xy 64.234822 -337.080098) (xy 64.269112 -337.045808) (xy 64.269112 -335.493868) (xy 64.250062 -335.474818)
			(xy 51.309778 -335.474818) (xy 51.152298 -335.632298) (xy 51.152298 -336.950558) (xy 51.281838 -337.080098)
			(xy 56.140858 -337.080098) (xy 56.336438 -337.275678) (xy 56.336438 -339.325458) (xy 56.004206 -339.65769)
			(xy 18.777966 -339.65769) (xy 18.52803 -339.65769) (xy 18.40484 -339.78088) (xy 18.40484 -344.580972)
			(xy 23.892002 -344.580972) (xy 23.892002 -343.277444) (xy 24.074628 -343.094818) (xy 25.568402 -343.094818)
			(xy 26.047954 -342.615266) (xy 26.047954 -340.330282) (xy 26.276046 -340.10219) (xy 31.214314 -340.10219)
			(xy 31.291022 -340.178898) (xy 31.291022 -344.424254) (xy 31.206948 -344.508328) (xy 25.548082 -344.508328)
			(xy 25.475438 -344.580972) (xy 32.172402 -344.580972) (xy 32.172402 -343.277444) (xy 32.355028 -343.094818)
			(xy 33.848802 -343.094818) (xy 34.328354 -342.615266) (xy 34.328354 -340.352888) (xy 34.535618 -340.145624)
			(xy 34.585402 -340.145624) (xy 34.628836 -340.10219) (xy 39.359078 -340.10219) (xy 39.43985 -340.182962)
			(xy 39.43985 -340.219284) (xy 39.553642 -340.333076) (xy 39.553642 -344.33891) (xy 39.388034 -344.504518)
			(xy 33.810702 -344.504518) (xy 33.744662 -344.570558) (xy 33.744662 -344.580972) (xy 40.478202 -344.580972)
			(xy 40.478202 -343.277444) (xy 40.660828 -343.094818) (xy 42.154602 -343.094818) (xy 42.634154 -342.615266)
			(xy 42.634154 -340.352888) (xy 42.841418 -340.145624) (xy 42.942002 -340.145624) (xy 42.985436 -340.10219)
			(xy 47.664878 -340.10219) (xy 47.77105 -340.208362) (xy 47.77105 -340.244684) (xy 47.859442 -340.333076)
			(xy 47.859442 -344.358214) (xy 47.714154 -344.503502) (xy 42.107358 -344.503502) (xy 42.050462 -344.560398)
			(xy 42.050462 -344.580972) (xy 48.834802 -344.580972) (xy 48.834802 -343.277444) (xy 49.017428 -343.094818)
			(xy 50.511202 -343.094818) (xy 50.990754 -342.615266) (xy 50.990754 -340.352888) (xy 51.198018 -340.145624)
			(xy 51.298602 -340.145624) (xy 51.338988 -340.105238) (xy 55.698644 -340.105238) (xy 55.698898 -340.105746)
			(xy 55.974234 -340.105746) (xy 56.021224 -340.152736) (xy 56.035702 -340.152736) (xy 56.216042 -340.333076)
			(xy 56.216042 -344.31351) (xy 56.025034 -344.504518) (xy 50.473102 -344.504518) (xy 50.41265 -344.56497)
			(xy 50.41265 -344.5764) (xy 57.166002 -344.5764) (xy 57.166002 -343.431114) (xy 57.29224 -343.304876)
			(xy 57.29224 -343.285064) (xy 57.475374 -343.10193) (xy 57.495186 -343.10193) (xy 57.548018 -343.049098)
			(xy 58.888122 -343.049098) (xy 59.321954 -342.615266) (xy 59.321954 -340.352888) (xy 59.428126 -340.246716)
			(xy 59.428126 -340.2203) (xy 59.567064 -340.081362) (xy 64.30645 -340.081362) (xy 64.381126 -340.156038)
			(xy 64.381126 -340.157562) (xy 64.431926 -340.208362) (xy 64.431926 -340.21776) (xy 64.547242 -340.333076)
			(xy 64.547242 -344.309954) (xy 64.357758 -344.499438) (xy 58.738516 -344.499438) (xy 58.738516 -344.919046)
			(xy 58.54573 -345.111832) (xy 57.814972 -345.111832) (xy 57.768998 -345.065858) (xy 57.65546 -345.065858)
			(xy 57.166002 -344.5764) (xy 50.41265 -344.5764) (xy 50.41265 -344.95359) (xy 50.249582 -345.116658)
			(xy 49.370488 -345.116658) (xy 48.834802 -344.580972) (xy 42.050462 -344.580972) (xy 42.050462 -344.928698)
			(xy 41.865042 -345.114118) (xy 41.011348 -345.114118) (xy 40.478202 -344.580972) (xy 33.744662 -344.580972)
			(xy 33.744662 -344.936318) (xy 33.564322 -345.116658) (xy 32.708088 -345.116658) (xy 32.172402 -344.580972)
			(xy 25.475438 -344.580972) (xy 25.471882 -344.584528) (xy 25.471882 -344.908378) (xy 25.263602 -345.116658)
			(xy 24.427688 -345.116658) (xy 23.892002 -344.580972) (xy 18.40484 -344.580972) (xy 18.40484 -350.88322)
			(xy 19.01444 -351.49282) (xy 22.19706 -351.49282)
		)
		(stroke
			(width 0)
			(type solid)
		)
		(fill yes)
		(layer "F.Cu")
		(net "GND")
	)
	(gr_poly
		(pts
			(xy 269.054072 -350.61652) (xy 269.054072 -350.30283) (xy 270.389604 -348.967044) (xy 270.389604 -346.553536)
			(xy 270.534638 -346.408502) (xy 272.35404 -346.408502) (xy 272.84045 -345.922092) (xy 274.496784 -345.922092)
			(xy 274.496784 -346.677488) (xy 274.185634 -346.988638) (xy 273.51355 -346.988638) (xy 273.484594 -347.017594)
			(xy 273.484594 -347.02115) (xy 273.42465 -347.081094) (xy 272.71091 -347.081094) (xy 272.70329 -347.088714)
			(xy 272.70329 -347.293692) (xy 272.710148 -347.30055) (xy 273.561302 -347.30055) (xy 273.641312 -347.38056)
			(xy 273.641312 -348.38894) (xy 273.59864 -348.431612) (xy 272.669 -348.431612) (xy 272.646394 -348.454218)
			(xy 272.646394 -348.61627) (xy 272.679414 -348.64929) (xy 273.609562 -348.64929) (xy 273.648932 -348.68866)
			(xy 273.648932 -348.961456) (xy 273.674586 -348.98711) (xy 273.69008 -348.984062) (xy 273.718703 -348.978955)
			(xy 273.776579 -348.973355) (xy 273.80565 -348.972886) (xy 273.812 -348.972886) (xy 273.844683 -348.973515)
			(xy 273.909667 -348.980646) (xy 273.973574 -348.99441) (xy 274.004786 -349.004128) (xy 274.012406 -349.006668)
			(xy 275.30552 -349.006668) (xy 275.341588 -348.991682) (xy 275.398484 -348.934786) (xy 275.398484 -347.525086)
			(xy 275.397976 -347.524578) (xy 275.397976 -347.029532) (xy 275.804376 -346.623132) (xy 279.40381 -346.623132)
			(xy 279.42921 -346.597732) (xy 280.494232 -346.597732) (xy 281.169872 -345.922092) (xy 282.761944 -345.922092)
			(xy 282.785312 -345.94546) (xy 282.785312 -346.62364) (xy 282.431744 -346.977208) (xy 281.80538 -346.977208)
			(xy 281.764994 -347.017594) (xy 281.764994 -347.02115) (xy 281.709622 -347.076522) (xy 280.960322 -347.076522)
			(xy 280.916634 -347.12021) (xy 280.916634 -347.27261) (xy 280.947114 -347.30309) (xy 281.839162 -347.30309)
			(xy 281.936952 -347.40088) (xy 281.936952 -348.37878) (xy 281.88666 -348.429072) (xy 280.946098 -348.429072)
			(xy 280.926794 -348.448376) (xy 280.926794 -348.61627) (xy 280.959814 -348.64929) (xy 281.879802 -348.64929)
			(xy 281.924252 -348.69374) (xy 281.924252 -348.974156) (xy 281.940508 -348.990412) (xy 281.97048 -348.984062)
			(xy 281.999103 -348.978955) (xy 282.056979 -348.973355) (xy 282.08605 -348.972886) (xy 282.0924 -348.972886)
			(xy 282.125083 -348.973515) (xy 282.190067 -348.980646) (xy 282.253974 -348.99441) (xy 282.285186 -349.004128)
			(xy 282.292806 -349.006668) (xy 283.58592 -349.006668) (xy 283.621988 -348.991682) (xy 283.678884 -348.934786)
			(xy 283.678884 -347.525086) (xy 283.677614 -347.523816) (xy 283.677614 -346.998798) (xy 284.034992 -346.64142)
			(xy 286.30372 -346.64142) (xy 286.364172 -346.701872) (xy 287.58007 -346.701872) (xy 287.701482 -346.58046)
			(xy 288.844482 -346.58046) (xy 289.50539 -345.919552) (xy 291.042344 -345.919552) (xy 291.080952 -345.95816)
			(xy 291.080952 -346.64142) (xy 290.752784 -346.969588) (xy 290.1188 -346.969588) (xy 290.070794 -347.017594)
			(xy 290.070794 -347.02115) (xy 290.014914 -347.07703) (xy 289.265614 -347.07703) (xy 289.222434 -347.12021)
			(xy 289.222434 -347.27261) (xy 289.247834 -347.29801) (xy 289.783774 -347.29801) (xy 289.786314 -347.29547)
			(xy 290.147502 -347.29547) (xy 290.232592 -347.38056) (xy 290.232592 -348.37116) (xy 290.174172 -348.42958)
			(xy 289.260534 -348.42958) (xy 289.232594 -348.45752) (xy 289.232594 -348.61627) (xy 289.265614 -348.64929)
			(xy 290.198302 -348.64929) (xy 290.217352 -348.66834) (xy 290.217352 -348.925134) (xy 290.27628 -348.984062)
			(xy 290.304903 -348.978955) (xy 290.362779 -348.973355) (xy 290.39185 -348.972886) (xy 290.3982 -348.972886)
			(xy 290.430883 -348.973515) (xy 290.495867 -348.980646) (xy 290.559774 -348.99441) (xy 290.590986 -349.004128)
			(xy 290.598606 -349.006668) (xy 291.89172 -349.006668) (xy 291.927788 -348.991682) (xy 291.957506 -348.961964)
			(xy 291.957506 -346.930472) (xy 292.238938 -346.64904) (xy 294.6019 -346.64904) (xy 294.702992 -346.750132)
			(xy 295.834562 -346.750132) (xy 295.984422 -346.600272) (xy 297.103546 -346.600272) (xy 297.784266 -345.919552)
			(xy 299.406564 -345.919552) (xy 299.437552 -345.95054) (xy 299.437552 -346.66174) (xy 299.114464 -346.984828)
			(xy 298.46016 -346.984828) (xy 298.427394 -347.017594) (xy 298.427394 -347.02115) (xy 298.369482 -347.079062)
			(xy 297.620182 -347.079062) (xy 297.579034 -347.12021) (xy 297.579034 -347.27261) (xy 297.610022 -347.303598)
			(xy 298.52747 -347.303598) (xy 298.581572 -347.3577) (xy 298.581572 -348.40164) (xy 298.553632 -348.42958)
			(xy 297.611292 -348.42958) (xy 297.589194 -348.451678) (xy 297.589194 -348.61627) (xy 297.622214 -348.64929)
			(xy 298.539662 -348.64929) (xy 298.586652 -348.69628) (xy 298.586652 -348.937834) (xy 298.63288 -348.984062)
			(xy 298.661503 -348.978955) (xy 298.719379 -348.973355) (xy 298.74845 -348.972886) (xy 298.7548 -348.972886)
			(xy 298.787483 -348.973515) (xy 298.852467 -348.980646) (xy 298.916374 -348.99441) (xy 298.947586 -349.004128)
			(xy 298.955206 -349.006668) (xy 300.24832 -349.006668) (xy 300.284388 -348.991682) (xy 300.341284 -348.934786)
			(xy 300.341284 -346.921328) (xy 300.626272 -346.63634) (xy 302.96104 -346.63634) (xy 303.006252 -346.681552)
			(xy 304.63363 -346.681552) (xy 304.75555 -346.559632) (xy 305.42865 -346.559632) (xy 306.06873 -345.919552)
			(xy 307.756052 -345.919552) (xy 307.756052 -346.66428) (xy 307.441092 -346.97924) (xy 306.776882 -346.97924)
			(xy 306.67833 -347.077792) (xy 305.97094 -347.077792) (xy 305.94681 -347.101922) (xy 305.94681 -347.280992)
			(xy 305.969162 -347.303344) (xy 306.805076 -347.303344) (xy 306.930552 -347.42882) (xy 306.930552 -348.3737)
			(xy 306.874418 -348.429834) (xy 305.954938 -348.429834) (xy 305.920394 -348.464378) (xy 305.920394 -348.61627)
			(xy 305.953414 -348.64929) (xy 306.888642 -348.64929) (xy 306.920392 -348.68104) (xy 306.920392 -348.96933)
			(xy 306.940204 -348.989142) (xy 306.96408 -348.984062) (xy 306.992703 -348.978955) (xy 307.050579 -348.973355)
			(xy 307.07965 -348.972886) (xy 307.086 -348.972886) (xy 307.118683 -348.973515) (xy 307.183667 -348.980646)
			(xy 307.247574 -348.99441) (xy 307.278786 -349.004128) (xy 307.286406 -349.006668) (xy 308.57952 -349.006668)
			(xy 308.615588 -348.991682) (xy 308.672484 -348.934786) (xy 308.672484 -346.966032) (xy 309.007256 -346.63126)
			(xy 311.38114 -346.63126) (xy 311.428892 -346.679012) (xy 315.232796 -346.679012) (xy 316.225936 -347.672152)
			(xy 316.871604 -347.672152) (xy 319.414144 -347.672152) (xy 320.958464 -346.127832) (xy 320.958464 -343.435432)
			(xy 318.641984 -341.118952) (xy 314.771786 -341.118952) (xy 314.23483 -340.581996) (xy 314.23483 -339.786214)
			(xy 314.10148 -339.652864) (xy 306.44973 -339.652864) (xy 305.94935 -339.152484) (xy 305.94935 -337.476592)
			(xy 306.35067 -337.075272) (xy 311.07253 -337.075272) (xy 311.28589 -336.861912) (xy 311.28589 -335.619852)
			(xy 311.13603 -335.469992) (xy 298.13123 -335.469992) (xy 297.97375 -335.627472) (xy 297.97375 -336.945732)
			(xy 298.10329 -337.075272) (xy 302.96231 -337.075272) (xy 303.28997 -337.402932) (xy 303.28997 -339.297772)
			(xy 302.934878 -339.652864) (xy 261.610348 -339.652864) (xy 261.116572 -340.14664) (xy 261.116572 -344.576146)
			(xy 270.713454 -344.576146) (xy 270.713454 -343.272618) (xy 270.89608 -343.089992) (xy 272.389854 -343.089992)
			(xy 272.869406 -342.61044) (xy 272.869406 -340.325456) (xy 273.097498 -340.097364) (xy 277.877778 -340.097364)
			(xy 277.979378 -340.198964) (xy 277.979378 -340.212934) (xy 278.094694 -340.32825) (xy 278.094694 -344.306906)
			(xy 277.904448 -344.497152) (xy 272.37055 -344.497152) (xy 272.291556 -344.576146) (xy 278.993854 -344.576146)
			(xy 278.993854 -343.272618) (xy 279.17648 -343.089992) (xy 280.670254 -343.089992) (xy 281.149806 -342.61044)
			(xy 281.149806 -340.348062) (xy 281.35707 -340.140798) (xy 281.406854 -340.140798) (xy 281.450288 -340.097364)
			(xy 286.18053 -340.097364) (xy 286.261302 -340.178136) (xy 286.261302 -340.214458) (xy 286.375094 -340.32825)
			(xy 286.375094 -344.30843) (xy 286.183832 -344.499692) (xy 280.69159 -344.499692) (xy 280.615136 -344.576146)
			(xy 287.299654 -344.576146) (xy 287.299654 -343.272618) (xy 287.48228 -343.089992) (xy 288.976054 -343.089992)
			(xy 289.455606 -342.61044) (xy 289.455606 -340.348062) (xy 289.66287 -340.140798) (xy 289.763454 -340.140798)
			(xy 289.806888 -340.097364) (xy 294.48633 -340.097364) (xy 294.592502 -340.203536) (xy 294.592502 -340.239858)
			(xy 294.680894 -340.32825) (xy 294.680894 -344.353388) (xy 294.535606 -344.498676) (xy 289.029394 -344.498676)
			(xy 289.03041 -344.499692) (xy 288.953956 -344.576146) (xy 295.656254 -344.576146) (xy 295.656254 -343.272618)
			(xy 295.83888 -343.089992) (xy 297.332654 -343.089992) (xy 297.812206 -342.61044) (xy 297.812206 -340.348062)
			(xy 298.01947 -340.140798) (xy 298.120054 -340.140798) (xy 298.16044 -340.100412) (xy 302.520096 -340.100412)
			(xy 302.52035 -340.10092) (xy 302.795686 -340.10092) (xy 302.842676 -340.14791) (xy 302.857154 -340.14791)
			(xy 303.037494 -340.32825) (xy 303.037494 -344.368628) (xy 302.90643 -344.499692) (xy 297.228768 -344.499692)
			(xy 297.228768 -344.571574) (xy 303.987454 -344.571574) (xy 303.987454 -343.426288) (xy 304.113692 -343.30005)
			(xy 304.113692 -343.280238) (xy 304.296826 -343.097104) (xy 304.316638 -343.097104) (xy 304.36947 -343.044272)
			(xy 305.709574 -343.044272) (xy 306.143406 -342.61044) (xy 306.143406 -340.348062) (xy 306.249578 -340.24189)
			(xy 306.249578 -340.215474) (xy 306.388516 -340.076536) (xy 311.127902 -340.076536) (xy 311.202578 -340.151212)
			(xy 311.202578 -340.152736) (xy 311.253378 -340.203536) (xy 311.253378 -340.212934) (xy 311.368694 -340.32825)
			(xy 311.368694 -344.345768) (xy 311.21985 -344.494612) (xy 305.559968 -344.494612) (xy 305.559968 -344.91422)
			(xy 305.367182 -345.107006) (xy 304.636424 -345.107006) (xy 304.59045 -345.061032) (xy 304.476912 -345.061032)
			(xy 303.987454 -344.571574) (xy 297.228768 -344.571574) (xy 297.228768 -344.91422) (xy 297.035982 -345.107006)
			(xy 296.305224 -345.107006) (xy 296.296588 -345.09837) (xy 296.178478 -345.09837) (xy 295.656254 -344.576146)
			(xy 288.953956 -344.576146) (xy 288.91357 -344.616532) (xy 288.91357 -344.989912) (xy 288.79419 -345.109292)
			(xy 287.8328 -345.109292) (xy 287.299654 -344.576146) (xy 280.615136 -344.576146) (xy 280.57983 -344.611452)
			(xy 280.57983 -344.969592) (xy 280.44013 -345.109292) (xy 279.527 -345.109292) (xy 278.993854 -344.576146)
			(xy 272.291556 -344.576146) (xy 272.27911 -344.588592) (xy 272.27911 -344.936572) (xy 272.10639 -345.109292)
			(xy 271.2466 -345.109292) (xy 270.713454 -344.576146) (xy 261.116572 -344.576146) (xy 261.116572 -347.08338)
			(xy 265.030712 -350.99752) (xy 268.673072 -350.99752)
		)
		(stroke
			(width 0)
			(type solid)
		)
		(fill yes)
		(layer "F.Cu")
		(net "GND")
	)
	(gr_poly
		(pts
			(xy 303.494948 -335.009744) (xy 303.505013 -335.009311) (xy 303.5236 -335.001578) (xy 303.531016 -334.994758)
			(xy 303.84496 -334.680814) (xy 303.851797 -334.673413) (xy 303.859507 -334.654814) (xy 303.859946 -334.644746)
			(xy 303.859946 -325.36257) (xy 303.8593 -325.350884) (xy 303.848832 -325.32998) (xy 303.83988 -325.322438)
			(xy 303.804041 -325.29439) (xy 303.73711 -325.232717) (xy 303.676115 -325.165167) (xy 303.62157 -325.09231)
			(xy 303.573933 -325.01476) (xy 303.533606 -324.933169) (xy 303.500929 -324.848224) (xy 303.476176 -324.760642)
			(xy 303.459557 -324.671159) (xy 303.451211 -324.58053) (xy 303.451209 -324.489517) (xy 303.459551 -324.398887)
			(xy 303.476166 -324.309403) (xy 303.500914 -324.22182) (xy 303.533587 -324.136874) (xy 303.57391 -324.055281)
			(xy 303.621544 -323.977728) (xy 303.676086 -323.904869) (xy 303.737078 -323.837316) (xy 303.804006 -323.77564)
			(xy 303.83988 -323.747638) (xy 303.84883 -323.740097) (xy 303.859289 -323.71919) (xy 303.859946 -323.707506)
			(xy 303.859946 -322.003674) (xy 303.859517 -321.993607) (xy 303.85179 -321.975015) (xy 303.84496 -321.967606)
			(xy 303.362614 -321.48526) (xy 303.355214 -321.478421) (xy 303.336615 -321.470708) (xy 303.326546 -321.470274)
			(xy 269.58925 -321.470274) (xy 269.579183 -321.470706) (xy 269.56059 -321.47843) (xy 269.553182 -321.48526)
			(xy 269.101316 -321.937126) (xy 269.094472 -321.944525) (xy 269.086744 -321.963123) (xy 269.08633 -321.973194)
			(xy 269.08633 -323.731128) (xy 269.08694 -323.742413) (xy 269.096569 -323.762829) (xy 269.104872 -323.770498)
			(xy 269.138271 -323.798644) (xy 269.200524 -323.859916) (xy 269.257143 -323.92643) (xy 269.307688 -323.99767)
			(xy 269.351766 -324.073081) (xy 269.389036 -324.15208) (xy 269.419208 -324.234052) (xy 269.442048 -324.318362)
			(xy 269.457379 -324.404355) (xy 269.465081 -324.491364) (xy 269.465552 -324.535) (xy 273.274584 -324.535)
			(xy 273.278575 -324.446139) (xy 273.290515 -324.357994) (xy 273.310309 -324.271274) (xy 273.337796 -324.186677)
			(xy 273.372755 -324.104885) (xy 273.414906 -324.026556) (xy 273.463908 -323.95232) (xy 273.519368 -323.882776)
			(xy 273.580838 -323.818483) (xy 273.647824 -323.759959) (xy 273.719786 -323.707675) (xy 273.796145 -323.662053)
			(xy 273.876287 -323.623458) (xy 273.959565 -323.592203) (xy 274.04531 -323.568539) (xy 274.132831 -323.552656)
			(xy 274.221423 -323.544683) (xy 274.265898 -323.544184) (xy 276.018498 -323.544184) (xy 276.062977 -323.544592)
			(xy 276.151578 -323.552566) (xy 276.239107 -323.56845) (xy 276.32486 -323.592116) (xy 276.408146 -323.623374)
			(xy 276.488295 -323.661972) (xy 276.564662 -323.707598) (xy 276.636631 -323.759887) (xy 276.703623 -323.818416)
			(xy 276.765099 -323.882715) (xy 276.820564 -323.952266) (xy 276.869571 -324.026508) (xy 276.911726 -324.104845)
			(xy 276.946689 -324.186644) (xy 276.974178 -324.271249) (xy 276.993974 -324.357977) (xy 277.005915 -324.446131)
			(xy 277.009906 -324.535) (xy 280.818384 -324.535) (xy 280.822375 -324.446139) (xy 280.834315 -324.357994)
			(xy 280.854109 -324.271274) (xy 280.881596 -324.186677) (xy 280.916555 -324.104885) (xy 280.958706 -324.026556)
			(xy 281.007708 -323.95232) (xy 281.063168 -323.882776) (xy 281.124638 -323.818483) (xy 281.191624 -323.759959)
			(xy 281.263586 -323.707675) (xy 281.339945 -323.662053) (xy 281.420087 -323.623458) (xy 281.503365 -323.592203)
			(xy 281.58911 -323.568539) (xy 281.676631 -323.552656) (xy 281.765223 -323.544683) (xy 281.809698 -323.544184)
			(xy 283.562298 -323.544184) (xy 283.606777 -323.544592) (xy 283.695378 -323.552566) (xy 283.782907 -323.56845)
			(xy 283.86866 -323.592116) (xy 283.951946 -323.623374) (xy 284.032095 -323.661972) (xy 284.108462 -323.707598)
			(xy 284.180431 -323.759887) (xy 284.247423 -323.818416) (xy 284.308899 -323.882715) (xy 284.364364 -323.952266)
			(xy 284.413371 -324.026508) (xy 284.455526 -324.104845) (xy 284.490489 -324.186644) (xy 284.517978 -324.271249)
			(xy 284.537774 -324.357977) (xy 284.549715 -324.446131) (xy 284.553706 -324.535) (xy 288.362484 -324.535)
			(xy 288.366475 -324.446142) (xy 288.378414 -324.357999) (xy 288.398206 -324.271281) (xy 288.425692 -324.186687)
			(xy 288.46065 -324.104897) (xy 288.502798 -324.026569) (xy 288.551798 -323.952335) (xy 288.607254 -323.882792)
			(xy 288.668721 -323.818499) (xy 288.735703 -323.759975) (xy 288.807662 -323.707691) (xy 288.884018 -323.662068)
			(xy 288.964155 -323.623472) (xy 289.04743 -323.592215) (xy 289.133171 -323.568548) (xy 289.220689 -323.552662)
			(xy 289.309278 -323.544685) (xy 289.353752 -323.544184) (xy 291.106352 -323.544184) (xy 291.150833 -323.54459)
			(xy 291.239436 -323.552561) (xy 291.326968 -323.568441) (xy 291.412725 -323.592105) (xy 291.496015 -323.623361)
			(xy 291.576167 -323.661957) (xy 291.652537 -323.707582) (xy 291.72451 -323.75987) (xy 291.791506 -323.8184)
			(xy 291.852985 -323.882699) (xy 291.908453 -323.952251) (xy 291.957463 -324.026494) (xy 291.99962 -324.104833)
			(xy 292.034585 -324.186635) (xy 292.062076 -324.271242) (xy 292.081873 -324.357972) (xy 292.093815 -324.446128)
			(xy 292.097806 -324.535) (xy 295.90647 -324.535) (xy 295.910461 -324.446138) (xy 295.922401 -324.357991)
			(xy 295.942195 -324.271269) (xy 295.969683 -324.18667) (xy 296.004643 -324.104876) (xy 296.046795 -324.026546)
			(xy 296.095799 -323.952309) (xy 296.151259 -323.882764) (xy 296.212731 -323.81847) (xy 296.279719 -323.759945)
			(xy 296.351682 -323.70766) (xy 296.428043 -323.662037) (xy 296.508187 -323.623443) (xy 296.591467 -323.592188)
			(xy 296.677213 -323.568524) (xy 296.764736 -323.552641) (xy 296.85333 -323.544668) (xy 296.897806 -323.544184)
			(xy 298.650406 -323.544184) (xy 298.694884 -323.544607) (xy 298.783483 -323.552582) (xy 298.87101 -323.568466)
			(xy 298.956761 -323.592132) (xy 299.040046 -323.62339) (xy 299.120193 -323.661987) (xy 299.196558 -323.707613)
			(xy 299.268525 -323.759901) (xy 299.335516 -323.818429) (xy 299.39699 -323.882727) (xy 299.452454 -323.952277)
			(xy 299.50146 -324.026518) (xy 299.543614 -324.104853) (xy 299.578576 -324.186651) (xy 299.606065 -324.271254)
			(xy 299.62586 -324.357981) (xy 299.6378 -324.446133) (xy 299.641792 -324.535) (xy 299.6378 -324.623867)
			(xy 299.62586 -324.712019) (xy 299.606065 -324.798746) (xy 299.578576 -324.883349) (xy 299.543614 -324.965147)
			(xy 299.50146 -325.043482) (xy 299.452454 -325.117723) (xy 299.39699 -325.187273) (xy 299.335516 -325.251571)
			(xy 299.268525 -325.310099) (xy 299.196558 -325.362387) (xy 299.120193 -325.408013) (xy 299.040046 -325.44661)
			(xy 298.956761 -325.477868) (xy 298.87101 -325.501534) (xy 298.783483 -325.517418) (xy 298.694884 -325.525393)
			(xy 298.650406 -325.525892) (xy 296.897806 -325.525892) (xy 296.85333 -325.525332) (xy 296.764736 -325.517359)
			(xy 296.677213 -325.501476) (xy 296.591467 -325.477812) (xy 296.508187 -325.446557) (xy 296.428043 -325.407963)
			(xy 296.351682 -325.36234) (xy 296.279719 -325.310055) (xy 296.212731 -325.25153) (xy 296.151259 -325.187236)
			(xy 296.095799 -325.117691) (xy 296.046795 -325.043454) (xy 296.004643 -324.965124) (xy 295.969683 -324.88333)
			(xy 295.942195 -324.798731) (xy 295.922401 -324.712009) (xy 295.910461 -324.623862) (xy 295.90647 -324.535)
			(xy 292.097806 -324.535) (xy 292.093815 -324.623872) (xy 292.081873 -324.712028) (xy 292.062076 -324.798758)
			(xy 292.034585 -324.883365) (xy 291.99962 -324.965167) (xy 291.957463 -325.043506) (xy 291.908453 -325.117749)
			(xy 291.852985 -325.187301) (xy 291.791506 -325.2516) (xy 291.72451 -325.31013) (xy 291.652537 -325.362418)
			(xy 291.576167 -325.408043) (xy 291.496015 -325.446639) (xy 291.412725 -325.477895) (xy 291.326968 -325.501559)
			(xy 291.239436 -325.517439) (xy 291.150833 -325.52541) (xy 291.106352 -325.525892) (xy 289.353752 -325.525892)
			(xy 289.309278 -325.525315) (xy 289.220689 -325.517338) (xy 289.133171 -325.501452) (xy 289.04743 -325.477785)
			(xy 288.964155 -325.446528) (xy 288.884018 -325.407932) (xy 288.807662 -325.362309) (xy 288.735703 -325.310025)
			(xy 288.668721 -325.251501) (xy 288.607254 -325.187208) (xy 288.551798 -325.117665) (xy 288.502798 -325.043431)
			(xy 288.46065 -324.965103) (xy 288.425692 -324.883313) (xy 288.398206 -324.798719) (xy 288.378414 -324.712001)
			(xy 288.366475 -324.623858) (xy 288.362484 -324.535) (xy 284.553706 -324.535) (xy 284.549715 -324.623869)
			(xy 284.537774 -324.712023) (xy 284.517978 -324.798751) (xy 284.490489 -324.883356) (xy 284.455526 -324.965155)
			(xy 284.413371 -325.043492) (xy 284.364364 -325.117734) (xy 284.308899 -325.187285) (xy 284.247423 -325.251584)
			(xy 284.180431 -325.310113) (xy 284.108462 -325.362402) (xy 284.032095 -325.408028) (xy 283.951946 -325.446626)
			(xy 283.86866 -325.477884) (xy 283.782907 -325.50155) (xy 283.695378 -325.517434) (xy 283.606777 -325.525408)
			(xy 283.562298 -325.525892) (xy 281.809698 -325.525892) (xy 281.765223 -325.525317) (xy 281.676631 -325.517344)
			(xy 281.58911 -325.501461) (xy 281.503365 -325.477797) (xy 281.420087 -325.446542) (xy 281.339945 -325.407947)
			(xy 281.263586 -325.362325) (xy 281.191624 -325.310041) (xy 281.124638 -325.251517) (xy 281.063168 -325.187224)
			(xy 281.007708 -325.11768) (xy 280.958706 -325.043444) (xy 280.916555 -324.965115) (xy 280.881596 -324.883323)
			(xy 280.854109 -324.798726) (xy 280.834315 -324.712006) (xy 280.822375 -324.623861) (xy 280.818384 -324.535)
			(xy 277.009906 -324.535) (xy 277.005915 -324.623869) (xy 276.993974 -324.712023) (xy 276.974178 -324.798751)
			(xy 276.946689 -324.883356) (xy 276.911726 -324.965155) (xy 276.869571 -325.043492) (xy 276.820564 -325.117734)
			(xy 276.765099 -325.187285) (xy 276.703623 -325.251584) (xy 276.636631 -325.310113) (xy 276.564662 -325.362402)
			(xy 276.488295 -325.408028) (xy 276.408146 -325.446626) (xy 276.32486 -325.477884) (xy 276.239107 -325.50155)
			(xy 276.151578 -325.517434) (xy 276.062977 -325.525408) (xy 276.018498 -325.525892) (xy 274.265898 -325.525892)
			(xy 274.221423 -325.525317) (xy 274.132831 -325.517344) (xy 274.04531 -325.501461) (xy 273.959565 -325.477797)
			(xy 273.876287 -325.446542) (xy 273.796145 -325.407947) (xy 273.719786 -325.362325) (xy 273.647824 -325.310041)
			(xy 273.580838 -325.251517) (xy 273.519368 -325.187224) (xy 273.463908 -325.11768) (xy 273.414906 -325.043444)
			(xy 273.372755 -324.965115) (xy 273.337796 -324.883323) (xy 273.310309 -324.798726) (xy 273.290515 -324.712006)
			(xy 273.278575 -324.623861) (xy 273.274584 -324.535) (xy 269.465552 -324.535) (xy 269.465552 -324.535038)
			(xy 269.465061 -324.57871) (xy 269.457346 -324.665713) (xy 269.442006 -324.7517) (xy 269.419159 -324.836004)
			(xy 269.388984 -324.917971) (xy 269.351714 -324.996964) (xy 269.307638 -325.072372) (xy 269.257098 -325.14361)
			(xy 269.200486 -325.210124) (xy 269.138241 -325.271399) (xy 269.104872 -325.299578) (xy 269.096508 -325.307199)
			(xy 269.086887 -325.327645) (xy 269.08633 -325.338948) (xy 269.08633 -331.575156) (xy 269.086722 -331.584348)
			(xy 269.093236 -331.601538) (xy 269.09903 -331.608684) (xy 269.123989 -331.637799) (xy 269.167484 -331.700959)
			(xy 269.203063 -331.768894) (xy 269.230207 -331.840618) (xy 269.248523 -331.915086) (xy 269.257744 -331.991218)
			(xy 269.258288 -332.029562) (xy 269.257852 -332.063896) (xy 269.250504 -332.132168) (xy 269.235845 -332.199253)
			(xy 269.214047 -332.264368) (xy 269.200122 -332.295754) (xy 269.196203 -332.305345) (xy 269.195621 -332.326036)
			(xy 269.203284 -332.345265) (xy 269.210282 -332.352904) (xy 269.330424 -332.473046) (xy 269.337821 -332.479894)
			(xy 269.35642 -332.487629) (xy 269.366492 -332.488032) (xy 271.204944 -332.488032) (xy 271.21501 -332.488464)
			(xy 271.2336 -332.496193) (xy 271.241012 -332.503018) (xy 271.84096 -333.102966) (xy 271.8478 -333.110366)
			(xy 271.855517 -333.128965) (xy 271.855946 -333.139034) (xy 271.855946 -334.847946) (xy 271.856379 -334.858011)
			(xy 271.86411 -334.876599) (xy 271.870932 -334.884014) (xy 271.981676 -334.994758) (xy 271.989077 -335.001597)
			(xy 272.007675 -335.009311) (xy 272.017744 -335.009744)
		)
		(stroke
			(width 0)
			(type solid)
		)
		(fill yes)
		(layer "F.Cu")
		(net "PVDDIO_P0")
	)
	(gr_poly
		(pts
			(xy 323.300852 -356.122986) (xy 350.900746 -356.122986) (xy 350.942402 -356.08133) (xy 352.769932 -356.08133)
			(xy 357.04526 -351.806002) (xy 357.04526 -341.715598) (xy 357.01077 -341.64287) (xy 356.948219 -341.494541)
			(xy 356.893142 -341.343277) (xy 356.845677 -341.189454) (xy 356.805941 -341.033456) (xy 356.774033 -340.87567)
			(xy 356.750034 -340.71649) (xy 356.734002 -340.556311) (xy 356.725977 -340.395532) (xy 356.725474 -340.315042)
			(xy 356.725474 -340.292944) (xy 356.695248 -340.262718) (xy 356.687848 -340.255878) (xy 356.669249 -340.248159)
			(xy 356.65918 -340.247732) (xy 352.12274 -340.247732) (xy 352.112675 -340.248167) (xy 352.09409 -340.2559)
			(xy 352.086672 -340.262718) (xy 352.06305 -340.28634) (xy 352.056205 -340.293738) (xy 352.048477 -340.312337)
			(xy 352.048064 -340.322408) (xy 352.048064 -342.21801) (xy 352.048491 -342.228078) (xy 352.056215 -342.246674)
			(xy 352.06305 -342.254078) (xy 352.068638 -342.259666) (xy 353.431348 -342.259666) (xy 353.441413 -342.2601)
			(xy 353.459998 -342.267834) (xy 353.467416 -342.274652) (xy 353.600766 -342.408002) (xy 353.607616 -342.415399)
			(xy 353.615355 -342.433997) (xy 353.615752 -342.44407) (xy 353.615752 -343.586054) (xy 353.616186 -343.596119)
			(xy 353.62392 -343.614704) (xy 353.630738 -343.622122) (xy 353.94265 -343.934034) (xy 353.949496 -343.941432)
			(xy 353.957226 -343.960031) (xy 353.957636 -343.970102) (xy 353.957636 -345.43873) (xy 353.957206 -345.448796)
			(xy 353.949476 -345.467387) (xy 353.94265 -345.474798) (xy 353.490022 -345.927426) (xy 353.482623 -345.934268)
			(xy 353.464024 -345.941986) (xy 353.453954 -345.942412) (xy 348.076266 -345.942412) (xy 348.066198 -345.941983)
			(xy 348.047602 -345.934261) (xy 348.040198 -345.927426) (xy 347.686122 -345.57335) (xy 347.657195 -345.571287)
			(xy 347.600412 -345.559514) (xy 347.546062 -345.539289) (xy 347.495396 -345.511076) (xy 347.44958 -345.475526)
			(xy 347.409668 -345.433456) (xy 347.376577 -345.385833) (xy 347.351069 -345.333754) (xy 347.33373 -345.278415)
			(xy 347.32496 -345.221091) (xy 347.324426 -345.192096) (xy 347.324922 -345.164049) (xy 347.333133 -345.10856)
			(xy 347.349377 -345.05487) (xy 347.373304 -345.004135) (xy 347.388434 -344.980514) (xy 347.388434 -344.742008)
			(xy 347.418152 -344.71229) (xy 347.418152 -339.01761) (xy 347.417729 -339.00754) (xy 347.410012 -338.988938)
			(xy 347.403166 -338.981542) (xy 346.84462 -338.422996) (xy 346.837772 -338.415598) (xy 346.830036 -338.397)
			(xy 346.829634 -338.386928) (xy 346.829634 -336.525616) (xy 347.31706 -336.03819) (xy 347.31706 -335.400904)
			(xy 347.31654 -335.391006) (xy 347.308956 -335.372714) (xy 347.302328 -335.365344) (xy 347.262704 -335.324958)
			(xy 347.255309 -335.318105) (xy 347.23671 -335.310359) (xy 347.226636 -335.309972) (xy 343.847166 -335.309972)
			(xy 343.837098 -335.310401) (xy 343.8185 -335.31812) (xy 343.811098 -335.324958) (xy 343.787222 -335.348834)
			(xy 343.780378 -335.356233) (xy 343.772653 -335.374832) (xy 343.772236 -335.384902) (xy 343.772236 -337.240372)
			(xy 343.774152 -337.251792) (xy 343.786772 -337.271175) (xy 343.806716 -337.282886) (xy 343.81821 -337.284314)
			(xy 345.051888 -337.284314) (xy 345.061959 -337.284735) (xy 345.080565 -337.292448) (xy 345.087956 -337.2993)
			(xy 345.320874 -337.532218) (xy 345.32772 -337.539616) (xy 345.335452 -337.558215) (xy 345.33586 -337.568286)
			(xy 345.33586 -338.300568) (xy 345.336297 -338.310631) (xy 345.344036 -338.329212) (xy 345.350846 -338.336636)
			(xy 345.727274 -338.713064) (xy 345.734113 -338.720465) (xy 345.741828 -338.739063) (xy 345.74226 -338.749132)
			(xy 345.74226 -340.446106) (xy 345.249246 -340.93912) (xy 339.927946 -340.93912) (xy 339.023452 -340.034626)
			(xy 339.023452 -335.340452) (xy 339.023019 -335.330387) (xy 339.015287 -335.3118) (xy 339.008466 -335.304384)
			(xy 338.940902 -335.23682) (xy 338.933504 -335.229971) (xy 338.914906 -335.222233) (xy 338.904834 -335.221834)
			(xy 335.52003 -335.221834) (xy 335.509966 -335.222271) (xy 335.491383 -335.230007) (xy 335.483962 -335.23682)
			(xy 335.456022 -335.26476) (xy 335.449183 -335.272161) (xy 335.441467 -335.290759) (xy 335.441036 -335.300828)
			(xy 335.441036 -337.189572) (xy 335.442952 -337.200992) (xy 335.455572 -337.220375) (xy 335.475516 -337.232086)
			(xy 335.48701 -337.233514) (xy 336.761582 -337.233514) (xy 336.771645 -337.233952) (xy 336.790227 -337.241689)
			(xy 336.79765 -337.2485) (xy 336.989674 -337.440524) (xy 336.99652 -337.447923) (xy 337.004249 -337.466521)
			(xy 337.00466 -337.476592) (xy 337.00466 -338.249768) (xy 337.005097 -338.259831) (xy 337.012836 -338.278412)
			(xy 337.019646 -338.285836) (xy 337.335876 -338.602066) (xy 337.3426 -338.6093) (xy 337.350217 -338.627505)
			(xy 337.350608 -338.637372) (xy 337.350608 -340.252558) (xy 337.350175 -340.262624) (xy 337.342446 -340.281214)
			(xy 337.335622 -340.288626) (xy 336.735928 -340.88832) (xy 331.540866 -340.88832) (xy 330.666852 -340.014306)
			(xy 330.666852 -335.377282) (xy 330.666424 -335.367214) (xy 330.6587 -335.348619) (xy 330.651866 -335.341214)
			(xy 330.59751 -335.286858) (xy 330.590115 -335.280004) (xy 330.571516 -335.272256) (xy 330.561442 -335.271872)
			(xy 327.145142 -335.271872) (xy 327.135076 -335.272305) (xy 327.116484 -335.280031) (xy 327.109074 -335.286858)
			(xy 327.098406 -335.297526) (xy 327.091563 -335.304926) (xy 327.083837 -335.323524) (xy 327.08342 -335.333594)
			(xy 327.08342 -337.204304) (xy 327.085333 -337.215236) (xy 327.097177 -337.23397) (xy 327.115926 -337.245789)
			(xy 327.126854 -337.247738) (xy 328.396346 -337.247738) (xy 328.406412 -337.24817) (xy 328.425001 -337.255901)
			(xy 328.432414 -337.262724) (xy 328.632058 -337.462368) (xy 328.638898 -337.469768) (xy 328.646615 -337.488367)
			(xy 328.647044 -337.498436) (xy 328.647044 -338.264246) (xy 328.647477 -338.274311) (xy 328.655208 -338.2929)
			(xy 328.66203 -338.300314) (xy 328.97826 -338.616544) (xy 328.984963 -338.623786) (xy 328.992538 -338.641991)
			(xy 328.992992 -338.65185) (xy 328.992992 -340.198456) (xy 328.990452 -340.200996) (xy 328.990452 -340.34095)
			(xy 328.990018 -340.351015) (xy 328.982286 -340.369602) (xy 328.975466 -340.377018) (xy 328.411078 -340.941406)
			(xy 328.403678 -340.948248) (xy 328.38508 -340.955974) (xy 328.37501 -340.956392) (xy 323.252338 -340.956392)
			(xy 322.40474 -340.108794) (xy 322.40474 -335.46669) (xy 322.404313 -335.456622) (xy 322.39659 -335.438026)
			(xy 322.389754 -335.430622) (xy 322.27647 -335.317338) (xy 322.269072 -335.310492) (xy 322.250473 -335.302762)
			(xy 322.240402 -335.302352) (xy 318.835278 -335.302352) (xy 318.825211 -335.302781) (xy 318.806617 -335.310506)
			(xy 318.79921 -335.317338) (xy 318.742822 -335.373726) (xy 318.735977 -335.381125) (xy 318.728249 -335.399723)
			(xy 318.727836 -335.409794) (xy 318.727836 -337.211416) (xy 318.729734 -337.22236) (xy 318.741566 -337.241122)
			(xy 318.760325 -337.252961) (xy 318.77127 -337.25485) (xy 320.163952 -337.25485) (xy 320.174017 -337.255284)
			(xy 320.192603 -337.263017) (xy 320.20002 -337.269836) (xy 320.276474 -337.34629) (xy 320.283325 -337.353687)
			(xy 320.291067 -337.372285) (xy 320.29146 -337.382358) (xy 320.29146 -338.337906) (xy 320.291886 -338.347974)
			(xy 320.299608 -338.366572) (xy 320.306446 -338.373974) (xy 320.669158 -338.736686) (xy 320.675996 -338.744087)
			(xy 320.683705 -338.762686) (xy 320.684144 -338.772754) (xy 320.684144 -342.59647) (xy 320.684581 -342.606534)
			(xy 320.692318 -342.625115) (xy 320.69913 -342.632538) (xy 321.476878 -343.410286) (xy 321.483713 -343.417688)
			(xy 321.49142 -343.436287) (xy 321.491864 -343.446354) (xy 321.491864 -346.25153) (xy 321.491435 -346.261597)
			(xy 321.483709 -346.28019) (xy 321.476878 -346.287598) (xy 319.59169 -348.172786) (xy 319.584291 -348.179632)
			(xy 319.565693 -348.187365) (xy 319.555622 -348.187772) (xy 315.929772 -348.187772) (xy 314.73521 -346.99321)
			(xy 309.164228 -346.99321) (xy 309.154164 -346.993647) (xy 309.135579 -347.00138) (xy 309.12816 -347.008196)
			(xy 309.093108 -347.043248) (xy 309.086268 -347.050649) (xy 309.07855 -347.069247) (xy 309.078122 -347.079316)
			(xy 309.078122 -348.905068) (xy 309.078558 -348.915132) (xy 309.086292 -348.933717) (xy 309.093108 -348.941136)
			(xy 309.131716 -348.979744) (xy 309.139113 -348.986594) (xy 309.157711 -348.994332) (xy 309.167784 -348.99473)
			(xy 310.427624 -348.99473) (xy 310.437692 -348.995158) (xy 310.456287 -349.002882) (xy 310.463692 -349.009716)
			(xy 310.62676 -349.172784) (xy 310.633598 -349.180185) (xy 310.641308 -349.198784) (xy 310.641746 -349.208852)
			(xy 310.641746 -350.492568) (xy 310.642183 -350.502632) (xy 310.64992 -350.521214) (xy 310.656732 -350.528636)
			(xy 311.432448 -351.304352) (xy 316.103 -351.304352) (xy 316.828424 -351.304352) (xy 317.498165 -351.974093)
			(xy 327.061826 -351.974093) (xy 327.061826 -351.889371) (xy 327.069879 -351.805034) (xy 327.085913 -351.721844)
			(xy 327.109781 -351.640554) (xy 327.141269 -351.561902) (xy 327.180091 -351.486599) (xy 327.225894 -351.415327)
			(xy 327.278265 -351.348731) (xy 327.33673 -351.287416) (xy 327.400758 -351.231935) (xy 327.46977 -351.182792)
			(xy 327.54314 -351.140432) (xy 327.620205 -351.105237) (xy 327.700267 -351.077528) (xy 327.7826 -351.057554)
			(xy 327.866459 -351.045497) (xy 327.951084 -351.041466) (xy 328.035709 -351.045497) (xy 328.119568 -351.057554)
			(xy 328.201901 -351.077528) (xy 328.281963 -351.105237) (xy 328.359028 -351.140432) (xy 328.432398 -351.182792)
			(xy 328.50141 -351.231935) (xy 328.565438 -351.287416) (xy 328.623903 -351.348731) (xy 328.676274 -351.415327)
			(xy 328.722077 -351.486599) (xy 328.760899 -351.561902) (xy 328.792387 -351.640554) (xy 328.816255 -351.721844)
			(xy 328.832289 -351.805034) (xy 328.840342 -351.889371) (xy 328.840846 -351.931732) (xy 328.840342 -351.974093)
			(xy 334.521806 -351.974093) (xy 334.521806 -351.889371) (xy 334.529859 -351.805034) (xy 334.545893 -351.721844)
			(xy 334.569761 -351.640554) (xy 334.601249 -351.561902) (xy 334.640071 -351.486599) (xy 334.685874 -351.415327)
			(xy 334.738245 -351.348731) (xy 334.79671 -351.287416) (xy 334.860738 -351.231935) (xy 334.92975 -351.182792)
			(xy 335.00312 -351.140432) (xy 335.080185 -351.105237) (xy 335.160247 -351.077528) (xy 335.24258 -351.057554)
			(xy 335.326439 -351.045497) (xy 335.411064 -351.041466) (xy 335.495689 -351.045497) (xy 335.579548 -351.057554)
			(xy 335.661881 -351.077528) (xy 335.741943 -351.105237) (xy 335.819008 -351.140432) (xy 335.892378 -351.182792)
			(xy 335.96139 -351.231935) (xy 336.025418 -351.287416) (xy 336.083883 -351.348731) (xy 336.136254 -351.415327)
			(xy 336.182057 -351.486599) (xy 336.220879 -351.561902) (xy 336.252367 -351.640554) (xy 336.276235 -351.721844)
			(xy 336.292269 -351.805034) (xy 336.300322 -351.889371) (xy 336.300826 -351.931732) (xy 336.300322 -351.974093)
			(xy 336.292269 -352.05843) (xy 336.276235 -352.14162) (xy 336.252367 -352.22291) (xy 336.220879 -352.301562)
			(xy 336.182057 -352.376865) (xy 336.136254 -352.448137) (xy 336.083883 -352.514733) (xy 336.025418 -352.576048)
			(xy 335.96139 -352.631529) (xy 335.892378 -352.680672) (xy 335.819008 -352.723032) (xy 335.741943 -352.758227)
			(xy 335.661881 -352.785936) (xy 335.579548 -352.80591) (xy 335.495689 -352.817967) (xy 335.411064 -352.821999)
			(xy 335.326439 -352.817967) (xy 335.24258 -352.80591) (xy 335.160247 -352.785936) (xy 335.080185 -352.758227)
			(xy 335.00312 -352.723032) (xy 334.92975 -352.680672) (xy 334.860738 -352.631529) (xy 334.79671 -352.576048)
			(xy 334.738245 -352.514733) (xy 334.685874 -352.448137) (xy 334.640071 -352.376865) (xy 334.601249 -352.301562)
			(xy 334.569761 -352.22291) (xy 334.545893 -352.14162) (xy 334.529859 -352.05843) (xy 334.521806 -351.974093)
			(xy 328.840342 -351.974093) (xy 328.832289 -352.05843) (xy 328.816255 -352.14162) (xy 328.792387 -352.22291)
			(xy 328.760899 -352.301562) (xy 328.722077 -352.376865) (xy 328.676274 -352.448137) (xy 328.623903 -352.514733)
			(xy 328.565438 -352.576048) (xy 328.50141 -352.631529) (xy 328.432398 -352.680672) (xy 328.359028 -352.723032)
			(xy 328.281963 -352.758227) (xy 328.201901 -352.785936) (xy 328.119568 -352.80591) (xy 328.035709 -352.817967)
			(xy 327.951084 -352.821999) (xy 327.866459 -352.817967) (xy 327.7826 -352.80591) (xy 327.700267 -352.785936)
			(xy 327.620205 -352.758227) (xy 327.54314 -352.723032) (xy 327.46977 -352.680672) (xy 327.400758 -352.631529)
			(xy 327.33673 -352.576048) (xy 327.278265 -352.514733) (xy 327.225894 -352.448137) (xy 327.180091 -352.376865)
			(xy 327.141269 -352.301562) (xy 327.109781 -352.22291) (xy 327.085913 -352.14162) (xy 327.069879 -352.05843)
			(xy 327.061826 -351.974093) (xy 317.498165 -351.974093) (xy 321.67703 -356.152958) (xy 323.27088 -356.152958)
		)
		(stroke
			(width 0)
			(type solid)
		)
		(fill yes)
		(layer "F.Cu")
		(net "SW_P12V_AUX_PVDDCR_CPU1_P0_FLT")
	)
	(gr_poly
		(pts
			(arc
				(start 432.081432 -408.58948)
				(mid 432.100955 -408.585579)
				(end 432.1175 -408.574494)
			)
			(arc
				(start 432.206654 -408.48534)
				(mid 432.217765 -408.468806)
				(end 432.22164 -408.449272)
			)
			(xy 432.22164 -399.765774) (xy 432.21402 -399.747232) (xy 432.207924 -399.741136)
			(arc
				(start 432.207924 -394.04163)
				(mid 432.204023 -394.022107)
				(end 432.192938 -394.005562)
			)
			(arc
				(start 431.067464 -392.880088)
				(mid 431.041473 -392.866082)
				(end 431.012092 -392.868912)
			)
			(arc
				(start 430.99101 -392.877548)
				(mid 430.981555 -392.880506)
				(end 430.971706 -392.881612)
			)
			(arc
				(start 430.39792 -392.881612)
				(mid 430.361999 -392.866733)
				(end 430.34712 -392.830812)
			)
			(xy 430.34712 -392.825224)
			(arc
				(start 430.158906 -392.825224)
				(mid 430.139383 -392.821323)
				(end 430.122838 -392.810238)
			)
			(arc
				(start 428.598838 -391.286238)
				(mid 428.582304 -391.275127)
				(end 428.56277 -391.271252)
			)
			(arc
				(start 427.130972 -391.271252)
				(mid 427.111449 -391.275153)
				(end 427.094904 -391.286238)
			)
			(arc
				(start 427.084998 -391.296144)
				(mid 427.073887 -391.312678)
				(end 427.070012 -391.332212)
			)
			(arc
				(start 427.070012 -392.019028)
				(mid 427.066111 -392.038551)
				(end 427.055026 -392.055096)
			)
			(arc
				(start 426.684186 -392.425936)
				(mid 426.673075 -392.44247)
				(end 426.6692 -392.462004)
			)
			(arc
				(start 426.6692 -393.677394)
				(mid 426.673101 -393.696917)
				(end 426.684186 -393.713462)
			)
			(arc
				(start 426.80636 -393.835636)
				(mid 426.822894 -393.846747)
				(end 426.842428 -393.850622)
			)
			(arc
				(start 427.51756 -393.850622)
				(mid 427.537083 -393.854523)
				(end 427.553628 -393.865608)
			)
			(arc
				(start 427.807882 -394.119862)
				(mid 427.818993 -394.136396)
				(end 427.822868 -394.15593)
			)
			(arc
				(start 427.822868 -395.536166)
				(mid 427.818967 -395.555689)
				(end 427.807882 -395.572234)
			)
			(arc
				(start 427.41342 -395.966696)
				(mid 427.402309 -395.98323)
				(end 427.398434 -396.002764)
			)
			(arc
				(start 427.398434 -397.274034)
				(mid 427.402335 -397.293557)
				(end 427.41342 -397.310102)
			)
			(xy 427.41596 -397.312896)
			(arc
				(start 429.041814 -397.312896)
				(mid 429.077735 -397.298017)
				(end 429.092614 -397.262096)
			)
			(arc
				(start 429.092614 -395.898624)
				(mid 429.088713 -395.879101)
				(end 429.077628 -395.862556)
			)
			(xy 428.649892 -395.43482) (xy 428.63516 -395.427454)
			(arc
				(start 428.626778 -395.426438)
				(mid 428.553725 -395.390271)
				(end 428.517558 -395.317218)
			)
			(xy 428.516542 -395.308836) (xy 428.509176 -395.294104) (xy 428.503842 -395.28877)
			(arc
				(start 428.503842 -394.12418)
				(mid 428.507743 -394.104657)
				(end 428.518828 -394.088112)
			)
			(arc
				(start 428.741332 -393.865608)
				(mid 428.757866 -393.854497)
				(end 428.7774 -393.850622)
			)
			(arc
				(start 430.236122 -393.850622)
				(mid 430.255645 -393.854523)
				(end 430.27219 -393.865608)
			)
			(arc
				(start 431.018442 -394.61186)
				(mid 431.029553 -394.628394)
				(end 431.033428 -394.647928)
			)
			(xy 431.033428 -400.317462) (xy 431.026062 -400.324828)
			(arc
				(start 431.026062 -400.586956)
				(mid 431.022161 -400.606479)
				(end 431.011076 -400.623024)
			)
			(arc
				(start 430.539652 -401.094448)
				(mid 430.523118 -401.105559)
				(end 430.503584 -401.109434)
			)
			(arc
				(start 429.251872 -401.109434)
				(mid 429.232349 -401.113335)
				(end 429.215804 -401.12442)
			)
			(arc
				(start 429.090582 -401.249642)
				(mid 429.079471 -401.266176)
				(end 429.075596 -401.28571)
			)
			(arc
				(start 429.075596 -401.916392)
				(mid 429.079497 -401.935915)
				(end 429.090582 -401.95246)
			)
			(arc
				(start 429.379888 -402.241766)
				(mid 429.390999 -402.2583)
				(end 429.394874 -402.277834)
			)
			(xy 429.394874 -403.707092) (xy 429.41875 -403.735286)
			(arc
				(start 429.437038 -403.738588)
				(mid 429.73886 -403.912293)
				(end 429.85817 -404.239476)
			)
			(arc
				(start 429.85817 -404.239476)
				(mid 429.709231 -404.599045)
				(end 429.349662 -404.747984)
			)
			(arc
				(start 429.349662 -404.747984)
				(mid 429.010047 -404.617949)
				(end 428.844202 -404.29434)
			)
			(xy 428.841916 -404.274782) (xy 428.813214 -404.249128)
			(arc
				(start 424.16476 -404.249128)
				(mid 424.128839 -404.264007)
				(end 424.11396 -404.299928)
			)
			(arc
				(start 424.11396 -404.4315)
				(mid 424.076704 -404.521572)
				(end 423.986706 -404.559008)
			)
			(arc
				(start 423.972736 -404.559008)
				(mid 423.953242 -404.562792)
				(end 423.936668 -404.57374)
			)
			(xy 423.71899 -404.791672) (xy 423.711624 -404.81631)
			(arc
				(start 423.714672 -404.829264)
				(mid 423.726119 -404.898186)
				(end 423.729912 -404.967948)
			)
			(arc
				(start 423.729912 -404.967948)
				(mid 423.094404 -405.603456)
				(end 422.458896 -404.967948)
			)
			(arc
				(start 422.458896 -404.967948)
				(mid 422.481787 -404.798918)
				(end 422.548812 -404.642066)
			)
			(arc
				(start 422.548812 -404.642066)
				(mid 422.554108 -404.62959)
				(end 422.555924 -404.616158)
			)
			(arc
				(start 422.555924 -404.245318)
				(mid 422.552023 -404.225795)
				(end 422.540938 -404.20925)
			)
			(arc
				(start 422.390316 -404.058628)
				(mid 422.373782 -404.047517)
				(end 422.354248 -404.043642)
			)
			(xy 422.257982 -404.043642)
			(arc
				(start 422.25214 -404.044912)
				(mid 422.216706 -404.051318)
				(end 422.180766 -404.053548)
			)
			(arc
				(start 421.937942 -404.053548)
				(mid 421.913055 -404.059919)
				(end 421.894508 -404.077678)
			)
			(arc
				(start 421.894508 -404.077678)
				(mid 421.770373 -404.224561)
				(end 421.607996 -404.327614)
			)
			(xy 421.59936 -404.331424)
			(arc
				(start 421.073072 -404.857712)
				(mid 421.056538 -404.868823)
				(end 421.037004 -404.872698)
			)
			(xy 402.463508 -404.872698)
			(arc
				(start 402.45411 -404.876508)
				(mid 402.4302 -404.88372)
				(end 402.405342 -404.88616)
			)
			(xy 402.343366 -404.88616)
			(arc
				(start 402.333968 -404.890224)
				(mid 402.275597 -404.908112)
				(end 402.214842 -404.9141)
			)
			(arc
				(start 402.214842 -404.9141)
				(mid 402.154091 -404.908092)
				(end 402.095716 -404.890224)
			)
			(xy 402.086318 -404.88616) (xy 402.053298 -404.88616) (xy 402.023834 -404.913846)
			(arc
				(start 402.022818 -404.934166)
				(mid 401.824027 -405.358646)
				(end 401.388326 -405.531574)
			)
			(arc
				(start 401.388326 -405.531574)
				(mid 400.938954 -405.345438)
				(end 400.752818 -404.896066)
			)
			(arc
				(start 400.752818 -404.896066)
				(mid 400.898888 -404.4907)
				(end 401.269962 -404.271734)
			)
			(xy 401.287996 -404.268178) (xy 401.311364 -404.240238)
			(arc
				(start 401.311364 -404.005034)
				(mid 401.307414 -403.985647)
				(end 401.296378 -403.96922)
			)
			(arc
				(start 401.271994 -403.944836)
				(mid 401.25546 -403.933725)
				(end 401.235926 -403.92985)
			)
			(arc
				(start 399.980912 -403.92985)
				(mid 399.961389 -403.933751)
				(end 399.944844 -403.944836)
			)
			(arc
				(start 399.47342 -404.41626)
				(mid 399.456886 -404.427371)
				(end 399.437352 -404.431246)
			)
			(arc
				(start 399.281904 -404.431246)
				(mid 399.245983 -404.446125)
				(end 399.231104 -404.482046)
			)
			(arc
				(start 399.231104 -404.87092)
				(mid 399.234888 -404.890414)
				(end 399.245836 -404.906988)
			)
			(arc
				(start 400.498056 -406.159208)
				(mid 400.514619 -406.170182)
				(end 400.534124 -406.17394)
			)
			(arc
				(start 400.764502 -406.17394)
				(mid 400.789389 -406.167569)
				(end 400.807936 -406.14981)
			)
			(arc
				(start 400.807936 -406.14981)
				(mid 401.039207 -405.927321)
				(end 401.349718 -405.84628)
			)
			(arc
				(start 401.349718 -405.84628)
				(mid 401.985226 -406.481788)
				(end 401.349718 -407.117296)
			)
			(arc
				(start 401.349718 -407.117296)
				(mid 401.039215 -407.03624)
				(end 400.807936 -406.813766)
			)
			(arc
				(start 400.807936 -406.813766)
				(mid 400.789366 -406.79605)
				(end 400.764502 -406.789636)
			)
			(arc
				(start 400.385534 -406.789636)
				(mid 400.267726 -406.766202)
				(end 400.167856 -406.699466)
			)
			(arc
				(start 399.250154 -405.781764)
				(mid 399.224163 -405.767758)
				(end 399.194782 -405.770588)
			)
			(xy 399.180558 -405.776684) (xy 399.16354 -405.80183)
			(arc
				(start 399.16354 -408.53868)
				(mid 399.178419 -408.574601)
				(end 399.21434 -408.58948)
			)
		)
		(stroke
			(width 0)
			(type solid)
		)
		(fill yes)
		(layer "F.Cu")
		(net "P1V8_CPU0_RT_1D")
	)
	(gr_poly
		(pts
			(xy 188.921644 -400.76247) (xy 188.921644 -400.33448) (xy 189.703202 -399.552922) (xy 191.621918 -399.552922)
			(xy 193.461386 -397.713454) (xy 196.042534 -397.713454) (xy 197.5739 -399.24482) (xy 197.5739 -399.7579)
			(xy 197.574323 -399.76797) (xy 197.582038 -399.786575) (xy 197.588886 -399.793968) (xy 197.660514 -399.865596)
			(xy 197.667913 -399.87244) (xy 197.686511 -399.88017) (xy 197.696582 -399.880582) (xy 201.525378 -399.880582)
			(xy 201.535442 -399.881019) (xy 201.554028 -399.888751) (xy 201.561446 -399.895568) (xy 201.561954 -399.896076)
			(xy 201.568794 -399.903476) (xy 201.576508 -399.922075) (xy 201.57694 -399.932144) (xy 201.57694 -400.754342)
			(xy 201.577436 -400.764341) (xy 201.585104 -400.782811) (xy 201.599257 -400.796941) (xy 201.61774 -400.80458)
			(xy 201.62774 -400.805142) (xy 202.053698 -400.805142) (xy 202.063684 -400.804603) (xy 202.082111 -400.796884)
			(xy 202.089512 -400.790156) (xy 202.146154 -400.733514) (xy 202.152972 -400.726172) (xy 202.160716 -400.707709)
			(xy 202.16114 -400.6977) (xy 202.16114 -399.76298) (xy 203.61656 -398.30756) (xy 206.80172 -398.30756)
			(xy 208.3181 -399.82394) (xy 208.318531 -399.834007) (xy 208.326255 -399.852601) (xy 208.333086 -399.860008)
			(xy 208.338674 -399.865596) (xy 208.346076 -399.872431) (xy 208.364675 -399.880139) (xy 208.374742 -399.880582)
			(xy 212.193378 -399.880582) (xy 212.203442 -399.881019) (xy 212.222028 -399.888751) (xy 212.229446 -399.895568)
			(xy 212.235034 -399.901156) (xy 212.241879 -399.908554) (xy 212.249603 -399.927153) (xy 212.25002 -399.937224)
			(xy 212.25002 -400.769582) (xy 212.250437 -400.779604) (xy 212.258104 -400.798124) (xy 212.272278 -400.812297)
			(xy 212.290798 -400.819963) (xy 212.30082 -400.820382) (xy 212.691218 -400.820382) (xy 212.701286 -400.819955)
			(xy 212.719884 -400.812234) (xy 212.727286 -400.805396) (xy 212.814154 -400.718528) (xy 212.820994 -400.711128)
			(xy 212.82871 -400.692529) (xy 212.82914 -400.68246) (xy 212.82914 -399.73504) (xy 214.26678 -398.2974)
			(xy 217.45702 -398.2974) (xy 218.98102 -399.8214) (xy 218.981444 -399.83147) (xy 218.98916 -399.850072)
			(xy 218.996006 -399.857468) (xy 219.004134 -399.865596) (xy 219.011534 -399.872437) (xy 219.030132 -399.88016)
			(xy 219.040202 -399.880582) (xy 222.863918 -399.880582) (xy 222.873987 -399.881008) (xy 222.892589 -399.888725)
			(xy 222.899986 -399.895568) (xy 222.900494 -399.896076) (xy 222.907329 -399.903478) (xy 222.915037 -399.922077)
			(xy 222.91548 -399.932144) (xy 222.91548 -400.78152) (xy 222.915906 -400.791589) (xy 222.923623 -400.81019)
			(xy 222.930466 -400.817588) (xy 222.943674 -400.830796) (xy 222.951076 -400.837631) (xy 222.969675 -400.845339)
			(xy 222.979742 -400.845782) (xy 223.046036 -400.845782) (xy 223.050608 -400.84502) (xy 223.065212 -400.842526)
			(xy 223.094721 -400.839858) (xy 223.109536 -400.839686) (xy 223.299274 -400.839686) (xy 223.31807 -400.832066)
			(xy 223.325182 -400.8247) (xy 223.487234 -400.662648) (xy 223.49408 -400.65525) (xy 223.501805 -400.636651)
			(xy 223.50222 -400.62658) (xy 223.50222 -399.86458) (xy 225.067876 -398.298924) (xy 228.093524 -398.298924)
			(xy 229.675182 -399.880582) (xy 233.526838 -399.880582) (xy 233.536906 -399.881011) (xy 233.555502 -399.888734)
			(xy 233.562906 -399.895568) (xy 233.565954 -399.898616) (xy 233.572803 -399.906013) (xy 233.580539 -399.924612)
			(xy 233.58094 -399.934684) (xy 233.58094 -400.769582) (xy 233.581357 -400.779603) (xy 233.589025 -400.798119)
			(xy 233.6032 -400.812287) (xy 233.621719 -400.819947) (xy 233.63174 -400.820382) (xy 234.103418 -400.820382)
			(xy 234.113486 -400.819955) (xy 234.132084 -400.812234) (xy 234.139486 -400.805396) (xy 234.155234 -400.789648)
			(xy 234.16208 -400.78225) (xy 234.169805 -400.763651) (xy 234.17022 -400.75358) (xy 234.17022 -400.12874)
			(xy 234.93222 -399.36674) (xy 237.370366 -399.36674) (xy 238.374682 -398.362424) (xy 238.374682 -387.287008)
			(xy 238.37011 -387.282436) (xy 238.37011 -383.42189) (xy 238.955834 -382.836166) (xy 242.417854 -382.836166)
			(xy 242.427919 -382.835732) (xy 242.446506 -382.828) (xy 242.453922 -382.82118) (xy 242.588796 -382.686306)
			(xy 242.595644 -382.678908) (xy 242.603381 -382.66031) (xy 242.603782 -382.650238) (xy 242.603782 -380.104142)
			(xy 242.799108 -379.908816) (xy 245.178072 -379.908816) (xy 245.38686 -380.117604) (xy 245.38686 -382.773936)
			(xy 245.387291 -382.784002) (xy 245.395022 -382.802591) (xy 245.401846 -382.810004) (xy 245.423436 -382.831594)
			(xy 245.430836 -382.838435) (xy 245.449434 -382.846158) (xy 245.459504 -382.84658) (xy 248.426986 -382.84658)
			(xy 248.437049 -382.846141) (xy 248.455629 -382.838402) (xy 248.463054 -382.831594) (xy 248.536206 -382.758442)
			(xy 248.543043 -382.75104) (xy 248.550755 -382.732442) (xy 248.551192 -382.722374) (xy 248.551192 -380.091696)
			(xy 248.734072 -379.908816) (xy 251.113036 -379.908816) (xy 251.241306 -380.037086) (xy 251.241306 -382.71196)
			(xy 251.24174 -382.722025) (xy 251.249471 -382.740613) (xy 251.256292 -382.748028) (xy 251.355606 -382.847342)
			(xy 251.363002 -382.854194) (xy 251.381601 -382.861935) (xy 251.391674 -382.862328) (xy 254.369316 -382.862328)
			(xy 254.379386 -382.861903) (xy 254.397988 -382.854187) (xy 254.405384 -382.847342) (xy 254.49403 -382.758696)
			(xy 254.500883 -382.751301) (xy 254.508627 -382.732702) (xy 254.509016 -382.722628) (xy 254.509016 -380.068836)
			(xy 254.669036 -379.908816) (xy 257.048 -379.908816) (xy 257.219704 -380.08052) (xy 257.219704 -382.773936)
			(xy 257.220134 -382.784003) (xy 257.227858 -382.802598) (xy 257.23469 -382.810004) (xy 257.26644 -382.841754)
			(xy 257.273839 -382.848599) (xy 257.292437 -382.856326) (xy 257.302508 -382.85674) (xy 260.229096 -382.85674)
			(xy 260.239165 -382.856316) (xy 260.257765 -382.848596) (xy 260.265164 -382.841754) (xy 260.430772 -382.676146)
			(xy 260.437613 -382.668746) (xy 260.445332 -382.650147) (xy 260.445758 -382.640078) (xy 260.445758 -380.067058)
			(xy 260.604 -379.908816) (xy 262.982964 -379.908816) (xy 263.125966 -380.051818) (xy 263.125966 -382.743202)
			(xy 263.126391 -382.753271) (xy 263.134113 -382.771868) (xy 263.140952 -382.77927) (xy 263.203436 -382.841754)
			(xy 263.210834 -382.8486) (xy 263.229433 -382.856328) (xy 263.239504 -382.85674) (xy 266.248642 -382.85674)
			(xy 266.258707 -382.856308) (xy 266.277295 -382.848576) (xy 266.28471 -382.841754) (xy 266.368022 -382.758442)
			(xy 266.374868 -382.751044) (xy 266.382594 -382.732445) (xy 266.383008 -382.722374) (xy 266.383008 -380.064772)
			(xy 266.538964 -379.908816) (xy 268.917928 -379.908816) (xy 269.062962 -380.05385) (xy 269.062962 -382.691386)
			(xy 269.063402 -382.701448) (xy 269.071146 -382.720024) (xy 269.077948 -382.727454) (xy 269.192502 -382.842008)
			(xy 269.199901 -382.848853) (xy 269.218499 -382.856586) (xy 269.22857 -382.856994) (xy 272.165064 -382.856994)
			(xy 272.175129 -382.856559) (xy 272.193716 -382.848828) (xy 272.201132 -382.842008) (xy 272.294858 -382.748282)
			(xy 272.301706 -382.740885) (xy 272.309441 -382.722286) (xy 272.309844 -382.712214) (xy 272.309844 -380.0729)
			(xy 272.473928 -379.908816) (xy 274.852892 -379.908816) (xy 275.020786 -380.07671) (xy 275.020786 -382.753616)
			(xy 275.021211 -382.763685) (xy 275.028928 -382.782287) (xy 275.035772 -382.789684) (xy 275.077682 -382.831594)
			(xy 275.085085 -382.838428) (xy 275.103683 -382.846134) (xy 275.11375 -382.84658) (xy 278.050498 -382.84658)
			(xy 278.060568 -382.846157) (xy 278.079171 -382.838441) (xy 278.086566 -382.831594) (xy 278.21128 -382.70688)
			(xy 278.218125 -382.699481) (xy 278.225856 -382.680883) (xy 278.226266 -382.670812) (xy 278.226266 -375.161048)
			(xy 276.632924 -373.567706) (xy 240.043716 -373.567706) (xy 240.036313 -373.574538) (xy 240.017714 -373.582241)
			(xy 240.007648 -373.582692) (xy 234.631992 -373.582692) (xy 234.60964 -373.605044) (xy 226.652328 -373.605044)
			(xy 220.05163 -380.205742) (xy 220.05163 -380.213616) (xy 219.548964 -380.716282) (xy 219.548964 -387.94817)
			(xy 219.33662 -388.160514) (xy 221.301066 -388.160514) (xy 221.305051 -387.979161) (xy 221.316998 -387.798159)
			(xy 221.336883 -387.617856) (xy 221.364669 -387.4386) (xy 221.400302 -387.260738) (xy 221.443713 -387.084613)
			(xy 221.494818 -386.910564) (xy 221.553519 -386.738929) (xy 221.619702 -386.570037) (xy 221.69324 -386.404215)
			(xy 221.773991 -386.241784) (xy 221.861798 -386.083056) (xy 221.956492 -385.928338) (xy 222.057891 -385.777929)
			(xy 222.165798 -385.632119) (xy 222.280007 -385.491189) (xy 222.400295 -385.355412) (xy 222.52643 -385.225049)
			(xy 222.658171 -385.100353) (xy 222.795261 -384.981564) (xy 222.937436 -384.868911) (xy 223.084423 -384.762611)
			(xy 223.235937 -384.662871) (xy 223.391686 -384.569881) (xy 223.551368 -384.483823) (xy 223.714677 -384.404862)
			(xy 223.881297 -384.33315) (xy 224.050905 -384.268826) (xy 224.223175 -384.212014) (xy 224.397775 -384.162824)
			(xy 224.574366 -384.12135) (xy 224.752609 -384.087673) (xy 224.932159 -384.061857) (xy 225.11267 -384.043953)
			(xy 225.293792 -384.033996) (xy 225.475178 -384.032003) (xy 225.656476 -384.03798) (xy 225.837336 -384.051914)
			(xy 226.01741 -384.073779) (xy 226.196349 -384.103532) (xy 226.373809 -384.141117) (xy 226.549447 -384.18646)
			(xy 226.722924 -384.239474) (xy 226.893904 -384.300056) (xy 227.062059 -384.368091) (xy 227.227063 -384.443445)
			(xy 227.388598 -384.525975) (xy 227.546352 -384.615521) (xy 227.70002 -384.711909) (xy 227.849306 -384.814954)
			(xy 227.993922 -384.924456) (xy 228.133589 -385.040205) (xy 228.268036 -385.161978) (xy 228.397006 -385.289538)
			(xy 228.520247 -385.42264) (xy 228.637524 -385.561026) (xy 228.748608 -385.704431) (xy 228.853287 -385.852576)
			(xy 228.951357 -386.005177) (xy 229.04263 -386.161937) (xy 229.126929 -386.322556) (xy 229.204091 -386.486722)
			(xy 229.273969 -386.654119) (xy 229.336426 -386.824424) (xy 229.391342 -386.997308) (xy 229.438612 -387.172437)
			(xy 229.478143 -387.349473) (xy 229.50986 -387.528075) (xy 229.533702 -387.707898) (xy 229.549622 -387.888595)
			(xy 229.55759 -388.069816) (xy 229.558088 -388.160514) (xy 229.55759 -388.251212) (xy 229.549622 -388.432433)
			(xy 229.533702 -388.61313) (xy 229.50986 -388.792953) (xy 229.478143 -388.971555) (xy 229.438612 -389.148591)
			(xy 229.391342 -389.32372) (xy 229.336426 -389.496604) (xy 229.273969 -389.666909) (xy 229.204091 -389.834306)
			(xy 229.126929 -389.998472) (xy 229.04263 -390.159091) (xy 228.951357 -390.315851) (xy 228.853287 -390.468452)
			(xy 228.748608 -390.616597) (xy 228.637524 -390.760002) (xy 228.520247 -390.898388) (xy 228.397006 -391.03149)
			(xy 228.268036 -391.15905) (xy 228.133589 -391.280823) (xy 227.993922 -391.396572) (xy 227.849306 -391.506074)
			(xy 227.70002 -391.609119) (xy 227.546352 -391.705507) (xy 227.388598 -391.795053) (xy 227.227063 -391.877583)
			(xy 227.062059 -391.952937) (xy 226.893904 -392.020972) (xy 226.722924 -392.081554) (xy 226.549447 -392.134568)
			(xy 226.373809 -392.179911) (xy 226.196349 -392.217496) (xy 226.01741 -392.247249) (xy 225.837336 -392.269114)
			(xy 225.656476 -392.283048) (xy 225.475178 -392.289025) (xy 225.293792 -392.287032) (xy 225.11267 -392.277075)
			(xy 224.932159 -392.259171) (xy 224.752609 -392.233355) (xy 224.574366 -392.199678) (xy 224.397775 -392.158204)
			(xy 224.223175 -392.109014) (xy 224.050905 -392.052202) (xy 223.881297 -391.987878) (xy 223.714677 -391.916166)
			(xy 223.551368 -391.837205) (xy 223.391686 -391.751147) (xy 223.235937 -391.658157) (xy 223.084423 -391.558417)
			(xy 222.937436 -391.452117) (xy 222.795261 -391.339464) (xy 222.658171 -391.220675) (xy 222.52643 -391.095979)
			(xy 222.400295 -390.965616) (xy 222.280007 -390.829839) (xy 222.165798 -390.688909) (xy 222.057891 -390.543099)
			(xy 221.956492 -390.39269) (xy 221.861798 -390.237972) (xy 221.773991 -390.079244) (xy 221.69324 -389.916813)
			(xy 221.619702 -389.750991) (xy 221.553519 -389.582099) (xy 221.494818 -389.410464) (xy 221.443713 -389.236415)
			(xy 221.400302 -389.06029) (xy 221.364669 -388.882428) (xy 221.336883 -388.703172) (xy 221.316998 -388.522869)
			(xy 221.305051 -388.341867) (xy 221.301066 -388.160514) (xy 219.33662 -388.160514) (xy 218.473528 -389.023606)
			(xy 213.164166 -389.023606) (xy 209.757772 -392.43) (xy 185.457084 -392.43) (xy 184.441084 -393.446)
			(xy 184.441084 -395.987016) (xy 185.194956 -396.740888) (xy 185.194956 -398.333976) (xy 185.031126 -398.49806)
			(xy 185.031126 -399.061178) (xy 185.03218 -399.072961) (xy 185.033321 -399.096593) (xy 185.033412 -399.108422)
			(xy 185.032964 -399.138968) (xy 185.025656 -399.199621) (xy 185.011134 -399.258961) (xy 184.989609 -399.316135)
			(xy 184.961389 -399.370319) (xy 184.926883 -399.420732) (xy 184.886586 -399.466649) (xy 184.841078 -399.507408)
			(xy 184.791017 -399.542422) (xy 184.737121 -399.571187) (xy 184.7088 -399.58264) (xy 184.7088 -399.83918)
			(xy 184.75198 -399.88236) (xy 188.25718 -399.88236) (xy 188.32576 -399.95094) (xy 188.32576 -400.90344)
			(xy 188.33338 -400.91106) (xy 188.773054 -400.91106)
		)
		(stroke
			(width 0)
			(type solid)
		)
		(fill yes)
		(layer "F.Cu")
		(net "P12V_AUX")
	)
	(gr_poly
		(pts
			(arc
				(start 11.06551 -138.392154)
				(mid 11.079458 -138.387334)
				(end 11.091418 -138.378692)
			)
			(xy 11.983466 -137.486644)
			(arc
				(start 11.987276 -137.4775)
				(mid 12.096348 -137.3153)
				(end 12.258548 -137.206228)
			)
			(xy 12.267692 -137.202418)
			(arc
				(start 12.42441 -137.0457)
				(mid 12.433043 -137.033735)
				(end 12.437872 -137.019792)
			)
			(xy 12.438888 -137.01014)
			(arc
				(start 12.438888 -135.620252)
				(mid 12.442789 -135.600729)
				(end 12.453874 -135.584184)
			)
			(arc
				(start 12.522962 -135.515096)
				(mid 12.539496 -135.503985)
				(end 12.55903 -135.50011)
			)
			(arc
				(start 13.545566 -135.50011)
				(mid 13.565089 -135.504011)
				(end 13.581634 -135.515096)
			)
			(arc
				(start 13.655802 -135.589264)
				(mid 13.666913 -135.605798)
				(end 13.670788 -135.625332)
			)
			(arc
				(start 13.670788 -136.124188)
				(mid 13.674689 -136.143711)
				(end 13.685774 -136.160256)
			)
			(arc
				(start 13.696442 -136.170924)
				(mid 13.712976 -136.182035)
				(end 13.73251 -136.18591)
			)
			(arc
				(start 13.827506 -136.18591)
				(mid 13.847029 -136.182009)
				(end 13.863574 -136.170924)
			)
			(arc
				(start 13.899134 -136.135364)
				(mid 13.910245 -136.11883)
				(end 13.91412 -136.099296)
			)
			(arc
				(start 13.91412 -135.57758)
				(mid 13.918021 -135.558057)
				(end 13.929106 -135.541512)
			)
			(arc
				(start 14.186662 -135.283956)
				(mid 14.203196 -135.272845)
				(end 14.22273 -135.26897)
			)
			(arc
				(start 14.665706 -135.26897)
				(mid 14.685229 -135.265069)
				(end 14.701774 -135.253984)
			)
			(arc
				(start 14.748002 -135.207756)
				(mid 14.759113 -135.191222)
				(end 14.762988 -135.171688)
			)
			(arc
				(start 14.762988 -134.081012)
				(mid 14.766889 -134.061489)
				(end 14.777974 -134.044944)
			)
			(arc
				(start 14.897862 -133.925056)
				(mid 14.914396 -133.913945)
				(end 14.93393 -133.91007)
			)
			(arc
				(start 14.964156 -133.91007)
				(mid 15.000077 -133.895191)
				(end 15.014956 -133.85927)
			)
			(xy 15.014956 -133.703822) (xy 15.007336 -133.68528) (xy 15.002256 -133.6802) (xy 14.99362 -133.6802)
			(xy 14.975078 -133.67258)
			(arc
				(start 14.777974 -133.475476)
				(mid 14.766863 -133.458942)
				(end 14.762988 -133.439408)
			)
			(arc
				(start 14.762988 -132.902452)
				(mid 14.759087 -132.882929)
				(end 14.748002 -132.866384)
			)
			(arc
				(start 14.719554 -132.837936)
				(mid 14.70302 -132.826825)
				(end 14.683486 -132.82295)
			)
			(arc
				(start 14.03223 -132.82295)
				(mid 14.012707 -132.819049)
				(end 13.996162 -132.807964)
			)
			(arc
				(start 13.916914 -132.728716)
				(mid 13.905803 -132.712182)
				(end 13.901928 -132.692648)
			)
			(arc
				(start 13.901928 -131.962652)
				(mid 13.898027 -131.943129)
				(end 13.886942 -131.926584)
			)
			(arc
				(start 13.876274 -131.915916)
				(mid 13.85974 -131.904805)
				(end 13.840206 -131.90093)
			)
			(arc
				(start 13.76045 -131.90093)
				(mid 13.740927 -131.904831)
				(end 13.724382 -131.915916)
			)
			(arc
				(start 13.690854 -131.949444)
				(mid 13.679743 -131.965978)
				(end 13.675868 -131.985512)
			)
			(arc
				(start 13.675868 -132.669788)
				(mid 13.671967 -132.689311)
				(end 13.660882 -132.705856)
			)
			(arc
				(start 13.574014 -132.792724)
				(mid 13.55748 -132.803835)
				(end 13.537946 -132.80771)
			)
			(arc
				(start 12.25931 -132.80771)
				(mid 12.239787 -132.803809)
				(end 12.223242 -132.792724)
			)
			(arc
				(start 12.113514 -132.682996)
				(mid 12.09698 -132.671885)
				(end 12.077446 -132.66801)
			)
			(arc
				(start 11.45667 -132.66801)
				(mid 11.437147 -132.671911)
				(end 11.420602 -132.682996)
			)
			(arc
				(start 11.409934 -132.693664)
				(mid 11.398823 -132.710198)
				(end 11.394948 -132.729732)
			)
			(arc
				(start 11.394948 -132.847588)
				(mid 11.398849 -132.867111)
				(end 11.409934 -132.883656)
			)
			(arc
				(start 11.428222 -132.901944)
				(mid 11.444756 -132.913055)
				(end 11.46429 -132.91693)
			)
			(arc
				(start 11.917426 -132.91693)
				(mid 11.936949 -132.920831)
				(end 11.953494 -132.931916)
			)
			(arc
				(start 11.979402 -132.957824)
				(mid 11.990513 -132.974358)
				(end 11.994388 -132.993892)
			)
			(arc
				(start 11.994388 -133.086348)
				(mid 11.990487 -133.105871)
				(end 11.979402 -133.122416)
			)
			(arc
				(start 11.963654 -133.138164)
				(mid 11.94712 -133.149275)
				(end 11.927586 -133.15315)
			)
			(arc
				(start 11.49223 -133.15315)
				(mid 11.472707 -133.157051)
				(end 11.456162 -133.168136)
			)
			(arc
				(start 11.422634 -133.201664)
				(mid 11.411523 -133.218198)
				(end 11.407648 -133.237732)
			)
			(arc
				(start 11.407648 -133.353048)
				(mid 11.411549 -133.372571)
				(end 11.422634 -133.389116)
			)
			(arc
				(start 11.430762 -133.397244)
				(mid 11.447296 -133.408355)
				(end 11.46683 -133.41223)
			)
			(arc
				(start 12.194286 -133.41223)
				(mid 12.213809 -133.416131)
				(end 12.230354 -133.427216)
			)
			(arc
				(start 12.345162 -133.542024)
				(mid 12.356273 -133.558558)
				(end 12.360148 -133.578092)
			)
			(arc
				(start 12.360148 -135.181848)
				(mid 12.356247 -135.201371)
				(end 12.345162 -135.217916)
			)
			(xy 11.641328 -135.922004)
			(arc
				(start 11.6078 -135.955532)
				(mid 11.591237 -135.966506)
				(end 11.571732 -135.970264)
			)
			(arc
				(start 10.870692 -135.970264)
				(mid 10.849766 -135.974774)
				(end 10.832592 -135.987536)
			)
			(arc
				(start 10.832592 -135.987536)
				(mid 10.775623 -136.043126)
				(end 10.710672 -136.089136)
			)
			(arc
				(start 10.710672 -136.089136)
				(mid 10.64841 -136.120734)
				(end 10.582402 -136.143492)
			)
			(arc
				(start 10.579354 -136.144508)
				(mid 10.499287 -136.164455)
				(end 10.417048 -136.171178)
			)
			(arc
				(start 10.41654 -136.171178)
				(mid 10.201045 -136.123259)
				(end 10.026142 -135.988552)
			)
			(arc
				(start 10.026142 -135.988552)
				(mid 10.008745 -135.975071)
				(end 9.98728 -135.970264)
			)
			(arc
				(start 9.61517 -135.970264)
				(mid 9.591885 -135.975915)
				(end 9.573768 -135.9916)
			)
			(arc
				(start 9.573768 -135.9916)
				(mid 9.492558 -136.061396)
				(end 9.388348 -136.086088)
			)
			(xy 9.089136 -136.086088)
			(arc
				(start 9.088628 -136.086088)
				(mid 8.927792 -136.020418)
				(end 8.861044 -135.860028)
			)
			(arc
				(start 8.861044 -135.793988)
				(mid 8.852442 -135.765704)
				(end 8.829548 -135.746998)
			)
			(xy 8.815324 -135.740902) (xy 8.785352 -135.746998)
			(arc
				(start 8.735314 -135.797036)
				(mid 8.724203 -135.81357)
				(end 8.720328 -135.833104)
			)
			(arc
				(start 8.720328 -135.840724)
				(mid 8.705449 -135.876645)
				(end 8.669528 -135.891524)
			)
			(xy 8.660384 -135.891524)
			(arc
				(start 8.660384 -136.1059)
				(mid 8.645505 -136.141821)
				(end 8.609584 -136.1567)
			)
			(arc
				(start 8.076692 -136.1567)
				(mid 8.040771 -136.141821)
				(end 8.025892 -136.1059)
			)
			(xy 8.025892 -136.06653) (xy 8.009382 -136.041384)
			(arc
				(start 7.995666 -136.035288)
				(mid 7.946535 -136.007768)
				(end 7.90321 -135.971788)
			)
			(arc
				(start 7.747 -135.815578)
				(mid 7.727363 -135.803293)
				(end 7.704328 -135.8011)
			)
			(arc
				(start 7.704328 -135.8011)
				(mid 7.683425 -135.803336)
				(end 7.662418 -135.804148)
			)
			(arc
				(start 6.238748 -135.804148)
				(mid 6.219225 -135.808049)
				(end 6.20268 -135.819134)
			)
			(arc
				(start 5.980938 -136.040622)
				(mid 5.969827 -136.057156)
				(end 5.965952 -136.07669)
			)
			(arc
				(start 5.965952 -137.19937)
				(mid 5.92868 -137.289352)
				(end 5.838698 -137.326624)
			)
			(arc
				(start 4.619498 -137.326624)
				(mid 4.529516 -137.289352)
				(end 4.492244 -137.19937)
			)
			(arc
				(start 4.492244 -135.698738)
				(mid 4.529516 -135.608756)
				(end 4.619498 -135.571484)
			)
			(arc
				(start 5.55879 -135.571484)
				(mid 5.578313 -135.567583)
				(end 5.594858 -135.556498)
			)
			(arc
				(start 5.87248 -135.278622)
				(mid 5.938826 -135.228285)
				(end 6.016244 -135.197596)
			)
			(xy 6.025134 -135.19531) (xy 6.04012 -135.18515)
			(arc
				(start 6.083808 -135.123682)
				(mid 6.091492 -135.107363)
				(end 6.092952 -135.089392)
			)
			(xy 6.092444 -135.077454)
			(arc
				(start 6.092444 -133.576822)
				(mid 6.129716 -133.48684)
				(end 6.219698 -133.449568)
			)
			(arc
				(start 7.438898 -133.449568)
				(mid 7.52888 -133.48684)
				(end 7.566152 -133.576822)
			)
			(arc
				(start 7.566152 -133.96976)
				(mid 7.581031 -134.005681)
				(end 7.616952 -134.02056)
			)
			(arc
				(start 7.956296 -134.02056)
				(mid 7.992217 -134.005681)
				(end 8.007096 -133.96976)
			)
			(xy 8.027416 -133.94944)
			(arc
				(start 8.271002 -133.94944)
				(mid 8.290525 -133.945539)
				(end 8.30707 -133.934454)
			)
			(arc
				(start 8.557514 -133.683756)
				(mid 8.568625 -133.667222)
				(end 8.5725 -133.647688)
			)
			(arc
				(start 8.5725 -133.507734)
				(mid 8.595934 -133.389926)
				(end 8.66267 -133.290056)
			)
			(arc
				(start 8.816086 -133.13664)
				(mid 8.915738 -133.070088)
				(end 9.033256 -133.046724)
			)
			(arc
				(start 9.722358 -133.046724)
				(mid 9.83985 -133.070152)
				(end 9.939528 -133.13664)
			)
			(arc
				(start 10.137648 -133.33476)
				(mid 10.158795 -133.347358)
				(end 10.183368 -133.348476)
			)
			(xy 10.19556 -133.34619) (xy 10.214864 -133.330188)
			(arc
				(start 10.233914 -133.284468)
				(mid 10.23687 -133.255111)
				(end 10.222992 -133.229096)
			)
			(xy 9.69391 -132.700014) (xy 9.690354 -132.696458) (xy 9.688322 -132.694426) (xy 9.688068 -132.693918)
			(xy 9.686544 -132.692394) (xy 9.674352 -132.678932) (xy 9.67359 -132.67817)
			(arc
				(start 9.645396 -132.665216)
				(mid 9.63499 -132.661646)
				(end 9.62406 -132.66039)
			)
			(arc
				(start 5.319014 -132.66039)
				(mid 5.307121 -132.661802)
				(end 5.2959 -132.665978)
			)
			(arc
				(start 5.2959 -132.665978)
				(mid 5.289191 -132.670052)
				(end 5.2832 -132.675122)
			)
			(arc
				(start 5.138928 -132.819394)
				(mid 5.122394 -132.830505)
				(end 5.10286 -132.83438)
			)
			(arc
				(start 4.492244 -132.83438)
				(mid 4.480351 -132.835792)
				(end 4.46913 -132.839968)
			)
			(arc
				(start 4.46913 -132.839968)
				(mid 4.462421 -132.844042)
				(end 4.45643 -132.849112)
			)
			(arc
				(start 3.95478 -133.350762)
				(mid 3.94972 -133.35676)
				(end 3.945636 -133.363462)
			)
			(arc
				(start 3.945636 -133.363462)
				(mid 3.941481 -133.374689)
				(end 3.940048 -133.386576)
			)
			(xy 3.940048 -137.357104)
			(arc
				(start 3.941064 -137.366756)
				(mid 3.945884 -137.380704)
				(end 3.954526 -137.392664)
			)
			(arc
				(start 4.391914 -137.830052)
				(mid 4.403879 -137.838685)
				(end 4.417822 -137.843514)
			)
			(xy 4.427474 -137.84453)
			(arc
				(start 8.65759 -137.84453)
				(mid 8.677113 -137.848431)
				(end 8.693658 -137.859516)
			)
			(arc
				(start 9.212834 -138.378692)
				(mid 9.224799 -138.387325)
				(end 9.238742 -138.392154)
			)
			(xy 9.248394 -138.39317) (xy 11.055858 -138.39317)
		)
		(stroke
			(width 0)
			(type solid)
		)
		(fill yes)
		(layer "F.Cu")
		(net "GND")
	)
	(gr_poly
		(pts
			(xy 463.826352 -420.311326) (xy 463.836419 -420.310894) (xy 463.855012 -420.303169) (xy 463.86242 -420.29634)
			(xy 464.00339 -420.15537) (xy 464.010233 -420.14797) (xy 464.017958 -420.129372) (xy 464.018376 -420.119302)
			(xy 464.018376 -408.015948) (xy 464.018808 -408.005881) (xy 464.026533 -407.987288) (xy 464.033362 -407.97988)
			(xy 466.736938 -405.276304) (xy 466.743792 -405.268909) (xy 466.751538 -405.25031) (xy 466.751924 -405.240236)
			(xy 466.751924 -374.338342) (xy 466.751491 -374.328276) (xy 466.743764 -374.309684) (xy 466.736938 -374.302274)
			(xy 466.49767 -374.063006) (xy 466.49027 -374.056164) (xy 466.471672 -374.048439) (xy 466.461602 -374.04802)
			(xy 440.535314 -374.04802) (xy 440.525251 -374.048459) (xy 440.506671 -374.056198) (xy 440.499246 -374.063006)
			(xy 440.087512 -374.47474) (xy 440.080671 -374.48214) (xy 440.072949 -374.500738) (xy 440.072526 -374.510808)
			(xy 440.072526 -379.59665) (xy 440.072959 -379.606716) (xy 440.080689 -379.625304) (xy 440.087512 -379.632718)
			(xy 440.340242 -379.885448) (xy 440.34764 -379.892293) (xy 440.366239 -379.900021) (xy 440.37631 -379.900434)
			(xy 464.298538 -379.900434) (xy 464.308604 -379.900865) (xy 464.327196 -379.908593) (xy 464.334606 -379.91542)
			(xy 464.927696 -380.50851) (xy 464.934541 -380.515909) (xy 464.942273 -380.534507) (xy 464.942682 -380.544578)
			(xy 464.942682 -388.84733) (xy 464.942253 -388.857397) (xy 464.934529 -388.875992) (xy 464.927696 -388.883398)
			(xy 464.208876 -389.602218) (xy 464.20148 -389.60907) (xy 464.182881 -389.616808) (xy 464.172808 -389.617204)
			(xy 459.677008 -389.617204) (xy 459.670912 -389.6233) (xy 440.145932 -389.6233) (xy 440.135867 -389.623736)
			(xy 440.117281 -389.631467) (xy 440.109864 -389.638286) (xy 439.97499 -389.77316) (xy 439.968143 -389.780557)
			(xy 439.960417 -389.799157) (xy 439.960004 -389.809228) (xy 439.960004 -390.917938) (xy 439.959574 -390.928005)
			(xy 439.95185 -390.9466) (xy 439.945018 -390.954006) (xy 439.754264 -391.14476) (xy 439.746717 -391.153205)
			(xy 439.739181 -391.17453) (xy 439.741514 -391.197028) (xy 439.746898 -391.20699) (xy 439.76016 -391.229544)
			(xy 439.781063 -391.277508) (xy 439.795217 -391.327879) (xy 439.802356 -391.379711) (xy 439.802778 -391.405872)
			(xy 439.802316 -391.433145) (xy 439.794558 -391.487135) (xy 439.779194 -391.539472) (xy 439.756538 -391.58909)
			(xy 439.727052 -391.634978) (xy 439.691334 -391.676203) (xy 439.650114 -391.711925) (xy 439.604229 -391.741417)
			(xy 439.554614 -391.764079) (xy 439.502279 -391.779448) (xy 439.448289 -391.787213) (xy 439.421016 -391.787634)
			(xy 439.394855 -391.787206) (xy 439.343023 -391.780066) (xy 439.292651 -391.765918) (xy 439.244682 -391.745026)
			(xy 439.222134 -391.731754) (xy 439.21216 -391.726391) (xy 439.189665 -391.724045) (xy 439.168334 -391.731561)
			(xy 439.159904 -391.73912) (xy 438.403746 -392.495278) (xy 438.396345 -392.502118) (xy 438.377747 -392.509836)
			(xy 438.367678 -392.510264) (xy 433.19446 -392.510264) (xy 433.184394 -392.510696) (xy 433.165807 -392.518428)
			(xy 433.158392 -392.52525) (xy 432.641756 -393.041886) (xy 432.634917 -393.049287) (xy 432.627205 -393.067885)
			(xy 432.62677 -393.077954) (xy 432.62677 -395.606016) (xy 440.40679 -395.606016) (xy 440.40679 -393.938252)
			(xy 440.407232 -393.928245) (xy 440.414963 -393.909782) (xy 440.421776 -393.902438) (xy 440.566556 -393.757658)
			(xy 440.573957 -393.750932) (xy 440.592384 -393.743214) (xy 440.60237 -393.742672) (xy 441.254134 -393.742672)
			(xy 441.25896 -393.742831) (xy 441.268422 -393.744752) (xy 441.27293 -393.746482) (xy 441.273184 -393.746482)
			(xy 441.282836 -393.750292) (xy 441.286138 -393.753594) (xy 441.293336 -393.760047) (xy 441.311124 -393.76757)
			(xy 441.330432 -393.767999) (xy 441.348536 -393.761274) (xy 441.355988 -393.755118) (xy 441.356242 -393.755118)
			(xy 441.357766 -393.753594) (xy 441.379356 -393.732258) (xy 441.386757 -393.725532) (xy 441.405184 -393.717814)
			(xy 441.41517 -393.717272) (xy 442.820806 -393.717272) (xy 442.830685 -393.716826) (xy 442.848984 -393.709375)
			(xy 442.856366 -393.702794) (xy 442.856874 -393.702286) (xy 443.173612 -393.385548) (xy 443.180425 -393.378127)
			(xy 443.18816 -393.359544) (xy 443.188598 -393.34948) (xy 443.188598 -391.445496) (xy 443.188995 -391.435423)
			(xy 443.196733 -391.416824) (xy 443.203584 -391.409428) (xy 443.577726 -391.035286) (xy 443.585121 -391.02844)
			(xy 443.603724 -391.020724) (xy 443.613794 -391.0203) (xy 448.847464 -391.0203) (xy 448.857535 -391.020718)
			(xy 448.876134 -391.028441) (xy 448.883532 -391.035286) (xy 449.049648 -391.201402) (xy 449.056474 -391.208813)
			(xy 449.064204 -391.227404) (xy 449.064634 -391.23747) (xy 449.064634 -392.324336) (xy 449.067428 -392.324336)
			(xy 449.067428 -394.598652) (xy 449.066983 -394.608659) (xy 449.059253 -394.627122) (xy 449.052442 -394.634466)
			(xy 448.800474 -394.886434) (xy 448.793096 -394.893189) (xy 448.774651 -394.900891) (xy 448.76466 -394.90142)
			(xy 441.490862 -394.90142) (xy 441.480739 -394.903717) (xy 441.463421 -394.915126) (xy 441.452014 -394.932445)
			(xy 441.449714 -394.942568) (xy 441.449714 -395.606016) (xy 449.49999 -395.606016) (xy 449.49999 -393.938252)
			(xy 449.500432 -393.928245) (xy 449.508163 -393.909782) (xy 449.514976 -393.902438) (xy 449.659756 -393.757658)
			(xy 449.667157 -393.750932) (xy 449.685584 -393.743214) (xy 449.69557 -393.742672) (xy 450.347334 -393.742672)
			(xy 450.357237 -393.743177) (xy 450.375538 -393.750756) (xy 450.382894 -393.757404) (xy 450.383148 -393.757658)
			(xy 450.392546 -393.766802) (xy 450.3999 -393.773283) (xy 450.41806 -393.780617) (xy 450.437644 -393.780617)
			(xy 450.455804 -393.773283) (xy 450.463158 -393.766802) (xy 450.472556 -393.757658) (xy 450.47281 -393.757404)
			(xy 450.480184 -393.750781) (xy 450.498473 -393.743196) (xy 450.50837 -393.742672) (xy 451.36308 -393.742672)
			(xy 451.373149 -393.742244) (xy 451.391747 -393.734526) (xy 451.399148 -393.727686) (xy 451.55739 -393.569444)
			(xy 451.564202 -393.562022) (xy 451.571938 -393.54344) (xy 451.572376 -393.533376) (xy 451.572376 -391.235946)
			(xy 451.572806 -391.225877) (xy 451.580521 -391.207278) (xy 451.587362 -391.199878) (xy 451.727824 -391.059416)
			(xy 451.735223 -391.052575) (xy 451.753823 -391.044855) (xy 451.763892 -391.04443) (xy 457.037186 -391.04443)
			(xy 457.047255 -391.044855) (xy 457.065854 -391.052575) (xy 457.073254 -391.059416) (xy 457.334874 -391.321036)
			(xy 457.341719 -391.328433) (xy 457.349436 -391.347034) (xy 457.34986 -391.357104) (xy 457.34986 -392.68527)
			(xy 457.350114 -392.68527) (xy 457.350114 -394.60424) (xy 457.349666 -394.614246) (xy 457.341939 -394.63271)
			(xy 457.335128 -394.640054) (xy 457.088748 -394.886434) (xy 457.081344 -394.893157) (xy 457.062919 -394.900877)
			(xy 457.052934 -394.90142) (xy 450.584062 -394.90142) (xy 450.573939 -394.903717) (xy 450.556621 -394.915126)
			(xy 450.545214 -394.932445) (xy 450.542914 -394.942568) (xy 450.542914 -395.606016) (xy 450.542454 -395.616021)
			(xy 450.534735 -395.634484) (xy 450.527928 -395.64183) (xy 450.383148 -395.78661) (xy 450.375741 -395.79333)
			(xy 450.357319 -395.801052) (xy 450.347334 -395.801596) (xy 449.69557 -395.801596) (xy 449.685567 -395.801121)
			(xy 449.667105 -395.793411) (xy 449.659756 -395.78661) (xy 449.514976 -395.64183) (xy 449.508247 -395.634431)
			(xy 449.50053 -395.616002) (xy 449.49999 -395.606016) (xy 441.449714 -395.606016) (xy 441.449254 -395.616021)
			(xy 441.441535 -395.634484) (xy 441.434728 -395.64183) (xy 441.289948 -395.78661) (xy 441.282541 -395.79333)
			(xy 441.264119 -395.801052) (xy 441.254134 -395.801596) (xy 440.60237 -395.801596) (xy 440.592367 -395.801121)
			(xy 440.573905 -395.793411) (xy 440.566556 -395.78661) (xy 440.421776 -395.64183) (xy 440.415047 -395.634431)
			(xy 440.40733 -395.616002) (xy 440.40679 -395.606016) (xy 432.62677 -395.606016) (xy 432.62677 -401.752054)
			(xy 432.627202 -401.762121) (xy 432.634927 -401.780714) (xy 432.641756 -401.788122) (xy 432.886358 -402.032724)
			(xy 432.893756 -402.03957) (xy 432.912355 -402.047295) (xy 432.922426 -402.04771) (xy 437.45531 -402.04771)
			(xy 437.46538 -402.047286) (xy 437.483982 -402.03957) (xy 437.491378 -402.032724) (xy 438.669176 -400.854926)
			(xy 438.676013 -400.847525) (xy 438.683725 -400.828926) (xy 438.684162 -400.818858) (xy 438.684162 -398.365218)
			(xy 438.684602 -398.355156) (xy 438.692344 -398.336579) (xy 438.699148 -398.32915) (xy 439.730642 -397.297656)
			(xy 439.73804 -397.29081) (xy 439.756639 -397.283082) (xy 439.76671 -397.28267) (xy 441.918344 -397.28267)
			(xy 441.93714 -397.27505) (xy 441.944252 -397.267684) (xy 441.957968 -397.253968) (xy 441.964813 -397.246569)
			(xy 441.972541 -397.227971) (xy 441.972954 -397.2179) (xy 441.972954 -396.57401) (xy 441.973377 -396.56394)
			(xy 441.981095 -396.545338) (xy 441.98794 -396.537942) (xy 442.059314 -396.466568) (xy 442.06671 -396.459717)
			(xy 442.085309 -396.451976) (xy 442.095382 -396.451582) (xy 442.608208 -396.451582) (xy 442.609732 -396.450058)
			(xy 444.16345 -396.450058) (xy 444.173515 -396.450492) (xy 444.192101 -396.458225) (xy 444.199518 -396.465044)
			(xy 444.220346 -396.485872) (xy 444.227187 -396.493272) (xy 444.234904 -396.511871) (xy 444.235332 -396.52194)
			(xy 444.235332 -397.292576) (xy 444.234827 -397.302627) (xy 444.227107 -397.321189) (xy 444.220346 -397.328644)
			(xy 444.021718 -397.527272) (xy 444.014316 -397.534109) (xy 443.995718 -397.541818) (xy 443.98565 -397.542258)
			(xy 443.41796 -397.542258) (xy 443.407955 -397.542752) (xy 443.389469 -397.550418) (xy 443.375319 -397.564568)
			(xy 443.367653 -397.583053) (xy 443.36716 -397.593058) (xy 443.36716 -398.85493) (xy 443.36673 -398.864997)
			(xy 443.359004 -398.88359) (xy 443.352174 -398.890998) (xy 443.310772 -398.9324) (xy 443.303361 -398.93908)
			(xy 443.284925 -398.946652) (xy 443.274958 -398.947132) (xy 442.438028 -398.947132) (xy 442.427964 -398.947569)
			(xy 442.409382 -398.955305) (xy 442.40196 -398.962118) (xy 442.401452 -398.962626) (xy 442.394604 -398.970024)
			(xy 442.386871 -398.988622) (xy 442.386466 -398.998694) (xy 442.386466 -399.130012) (xy 442.386956 -399.140021)
			(xy 442.394616 -399.158514) (xy 442.408767 -399.172672) (xy 442.427258 -399.18034) (xy 442.437266 -399.180812)
			(xy 443.279784 -399.180812) (xy 443.289847 -399.181251) (xy 443.308428 -399.188988) (xy 443.315852 -399.195798)
			(xy 443.361064 -399.24101) (xy 443.367913 -399.248407) (xy 443.375649 -399.267006) (xy 443.37605 -399.277078)
			(xy 443.37605 -399.45818) (xy 443.376534 -399.468194) (xy 443.384188 -399.486701) (xy 443.39834 -399.500873)
			(xy 443.416837 -399.508552) (xy 443.42685 -399.50898) (xy 445.089534 -399.50898) (xy 445.099536 -399.508486)
			(xy 445.118012 -399.50082) (xy 445.13215 -399.486667) (xy 445.139797 -399.468182) (xy 445.140334 -399.45818)
			(xy 445.140334 -397.267938) (xy 445.140769 -397.257874) (xy 445.148503 -397.239289) (xy 445.15532 -397.23187)
			(xy 445.222122 -397.165068) (xy 445.229518 -397.158218) (xy 445.248117 -397.150481) (xy 445.25819 -397.150082)
			(xy 447.883788 -397.150082) (xy 447.89386 -397.150502) (xy 447.912469 -397.158212) (xy 447.919856 -397.165068)
			(xy 448.016376 -397.261588) (xy 448.023778 -397.268424) (xy 448.042376 -397.276132) (xy 448.052444 -397.276574)
			(xy 449.32727 -397.276574) (xy 449.337321 -397.277078) (xy 449.355885 -397.284797) (xy 449.363338 -397.29156)
			(xy 449.47332 -397.401542) (xy 449.480717 -397.408391) (xy 449.499316 -397.416128) (xy 449.509388 -397.416528)
			(xy 450.888354 -397.416528) (xy 450.90715 -397.408908) (xy 450.914262 -397.401542) (xy 451.03669 -397.279114)
			(xy 451.043524 -397.271711) (xy 451.051229 -397.253113) (xy 451.051676 -397.243046) (xy 451.051676 -396.57401)
			(xy 451.052097 -396.563938) (xy 451.059806 -396.545329) (xy 451.066662 -396.537942) (xy 451.138036 -396.466568)
			(xy 451.145433 -396.45972) (xy 451.164032 -396.451988) (xy 451.174104 -396.451582) (xy 451.68693 -396.451582)
			(xy 451.688454 -396.450058) (xy 453.242172 -396.450058) (xy 453.252235 -396.450496) (xy 453.270815 -396.458235)
			(xy 453.27824 -396.465044) (xy 453.299068 -396.485872) (xy 453.305907 -396.493273) (xy 453.31362 -396.511871)
			(xy 453.314054 -396.52194) (xy 453.314054 -397.292576) (xy 453.313616 -397.302639) (xy 453.305877 -397.321219)
			(xy 453.299068 -397.328644) (xy 453.10044 -397.527272) (xy 453.09304 -397.534112) (xy 453.074441 -397.541829)
			(xy 453.064372 -397.542258) (xy 452.458836 -397.542258) (xy 452.456804 -397.54429) (xy 452.456804 -398.829784)
			(xy 452.456315 -398.839745) (xy 452.448723 -398.858165) (xy 452.442072 -398.865598) (xy 452.377048 -398.930622)
			(xy 452.369651 -398.937469) (xy 452.351051 -398.945197) (xy 452.34098 -398.945608) (xy 451.532752 -398.945608)
			(xy 451.522686 -398.94604) (xy 451.504095 -398.953768) (xy 451.496684 -398.960594) (xy 451.494652 -398.962626)
			(xy 451.487804 -398.970024) (xy 451.480071 -398.988622) (xy 451.479666 -398.998694) (xy 451.479666 -399.130012)
			(xy 451.480156 -399.140021) (xy 451.487816 -399.158514) (xy 451.501967 -399.172672) (xy 451.520458 -399.18034)
			(xy 451.530466 -399.180812) (xy 452.310246 -399.180812) (xy 452.320312 -399.181244) (xy 452.338903 -399.188971)
			(xy 452.346314 -399.195798) (xy 452.443342 -399.292826) (xy 452.450191 -399.300223) (xy 452.457925 -399.318822)
			(xy 452.458328 -399.328894) (xy 452.458328 -399.498566) (xy 452.46036 -399.500598) (xy 454.169526 -399.500598)
			(xy 454.17953 -399.500105) (xy 454.198013 -399.492441) (xy 454.212157 -399.478289) (xy 454.219811 -399.459802)
			(xy 454.220326 -399.449798) (xy 454.220326 -397.266668) (xy 454.220756 -397.256601) (xy 454.228481 -397.238007)
			(xy 454.235312 -397.2306) (xy 454.300844 -397.165068) (xy 454.308242 -397.158221) (xy 454.326841 -397.150492)
			(xy 454.336912 -397.150082) (xy 458.373734 -397.150082) (xy 458.383802 -397.150511) (xy 458.402399 -397.158232)
			(xy 458.409802 -397.165068) (xy 458.67701 -397.432276) (xy 458.683854 -397.439674) (xy 458.691575 -397.458274)
			(xy 458.691996 -397.468344) (xy 458.691996 -405.124666) (xy 458.692431 -405.134731) (xy 458.700162 -405.153318)
			(xy 458.706982 -405.160734) (xy 458.71384 -405.167592) (xy 458.71384 -412.90621) (xy 458.713413 -412.916278)
			(xy 458.70569 -412.934874) (xy 458.698854 -412.942278) (xy 458.41793 -413.223202) (xy 458.410528 -413.230037)
			(xy 458.391929 -413.237746) (xy 458.381862 -413.238188) (xy 455.295 -413.238188) (xy 455.284929 -413.238611)
			(xy 455.266324 -413.246324) (xy 455.258932 -413.253174) (xy 454.950068 -413.562038) (xy 454.94322 -413.569435)
			(xy 454.935489 -413.588034) (xy 454.935082 -413.598106) (xy 454.935082 -419.92423) (xy 454.93551 -419.934298)
			(xy 454.94323 -419.952896) (xy 454.950068 -419.960298) (xy 455.28611 -420.29634) (xy 455.293506 -420.303192)
			(xy 455.312105 -420.310932) (xy 455.322178 -420.311326)
		)
		(stroke
			(width 0)
			(type solid)
		)
		(fill yes)
		(layer "F.Cu")
		(net "GND")
	)
	(gr_poly
		(pts
			(xy 445.369188 -77.85354) (xy 445.37906 -77.853068) (xy 445.397345 -77.845612) (xy 445.404748 -77.839062)
			(xy 446.033906 -77.209904) (xy 446.041305 -77.203058) (xy 446.059903 -77.195325) (xy 446.069974 -77.194918)
			(xy 467.454996 -77.194918) (xy 467.464875 -77.194463) (xy 467.483181 -77.187027) (xy 467.490556 -77.18044)
			(xy 468.83701 -75.833986) (xy 468.837518 -75.833478) (xy 468.844109 -75.8261) (xy 468.851576 -75.807801)
			(xy 468.851996 -75.797918) (xy 468.851996 -54.049168) (xy 468.851561 -54.04001) (xy 468.845053 -54.022884)
			(xy 468.832975 -54.009108) (xy 468.825072 -54.004464) (xy 468.733378 -53.955696) (xy 468.705438 -53.95722)
			(xy 468.6935 -53.965094) (xy 468.627109 -54.009265) (xy 468.490633 -54.09178) (xy 468.350245 -54.167449)
			(xy 468.20629 -54.236088) (xy 468.059119 -54.297529) (xy 467.909091 -54.351622) (xy 467.756573 -54.398234)
			(xy 467.601937 -54.437253) (xy 467.445563 -54.468581) (xy 467.287831 -54.492144) (xy 467.129128 -54.507882)
			(xy 466.969841 -54.515759) (xy 466.8901 -54.516274) (xy 466.877146 -54.516274) (xy 466.795613 -54.515434)
			(xy 466.632784 -54.506542) (xy 466.470613 -54.489435) (xy 466.309512 -54.464157) (xy 466.149895 -54.430772)
			(xy 465.992168 -54.389366) (xy 465.836734 -54.340045) (xy 465.68399 -54.282934) (xy 465.534327 -54.218179)
			(xy 465.388126 -54.145946) (xy 465.245761 -54.066419) (xy 465.107596 -53.979802) (xy 464.973983 -53.886315)
			(xy 464.845263 -53.786197) (xy 464.721766 -53.679704) (xy 464.603807 -53.567108) (xy 464.491687 -53.448696)
			(xy 464.385692 -53.324771) (xy 464.286093 -53.19565) (xy 464.193144 -53.061661) (xy 464.107084 -52.923149)
			(xy 464.02813 -52.780465) (xy 463.956487 -52.633974) (xy 463.892335 -52.484051) (xy 463.835839 -52.331079)
			(xy 463.787144 -52.175448) (xy 463.746373 -52.017555) (xy 463.713632 -51.857805) (xy 463.689002 -51.696604)
			(xy 463.672548 -51.534365) (xy 463.664311 -51.371502) (xy 463.663792 -51.289966) (xy 463.664279 -51.210777)
			(xy 463.672052 -51.05259) (xy 463.687577 -50.894975) (xy 463.710817 -50.738311) (xy 463.741717 -50.582977)
			(xy 463.780201 -50.429346) (xy 463.826177 -50.277788) (xy 463.879534 -50.128669) (xy 463.940144 -49.982347)
			(xy 464.00786 -49.839176) (xy 464.08252 -49.699499) (xy 464.163943 -49.563654) (xy 464.251934 -49.431969)
			(xy 464.346281 -49.304759) (xy 464.446755 -49.182332) (xy 464.553116 -49.064982) (xy 464.665107 -48.952993)
			(xy 464.782457 -48.846633) (xy 464.904886 -48.74616) (xy 465.032096 -48.651815) (xy 465.163783 -48.563825)
			(xy 465.299629 -48.482403) (xy 465.439306 -48.407745) (xy 465.582478 -48.34003) (xy 465.7288 -48.279422)
			(xy 465.87792 -48.226066) (xy 466.029479 -48.180092) (xy 466.18311 -48.141609) (xy 466.338445 -48.110711)
			(xy 466.495109 -48.087473) (xy 466.652724 -48.071949) (xy 466.810911 -48.064178) (xy 466.8901 -48.063658)
			(xy 466.96984 -48.064159) (xy 467.129124 -48.072057) (xy 467.287824 -48.087813) (xy 467.445551 -48.111389)
			(xy 467.601922 -48.142728) (xy 467.756553 -48.181753) (xy 467.909068 -48.228368) (xy 468.059094 -48.28246)
			(xy 468.206265 -48.343898) (xy 468.350222 -48.41253) (xy 468.490612 -48.488189) (xy 468.627094 -48.570691)
			(xy 468.6935 -48.614838) (xy 468.705438 -48.622712) (xy 468.733378 -48.624236) (xy 468.825072 -48.575468)
			(xy 468.832998 -48.570839) (xy 468.845136 -48.55709) (xy 468.851618 -48.539934) (xy 468.851996 -48.530764)
			(xy 468.851996 -44.615608) (xy 468.851574 -44.605537) (xy 468.843861 -44.586931) (xy 468.83701 -44.57954)
			(xy 467.195662 -42.938192) (xy 467.18855 -42.930826) (xy 467.169754 -42.923206) (xy 459.693264 -42.923206)
			(xy 459.682828 -42.923707) (xy 459.66369 -42.932033) (xy 459.649483 -42.947322) (xy 459.645512 -42.956988)
			(xy 459.608174 -43.062906) (xy 459.61681 -43.093386) (xy 459.62951 -43.1038) (xy 459.651265 -43.122019)
			(xy 459.689665 -43.163795) (xy 459.721456 -43.210796) (xy 459.745936 -43.261987) (xy 459.762566 -43.316239)
			(xy 459.770979 -43.372355) (xy 459.771496 -43.400726) (xy 459.77101 -43.427977) (xy 459.763254 -43.481925)
			(xy 459.747899 -43.53422) (xy 459.725257 -43.583797) (xy 459.695791 -43.629647) (xy 459.6601 -43.670838)
			(xy 459.618909 -43.706529) (xy 459.573059 -43.735995) (xy 459.523482 -43.758637) (xy 459.471187 -43.773992)
			(xy 459.417239 -43.781748) (xy 459.362737 -43.781748) (xy 459.308789 -43.773992) (xy 459.256494 -43.758637)
			(xy 459.206917 -43.735995) (xy 459.161067 -43.706529) (xy 459.119876 -43.670838) (xy 459.084185 -43.629647)
			(xy 459.054719 -43.583797) (xy 459.032077 -43.53422) (xy 459.016722 -43.481925) (xy 459.008966 -43.427977)
			(xy 459.00848 -43.400726) (xy 459.008998 -43.372354) (xy 459.017401 -43.316235) (xy 459.034026 -43.26198)
			(xy 459.058505 -43.210787) (xy 459.090299 -43.163785) (xy 459.128705 -43.122013) (xy 459.150466 -43.1038)
			(xy 459.163166 -43.09364) (xy 459.171802 -43.062906) (xy 459.134464 -42.956988) (xy 459.130477 -42.947345)
			(xy 459.116238 -42.93212) (xy 459.097133 -42.923781) (xy 459.086712 -42.923206) (xy 450.785992 -42.923206)
			(xy 450.775923 -42.923631) (xy 450.757321 -42.931348) (xy 450.749924 -42.938192) (xy 449.581016 -44.1071)
			(xy 443.43066 -44.1071) (xy 429.4505 -44.1071) (xy 429.14316 -44.41444) (xy 429.14316 -55.2577) (xy 430.3649 -55.2577)
			(xy 430.3649 -54.0766) (xy 430.3649 -46.44644) (xy 431.15738 -45.65396) (xy 442.62421 -45.65396)
			(xy 444.14821 -47.17796) (xy 444.148718 -47.178468) (xy 444.156099 -47.185047) (xy 444.1744 -47.192486)
			(xy 444.184278 -47.192946) (xy 450.737478 -47.192946) (xy 450.747357 -47.192492) (xy 450.765656 -47.185047)
			(xy 450.773038 -47.178468) (xy 450.873876 -47.07763) (xy 450.874384 -47.077122) (xy 450.880948 -47.06973)
			(xy 450.888395 -47.051437) (xy 450.888862 -47.041562) (xy 450.888862 -45.017944) (xy 450.889294 -45.007875)
			(xy 450.897008 -44.989276) (xy 450.903848 -44.981876) (xy 451.57263 -44.313094) (xy 451.580025 -44.306248)
			(xy 451.598628 -44.298532) (xy 451.608698 -44.298108) (xy 458.78877 -44.298108) (xy 458.797471 -44.297744)
			(xy 458.813876 -44.291944) (xy 458.827381 -44.280973) (xy 458.832204 -44.273724) (xy 458.8471 -44.250012)
			(xy 458.882747 -44.206827) (xy 458.924327 -44.16932) (xy 458.970945 -44.138298) (xy 459.0216 -44.114428)
			(xy 459.075201 -44.098224) (xy 459.130596 -44.090034) (xy 459.186592 -44.090034) (xy 459.241987 -44.098224)
			(xy 459.295588 -44.114428) (xy 459.346243 -44.138298) (xy 459.392861 -44.16932) (xy 459.434441 -44.206827)
			(xy 459.470088 -44.250012) (xy 459.484984 -44.273724) (xy 459.489854 -44.280938) (xy 459.503344 -44.291909)
			(xy 459.519724 -44.297744) (xy 459.528418 -44.298108) (xy 461.34147 -44.298108) (xy 461.351538 -44.298547)
			(xy 461.370136 -44.306258) (xy 461.377538 -44.313094) (xy 461.463898 -44.399454) (xy 461.473243 -44.4078)
			(xy 461.497219 -44.414984) (xy 461.509618 -44.41317) (xy 461.605122 -44.39412) (xy 461.624426 -44.378118)
			(xy 461.629506 -44.36618) (xy 461.640681 -44.34032) (xy 461.669519 -44.291926) (xy 461.705161 -44.248301)
			(xy 461.746833 -44.210393) (xy 461.793627 -44.179028) (xy 461.844527 -44.154887) (xy 461.898423 -44.138496)
			(xy 461.954145 -44.130211) (xy 461.982312 -44.129706) (xy 462.009566 -44.130144) (xy 462.063518 -44.137903)
			(xy 462.115818 -44.153261) (xy 462.165399 -44.175906) (xy 462.211253 -44.205377) (xy 462.252446 -44.241073)
			(xy 462.288139 -44.282268) (xy 462.317607 -44.328124) (xy 462.340248 -44.377707) (xy 462.355603 -44.430007)
			(xy 462.363358 -44.48396) (xy 462.36382 -44.511214) (xy 462.363289 -44.539378) (xy 462.354992 -44.595093)
			(xy 462.338594 -44.648982) (xy 462.314453 -44.699876) (xy 462.283093 -44.746668) (xy 462.245194 -44.788341)
			(xy 462.201581 -44.82399) (xy 462.153202 -44.852841) (xy 462.127346 -44.86402) (xy 462.115408 -44.8691)
			(xy 462.099406 -44.888404) (xy 462.080356 -44.983908) (xy 462.078926 -44.993125) (xy 462.082054 -45.011497)
			(xy 462.086452 -45.019722) (xy 462.089754 -45.02531) (xy 462.661254 -45.59681) (xy 462.668085 -45.604218)
			(xy 462.675811 -45.622811) (xy 462.67624 -45.632878) (xy 462.67624 -53.426614) (xy 462.675838 -53.436686)
			(xy 462.668103 -53.455285) (xy 462.661254 -53.462682) (xy 462.139538 -53.984398) (xy 462.132119 -53.991214)
			(xy 462.113534 -53.998948) (xy 462.10347 -53.999384) (xy 461.253078 -53.999384) (xy 461.243007 -53.998974)
			(xy 461.224409 -53.991243) (xy 461.21701 -53.984398) (xy 460.666846 -53.434234) (xy 460.660035 -53.426811)
			(xy 460.652297 -53.40823) (xy 460.65186 -53.398166) (xy 460.65186 -52.59451) (xy 460.65144 -52.58444)
			(xy 460.643717 -52.565841) (xy 460.636874 -52.558442) (xy 460.585566 -52.507134) (xy 460.578454 -52.499768)
			(xy 460.559658 -52.492148) (xy 459.298802 -52.492148) (xy 459.288731 -52.491736) (xy 459.270132 -52.484007)
			(xy 459.262734 -52.477162) (xy 459.173326 -52.387754) (xy 459.166521 -52.380326) (xy 459.15878 -52.361748)
			(xy 459.15834 -52.351686) (xy 459.15834 -51.674268) (xy 459.15326 -51.669188) (xy 457.52512 -51.669188)
			(xy 457.52258 -51.666648) (xy 457.52258 -50.767488) (xy 457.52512 -50.764948) (xy 458.27188 -50.764948)
			(xy 458.27442 -50.762408) (xy 458.27442 -48.798988) (xy 458.26934 -48.793908) (xy 454.72858 -48.793908)
			(xy 454.72604 -48.796448) (xy 454.72604 -50.414428) (xy 454.726397 -50.424456) (xy 454.734084 -50.442981)
			(xy 454.748276 -50.457154) (xy 454.766811 -50.464816) (xy 454.77684 -50.465228) (xy 455.87412 -50.465228)
			(xy 455.87666 -50.467768) (xy 455.87666 -53.132228) (xy 455.87412 -53.134768) (xy 455.471784 -53.134768)
			(xy 455.46359 -53.135076) (xy 455.448045 -53.14026) (xy 455.441304 -53.144928) (xy 455.437494 -53.147976)
			(xy 455.42073 -53.16474) (xy 455.41337 -53.171382) (xy 455.39507 -53.178957) (xy 455.38517 -53.179472)
			(xy 452.30796 -53.179472) (xy 452.299463 -53.180427) (xy 452.283761 -53.187167) (xy 452.277226 -53.19268)
			(xy 452.264018 -53.205888) (xy 452.256668 -53.212541) (xy 452.23836 -53.220109) (xy 452.228458 -53.22062)
			(xy 452.018908 -53.22062) (xy 452.014844 -53.216556) (xy 449.205604 -53.216556) (xy 449.200524 -53.218588)
			(xy 444.088012 -53.218588) (xy 441.445396 -55.861204) (xy 441.445396 -55.88508) (xy 430.99228 -55.88508)
			(xy 430.3649 -55.2577) (xy 429.14316 -55.2577) (xy 429.14316 -57.03316) (xy 429.387 -57.277) (xy 430.53 -57.277)
			(xy 430.657 -57.404) (xy 430.911 -57.658) (xy 430.911 -58.253376) (xy 453.361552 -58.253376) (xy 453.361552 -53.68544)
			(xy 453.361998 -53.675434) (xy 453.369727 -53.656971) (xy 453.376538 -53.649626) (xy 453.607424 -53.41874)
			(xy 453.614797 -53.412116) (xy 453.633087 -53.404531) (xy 453.642984 -53.404008) (xy 454.627996 -53.404008)
			(xy 454.628758 -53.403246) (xy 454.636169 -53.396531) (xy 454.654588 -53.388804) (xy 454.664572 -53.38826)
			(xy 458.714348 -53.38826) (xy 458.724354 -53.388711) (xy 458.742817 -53.396437) (xy 458.750162 -53.403246)
			(xy 458.798422 -53.451506) (xy 458.80582 -53.458349) (xy 458.824421 -53.466067) (xy 458.83449 -53.466492)
			(xy 458.990192 -53.466492) (xy 459.000198 -53.466994) (xy 459.018688 -53.47465) (xy 459.032841 -53.488798)
			(xy 459.040502 -53.507286) (xy 459.040992 -53.517292) (xy 459.040992 -53.591968) (xy 459.040554 -53.601988)
			(xy 459.032893 -53.620506) (xy 459.018726 -53.63468) (xy 459.000212 -53.642349) (xy 458.990192 -53.642768)
			(xy 458.988668 -53.642768) (xy 458.978694 -53.643254) (xy 458.960255 -53.650871) (xy 458.946114 -53.664942)
			(xy 458.938405 -53.683342) (xy 458.937868 -53.693314) (xy 458.937868 -58.123836) (xy 458.937404 -58.13384)
			(xy 458.929687 -58.152303) (xy 458.922882 -58.15965) (xy 458.605382 -58.47715) (xy 458.598003 -58.483904)
			(xy 458.579559 -58.491605) (xy 458.569568 -58.492136) (xy 453.600312 -58.492136) (xy 453.590304 -58.491707)
			(xy 453.571841 -58.483966) (xy 453.564498 -58.47715) (xy 453.376538 -58.28919) (xy 453.3698 -58.281798)
			(xy 453.362087 -58.263364) (xy 453.361552 -58.253376) (xy 430.911 -58.253376) (xy 430.911 -59.563)
			(xy 431.165 -59.817) (xy 437.388 -59.817) (xy 437.642 -60.071) (xy 437.642 -65.413382) (xy 437.896 -65.667382)
			(xy 463.966052 -65.667382) (xy 463.976118 -65.667814) (xy 463.994711 -65.67554) (xy 464.00212 -65.682368)
			(xy 464.715606 -66.395854) (xy 464.722443 -66.403256) (xy 464.730157 -66.421854) (xy 464.730592 -66.431922)
			(xy 464.730592 -73.442322) (xy 464.730165 -73.45239) (xy 464.722444 -73.470988) (xy 464.715606 -73.47839)
			(xy 464.243674 -73.950322) (xy 464.236278 -73.957173) (xy 464.217679 -73.96491) (xy 464.207606 -73.965308)
			(xy 463.58683 -73.965308) (xy 463.58429 -73.967848) (xy 446.546986 -73.967848) (xy 446.544446 -73.965308)
			(xy 445.995552 -73.965308) (xy 445.985485 -73.964877) (xy 445.966893 -73.957151) (xy 445.959484 -73.950322)
			(xy 445.713358 -73.704196) (xy 445.706246 -73.69683) (xy 445.68745 -73.68921) (xy 444.561468 -73.68921)
			(xy 444.551401 -73.689639) (xy 444.532806 -73.697363) (xy 444.5254 -73.704196) (xy 444.003176 -74.22642)
			(xy 443.99581 -74.233532) (xy 443.98819 -74.252328) (xy 443.98819 -74.520044) (xy 444.46139 -74.520044)
			(xy 444.465461 -74.464422) (xy 444.477587 -74.409985) (xy 444.49751 -74.357894) (xy 444.524806 -74.309259)
			(xy 444.558892 -74.265116) (xy 444.599041 -74.226407) (xy 444.644399 -74.193956) (xy 444.693999 -74.168455)
			(xy 444.746783 -74.150448) (xy 444.801626 -74.140318) (xy 444.85736 -74.138281) (xy 444.912797 -74.144381)
			(xy 444.966754 -74.158487) (xy 445.018083 -74.180299) (xy 445.065689 -74.209353) (xy 445.108557 -74.245028)
			(xy 445.145774 -74.286565) (xy 445.176547 -74.333078) (xy 445.200219 -74.383575) (xy 445.216287 -74.436982)
			(xy 445.224407 -74.492158) (xy 445.224916 -74.520044) (xy 445.224407 -74.54793) (xy 445.216287 -74.603106)
			(xy 445.200219 -74.656513) (xy 445.176547 -74.70701) (xy 445.145774 -74.753523) (xy 445.108557 -74.79506)
			(xy 445.065689 -74.830735) (xy 445.018083 -74.859789) (xy 444.966754 -74.881601) (xy 444.912797 -74.895707)
			(xy 444.85736 -74.901807) (xy 444.801626 -74.89977) (xy 444.746783 -74.88964) (xy 444.693999 -74.871633)
			(xy 444.644399 -74.846132) (xy 444.599041 -74.813681) (xy 444.558892 -74.774972) (xy 444.524806 -74.730829)
			(xy 444.49751 -74.682194) (xy 444.477587 -74.630103) (xy 444.465461 -74.575666) (xy 444.46139 -74.520044)
			(xy 443.98819 -74.520044) (xy 443.98819 -77.55636) (xy 443.988657 -77.566234) (xy 443.99611 -77.584523)
			(xy 444.002668 -77.59192) (xy 444.249302 -77.838554) (xy 444.24981 -77.839062) (xy 444.257189 -77.84565)
			(xy 444.275488 -77.853115) (xy 444.28537 -77.85354)
		)
		(stroke
			(width 0)
			(type solid)
		)
		(fill yes)
		(layer "F.Cu")
		(net "GND")
	)
	(gr_poly
		(pts
			(xy 80.104234 -182.515002) (xy 80.114301 -182.514573) (xy 80.132897 -182.50685) (xy 80.140302 -182.500016)
			(xy 80.16113 -182.479188) (xy 80.168526 -182.472337) (xy 80.187125 -182.464599) (xy 80.197198 -182.464202)
			(xy 81.852516 -182.464202) (xy 81.862522 -182.463711) (xy 81.881008 -182.456049) (xy 81.895157 -182.441896)
			(xy 81.902814 -182.423408) (xy 81.903316 -182.413402) (xy 81.903316 -180.53431) (xy 81.90283 -180.5243)
			(xy 81.895173 -180.505802) (xy 81.88102 -180.491642) (xy 81.862526 -180.483975) (xy 81.852516 -180.48351)
			(xy 80.47482 -180.48351) (xy 80.464756 -180.483073) (xy 80.446172 -180.475339) (xy 80.438752 -180.468524)
			(xy 80.40624 -180.436012) (xy 80.399387 -180.428616) (xy 80.391642 -180.410018) (xy 80.391254 -180.399944)
			(xy 80.391254 -179.453794) (xy 80.390828 -179.443725) (xy 80.383107 -179.425127) (xy 80.376268 -179.417726)
			(xy 79.929736 -178.971194) (xy 79.84744 -178.889152) (xy 79.840597 -178.881753) (xy 79.832874 -178.863154)
			(xy 79.832454 -178.853084) (xy 79.832454 -176.902618) (xy 79.832894 -176.892556) (xy 79.840635 -176.873978)
			(xy 79.84744 -176.86655) (xy 80.007968 -176.706022) (xy 80.015334 -176.69891) (xy 80.022954 -176.680114)
			(xy 80.022954 -176.082452) (xy 80.023387 -176.072387) (xy 80.03112 -176.0538) (xy 80.03794 -176.046384)
			(xy 80.147668 -175.936656) (xy 80.155067 -175.929814) (xy 80.173666 -175.922096) (xy 80.183736 -175.92167)
			(xy 81.48193 -175.92167) (xy 81.491998 -175.922098) (xy 81.510598 -175.929816) (xy 81.517998 -175.936656)
			(xy 82.364072 -176.78273) (xy 82.371471 -176.789573) (xy 82.39007 -176.797292) (xy 82.40014 -176.797716)
			(xy 86.228428 -176.797716) (xy 86.238496 -176.798145) (xy 86.257091 -176.805868) (xy 86.264496 -176.812702)
			(xy 86.510368 -177.058574) (xy 86.517206 -177.065975) (xy 86.524919 -177.084574) (xy 86.525354 -177.094642)
			(xy 86.525354 -182.121556) (xy 86.525789 -182.13162) (xy 86.533524 -182.150205) (xy 86.54034 -182.157624)
			(xy 86.802214 -182.419498) (xy 86.809326 -182.426864) (xy 86.828122 -182.434484) (xy 88.514174 -182.434484)
			(xy 88.524238 -182.434047) (xy 88.542821 -182.426312) (xy 88.550242 -182.419498) (xy 88.573356 -182.396384)
			(xy 88.573356 -182.39613) (xy 90.246454 -182.39613) (xy 90.256484 -182.395719) (xy 90.275022 -182.388058)
			(xy 90.289216 -182.373885) (xy 90.296904 -182.355359) (xy 90.297254 -182.34533) (xy 90.297254 -180.466238)
			(xy 90.29684 -180.456215) (xy 90.289176 -180.437693) (xy 90.275 -180.42352) (xy 90.256477 -180.415858)
			(xy 90.246454 -180.415438) (xy 88.8746 -180.415438) (xy 88.864531 -180.415013) (xy 88.845933 -180.407292)
			(xy 88.838532 -180.400452) (xy 88.7857 -180.34762) (xy 88.778866 -180.340217) (xy 88.771161 -180.321619)
			(xy 88.770714 -180.311552) (xy 88.770714 -179.438808) (xy 88.770293 -179.428737) (xy 88.762582 -179.410129)
			(xy 88.755728 -179.40274) (xy 88.232234 -178.879246) (xy 88.225392 -178.871846) (xy 88.217672 -178.853248)
			(xy 88.217248 -178.843178) (xy 88.217248 -177.13706) (xy 88.21768 -177.126994) (xy 88.22541 -177.108405)
			(xy 88.232234 -177.100992) (xy 88.574118 -176.759108) (xy 88.581517 -176.752264) (xy 88.600115 -176.744535)
			(xy 88.610186 -176.744122) (xy 94.674182 -176.744122) (xy 94.684245 -176.744561) (xy 94.702826 -176.752298)
			(xy 94.71025 -176.759108) (xy 94.955868 -177.004726) (xy 94.962714 -177.012124) (xy 94.970444 -177.030723)
			(xy 94.970854 -177.040794) (xy 94.970854 -182.30723) (xy 94.971284 -182.317297) (xy 94.979012 -182.335888)
			(xy 94.98584 -182.343298) (xy 95.08744 -182.444898) (xy 95.094552 -182.452264) (xy 95.113348 -182.459884)
			(xy 96.897952 -182.459884) (xy 96.908018 -182.459451) (xy 96.926607 -182.451721) (xy 96.93402 -182.444898)
			(xy 96.95053 -182.428388) (xy 96.957926 -182.421537) (xy 96.976525 -182.413799) (xy 96.986598 -182.413402)
			(xy 98.641154 -182.413402) (xy 98.651182 -182.41299) (xy 98.669715 -182.405329) (xy 98.683902 -182.391155)
			(xy 98.691581 -182.372629) (xy 98.691954 -182.362602) (xy 98.691954 -180.48351) (xy 98.691535 -180.473491)
			(xy 98.683866 -180.454978) (xy 98.669691 -180.440814) (xy 98.651174 -180.433157) (xy 98.641154 -180.43271)
			(xy 97.24136 -180.43271) (xy 97.231293 -180.43228) (xy 97.212698 -180.424557) (xy 97.205292 -180.417724)
			(xy 97.143316 -180.355748) (xy 97.136476 -180.348348) (xy 97.128758 -180.329749) (xy 97.12833 -180.31968)
			(xy 97.12833 -179.42433) (xy 97.127826 -179.414279) (xy 97.120108 -179.395715) (xy 97.113344 -179.388262)
			(xy 96.7232 -178.998118) (xy 96.716367 -178.990715) (xy 96.708662 -178.972117) (xy 96.708214 -178.96205)
			(xy 96.708214 -177.236374) (xy 96.708642 -177.226306) (xy 96.716365 -177.20771) (xy 96.7232 -177.200306)
			(xy 97.149412 -176.774094) (xy 97.156811 -176.76725) (xy 97.175409 -176.759521) (xy 97.18548 -176.759108)
			(xy 101.49586 -176.759108) (xy 101.941376 -176.313592) (xy 102.406196 -176.313592) (xy 103.153972 -176.313592)
			(xy 103.164037 -176.314028) (xy 103.182623 -176.32176) (xy 103.19004 -176.328578) (xy 103.403908 -176.542446)
			(xy 103.410746 -176.549847) (xy 103.418463 -176.568445) (xy 103.418894 -176.578514) (xy 103.418894 -177.182018)
			(xy 103.41932 -177.192087) (xy 103.427038 -177.210687) (xy 103.43388 -177.218086) (xy 103.548688 -177.332894)
			(xy 103.555537 -177.340292) (xy 103.563275 -177.35889) (xy 103.563674 -177.368962) (xy 103.563674 -177.889916)
			(xy 103.564099 -177.899985) (xy 103.571815 -177.918588) (xy 103.57866 -177.925984) (xy 103.580692 -177.928016)
			(xy 103.588086 -177.934873) (xy 103.606685 -177.942623) (xy 103.61676 -177.943002) (xy 105.275634 -177.943002)
			(xy 105.285701 -177.942573) (xy 105.304297 -177.93485) (xy 105.311702 -177.928016) (xy 105.33253 -177.907188)
			(xy 105.339926 -177.900337) (xy 105.358525 -177.892599) (xy 105.368598 -177.892202) (xy 107.023916 -177.892202)
			(xy 107.033922 -177.891711) (xy 107.052408 -177.884049) (xy 107.066557 -177.869896) (xy 107.074214 -177.851408)
			(xy 107.074716 -177.841402) (xy 107.074716 -175.96231) (xy 107.07423 -175.9523) (xy 107.066573 -175.933802)
			(xy 107.05242 -175.919642) (xy 107.033926 -175.911975) (xy 107.023916 -175.91151) (xy 105.64622 -175.91151)
			(xy 105.636156 -175.911073) (xy 105.617572 -175.903339) (xy 105.610152 -175.896524) (xy 105.550716 -175.837088)
			(xy 105.54387 -175.829689) (xy 105.536137 -175.811091) (xy 105.53573 -175.80102) (xy 105.53573 -174.85233)
			(xy 105.535226 -174.842279) (xy 105.527508 -174.823715) (xy 105.520744 -174.816262) (xy 105.083864 -174.379382)
			(xy 105.077014 -174.371985) (xy 105.069276 -174.353387) (xy 105.068878 -174.343314) (xy 105.068878 -169.904918)
			(xy 105.068439 -169.894855) (xy 105.060702 -169.876274) (xy 105.053892 -169.86885) (xy 103.051864 -167.866822)
			(xy 103.045023 -167.859422) (xy 103.037307 -167.840823) (xy 103.036878 -167.830754) (xy 103.036878 -159.09163)
			(xy 102.59822 -158.652972) (xy 82.9564 -158.652972) (xy 81.87182 -157.568392) (xy 60.656978 -157.568392)
			(xy 60.646909 -157.568819) (xy 60.62831 -157.576538) (xy 60.62091 -157.583378) (xy 59.617864 -158.586424)
			(xy 59.611015 -158.593821) (xy 59.603279 -158.61242) (xy 59.602878 -158.622492) (xy 59.602878 -168.412414)
			(xy 59.603303 -168.422484) (xy 59.611019 -168.441086) (xy 59.617864 -168.448482) (xy 59.84748 -168.678098)
			(xy 59.854883 -168.684932) (xy 59.873481 -168.692637) (xy 59.883548 -168.693084) (xy 63.473838 -168.693084)
			(xy 63.483905 -168.692654) (xy 63.502498 -168.684928) (xy 63.509906 -168.678098) (xy 63.52413 -168.663874)
			(xy 63.531527 -168.657024) (xy 63.550126 -168.649289) (xy 63.560198 -168.648888) (xy 65.213992 -168.648888)
			(xy 65.224063 -168.648466) (xy 65.242668 -168.640752) (xy 65.25006 -168.633902) (xy 65.25133 -168.632632)
			(xy 65.258173 -168.625233) (xy 65.265894 -168.606634) (xy 65.266316 -168.596564) (xy 65.266316 -166.718996)
			(xy 65.265828 -166.708988) (xy 65.258168 -166.690494) (xy 65.244016 -166.676339) (xy 65.225524 -166.668675)
			(xy 65.215516 -166.668196) (xy 63.8683 -166.668196) (xy 63.85823 -166.667773) (xy 63.839626 -166.660058)
			(xy 63.832232 -166.65321) (xy 63.75654 -166.577518) (xy 63.749702 -166.570117) (xy 63.741991 -166.551518)
			(xy 63.741554 -166.54145) (xy 63.741554 -165.725094) (xy 63.741128 -165.715025) (xy 63.733407 -165.696427)
			(xy 63.726568 -165.689026) (xy 63.300864 -165.263322) (xy 63.294023 -165.255922) (xy 63.286307 -165.237323)
			(xy 63.285878 -165.227254) (xy 63.285878 -162.52317) (xy 63.286306 -162.513102) (xy 63.294026 -162.494503)
			(xy 63.300864 -162.487102) (xy 63.459868 -162.328098) (xy 63.46727 -162.321262) (xy 63.485868 -162.313553)
			(xy 63.495936 -162.313112) (xy 65.092072 -162.313112) (xy 65.102136 -162.313549) (xy 65.12072 -162.321283)
			(xy 65.12814 -162.328098) (xy 65.893696 -163.093654) (xy 65.901092 -163.100506) (xy 65.919691 -163.108249)
			(xy 65.929764 -163.10864) (xy 69.371464 -163.10864) (xy 69.381528 -163.109076) (xy 69.400112 -163.116811)
			(xy 69.407532 -163.123626) (xy 70.154038 -163.870386) (xy 70.160878 -163.877786) (xy 70.16859 -163.896385)
			(xy 70.169024 -163.906454) (xy 70.169024 -168.504559) (xy 82.100416 -168.504559) (xy 82.100416 -168.419837)
			(xy 82.108469 -168.3355) (xy 82.124503 -168.25231) (xy 82.148371 -168.17102) (xy 82.179859 -168.092368)
			(xy 82.218681 -168.017065) (xy 82.264484 -167.945793) (xy 82.316855 -167.879197) (xy 82.37532 -167.817882)
			(xy 82.439348 -167.762401) (xy 82.50836 -167.713258) (xy 82.58173 -167.670898) (xy 82.658795 -167.635703)
			(xy 82.738857 -167.607994) (xy 82.82119 -167.58802) (xy 82.905049 -167.575963) (xy 82.989674 -167.571932)
			(xy 83.074299 -167.575963) (xy 83.158158 -167.58802) (xy 83.240491 -167.607994) (xy 83.320553 -167.635703)
			(xy 83.397618 -167.670898) (xy 83.470988 -167.713258) (xy 83.54 -167.762401) (xy 83.604028 -167.817882)
			(xy 83.662493 -167.879197) (xy 83.714864 -167.945793) (xy 83.760667 -168.017065) (xy 83.799489 -168.092368)
			(xy 83.830977 -168.17102) (xy 83.854845 -168.25231) (xy 83.870879 -168.3355) (xy 83.878932 -168.419837)
			(xy 83.879436 -168.462198) (xy 83.878932 -168.504559) (xy 91.498416 -168.504559) (xy 91.498416 -168.419837)
			(xy 91.506469 -168.3355) (xy 91.522503 -168.25231) (xy 91.546371 -168.17102) (xy 91.577859 -168.092368)
			(xy 91.616681 -168.017065) (xy 91.662484 -167.945793) (xy 91.714855 -167.879197) (xy 91.77332 -167.817882)
			(xy 91.837348 -167.762401) (xy 91.90636 -167.713258) (xy 91.97973 -167.670898) (xy 92.056795 -167.635703)
			(xy 92.136857 -167.607994) (xy 92.21919 -167.58802) (xy 92.303049 -167.575963) (xy 92.387674 -167.571932)
			(xy 92.472299 -167.575963) (xy 92.556158 -167.58802) (xy 92.638491 -167.607994) (xy 92.718553 -167.635703)
			(xy 92.795618 -167.670898) (xy 92.868988 -167.713258) (xy 92.938 -167.762401) (xy 93.002028 -167.817882)
			(xy 93.060493 -167.879197) (xy 93.112864 -167.945793) (xy 93.158667 -168.017065) (xy 93.197489 -168.092368)
			(xy 93.228977 -168.17102) (xy 93.252845 -168.25231) (xy 93.268879 -168.3355) (xy 93.276932 -168.419837)
			(xy 93.277436 -168.462198) (xy 93.276932 -168.504559) (xy 93.268879 -168.588896) (xy 93.252845 -168.672086)
			(xy 93.228977 -168.753376) (xy 93.197489 -168.832028) (xy 93.158667 -168.907331) (xy 93.112864 -168.978603)
			(xy 93.060493 -169.045199) (xy 93.002028 -169.106514) (xy 92.938 -169.161995) (xy 92.868988 -169.211138)
			(xy 92.795618 -169.253498) (xy 92.718553 -169.288693) (xy 92.638491 -169.316402) (xy 92.556158 -169.336376)
			(xy 92.472299 -169.348433) (xy 92.387674 -169.352465) (xy 92.303049 -169.348433) (xy 92.21919 -169.336376)
			(xy 92.136857 -169.316402) (xy 92.056795 -169.288693) (xy 91.97973 -169.253498) (xy 91.90636 -169.211138)
			(xy 91.837348 -169.161995) (xy 91.77332 -169.106514) (xy 91.714855 -169.045199) (xy 91.662484 -168.978603)
			(xy 91.616681 -168.907331) (xy 91.577859 -168.832028) (xy 91.546371 -168.753376) (xy 91.522503 -168.672086)
			(xy 91.506469 -168.588896) (xy 91.498416 -168.504559) (xy 83.878932 -168.504559) (xy 83.870879 -168.588896)
			(xy 83.854845 -168.672086) (xy 83.830977 -168.753376) (xy 83.799489 -168.832028) (xy 83.760667 -168.907331)
			(xy 83.714864 -168.978603) (xy 83.662493 -169.045199) (xy 83.604028 -169.106514) (xy 83.54 -169.161995)
			(xy 83.470988 -169.211138) (xy 83.397618 -169.253498) (xy 83.320553 -169.288693) (xy 83.240491 -169.316402)
			(xy 83.158158 -169.336376) (xy 83.074299 -169.348433) (xy 82.989674 -169.352465) (xy 82.905049 -169.348433)
			(xy 82.82119 -169.336376) (xy 82.738857 -169.316402) (xy 82.658795 -169.288693) (xy 82.58173 -169.253498)
			(xy 82.50836 -169.211138) (xy 82.439348 -169.161995) (xy 82.37532 -169.106514) (xy 82.316855 -169.045199)
			(xy 82.264484 -168.978603) (xy 82.218681 -168.907331) (xy 82.179859 -168.832028) (xy 82.148371 -168.753376)
			(xy 82.124503 -168.672086) (xy 82.108469 -168.588896) (xy 82.100416 -168.504559) (xy 70.169024 -168.504559)
			(xy 70.169024 -170.543474) (xy 70.169461 -170.553538) (xy 70.177197 -170.57212) (xy 70.18401 -170.579542)
			(xy 70.468236 -170.863768) (xy 70.475079 -170.871167) (xy 70.482799 -170.889766) (xy 70.483222 -170.899836)
			(xy 70.483222 -170.954446) (xy 70.483984 -170.955208) (xy 70.483984 -172.448982) (xy 70.483545 -172.459045)
			(xy 70.475808 -172.477627) (xy 70.468998 -172.48505) (xy 70.15226 -172.801788) (xy 70.15099 -172.801788)
			(xy 69.904864 -173.047914) (xy 69.898013 -173.05531) (xy 69.890274 -173.073909) (xy 69.889878 -173.083982)
			(xy 69.889878 -177.206402) (xy 69.890301 -177.216473) (xy 69.898013 -177.235079) (xy 69.904864 -177.24247)
			(xy 70.027292 -177.364898) (xy 70.034404 -177.372264) (xy 70.0532 -177.379884) (xy 71.797672 -177.379884)
			(xy 71.807736 -177.379447) (xy 71.82632 -177.371713) (xy 71.83374 -177.364898) (xy 71.83755 -177.361088)
			(xy 71.844947 -177.35424) (xy 71.863546 -177.34651) (xy 71.873618 -177.346102) (xy 73.528936 -177.346102)
			(xy 73.538939 -177.345608) (xy 73.557419 -177.337942) (xy 73.571561 -177.32379) (xy 73.579214 -177.305305)
			(xy 73.579736 -177.295302) (xy 73.579736 -175.41621) (xy 73.57925 -175.406198) (xy 73.571594 -175.387697)
			(xy 73.557442 -175.373532) (xy 73.538947 -175.365859) (xy 73.528936 -175.36541) (xy 72.20204 -175.36541)
			(xy 72.191974 -175.364976) (xy 72.173385 -175.357248) (xy 72.165972 -175.350424) (xy 72.0598 -175.244252)
			(xy 72.052961 -175.236851) (xy 72.045244 -175.218253) (xy 72.044814 -175.208184) (xy 72.044814 -174.044102)
			(xy 72.044392 -174.034031) (xy 72.036679 -174.015425) (xy 72.029828 -174.008034) (xy 71.54926 -173.527466)
			(xy 71.542412 -173.520068) (xy 71.534681 -173.50147) (xy 71.534274 -173.491398) (xy 71.534274 -171.914312)
			(xy 71.534694 -171.90424) (xy 71.542403 -171.88563) (xy 71.54926 -171.878244) (xy 71.934832 -171.492672)
			(xy 71.942198 -171.48556) (xy 71.949818 -171.466764) (xy 71.949818 -170.918632) (xy 71.950254 -170.908568)
			(xy 71.957988 -170.889983) (xy 71.964804 -170.882564) (xy 72.109584 -170.737784) (xy 72.116983 -170.730942)
			(xy 72.135582 -170.723225) (xy 72.145652 -170.722798) (xy 73.440798 -170.722798) (xy 73.450868 -170.723221)
			(xy 73.469473 -170.730934) (xy 73.476866 -170.737784) (xy 74.373486 -171.634404) (xy 74.380889 -171.641236)
			(xy 74.399488 -171.648939) (xy 74.409554 -171.64939) (xy 77.587094 -171.64939) (xy 77.597165 -171.649812)
			(xy 77.615772 -171.657523) (xy 77.623162 -171.664376) (xy 78.256892 -172.298106) (xy 78.263738 -172.305505)
			(xy 78.271472 -172.324103) (xy 78.271878 -172.334174) (xy 78.271878 -179.105814) (xy 78.272303 -179.115884)
			(xy 78.280019 -179.134486) (xy 78.286864 -179.141882) (xy 78.782418 -179.637436) (xy 78.789268 -179.644832)
			(xy 78.797002 -179.663432) (xy 78.797404 -179.673504) (xy 78.797404 -181.146196) (xy 78.796982 -181.156267)
			(xy 78.789269 -181.174872) (xy 78.782418 -181.182264) (xy 78.286864 -181.677818) (xy 78.280014 -181.685215)
			(xy 78.272276 -181.703813) (xy 78.271878 -181.713886) (xy 78.271878 -182.388002) (xy 78.272301 -182.398073)
			(xy 78.280013 -182.416679) (xy 78.286864 -182.42407) (xy 78.36281 -182.500016) (xy 78.369922 -182.507382)
			(xy 78.388718 -182.515002)
		)
		(stroke
			(width 0)
			(type solid)
		)
		(fill yes)
		(layer "F.Cu")
		(net "SW_P12V_AUX_PVDDCR_CPU0_P1_FLT")
	)
	(gr_poly
		(pts
			(xy 393.765278 -193.62928) (xy 393.765278 -188.873638) (xy 394.302996 -188.33592) (xy 400.144996 -188.33592)
			(xy 400.250914 -188.230002) (xy 400.250914 -186.8678) (xy 400.065494 -186.68238) (xy 395.445234 -186.68238)
			(xy 395.109192 -186.346338) (xy 395.109192 -186.286394) (xy 395.107414 -186.284616) (xy 395.107414 -184.652412)
			(xy 395.109192 -184.650634) (xy 395.109192 -184.573418) (xy 395.376654 -184.305956) (xy 395.45387 -184.305956)
			(xy 395.45514 -184.304686) (xy 400.933412 -184.304686) (xy 401.807934 -183.430164) (xy 401.807934 -181.304438)
			(xy 401.604734 -181.101238) (xy 400.775678 -181.101238) (xy 400.62404 -181.252876) (xy 400.62404 -183.518048)
			(xy 400.402552 -183.739536) (xy 395.33195 -183.739536) (xy 395.15161 -183.559196) (xy 395.15161 -179.7431)
			(xy 395.29893 -179.59578) (xy 395.29893 -179.380896) (xy 400.553682 -179.380896) (xy 400.960336 -178.974242)
			(xy 400.960336 -178.973226) (xy 401.153122 -178.78044) (xy 401.88388 -178.78044) (xy 401.884642 -178.781202)
			(xy 402.308314 -178.781202) (xy 403.524974 -177.564542) (xy 403.524974 -176.043336) (xy 403.834854 -175.733456)
			(xy 409.82646 -175.733456) (xy 410.021278 -175.538638) (xy 410.021278 -174.18431) (xy 411.072076 -173.133512)
			(xy 411.865318 -173.133512) (xy 412.012638 -172.986192) (xy 412.012638 -171.229782) (xy 412.342838 -170.899582)
			(xy 426.281088 -170.899582) (xy 426.598588 -170.582082) (xy 426.598588 -157.969458) (xy 426.249338 -157.620208)
			(xy 421.1955 -157.620208) (xy 421.009318 -157.80639) (xy 421.009318 -159.966152) (xy 419.919658 -161.055812)
			(xy 419.919658 -163.623752) (xy 419.663372 -163.880038) (xy 417.821618 -163.880038) (xy 417.15436 -164.547296)
			(xy 415.443924 -164.547296) (xy 415.443924 -163.869116) (xy 415.464498 -163.869116) (xy 415.464498 -163.859464)
			(xy 415.449258 -163.844224) (xy 415.443924 -163.844224) (xy 415.443924 -163.823396) (xy 415.789364 -163.477956)
			(xy 416.278314 -163.477956) (xy 416.350958 -163.405312) (xy 417.234878 -163.405312) (xy 417.247578 -163.392612)
			(xy 417.247578 -163.191952) (xy 417.234878 -163.179252) (xy 416.330638 -163.179252) (xy 416.279838 -163.128452)
			(xy 416.279838 -162.131502) (xy 416.354768 -162.056572) (xy 417.336478 -162.056572) (xy 417.387278 -162.005772)
			(xy 417.387278 -161.871152) (xy 417.344098 -161.827972) (xy 416.387534 -161.827972) (xy 416.279838 -161.720276)
			(xy 416.279838 -161.517076) (xy 416.272218 -161.509456) (xy 414.534858 -161.509456) (xy 414.527238 -161.517076)
			(xy 414.527238 -163.541202) (xy 414.224216 -163.844224) (xy 409.646882 -163.844224) (xy 409.589478 -163.901628)
			(xy 409.589478 -164.406072) (xy 410.529278 -165.345872) (xy 410.529278 -168.401238) (xy 410.173678 -168.756838)
			(xy 409.388818 -168.756838) (xy 408.76728 -169.378376) (xy 408.25293 -169.37863) (xy 407.086816 -169.37863)
			(xy 407.08961 -169.381424) (xy 407.061924 -169.381424) (xy 407.061924 -168.695116) (xy 407.062178 -168.695116)
			(xy 407.061924 -168.694862) (xy 407.061924 -168.684702) (xy 407.44267 -168.303956) (xy 407.913078 -168.303956)
			(xy 407.985722 -168.231312) (xy 408.857958 -168.231312) (xy 408.863038 -168.226232) (xy 408.863038 -168.01338)
			(xy 408.850338 -168.00068) (xy 407.944066 -168.00068) (xy 407.897838 -167.954452) (xy 407.897838 -166.962582)
			(xy 407.980388 -166.880032) (xy 408.857958 -166.880032) (xy 408.865578 -166.872412) (xy 408.865578 -166.666672)
			(xy 408.855418 -166.656512) (xy 408.008074 -166.656512) (xy 407.897838 -166.546276) (xy 407.897838 -166.343076)
			(xy 407.890218 -166.335456) (xy 406.152858 -166.335456) (xy 406.145238 -166.343076) (xy 406.145238 -168.341802)
			(xy 405.812498 -168.674542) (xy 401.154392 -168.674542) (xy 401.153122 -168.675812) (xy 400.986498 -168.675812)
			(xy 400.785838 -168.876472) (xy 400.785838 -170.15587) (xy 411.85719 -170.15587) (xy 411.85719 -166.339774)
			(xy 412.017972 -166.178992) (xy 412.017972 -165.97757) (xy 417.04641 -165.97757) (xy 417.04641 -166.116508)
			(xy 417.665916 -166.116508) (xy 417.665916 -165.5699) (xy 417.858702 -165.377114) (xy 418.58946 -165.377114)
			(xy 419.112192 -165.899846) (xy 419.112192 -167.203882) (xy 418.929058 -167.387016) (xy 418.26688 -167.387016)
			(xy 418.204904 -167.325294) (xy 418.164518 -167.36568) (xy 417.45662 -167.36568) (xy 417.36264 -167.45966)
			(xy 417.36264 -170.132248) (xy 417.158678 -170.33621) (xy 412.03753 -170.33621) (xy 411.85719 -170.15587)
			(xy 400.785838 -170.15587) (xy 400.785838 -170.839892) (xy 401.028154 -171.082208) (xy 401.028154 -172.565314)
			(xy 402.021294 -173.558454) (xy 402.021294 -174.98187) (xy 403.47519 -174.98187) (xy 403.47519 -171.165774)
			(xy 403.620478 -171.020486) (xy 403.620478 -170.80357) (xy 408.636978 -170.80357) (xy 408.636978 -170.80611)
			(xy 409.249118 -170.80611) (xy 409.283916 -170.771312) (xy 409.283916 -170.3959) (xy 409.476702 -170.203114)
			(xy 410.20746 -170.203114) (xy 410.730192 -170.725846) (xy 410.730192 -172.029882) (xy 410.694378 -172.065696)
			(xy 410.694378 -172.07357) (xy 410.564838 -172.20311) (xy 410.556964 -172.20311) (xy 410.547058 -172.213016)
			(xy 409.88488 -172.213016) (xy 409.874974 -172.20311) (xy 409.073858 -172.20311) (xy 409.068524 -172.197776)
			(xy 409.00604 -172.26026) (xy 409.00604 -174.958248) (xy 408.802078 -175.16221) (xy 403.65553 -175.16221)
			(xy 403.47519 -174.98187) (xy 402.021294 -174.98187) (xy 402.021294 -177.087022) (xy 401.791678 -177.316638)
			(xy 401.082764 -177.316638) (xy 400.313652 -178.08575) (xy 400.059144 -178.08575) (xy 399.932144 -177.95875)
			(xy 398.738344 -177.95875) (xy 398.738344 -177.254916) (xy 399.111978 -176.881282) (xy 399.576798 -176.881282)
			(xy 399.649188 -176.808892) (xy 400.529298 -176.808892) (xy 400.536918 -176.801272) (xy 400.536918 -176.587912)
			(xy 400.531838 -176.582832) (xy 399.625312 -176.582832) (xy 399.574258 -176.531778) (xy 399.574258 -175.530002)
			(xy 399.646648 -175.457612) (xy 400.531838 -175.457612) (xy 400.536918 -175.452532) (xy 400.536918 -175.239172)
			(xy 400.531838 -175.234092) (xy 399.684748 -175.234092) (xy 399.574258 -175.123602) (xy 399.574258 -174.920402)
			(xy 399.566638 -174.912782) (xy 397.829278 -174.912782) (xy 397.821658 -174.920402) (xy 397.821658 -176.901602)
			(xy 397.47571 -177.24755) (xy 393.130278 -177.24755) (xy 393.003278 -177.37455) (xy 393.003278 -177.61331)
			(xy 393.257278 -177.86731) (xy 393.257278 -178.62931) (xy 393.573508 -178.94554) (xy 393.573508 -182.842408)
			(xy 393.511278 -182.904638) (xy 392.695176 -182.904638) (xy 391.898632 -183.701182) (xy 391.644124 -183.701182)
			(xy 391.644124 -183.700928) (xy 391.52322 -183.580024) (xy 390.349994 -183.580024) (xy 390.344152 -183.574182)
			(xy 390.323324 -183.574182) (xy 390.323324 -183.553354) (xy 390.322054 -183.552084) (xy 390.322054 -183.385714)
			(xy 390.323324 -183.384444) (xy 390.323324 -182.832756) (xy 390.659366 -182.496714) (xy 391.169398 -182.496714)
			(xy 391.24128 -182.424832) (xy 392.116818 -182.424832) (xy 392.119358 -182.422292) (xy 392.119358 -182.203852)
			(xy 392.114278 -182.198772) (xy 391.2108 -182.198772) (xy 391.159238 -182.14721) (xy 391.159238 -181.123082)
			(xy 391.208768 -181.073552) (xy 392.119358 -181.073552) (xy 392.121898 -181.071012) (xy 392.121898 -180.855112)
			(xy 392.114278 -180.847492) (xy 391.267696 -180.847492) (xy 391.159238 -180.739034) (xy 391.159238 -180.535834)
			(xy 391.151618 -180.528214) (xy 389.414258 -180.528214) (xy 389.406638 -180.535834) (xy 389.406638 -182.471822)
			(xy 389.015478 -182.862982) (xy 386.919724 -182.862982) (xy 386.919724 -182.862728) (xy 385.298188 -182.862728)
			(xy 385.21894 -182.941976) (xy 384.326638 -182.941976) (xy 383.688082 -183.580532) (xy 381.992124 -183.580532)
			(xy 381.992124 -182.863236) (xy 382.358646 -182.496714) (xy 382.840738 -182.496714) (xy 382.91516 -182.422292)
			(xy 383.785618 -182.422292) (xy 383.793238 -182.414672) (xy 383.793238 -182.208932) (xy 383.783078 -182.198772)
			(xy 382.8796 -182.198772) (xy 382.828038 -182.14721) (xy 382.828038 -181.156102) (xy 382.910588 -181.073552)
			(xy 383.783078 -181.073552) (xy 383.788158 -181.068472) (xy 383.788158 -180.852572) (xy 383.783078 -180.847492)
			(xy 382.936496 -180.847492) (xy 382.828038 -180.739034) (xy 382.828038 -180.535834) (xy 382.820418 -180.528214)
			(xy 381.083058 -180.528214) (xy 381.075438 -180.535834) (xy 381.075438 -182.515002) (xy 380.727458 -182.862982)
			(xy 377.003818 -182.862982) (xy 376.924824 -182.941976) (xy 375.881138 -182.941976) (xy 375.292112 -183.531002)
			(xy 373.589296 -183.531002) (xy 373.589296 -182.820564) (xy 373.955818 -182.454042) (xy 374.438418 -182.454042)
			(xy 374.510808 -182.381652) (xy 375.380758 -182.381652) (xy 375.385838 -182.376572) (xy 375.385838 -182.160672)
			(xy 375.380758 -182.155592) (xy 374.476264 -182.155592) (xy 374.42521 -182.104538) (xy 374.42521 -181.12105)
			(xy 374.515888 -181.030372) (xy 375.380758 -181.030372) (xy 375.388378 -181.022752) (xy 375.388378 -180.814472)
			(xy 375.380758 -180.806852) (xy 374.5357 -180.806852) (xy 374.42521 -180.696362) (xy 374.42521 -180.493162)
			(xy 374.41759 -180.485542) (xy 372.68023 -180.485542) (xy 372.67261 -180.493162) (xy 372.67261 -182.48503)
			(xy 372.33733 -182.82031) (xy 368.78895 -182.82031) (xy 368.365278 -182.396638) (xy 368.365278 -181.888638)
			(xy 367.987326 -181.510686) (xy 367.099342 -181.510686) (xy 366.74044 -181.869588) (xy 366.74044 -184.131966)
			(xy 366.532668 -184.339738) (xy 361.82173 -184.339738) (xy 361.64139 -184.159398) (xy 361.64139 -180.343302)
			(xy 361.642152 -180.34254) (xy 361.642152 -180.163724) (xy 361.824778 -179.981098) (xy 367.043462 -179.981098)
			(xy 367.450116 -179.574444) (xy 367.450116 -179.573428) (xy 367.642902 -179.380642) (xy 367.98504 -179.380642)
			(xy 368.238278 -179.127404) (xy 368.238278 -178.113436) (xy 368.111278 -177.986436) (xy 367.502948 -177.986436)
			(xy 366.803432 -178.685952) (xy 366.548924 -178.685952) (xy 366.421924 -178.558952) (xy 365.228124 -178.558952)
			(xy 365.228124 -177.869596) (xy 365.616236 -177.481484) (xy 366.064038 -177.481484) (xy 366.13719 -177.408332)
			(xy 367.024158 -177.408332) (xy 367.029238 -177.403252) (xy 367.029238 -177.189892) (xy 367.021618 -177.182272)
			(xy 366.11433 -177.182272) (xy 366.064038 -177.13198) (xy 366.064038 -176.126902) (xy 366.131348 -176.059592)
			(xy 367.019078 -176.059592) (xy 367.026698 -176.051972) (xy 367.026698 -175.841152) (xy 367.019078 -175.833532)
			(xy 366.173766 -175.833532) (xy 366.064038 -175.723804) (xy 366.064038 -175.520604) (xy 366.056418 -175.512984)
			(xy 364.319058 -175.512984) (xy 364.311438 -175.520604) (xy 364.311438 -177.508662) (xy 363.972348 -177.847752)
			(xy 361.824524 -177.847752) (xy 361.767882 -177.79111) (xy 360.288078 -177.79111) (xy 360.078274 -177.581306)
			(xy 360.078274 -173.557438) (xy 359.773474 -173.252638) (xy 358.818434 -173.252638) (xy 358.589834 -173.481238)
			(xy 358.589834 -175.806354) (xy 358.386634 -176.009554) (xy 358.307132 -176.009554) (xy 358.252268 -176.064418)
			(xy 353.54133 -176.064418) (xy 353.36099 -175.884078) (xy 353.36099 -172.067982) (xy 353.484434 -171.944538)
			(xy 353.484434 -171.765722) (xy 353.544378 -171.705778) (xy 358.710738 -171.705778) (xy 359.322878 -171.093638)
			(xy 359.951274 -171.093638) (xy 360.078274 -170.966638) (xy 360.078274 -169.986452) (xy 359.907078 -169.815256)
			(xy 359.118408 -169.815256) (xy 358.523032 -170.410632) (xy 358.268524 -170.410632) (xy 358.141524 -170.283632)
			(xy 356.947724 -170.283632) (xy 356.947724 -169.576496) (xy 357.318056 -169.206164) (xy 357.786178 -169.206164)
			(xy 357.85679 -169.135552) (xy 358.738678 -169.135552) (xy 358.741218 -169.133012) (xy 358.741218 -168.909492)
			(xy 358.738678 -168.906952) (xy 357.83393 -168.906952) (xy 357.783638 -168.85666) (xy 357.783638 -167.854122)
			(xy 357.853488 -167.784272) (xy 358.738678 -167.784272) (xy 358.746298 -167.776652) (xy 358.746298 -167.563292)
			(xy 358.741218 -167.558212) (xy 357.893366 -167.558212) (xy 357.783638 -167.448484) (xy 357.783638 -167.245284)
			(xy 357.776018 -167.237664) (xy 356.038658 -167.237664) (xy 356.031038 -167.245284) (xy 356.031038 -169.258742)
			(xy 355.717348 -169.572432) (xy 352.044 -169.572432) (xy 351.780094 -169.308526) (xy 351.780094 -165.049454)
			(xy 351.568766 -164.838126) (xy 350.553782 -164.838126) (xy 350.309434 -165.082474) (xy 350.309434 -167.475154)
			(xy 350.106234 -167.678354) (xy 349.975932 -167.678354) (xy 349.946468 -167.707818) (xy 345.23553 -167.707818)
			(xy 345.05519 -167.527478) (xy 345.05519 -163.711382) (xy 345.055952 -163.71062) (xy 345.055952 -163.531804)
			(xy 345.238578 -163.349178) (xy 350.42221 -163.349178) (xy 351.021904 -162.749484) (xy 351.575878 -162.749484)
			(xy 351.780094 -162.545268) (xy 351.780094 -161.688272) (xy 351.575878 -161.484056) (xy 350.997774 -161.484056)
			(xy 350.561656 -161.920174) (xy 350.217232 -161.920174) (xy 350.217232 -162.054032) (xy 349.962724 -162.054032)
			(xy 349.962724 -161.927032) (xy 348.641924 -161.927032) (xy 348.641924 -161.240724) (xy 348.656148 -161.240724)
			(xy 348.656148 -161.232596) (xy 348.641924 -161.218372) (xy 348.641924 -161.212276) (xy 349.004636 -160.849564)
			(xy 349.480378 -160.849564) (xy 349.55353 -160.776412) (xy 350.432878 -160.776412) (xy 350.440498 -160.768792)
			(xy 350.440498 -160.560512) (xy 350.432878 -160.552892) (xy 349.53067 -160.552892) (xy 349.477838 -160.50006)
			(xy 349.477838 -159.520636) (xy 349.570802 -159.427672) (xy 350.432878 -159.427672) (xy 350.437958 -159.422592)
			(xy 350.437958 -159.206692) (xy 350.432878 -159.201612) (xy 349.587566 -159.201612) (xy 349.477838 -159.091884)
			(xy 349.477838 -158.888684) (xy 349.470218 -158.881064) (xy 347.732858 -158.881064) (xy 347.725238 -158.888684)
			(xy 347.725238 -160.889442) (xy 347.398848 -161.215832) (xy 345.492324 -161.215832) (xy 345.492324 -161.219134)
			(xy 337.857338 -161.219134) (xy 337.632294 -161.444178) (xy 337.632294 -165.334188) (xy 337.854544 -165.556438)
			(xy 342.381078 -165.556438) (xy 343.473278 -166.648638) (xy 343.473278 -167.436038) (xy 344.30843 -168.27119)
			(xy 350.08439 -168.27119) (xy 350.332294 -168.519094) (xy 350.332294 -170.078654) (xy 350.458278 -170.204638)
			(xy 351.347278 -170.204638) (xy 352.236278 -171.093638) (xy 352.236278 -176.046638) (xy 352.79203 -176.60239)
			(xy 358.40035 -176.60239) (xy 358.622854 -176.824894) (xy 358.622854 -178.458114) (xy 358.836214 -178.671474)
			(xy 359.856278 -178.671474) (xy 360.516678 -179.331874) (xy 360.516678 -184.149238) (xy 361.14101 -184.77357)
			(xy 366.80521 -184.77357) (xy 367.184178 -185.152538) (xy 367.184178 -186.524138) (xy 367.476278 -186.816238)
			(xy 368.187478 -186.816238) (xy 368.874294 -187.503054) (xy 368.874294 -189.131956) (xy 370.002562 -189.131956)
			(xy 370.002562 -185.31586) (xy 370.15674 -185.161682) (xy 370.15674 -184.953656) (xy 375.186702 -184.953656)
			(xy 375.186702 -185.092594) (xy 375.811288 -185.092594) (xy 375.811288 -184.545986) (xy 376.004074 -184.3532)
			(xy 376.734832 -184.3532) (xy 377.257564 -184.875932) (xy 377.257564 -186.179968) (xy 377.07443 -186.363102)
			(xy 376.412252 -186.363102) (xy 376.350276 -186.30138) (xy 376.30989 -186.341766) (xy 375.601992 -186.341766)
			(xy 375.101612 -186.842146) (xy 375.101612 -189.104524) (xy 375.031508 -189.174628) (xy 378.40539 -189.174628)
			(xy 378.40539 -185.259472) (xy 378.555758 -185.109104) (xy 378.555758 -184.996328) (xy 383.592324 -184.996328)
			(xy 383.592324 -185.063638) (xy 384.214116 -185.063638) (xy 384.214116 -184.557924) (xy 384.429 -184.34304)
			(xy 385.13766 -184.34304) (xy 385.660392 -184.865772) (xy 385.660392 -186.22264) (xy 385.477258 -186.405774)
			(xy 384.81508 -186.405774) (xy 384.753104 -186.344052) (xy 384.712718 -186.384438) (xy 384.00482 -186.384438)
			(xy 383.50444 -186.884818) (xy 383.50444 -189.147196) (xy 383.477008 -189.174628) (xy 386.73659 -189.174628)
			(xy 386.73659 -185.227722) (xy 386.863336 -185.100976) (xy 386.863336 -184.98947) (xy 391.911332 -184.98947)
			(xy 391.911332 -185.09107) (xy 392.54176 -185.09107) (xy 392.54176 -184.5183) (xy 392.7094 -184.35066)
			(xy 393.5095 -184.35066) (xy 393.991592 -184.832752) (xy 393.991592 -186.22264) (xy 393.808458 -186.405774)
			(xy 393.14628 -186.405774) (xy 393.084304 -186.344052) (xy 393.043918 -186.384438) (xy 392.33602 -186.384438)
			(xy 391.83564 -186.884818) (xy 391.83564 -189.147196) (xy 391.627868 -189.354968) (xy 386.91693 -189.354968)
			(xy 386.73659 -189.174628) (xy 383.477008 -189.174628) (xy 383.296668 -189.354968) (xy 378.58573 -189.354968)
			(xy 378.40539 -189.174628) (xy 375.031508 -189.174628) (xy 374.89384 -189.312296) (xy 370.182902 -189.312296)
			(xy 370.002562 -189.131956) (xy 368.874294 -189.131956) (xy 368.874294 -189.509654) (xy 369.145566 -189.780926)
			(xy 391.835894 -189.780926) (xy 392.139932 -190.084964) (xy 392.140694 -190.084964) (xy 392.140694 -191.972184)
			(xy 391.899394 -192.213484) (xy 387.307074 -192.213484) (xy 386.984494 -192.536064) (xy 386.984494 -193.910204)
			(xy 387.083554 -194.009264) (xy 393.385294 -194.009264)
		)
		(stroke
			(width 0)
			(type solid)
		)
		(fill yes)
		(layer "F.Cu")
		(net "GND")
	)
	(gr_poly
		(pts
			(xy 203.786994 -368.23142) (xy 203.797065 -368.230999) (xy 203.815673 -368.223288) (xy 203.823062 -368.216434)
			(xy 205.18628 -366.853216) (xy 205.193115 -366.845814) (xy 205.200822 -366.827215) (xy 205.201266 -366.817148)
			(xy 205.201266 -349.192596) (xy 205.200841 -349.182527) (xy 205.193122 -349.163927) (xy 205.18628 -349.156528)
			(xy 204.705458 -348.675706) (xy 204.698057 -348.668865) (xy 204.679459 -348.661145) (xy 204.66939 -348.66072)
			(xy 203.713842 -348.66072) (xy 203.703776 -348.660287) (xy 203.685185 -348.65256) (xy 203.677774 -348.645734)
			(xy 202.516486 -347.484446) (xy 202.509089 -347.477597) (xy 202.49049 -347.46986) (xy 202.480418 -347.46946)
			(xy 197.587362 -347.46946) (xy 197.577296 -347.469029) (xy 197.558705 -347.4613) (xy 197.551294 -347.454474)
			(xy 196.214746 -346.117926) (xy 196.207906 -346.110526) (xy 196.200191 -346.091927) (xy 196.19976 -346.081858)
			(xy 196.19976 -342.684862) (xy 196.199329 -342.674796) (xy 196.1916 -342.656205) (xy 196.184774 -342.648794)
			(xy 195.95084 -342.41486) (xy 195.943441 -342.408016) (xy 195.924842 -342.400294) (xy 195.914772 -342.399874)
			(xy 170.931078 -342.399874) (xy 170.92101 -342.399446) (xy 170.902414 -342.391723) (xy 170.89501 -342.384888)
			(xy 170.58894 -342.078818) (xy 170.582102 -342.071417) (xy 170.574391 -342.052818) (xy 170.573954 -342.04275)
			(xy 170.573954 -334.739234) (xy 170.573517 -334.72917) (xy 170.565781 -334.710588) (xy 170.558968 -334.703166)
			(xy 170.13174 -334.275938) (xy 170.12434 -334.269097) (xy 170.105741 -334.261378) (xy 170.095672 -334.260952)
			(xy 168.237916 -334.260952) (xy 168.227854 -334.260512) (xy 168.209276 -334.252771) (xy 168.201848 -334.245966)
			(xy 167.85082 -333.894938) (xy 167.843981 -333.887537) (xy 167.836266 -333.868939) (xy 167.835834 -333.85887)
			(xy 167.835834 -332.171294) (xy 167.836259 -332.161225) (xy 167.843979 -332.142625) (xy 167.85082 -332.135226)
			(xy 168.32453 -331.661516) (xy 168.331929 -331.654673) (xy 168.350528 -331.646946) (xy 168.360598 -331.64653)
			(xy 170.580812 -331.64653) (xy 170.590881 -331.646956) (xy 170.609479 -331.654677) (xy 170.61688 -331.661516)
			(xy 170.934888 -331.979524) (xy 170.941732 -331.986923) (xy 170.94946 -332.005521) (xy 170.949874 -332.015592)
			(xy 170.949874 -332.52791) (xy 170.950298 -332.53798) (xy 170.958012 -332.556584) (xy 170.96486 -332.563978)
			(xy 171.02328 -332.622398) (xy 171.030683 -332.629232) (xy 171.049281 -332.636937) (xy 171.059348 -332.637384)
			(xy 194.064128 -332.637384) (xy 194.08267 -332.629764) (xy 194.085718 -332.626716) (xy 195.565268 -332.626716)
			(xy 195.575333 -332.626281) (xy 195.593921 -332.618551) (xy 195.601336 -332.61173) (xy 195.809108 -332.403958)
			(xy 195.815947 -332.396557) (xy 195.823665 -332.377959) (xy 195.824094 -332.36789) (xy 195.824094 -326.570594)
			(xy 195.82367 -326.560524) (xy 195.815953 -326.541922) (xy 195.809108 -326.534526) (xy 195.37426 -326.099678)
			(xy 195.366863 -326.092829) (xy 195.348264 -326.085097) (xy 195.338192 -326.084692) (xy 163.26231 -326.084692)
			(xy 163.252239 -326.085113) (xy 163.233631 -326.092824) (xy 163.226242 -326.099678) (xy 161.470086 -327.855834)
			(xy 161.463235 -327.86323) (xy 161.4555 -327.881829) (xy 161.4551 -327.891902) (xy 161.4551 -342.083644)
			(xy 161.455531 -342.093711) (xy 161.463257 -342.112303) (xy 161.470086 -342.119712) (xy 161.900616 -342.550242)
			(xy 161.908013 -342.557092) (xy 161.926611 -342.56483) (xy 161.936684 -342.565228) (xy 167.494966 -342.565228)
			(xy 167.50503 -342.565664) (xy 167.523615 -342.573398) (xy 167.531034 -342.580214) (xy 169.82821 -344.87739)
			(xy 169.835068 -344.884784) (xy 169.84282 -344.903383) (xy 169.843196 -344.913458) (xy 169.843196 -349.14205)
			(xy 178.338226 -349.14205) (xy 178.338226 -347.880686) (xy 178.338637 -347.870615) (xy 178.346367 -347.852017)
			(xy 178.353212 -347.844618) (xy 178.592734 -347.605096) (xy 178.600128 -347.598248) (xy 178.618732 -347.590533)
			(xy 178.628802 -347.59011) (xy 179.800504 -347.59011) (xy 179.810577 -347.589711) (xy 179.829176 -347.581974)
			(xy 179.836572 -347.575124) (xy 180.415438 -346.996258) (xy 180.422294 -346.988871) (xy 180.430003 -346.970262)
			(xy 180.430424 -346.96019) (xy 180.430424 -344.254074) (xy 180.4416 -344.254074) (xy 180.782214 -343.91346)
			(xy 180.78961 -343.906616) (xy 180.808213 -343.8989) (xy 180.818282 -343.898474) (xy 185.017918 -343.898474)
			(xy 185.027991 -343.898871) (xy 185.046589 -343.906609) (xy 185.053986 -343.91346) (xy 185.49747 -344.356944)
			(xy 185.504318 -344.364338) (xy 185.512034 -344.382942) (xy 185.512456 -344.393012) (xy 185.512456 -349.01251)
			(xy 185.512047 -349.022581) (xy 185.504316 -349.04118) (xy 185.49747 -349.048578) (xy 185.474864 -349.071184)
			(xy 185.467469 -349.07803) (xy 185.448866 -349.085747) (xy 185.438796 -349.08617) (xy 185.409078 -349.08617)
			(xy 185.409078 -349.085662) (xy 180.43906 -349.085662) (xy 180.409342 -349.055944) (xy 180.409342 -349.047054)
			(xy 180.408851 -349.037049) (xy 180.401184 -349.018564) (xy 180.387033 -349.004414) (xy 180.368547 -348.996749)
			(xy 180.358542 -348.996254) (xy 179.833778 -348.996254) (xy 179.823775 -348.996769) (xy 179.805291 -349.004427)
			(xy 179.79114 -349.018571) (xy 179.783473 -349.037051) (xy 179.782978 -349.047054) (xy 179.782978 -349.16745)
			(xy 186.664854 -349.16745) (xy 186.664854 -347.906086) (xy 186.665258 -347.896014) (xy 186.672992 -347.877416)
			(xy 186.67984 -347.870018) (xy 186.937904 -347.611954) (xy 186.945303 -347.605113) (xy 186.963903 -347.597395)
			(xy 186.973972 -347.596968) (xy 188.140848 -347.596968) (xy 188.150915 -347.596524) (xy 188.169514 -347.588817)
			(xy 188.176916 -347.581982) (xy 188.742066 -347.016832) (xy 188.74888 -347.009411) (xy 188.756616 -346.990828)
			(xy 188.757052 -346.980764) (xy 188.757052 -344.265504) (xy 188.757466 -344.255433) (xy 188.765193 -344.236835)
			(xy 188.772038 -344.229436) (xy 189.062614 -343.93886) (xy 189.07001 -343.932016) (xy 189.088613 -343.9243)
			(xy 189.098682 -343.923874) (xy 193.349118 -343.923874) (xy 193.359191 -343.924271) (xy 193.377789 -343.932009)
			(xy 193.385186 -343.93886) (xy 193.824098 -344.377772) (xy 193.830918 -344.385188) (xy 193.838649 -344.403775)
			(xy 193.839084 -344.41384) (xy 193.839084 -349.04807) (xy 193.831464 -349.066612) (xy 193.826892 -349.071184)
			(xy 193.819487 -349.078018) (xy 193.800892 -349.085742) (xy 193.790824 -349.08617) (xy 193.760598 -349.08617)
			(xy 193.735706 -349.111062) (xy 188.782198 -349.111062) (xy 188.772172 -349.110681) (xy 188.753648 -349.103003)
			(xy 188.739474 -349.088819) (xy 188.731811 -349.070288) (xy 188.731398 -349.060262) (xy 188.731398 -349.034354)
			(xy 188.726318 -349.029274) (xy 188.707776 -349.021654) (xy 188.160406 -349.021654) (xy 188.150404 -349.022192)
			(xy 188.131922 -349.029841) (xy 188.11777 -349.043978) (xy 188.110102 -349.062453) (xy 188.109606 -349.072454)
			(xy 188.109606 -349.497396) (xy 188.109204 -349.507468) (xy 188.10147 -349.526067) (xy 188.09462 -349.533464)
			(xy 187.932314 -349.69577) (xy 187.9249 -349.702592) (xy 187.906311 -349.710323) (xy 187.896246 -349.710756)
			(xy 187.20816 -349.710756) (xy 187.198087 -349.710363) (xy 187.179489 -349.702621) (xy 187.172092 -349.69577)
			(xy 186.67984 -349.203518) (xy 186.673021 -349.196101) (xy 186.665288 -349.177515) (xy 186.664854 -349.16745)
			(xy 179.782978 -349.16745) (xy 179.782978 -349.471996) (xy 179.782556 -349.482066) (xy 179.774834 -349.500664)
			(xy 179.767992 -349.508064) (xy 179.605686 -349.67037) (xy 179.598281 -349.677204) (xy 179.579686 -349.684928)
			(xy 179.569618 -349.685356) (xy 178.881532 -349.685356) (xy 178.871463 -349.684925) (xy 178.852865 -349.67721)
			(xy 178.845464 -349.67037) (xy 178.353212 -349.178118) (xy 178.346389 -349.170704) (xy 178.338659 -349.152116)
			(xy 178.338226 -349.14205) (xy 169.843196 -349.14205) (xy 169.843196 -354.348542) (xy 169.843627 -354.358609)
			(xy 169.851352 -354.377203) (xy 169.858182 -354.38461) (xy 170.89501 -355.421438) (xy 170.902406 -355.42829)
			(xy 170.921005 -355.43603) (xy 170.931078 -355.436424) (xy 176.253394 -355.436424) (xy 176.263404 -355.435937)
			(xy 176.281902 -355.42828) (xy 176.296063 -355.414127) (xy 176.303732 -355.395634) (xy 176.304194 -355.385624)
			(xy 176.304194 -351.429574) (xy 176.304621 -351.419506) (xy 176.312342 -351.400907) (xy 176.31918 -351.393506)
			(xy 176.722278 -350.990408) (xy 176.72968 -350.983573) (xy 176.748279 -350.975866) (xy 176.758346 -350.975422)
			(xy 179.957222 -350.975422) (xy 179.967291 -350.974996) (xy 179.985892 -350.967278) (xy 179.99329 -350.960436)
			(xy 180.434234 -350.519492) (xy 180.441635 -350.512652) (xy 180.460233 -350.504931) (xy 180.470302 -350.504506)
			(xy 180.684932 -350.504506) (xy 180.684932 -350.507808) (xy 181.954932 -350.507808) (xy 181.964935 -350.508302)
			(xy 181.983414 -350.515967) (xy 181.997555 -350.530119) (xy 182.005206 -350.548605) (xy 182.005732 -350.558608)
			(xy 182.005732 -351.362264) (xy 182.005229 -351.372316) (xy 181.997513 -351.390881) (xy 181.990746 -351.398332)
			(xy 181.818788 -351.57029) (xy 181.811389 -351.577135) (xy 181.792791 -351.584867) (xy 181.78272 -351.585276)
			(xy 181.18963 -351.585276) (xy 181.179565 -351.585711) (xy 181.160977 -351.593441) (xy 181.153562 -351.600262)
			(xy 181.112668 -351.641156) (xy 181.10527 -351.648002) (xy 181.086671 -351.655732) (xy 181.0766 -351.656142)
			(xy 180.221636 -351.656142) (xy 180.211572 -351.656578) (xy 180.192988 -351.664314) (xy 180.185568 -351.671128)
			(xy 180.185314 -351.671382) (xy 180.177694 -351.689924) (xy 180.177694 -351.86239) (xy 180.185314 -351.880932)
			(xy 180.186838 -351.882456) (xy 181.096412 -351.882456) (xy 181.10648 -351.882883) (xy 181.125076 -351.890607)
			(xy 181.13248 -351.897442) (xy 181.154832 -351.919794) (xy 181.161687 -351.927189) (xy 181.169434 -351.945788)
			(xy 181.169818 -351.955862) (xy 181.169818 -352.88728) (xy 181.169381 -352.897344) (xy 181.161648 -352.915929)
			(xy 181.154832 -352.923348) (xy 181.087014 -352.991166) (xy 181.079613 -352.998003) (xy 181.061014 -353.005711)
			(xy 181.050946 -353.006152) (xy 180.236114 -353.006152) (xy 180.226052 -353.006592) (xy 180.207475 -353.014334)
			(xy 180.200046 -353.021138) (xy 180.121814 -353.09937) (xy 180.114977 -353.106772) (xy 180.107266 -353.12537)
			(xy 180.106828 -353.135438) (xy 180.106828 -353.144582) (xy 180.182012 -353.219766) (xy 180.18941 -353.226614)
			(xy 180.208008 -353.23435) (xy 180.21808 -353.234752) (xy 180.958744 -353.234752) (xy 180.968809 -353.235185)
			(xy 180.987397 -353.242916) (xy 180.994812 -353.249738) (xy 181.014624 -353.26955) (xy 181.022022 -353.276398)
			(xy 181.04062 -353.284131) (xy 181.050692 -353.284536) (xy 181.090316 -353.284536) (xy 181.100384 -353.284963)
			(xy 181.118981 -353.292685) (xy 181.126384 -353.299522) (xy 181.154832 -353.32797) (xy 181.161675 -353.335369)
			(xy 181.169394 -353.353968) (xy 181.169818 -353.364038) (xy 181.169818 -353.535488) (xy 181.170326 -353.536758)
			(xy 181.195726 -353.553776) (xy 182.90413 -353.553776) (xy 182.9054 -353.553268) (xy 182.922418 -353.527868)
			(xy 182.922418 -351.376742) (xy 182.922852 -351.366677) (xy 182.930583 -351.348089) (xy 182.937404 -351.340674)
			(xy 183.034178 -351.2439) (xy 183.041581 -351.237066) (xy 183.060179 -351.22936) (xy 183.070246 -351.228914)
			(xy 186.836558 -351.228914) (xy 186.846624 -351.228481) (xy 186.865214 -351.220753) (xy 186.872626 -351.213928)
			(xy 187.08624 -351.00006) (xy 187.093638 -350.993213) (xy 187.112237 -350.985484) (xy 187.122308 -350.985074)
			(xy 188.307726 -350.985074) (xy 188.317794 -350.984646) (xy 188.336389 -350.976922) (xy 188.343794 -350.970088)
			(xy 188.768228 -350.545654) (xy 188.775626 -350.538806) (xy 188.794224 -350.531074) (xy 188.804296 -350.530668)
			(xy 189.01156 -350.530668) (xy 189.01156 -350.533208) (xy 190.28156 -350.533208) (xy 190.291586 -350.533621)
			(xy 190.310115 -350.541284) (xy 190.324298 -350.555458) (xy 190.331973 -350.573982) (xy 190.33236 -350.584008)
			(xy 190.33236 -351.387664) (xy 190.331924 -351.397728) (xy 190.324189 -351.416312) (xy 190.317374 -351.423732)
			(xy 190.145416 -351.59569) (xy 190.138013 -351.602524) (xy 190.119415 -351.61023) (xy 190.109348 -351.610676)
			(xy 189.37478 -351.610676) (xy 189.364711 -351.611102) (xy 189.346109 -351.618819) (xy 189.338712 -351.625662)
			(xy 189.297818 -351.666556) (xy 189.290417 -351.673394) (xy 189.271818 -351.681106) (xy 189.26175 -351.681542)
			(xy 188.497464 -351.681542) (xy 188.487398 -351.681973) (xy 188.468807 -351.689701) (xy 188.461396 -351.696528)
			(xy 188.457586 -351.700338) (xy 188.450736 -351.707734) (xy 188.443002 -351.726334) (xy 188.4426 -351.736406)
			(xy 188.4426 -351.85604) (xy 188.443031 -351.866107) (xy 188.450755 -351.884701) (xy 188.457586 -351.892108)
			(xy 188.463174 -351.897696) (xy 188.481716 -351.905316) (xy 189.4205 -351.905316) (xy 189.43057 -351.90574)
			(xy 189.449173 -351.913456) (xy 189.456568 -351.920302) (xy 189.48146 -351.945194) (xy 189.488312 -351.95259)
			(xy 189.496055 -351.971189) (xy 189.496446 -351.981262) (xy 189.496446 -352.914712) (xy 189.496019 -352.92478)
			(xy 189.488296 -352.943376) (xy 189.48146 -352.95078) (xy 189.41288 -353.01936) (xy 189.405482 -353.026208)
			(xy 189.386884 -353.033941) (xy 189.376812 -353.034346) (xy 188.48451 -353.034346) (xy 188.47444 -353.034769)
			(xy 188.455837 -353.042486) (xy 188.448442 -353.049332) (xy 188.403992 -353.093782) (xy 188.39716 -353.101186)
			(xy 188.389456 -353.119784) (xy 188.389006 -353.12985) (xy 188.389006 -353.167188) (xy 188.389427 -353.177259)
			(xy 188.397139 -353.195866) (xy 188.403992 -353.203256) (xy 188.4426 -353.241864) (xy 188.449997 -353.248714)
			(xy 188.468595 -353.256454) (xy 188.478668 -353.25685) (xy 189.363858 -353.25685) (xy 189.373922 -353.257285)
			(xy 189.392507 -353.26502) (xy 189.399926 -353.271836) (xy 189.48146 -353.35337) (xy 189.4883 -353.36077)
			(xy 189.496015 -353.379369) (xy 189.496446 -353.389438) (xy 189.496446 -353.560888) (xy 189.496954 -353.562158)
			(xy 189.522354 -353.579176) (xy 191.230758 -353.579176) (xy 191.232028 -353.578668) (xy 191.249046 -353.553268)
			(xy 191.249046 -351.402142) (xy 191.249481 -351.392078) (xy 191.257215 -351.373493) (xy 191.264032 -351.366074)
			(xy 191.37376 -351.256346) (xy 191.38116 -351.249504) (xy 191.399758 -351.241784) (xy 191.409828 -351.24136)
			(xy 193.928746 -351.24136) (xy 193.938811 -351.241793) (xy 193.957398 -351.249526) (xy 193.964814 -351.256346)
			(xy 193.974974 -351.266506) (xy 193.982377 -351.27334) (xy 194.000975 -351.281047) (xy 194.011042 -351.281492)
			(xy 194.983608 -351.281492) (xy 194.986402 -351.278952) (xy 194.98818 -351.28073) (xy 195.255134 -351.28073)
			(xy 195.255134 -351.27692) (xy 197.02272 -351.27692) (xy 197.032788 -351.277347) (xy 197.051385 -351.285069)
			(xy 197.058788 -351.291906) (xy 197.706488 -351.939606) (xy 197.713335 -351.947004) (xy 197.721069 -351.965602)
			(xy 197.721474 -351.975674) (xy 197.721474 -365.004604) (xy 197.72105 -365.014673) (xy 197.713331 -365.033274)
			(xy 197.706488 -365.040672) (xy 195.932806 -366.814354) (xy 195.92541 -366.821206) (xy 195.906812 -366.82895)
			(xy 195.896738 -366.82934) (xy 183.993282 -366.82934) (xy 183.983215 -366.828912) (xy 183.964621 -366.821186)
			(xy 183.957214 -366.814354) (xy 182.343806 -365.200946) (xy 182.33641 -365.194094) (xy 182.317812 -365.18635)
			(xy 182.307738 -365.18596) (xy 180.150262 -365.18596) (xy 180.140196 -365.186392) (xy 180.121607 -365.194122)
			(xy 180.114194 -365.200946) (xy 180.062886 -365.252254) (xy 180.056039 -365.259651) (xy 180.048311 -365.278251)
			(xy 180.0479 -365.288322) (xy 180.0479 -366.879378) (xy 180.0479 -367.170208) (xy 180.538374 -367.660682)
			(xy 181.039514 -367.660682) (xy 181.043587 -367.605023) (xy 181.055722 -367.55055) (xy 181.075658 -367.498424)
			(xy 181.102972 -367.449756) (xy 181.13708 -367.405584) (xy 181.177257 -367.366849) (xy 181.222645 -367.334377)
			(xy 181.272277 -367.308859) (xy 181.325097 -367.29084) (xy 181.379976 -367.280703) (xy 181.435747 -367.278665)
			(xy 181.491221 -367.284768) (xy 181.545214 -367.298884) (xy 181.596577 -367.320711) (xy 181.644215 -367.349784)
			(xy 181.687111 -367.385483) (xy 181.724353 -367.427047) (xy 181.755147 -367.473591) (xy 181.778835 -367.524122)
			(xy 181.794913 -367.577564) (xy 181.803039 -367.632778) (xy 181.803548 -367.660682) (xy 181.803039 -367.688586)
			(xy 181.794913 -367.7438) (xy 181.778835 -367.797242) (xy 181.755147 -367.847773) (xy 181.724353 -367.894317)
			(xy 181.687111 -367.935881) (xy 181.644215 -367.97158) (xy 181.596577 -368.000653) (xy 181.545214 -368.02248)
			(xy 181.491221 -368.036596) (xy 181.435747 -368.042699) (xy 181.379976 -368.040661) (xy 181.325097 -368.030524)
			(xy 181.272277 -368.012505) (xy 181.222645 -367.986987) (xy 181.177257 -367.954515) (xy 181.13708 -367.91578)
			(xy 181.102972 -367.871608) (xy 181.075658 -367.82294) (xy 181.055722 -367.770814) (xy 181.043587 -367.716341)
			(xy 181.039514 -367.660682) (xy 180.538374 -367.660682) (xy 181.109112 -368.23142) (xy 181.399942 -368.23142)
		)
		(stroke
			(width 0)
			(type solid)
		)
		(fill yes)
		(layer "F.Cu")
		(net "GND")
	)
	(gr_poly
		(pts
			(xy 102.909116 -188.632846) (xy 102.909116 -186.896502) (xy 102.909878 -186.89574) (xy 102.909878 -186.464956)
			(xy 102.799388 -186.354466) (xy 102.2985 -186.354466) (xy 101.629464 -187.023502) (xy 101.629464 -189.041024)
			(xy 101.434392 -189.236096) (xy 101.31806 -189.236096) (xy 101.29266 -189.261496) (xy 96.581722 -189.261496)
			(xy 96.401382 -189.081156) (xy 96.401382 -185.110628) (xy 96.576642 -184.935368) (xy 101.732334 -184.935368)
			(xy 102.425754 -184.241948) (xy 103.270558 -184.241948) (xy 103.588566 -184.559956) (xy 104.783382 -184.559956)
			(xy 104.783382 -180.59273) (xy 104.956864 -180.419248) (xy 110.034578 -180.419248) (xy 110.744762 -179.709064)
			(xy 110.897416 -179.709064) (xy 110.89767 -179.70881) (xy 111.7854 -179.70881) (xy 111.84509 -179.7685)
			(xy 111.84509 -180.111654) (xy 112.037622 -180.304186) (xy 112.037622 -181.607714) (xy 111.854996 -181.79034)
			(xy 111.753396 -181.79034) (xy 111.656876 -181.88686) (xy 110.7186 -181.88686) (xy 110.65764 -181.94782)
			(xy 110.65764 -184.53862) (xy 110.455964 -184.740296) (xy 104.963722 -184.740296) (xy 104.783382 -184.559956)
			(xy 103.588566 -184.559956) (xy 104.231694 -185.203084) (xy 109.767878 -185.203084) (xy 109.813344 -185.24855)
			(xy 110.40999 -185.24855) (xy 110.65764 -185.4962) (xy 110.65764 -187.07862) (xy 110.246414 -187.489846)
			(xy 109.82452 -187.489846) (xy 109.817154 -187.497212) (xy 105.118154 -187.497212) (xy 104.940354 -187.675012)
			(xy 104.940354 -189.148212) (xy 105.143554 -189.351412) (xy 112.09655 -189.351412) (xy 112.307878 -189.140084)
			(xy 112.307878 -183.679084) (xy 112.85855 -183.128412) (xy 118.33733 -183.128412) (xy 118.403878 -183.061864)
			(xy 118.403878 -181.51221) (xy 118.21668 -181.325012) (xy 113.296954 -181.325012) (xy 113.017554 -181.045612)
			(xy 113.017554 -179.395374) (xy 113.432844 -178.980084) (xy 118.598696 -178.980084) (xy 119.088154 -178.490626)
			(xy 119.088154 -176.151286) (xy 119.038878 -176.10201) (xy 118.734078 -176.10201) (xy 118.65864 -176.177448)
			(xy 118.65864 -178.26482) (xy 118.431564 -178.491896) (xy 113.193322 -178.491896) (xy 113.012982 -178.311556)
			(xy 113.012982 -174.316136) (xy 113.196116 -174.133256) (xy 118.201694 -174.133256) (xy 118.201694 -174.272194)
			(xy 118.82247 -174.272194) (xy 118.82247 -173.72584) (xy 119.014748 -173.533562) (xy 119.744998 -173.533562)
			(xy 120.091962 -173.880526) (xy 120.904762 -173.880526) (xy 121.197878 -173.58741) (xy 121.197878 -172.630084)
			(xy 121.451878 -172.376084) (xy 126.912624 -172.376084) (xy 127.700278 -171.589446) (xy 127.700278 -169.16781)
			(xy 127.547878 -169.01541) (xy 127.039878 -169.01541) (xy 126.86284 -169.192448) (xy 126.86284 -171.55922)
			(xy 126.661164 -171.760896) (xy 126.309628 -171.760896) (xy 126.2761 -171.794424) (xy 121.565162 -171.794424)
			(xy 121.531634 -171.760896) (xy 121.473722 -171.760896) (xy 121.293382 -171.580556) (xy 121.293382 -167.614092)
			(xy 121.505218 -167.402256) (xy 126.511558 -167.402256) (xy 126.511558 -167.541194) (xy 127.10287 -167.541194)
			(xy 127.10287 -166.99484) (xy 127.295148 -166.802562) (xy 128.025398 -166.802562) (xy 128.055878 -166.772082)
			(xy 128.055878 -166.489888) (xy 128.773682 -165.772084) (xy 129.535682 -165.772084) (xy 129.756154 -165.551612)
			(xy 129.756154 -163.952174) (xy 130.095244 -163.613084) (xy 135.929878 -163.613084) (xy 136.183878 -163.359084)
			(xy 136.183878 -161.835084) (xy 136.945878 -161.073084) (xy 142.424404 -161.073084) (xy 142.813278 -160.68421)
			(xy 142.813278 -156.64561) (xy 142.813278 -143.996918) (xy 142.14856 -143.3322) (xy 130.43662 -143.3322)
			(xy 129.72034 -144.04848) (xy 129.72034 -148.3106) (xy 131.33324 -149.9235) (xy 138.18362 -149.9235)
			(xy 138.80338 -150.54326) (xy 138.80338 -155.728924) (xy 138.28522 -156.247084) (xy 137.199878 -156.247084)
			(xy 136.781286 -156.665676) (xy 135.693658 -156.665676) (xy 135.037322 -157.322012) (xy 133.362954 -157.322012)
			(xy 133.359652 -157.31871) (xy 133.338316 -157.31871) (xy 133.338316 -157.297374) (xy 133.337554 -157.296612)
			(xy 133.337554 -157.129734) (xy 133.338316 -157.128972) (xy 133.338316 -156.612844) (xy 133.709918 -156.241242)
			(xy 134.178294 -156.241242) (xy 134.250684 -156.168852) (xy 135.130794 -156.168852) (xy 135.135874 -156.163772)
			(xy 135.135874 -155.947872) (xy 135.130794 -155.942792) (xy 134.225284 -155.942792) (xy 134.17423 -155.891738)
			(xy 134.17423 -154.89301) (xy 134.247128 -154.820112) (xy 135.130794 -154.820112) (xy 135.135874 -154.815032)
			(xy 135.135874 -154.596592) (xy 135.130794 -154.591512) (xy 134.28218 -154.591512) (xy 134.17423 -154.483562)
			(xy 134.17423 -154.280362) (xy 134.16661 -154.272742) (xy 132.42925 -154.272742) (xy 132.42163 -154.280362)
			(xy 132.42163 -156.25953) (xy 132.07365 -156.60751) (xy 129.934716 -156.60751) (xy 129.934716 -156.598112)
			(xy 127.45085 -156.598112) (xy 127.343154 -156.705808) (xy 127.343154 -159.170878) (xy 128.130554 -159.958278)
			(xy 128.130554 -162.919156) (xy 129.751582 -162.919156) (xy 129.751582 -158.942786) (xy 129.953512 -158.740856)
			(xy 134.9502 -158.740856) (xy 134.9502 -158.879794) (xy 135.560308 -158.879794) (xy 135.560308 -158.333186)
			(xy 135.753094 -158.1404) (xy 136.483852 -158.1404) (xy 137.006584 -158.663132) (xy 137.006584 -159.967168)
			(xy 136.73582 -160.237932) (xy 135.313928 -160.237932) (xy 135.16864 -160.38322) (xy 135.16864 -162.87242)
			(xy 134.941564 -163.099496) (xy 129.931922 -163.099496) (xy 129.751582 -162.919156) (xy 128.130554 -162.919156)
			(xy 128.130554 -165.373812) (xy 127.952754 -165.551612) (xy 127.010922 -165.551612) (xy 126.455424 -166.10711)
			(xy 126.200916 -166.10711) (xy 126.095252 -166.001446) (xy 124.901452 -166.001446) (xy 124.880116 -165.98011)
			(xy 124.880116 -165.281864) (xy 125.259338 -164.902642) (xy 125.720094 -164.902642) (xy 125.792484 -164.830252)
			(xy 126.672594 -164.830252) (xy 126.675134 -164.827712) (xy 126.675134 -164.609272) (xy 126.670054 -164.604192)
			(xy 125.767084 -164.604192) (xy 125.71603 -164.553138) (xy 125.71603 -163.56965) (xy 125.804168 -163.481512)
			(xy 126.672594 -163.481512) (xy 126.682754 -163.471352) (xy 126.682754 -163.263072) (xy 126.672594 -163.252912)
			(xy 125.82398 -163.252912) (xy 125.71603 -163.144962) (xy 125.71603 -162.941762) (xy 125.70841 -162.934142)
			(xy 123.97105 -162.934142) (xy 123.96343 -162.941762) (xy 123.96343 -164.92855) (xy 123.619768 -165.272212)
			(xy 119.088154 -165.272212) (xy 119.037354 -165.323012) (xy 119.037354 -165.88486) (xy 119.824754 -166.67226)
			(xy 119.824754 -168.08196) (xy 119.824754 -172.130212) (xy 119.703342 -172.251624) (xy 118.76151 -172.251624)
			(xy 118.301008 -172.712126) (xy 116.599716 -172.712126) (xy 116.599716 -172.000164) (xy 116.966238 -171.633642)
			(xy 117.439694 -171.633642) (xy 117.512084 -171.561252) (xy 118.389654 -171.561252) (xy 118.399814 -171.551092)
			(xy 118.399814 -171.342812) (xy 118.392194 -171.335192) (xy 117.486684 -171.335192) (xy 117.43563 -171.284138)
			(xy 117.43563 -170.29811) (xy 117.523768 -170.209972) (xy 118.394734 -170.209972) (xy 118.402354 -170.202352)
			(xy 118.402354 -169.996612) (xy 118.392194 -169.986452) (xy 117.54612 -169.986452) (xy 117.43563 -169.875962)
			(xy 117.43563 -169.672762) (xy 117.42801 -169.665142) (xy 115.69065 -169.665142) (xy 115.68303 -169.672762)
			(xy 115.68303 -171.69511) (xy 115.37823 -171.99991) (xy 110.83798 -171.99991) (xy 110.76686 -172.07103)
			(xy 110.76686 -172.49902) (xy 111.201708 -172.933868) (xy 111.201708 -173.793912) (xy 111.672878 -174.265336)
			(xy 111.672878 -178.129438) (xy 111.515906 -178.28641) (xy 110.732316 -178.28641) (xy 110.610396 -178.16449)
			(xy 110.610396 -177.87747) (xy 110.311692 -177.578766) (xy 109.252258 -177.578766) (xy 109.20603 -177.532538)
			(xy 109.20603 -176.55667) (xy 109.304328 -176.458372) (xy 110.162594 -176.458372) (xy 110.170214 -176.450752)
			(xy 110.170214 -176.242472) (xy 110.162594 -176.234852) (xy 109.31652 -176.234852) (xy 109.20603 -176.124362)
			(xy 109.20603 -175.921162) (xy 109.19841 -175.913542) (xy 107.46105 -175.913542) (xy 107.45343 -175.921162)
			(xy 107.45343 -177.381662) (xy 107.450382 -177.38471) (xy 107.450382 -177.977292) (xy 107.190794 -178.23688)
			(xy 103.536496 -178.23688) (xy 103.533194 -178.240182) (xy 103.533194 -178.95951) (xy 108.370116 -178.95951)
			(xy 108.370116 -178.248564) (xy 108.736638 -177.882042) (xy 109.211364 -177.882042) (xy 109.283754 -177.809652)
			(xy 110.1979 -177.809652) (xy 110.420912 -178.032664) (xy 110.420912 -178.458876) (xy 109.945424 -178.934364)
			(xy 109.945424 -179.08651) (xy 109.690916 -179.08651) (xy 109.690916 -178.95951) (xy 108.370116 -178.95951)
			(xy 103.533194 -178.95951) (xy 103.533194 -182.47614) (xy 103.232712 -182.776622) (xy 102.362 -182.776622)
			(xy 102.224332 -182.638954) (xy 102.224332 -182.408322) (xy 101.915976 -182.099966) (xy 100.870258 -182.099966)
			(xy 100.82403 -182.053738) (xy 100.82403 -181.07787) (xy 100.919788 -180.982112) (xy 101.780594 -180.982112)
			(xy 101.788214 -180.974492) (xy 101.788214 -180.761132) (xy 101.780594 -180.753512) (xy 100.93198 -180.753512)
			(xy 100.82403 -180.645562) (xy 100.82403 -180.442362) (xy 100.81641 -180.434742) (xy 99.07905 -180.434742)
			(xy 99.07143 -180.442362) (xy 99.07143 -181.902862) (xy 99.072446 -181.903878) (xy 99.072446 -182.438294)
			(xy 98.763328 -182.747412) (xy 94.040198 -182.747412) (xy 93.829124 -182.536338) (xy 93.829124 -182.493412)
			(xy 93.422724 -182.087012) (xy 92.509848 -182.087012) (xy 92.498926 -182.07609) (xy 92.430346 -182.007764)
			(xy 92.430346 -181.91099) (xy 92.428314 -181.90591) (xy 92.428314 -181.063138) (xy 92.430346 -181.057804)
			(xy 92.430346 -181.01691) (xy 92.461842 -180.985414) (xy 92.461842 -180.98389) (xy 92.474542 -180.97119)
			(xy 93.310202 -180.97119) (xy 93.330522 -180.95087) (xy 93.330522 -180.76799) (xy 93.297502 -180.73497)
			(xy 92.465906 -180.73497) (xy 92.430346 -180.69941) (xy 92.430346 -180.64099) (xy 92.428314 -180.63591)
			(xy 92.428314 -180.449474) (xy 92.413328 -180.413406) (xy 92.3925 -180.392578) (xy 92.364052 -180.380894)
			(xy 92.352368 -180.384196) (xy 92.336181 -180.388962) (xy 92.303397 -180.396966) (xy 92.286836 -180.400198)
			(xy 92.258213 -180.405302) (xy 92.200337 -180.410894) (xy 92.171266 -180.411374) (xy 92.164916 -180.411374)
			(xy 92.132233 -180.410745) (xy 92.067249 -180.403616) (xy 92.003341 -180.389852) (xy 91.97213 -180.380132)
			(xy 91.96451 -180.377592) (xy 90.711274 -180.377592) (xy 90.675714 -180.413152) (xy 90.675714 -181.889908)
			(xy 90.676984 -181.889908) (xy 90.676984 -182.413656) (xy 90.34272 -182.74792) (xy 88.146128 -182.74792)
			(xy 88.09482 -182.696612) (xy 86.492334 -182.696612) (xy 86.327234 -182.861712) (xy 85.8266 -182.861712)
			(xy 85.115654 -182.150766) (xy 84.080858 -182.150766) (xy 84.03463 -182.104538) (xy 84.03463 -181.11597)
			(xy 84.117688 -181.032912) (xy 84.991194 -181.032912) (xy 85.001354 -181.022752) (xy 85.001354 -180.814472)
			(xy 84.993734 -180.806852) (xy 84.14512 -180.806852) (xy 84.03463 -180.696362) (xy 84.03463 -180.493162)
			(xy 84.02701 -180.485542) (xy 82.28965 -180.485542) (xy 82.28203 -180.493162) (xy 82.28203 -182.468266)
			(xy 81.938876 -182.81142) (xy 78.299564 -182.81142) (xy 78.017878 -182.529734) (xy 78.017878 -181.457854)
			(xy 77.920342 -181.360318) (xy 76.75118 -181.360318) (xy 76.493878 -181.61762) (xy 76.493878 -183.399938)
			(xy 83.195668 -183.399938) (xy 83.195668 -182.847234) (xy 83.58886 -182.454042) (xy 84.047584 -182.454042)
			(xy 84.119974 -182.381652) (xy 84.993988 -182.381652) (xy 85.303106 -182.69077) (xy 85.303106 -183.289702)
			(xy 85.12937 -183.463438) (xy 91.595956 -183.463438) (xy 91.595956 -182.754524) (xy 91.921838 -182.428642)
			(xy 92.430346 -182.428642) (xy 92.543376 -182.315612) (xy 93.414088 -182.315612) (xy 93.575378 -182.476902)
			(xy 93.575378 -182.477156) (xy 93.622368 -182.524146) (xy 93.622368 -182.98922) (xy 93.178376 -183.433212)
			(xy 99.987354 -183.433212) (xy 99.987354 -182.876698) (xy 99.988116 -182.875936) (xy 99.988116 -182.787544)
			(xy 100.372418 -182.403242) (xy 100.829364 -182.403242) (xy 100.901754 -182.330852) (xy 101.8159 -182.330852)
			(xy 102.009956 -182.524908) (xy 102.009956 -183.021732) (xy 101.563424 -183.468264) (xy 101.563424 -183.60771)
			(xy 101.308916 -183.60771) (xy 101.308916 -183.48071) (xy 99.988116 -183.48071) (xy 99.988116 -183.433974)
			(xy 99.987354 -183.433212) (xy 93.178376 -183.433212) (xy 93.171264 -183.440324) (xy 93.171264 -183.590438)
			(xy 92.916756 -183.590438) (xy 92.916756 -183.463438) (xy 91.595956 -183.463438) (xy 85.12937 -183.463438)
			(xy 85.08873 -183.504078) (xy 84.774024 -183.504078) (xy 84.774024 -183.65851) (xy 84.519516 -183.65851)
			(xy 84.519516 -183.53151) (xy 83.198716 -183.53151) (xy 83.198716 -183.402986) (xy 83.195668 -183.399938)
			(xy 76.493878 -183.399938) (xy 76.493878 -183.926734) (xy 76.32065 -184.099962) (xy 76.273914 -184.099962)
			(xy 76.17968 -184.194196) (xy 71.468742 -184.194196) (xy 71.288402 -184.013856) (xy 71.288402 -180.043582)
			(xy 71.46036 -179.871624) (xy 76.592176 -179.871624) (xy 77.249528 -179.214272) (xy 77.99832 -179.214272)
			(xy 78.017878 -179.194714) (xy 78.017878 -177.962052) (xy 78.017624 -177.962052) (xy 78.017624 -177.750978)
			(xy 77.941424 -177.674778) (xy 77.38872 -177.674778) (xy 76.756768 -177.042826) (xy 75.754738 -177.042826)
			(xy 75.70851 -176.996598) (xy 75.70851 -176.01057) (xy 75.804268 -175.914812) (xy 76.667614 -175.914812)
			(xy 76.682854 -175.899572) (xy 76.682854 -175.698912) (xy 76.670154 -175.686212) (xy 75.8063 -175.686212)
			(xy 75.70851 -175.588422) (xy 75.70851 -175.385222) (xy 75.70089 -175.377602) (xy 73.96353 -175.377602)
			(xy 73.95591 -175.385222) (xy 73.95591 -177.350928) (xy 73.615804 -177.691034) (xy 69.870828 -177.691034)
			(xy 69.635878 -177.456084) (xy 69.635878 -172.95241) (xy 69.254878 -172.57141) (xy 68.62064 -172.57141)
			(xy 68.13423 -173.05528) (xy 68.13423 -175.258222) (xy 67.971416 -175.421036) (xy 67.942206 -175.421036)
			(xy 67.86626 -175.496982) (xy 63.155322 -175.496982) (xy 62.974982 -175.316642) (xy 62.974982 -171.344844)
			(xy 63.17107 -171.148756) (xy 68.323968 -171.148756) (xy 69.027802 -170.444922) (xy 69.536564 -170.444922)
			(xy 69.65315 -170.328336) (xy 69.65315 -169.592498) (xy 69.658738 -169.58691) (xy 69.658738 -169.080688)
			(xy 69.56679 -168.98874) (xy 69.101208 -168.98874) (xy 68.448174 -168.335706) (xy 67.43954 -168.335706)
			(xy 67.393312 -168.289478) (xy 67.393312 -167.297608) (xy 67.473068 -167.217852) (xy 68.354194 -167.217852)
			(xy 68.361814 -167.210232) (xy 68.361814 -166.996872) (xy 68.354194 -166.989252) (xy 67.501262 -166.989252)
			(xy 67.393312 -166.881302) (xy 67.393312 -166.678102) (xy 67.385692 -166.670482) (xy 65.648332 -166.670482)
			(xy 65.640712 -166.678102) (xy 65.640712 -168.674288) (xy 65.298066 -169.016934) (xy 59.515756 -169.016934)
			(xy 59.161934 -168.663112) (xy 59.161934 -164.365432) (xy 58.829194 -164.032692) (xy 51.905154 -164.032692)
			(xy 51.898804 -164.039042) (xy 50.529744 -164.039042) (xy 50.246534 -164.322252) (xy 50.246534 -169.622724)
			(xy 66.560954 -169.622724) (xy 66.560954 -169.145458) (xy 66.561716 -169.144696) (xy 66.561716 -169.013124)
			(xy 66.935858 -168.638982) (xy 67.405504 -168.638982) (xy 67.477894 -168.566592) (xy 68.352416 -168.566592)
			(xy 68.635626 -168.849802) (xy 68.635626 -169.38371) (xy 68.294504 -169.724832) (xy 68.137024 -169.724832)
			(xy 68.137024 -169.843196) (xy 67.882516 -169.843196) (xy 67.882516 -169.724832) (xy 66.663062 -169.724832)
			(xy 66.654426 -169.716196) (xy 66.561716 -169.716196) (xy 66.561716 -169.623486) (xy 66.560954 -169.622724)
			(xy 50.246534 -169.622724) (xy 50.246534 -174.284894) (xy 52.020724 -176.059084) (xy 68.111878 -176.059084)
			(xy 68.238878 -176.186084) (xy 68.238878 -177.964084) (xy 68.320666 -178.045872) (xy 68.873878 -178.045872)
			(xy 69.170296 -178.34229) (xy 74.86396 -178.34229) (xy 74.86396 -177.714148) (xy 75.232006 -177.346102)
			(xy 75.721464 -177.346102) (xy 75.806554 -177.261012) (xy 76.727812 -177.261012) (xy 76.966572 -177.499772)
			(xy 76.966572 -178.189636) (xy 76.74356 -178.412648) (xy 76.450444 -178.412648) (xy 76.450444 -178.54041)
			(xy 76.195936 -178.54041) (xy 76.195936 -178.41341) (xy 74.875136 -178.41341) (xy 74.875136 -178.353466)
			(xy 74.86396 -178.34229) (xy 69.170296 -178.34229) (xy 69.889878 -179.061872) (xy 69.889878 -183.502808)
			(xy 71.137018 -184.749948) (xy 76.421742 -184.749948) (xy 76.620878 -184.949084) (xy 76.620878 -186.473084)
			(xy 76.874878 -186.727084) (xy 78.271878 -186.727084) (xy 78.525878 -186.981084) (xy 78.525878 -186.9948)
			(xy 78.986888 -187.45581) (xy 78.986888 -189.131956) (xy 79.611982 -189.131956) (xy 79.611982 -185.166)
			(xy 79.824326 -184.953656) (xy 85.020658 -184.953656) (xy 85.42147 -184.552844) (xy 85.42147 -184.54624)
			(xy 85.46211 -184.5056) (xy 85.46211 -184.286144) (xy 85.546438 -184.201816) (xy 86.280752 -184.201816)
			(xy 86.430104 -184.351168) (xy 86.430104 -184.440068) (xy 86.866222 -184.876186) (xy 86.866222 -186.179714)
			(xy 86.65337 -186.392566) (xy 85.460586 -186.392566) (xy 84.828888 -187.024264) (xy 84.828888 -189.058296)
			(xy 84.8233 -189.063884) (xy 88.009222 -189.063884) (xy 88.009222 -185.094372) (xy 88.21801 -184.885584)
			(xy 93.168978 -184.885584) (xy 93.168978 -184.88533) (xy 93.452188 -184.88533) (xy 93.81871 -184.518808)
			(xy 93.81871 -184.478168) (xy 94.010988 -184.28589) (xy 94.051628 -184.28589) (xy 94.055692 -184.281826)
			(xy 94.802706 -184.281826) (xy 95.263462 -184.742582) (xy 95.263462 -186.111642) (xy 95.080836 -186.294268)
			(xy 94.419166 -186.294268) (xy 94.393512 -186.268614) (xy 94.320614 -186.268614) (xy 94.316296 -186.272932)
			(xy 93.658182 -186.272932) (xy 93.108272 -186.822842) (xy 93.108272 -189.036452) (xy 92.9005 -189.244224)
			(xy 88.189562 -189.244224) (xy 88.009222 -189.063884) (xy 84.8233 -189.063884) (xy 84.621116 -189.266068)
			(xy 84.549488 -189.266068) (xy 84.50326 -189.312296) (xy 79.792322 -189.312296) (xy 79.611982 -189.131956)
			(xy 78.986888 -189.131956) (xy 78.986888 -189.514226) (xy 79.247746 -189.775084) (xy 101.766878 -189.775084)
		)
		(stroke
			(width 0)
			(type solid)
		)
		(fill yes)
		(layer "F.Cu")
		(net "GND")
	)
	(gr_poly
		(pts
			(xy 37.377878 -407.303732) (xy 37.387929 -407.303227) (xy 37.406491 -407.295507) (xy 37.413946 -407.288746)
			(xy 37.822632 -406.88006) (xy 37.827458 -406.84704) (xy 37.81933 -406.832054) (xy 37.777386 -406.754012)
			(xy 37.699228 -406.594984) (xy 37.627739 -406.432848) (xy 37.563043 -406.267884) (xy 37.505252 -406.100376)
			(xy 37.454465 -405.930613) (xy 37.410769 -405.758888) (xy 37.374241 -405.585498) (xy 37.344942 -405.41074)
			(xy 37.322924 -405.234916) (xy 37.308224 -405.05833) (xy 37.300868 -404.881286) (xy 37.300408 -404.792688)
			(xy 37.300898 -404.700711) (xy 37.308826 -404.516927) (xy 37.324666 -404.333656) (xy 37.348388 -404.151238)
			(xy 37.379949 -403.970011) (xy 37.419291 -403.790313) (xy 37.466339 -403.612477) (xy 37.521007 -403.436834)
			(xy 37.583192 -403.263709) (xy 37.652781 -403.093425) (xy 37.729642 -402.926298) (xy 37.813635 -402.762638)
			(xy 37.8587 -402.682456) (xy 37.861796 -402.676639) (xy 37.865141 -402.663898) (xy 37.865304 -402.65731)
			(xy 37.865304 -382.31699) (xy 37.864879 -382.306921) (xy 37.857163 -382.288318) (xy 37.850318 -382.280922)
			(xy 37.577014 -382.007618) (xy 37.569612 -382.000783) (xy 37.551013 -381.993077) (xy 37.540946 -381.992632)
			(xy 28.676346 -381.992632) (xy 28.657296 -381.984504) (xy 28.650692 -381.977646) (xy 14.203172 -381.977646)
			(xy 14.193105 -381.977216) (xy 14.174513 -381.969489) (xy 14.167104 -381.96266) (xy 13.560806 -381.356108)
			(xy 13.553408 -381.34926) (xy 13.53481 -381.341522) (xy 13.524738 -381.341122) (xy 9.4361 -381.341122)
			(xy 9.42603 -381.341546) (xy 9.407428 -381.349262) (xy 9.400032 -381.356108) (xy 9.390888 -381.365252)
			(xy 9.38404 -381.372649) (xy 9.376311 -381.391248) (xy 9.375902 -381.40132) (xy 9.375902 -381.922274)
			(xy 9.375465 -381.932338) (xy 9.367732 -381.950923) (xy 9.360916 -381.958342) (xy 9.11733 -382.201928)
			(xy 9.109931 -382.208771) (xy 9.091332 -382.216491) (xy 9.081262 -382.216914) (xy 6.024372 -382.216914)
			(xy 6.014304 -382.216486) (xy 5.995705 -382.208766) (xy 5.988304 -382.201928) (xy 5.396484 -381.610108)
			(xy 5.389627 -381.602714) (xy 5.381877 -381.584115) (xy 5.381498 -381.57404) (xy 5.381498 -373.632984)
			(xy 5.381924 -373.622915) (xy 5.389642 -373.604315) (xy 5.396484 -373.596916) (xy 5.7658 -373.2276)
			(xy 5.773199 -373.220753) (xy 5.791796 -373.213019) (xy 5.801868 -373.212614) (xy 26.09469 -373.212614)
			(xy 26.104761 -373.212193) (xy 26.12337 -373.204483) (xy 26.130758 -373.197628) (xy 26.481786 -372.8466)
			(xy 26.488634 -372.839202) (xy 26.49637 -372.820604) (xy 26.496772 -372.810532) (xy 26.496772 -369.40236)
			(xy 26.496341 -369.392294) (xy 26.488613 -369.373702) (xy 26.481786 -369.366292) (xy 26.130758 -369.015264)
			(xy 26.12336 -369.008417) (xy 26.104761 -369.000688) (xy 26.09469 -369.000278) (xy 3.615436 -369.000278)
			(xy 3.60537 -369.000712) (xy 3.586781 -369.00844) (xy 3.579368 -369.015264) (xy 3.350006 -369.244626)
			(xy 3.343163 -369.252026) (xy 3.335437 -369.270624) (xy 3.33502 -369.280694) (xy 3.33502 -387.214872)
			(xy 11.837416 -387.214872) (xy 11.837416 -385.547108) (xy 11.837906 -385.537204) (xy 11.845497 -385.518904)
			(xy 11.852148 -385.511548) (xy 11.996928 -385.366768) (xy 12.004306 -385.360012) (xy 12.022751 -385.352311)
			(xy 12.032742 -385.351782) (xy 12.683744 -385.351782) (xy 12.688836 -385.351939) (xy 12.698816 -385.353978)
			(xy 12.703556 -385.355846) (xy 12.7127 -385.359656) (xy 12.717526 -385.364228) (xy 12.724955 -385.370558)
			(xy 12.74319 -385.377481) (xy 12.762692 -385.377117) (xy 12.780656 -385.36952) (xy 12.787884 -385.362958)
			(xy 12.809728 -385.341368) (xy 12.817106 -385.334612) (xy 12.835551 -385.326911) (xy 12.845542 -385.326382)
			(xy 14.251432 -385.326382) (xy 14.261504 -385.325978) (xy 14.280102 -385.318243) (xy 14.2875 -385.311396)
			(xy 14.61643 -384.982466) (xy 14.621002 -384.977132) (xy 14.626082 -384.970782) (xy 14.631416 -384.95478)
			(xy 14.631416 -384.116326) (xy 14.646148 -384.116326) (xy 14.646148 -383.135124) (xy 14.646573 -383.125054)
			(xy 14.654293 -383.106456) (xy 14.661134 -383.099056) (xy 15.031212 -382.728978) (xy 15.038611 -382.722137)
			(xy 15.057211 -382.714418) (xy 15.06728 -382.713992) (xy 20.256246 -382.713992) (xy 20.266315 -382.714421)
			(xy 20.284915 -382.722137) (xy 20.292314 -382.728978) (xy 20.480274 -382.916938) (xy 20.487119 -382.924334)
			(xy 20.494837 -382.942936) (xy 20.49526 -382.953006) (xy 20.49526 -384.116326) (xy 20.497292 -384.116326)
			(xy 20.497292 -386.207254) (xy 20.496831 -386.217258) (xy 20.489111 -386.235721) (xy 20.482306 -386.243068)
			(xy 20.230338 -386.495036) (xy 20.222938 -386.501764) (xy 20.20451 -386.509481) (xy 20.194524 -386.510022)
			(xy 19.093688 -386.510022) (xy 19.064732 -386.5372) (xy 19.063208 -386.557266) (xy 19.062109 -386.566791)
			(xy 19.053849 -386.584077) (xy 19.039823 -386.597127) (xy 19.021988 -386.604123) (xy 19.012408 -386.60451)
			(xy 14.111732 -386.60451) (xy 14.101661 -386.604092) (xy 14.083062 -386.596368) (xy 14.075664 -386.589524)
			(xy 14.068552 -386.582412) (xy 14.060932 -386.56387) (xy 14.060932 -386.554726) (xy 14.059391 -386.545617)
			(xy 14.050891 -386.529242) (xy 14.037112 -386.516971) (xy 14.019866 -386.510417) (xy 14.01064 -386.510022)
			(xy 12.930124 -386.510022) (xy 12.920102 -386.51044) (xy 12.901581 -386.518106) (xy 12.887407 -386.532279)
			(xy 12.87974 -386.5508) (xy 12.879324 -386.560822) (xy 12.879324 -387.214872) (xy 20.930616 -387.214872)
			(xy 20.930616 -385.547108) (xy 20.931106 -385.537204) (xy 20.938697 -385.518904) (xy 20.945348 -385.511548)
			(xy 21.090128 -385.366768) (xy 21.097506 -385.360012) (xy 21.115951 -385.352311) (xy 21.125942 -385.351782)
			(xy 21.777198 -385.351782) (xy 21.787105 -385.352252) (xy 21.805405 -385.359855) (xy 21.812758 -385.366514)
			(xy 21.813012 -385.366768) (xy 21.822664 -385.376166) (xy 21.830018 -385.382647) (xy 21.848178 -385.389981)
			(xy 21.867762 -385.389981) (xy 21.885922 -385.382647) (xy 21.893276 -385.376166) (xy 21.902928 -385.366768)
			(xy 21.903182 -385.366514) (xy 21.910532 -385.359861) (xy 21.92884 -385.352293) (xy 21.938742 -385.351782)
			(xy 22.862032 -385.351782) (xy 22.872104 -385.351378) (xy 22.890702 -385.343643) (xy 22.8981 -385.336796)
			(xy 22.94509 -385.289806) (xy 22.952456 -385.282694) (xy 22.960076 -385.263898) (xy 22.960076 -384.116326)
			(xy 22.975062 -384.116326) (xy 22.975062 -382.944624) (xy 22.975484 -382.934554) (xy 22.983205 -382.915955)
			(xy 22.990048 -382.908556) (xy 23.137114 -382.76149) (xy 23.144514 -382.75465) (xy 23.163113 -382.746931)
			(xy 23.173182 -382.746504) (xy 28.321762 -382.746504) (xy 28.331833 -382.746922) (xy 28.350432 -382.754645)
			(xy 28.35783 -382.76149) (xy 28.3591 -382.76149) (xy 28.7655 -383.16789) (xy 28.772328 -383.175299)
			(xy 28.780055 -383.193891) (xy 28.780486 -383.203958) (xy 28.780486 -383.870962) (xy 28.779978 -383.87147)
			(xy 28.779978 -384.556) (xy 28.779724 -384.556254) (xy 28.779724 -386.213096) (xy 28.779252 -386.223003)
			(xy 28.77165 -386.241303) (xy 28.764992 -386.248656) (xy 28.518612 -386.495036) (xy 28.511221 -386.501775)
			(xy 28.492786 -386.509486) (xy 28.482798 -386.510022) (xy 28.172156 -386.510022) (xy 28.1432 -386.5372)
			(xy 28.141676 -386.557266) (xy 28.140608 -386.566797) (xy 28.132341 -386.584088) (xy 28.118305 -386.597139)
			(xy 28.10046 -386.604128) (xy 28.090876 -386.60451) (xy 23.190708 -386.60451) (xy 23.180636 -386.604104)
			(xy 23.162037 -386.596372) (xy 23.15464 -386.589524) (xy 23.147528 -386.582412) (xy 23.139908 -386.56387)
			(xy 23.139908 -386.557012) (xy 23.138777 -386.547544) (xy 23.130559 -386.53036) (xy 23.116615 -386.517382)
			(xy 23.098887 -386.510415) (xy 23.089362 -386.510022) (xy 22.023324 -386.510022) (xy 22.013302 -386.51044)
			(xy 21.994781 -386.518106) (xy 21.980607 -386.532279) (xy 21.97294 -386.5508) (xy 21.972524 -386.560822)
			(xy 21.972524 -387.214872) (xy 21.972039 -387.224777) (xy 21.964446 -387.243078) (xy 21.957792 -387.250432)
			(xy 21.813012 -387.395212) (xy 21.805618 -387.401948) (xy 21.787186 -387.409661) (xy 21.777198 -387.410198)
			(xy 21.125942 -387.410198) (xy 21.115934 -387.409764) (xy 21.09747 -387.402028) (xy 21.090128 -387.395212)
			(xy 20.945348 -387.250432) (xy 20.938706 -387.243073) (xy 20.931131 -387.224773) (xy 20.930616 -387.214872)
			(xy 12.879324 -387.214872) (xy 12.878839 -387.224777) (xy 12.871246 -387.243078) (xy 12.864592 -387.250432)
			(xy 12.719812 -387.395212) (xy 12.712418 -387.401948) (xy 12.693986 -387.409661) (xy 12.683998 -387.410198)
			(xy 12.032742 -387.410198) (xy 12.022734 -387.409764) (xy 12.00427 -387.402028) (xy 11.996928 -387.395212)
			(xy 11.852148 -387.250432) (xy 11.845506 -387.243073) (xy 11.837931 -387.224773) (xy 11.837416 -387.214872)
			(xy 3.33502 -387.214872) (xy 3.33502 -401.275042) (xy 3.335451 -401.285108) (xy 3.343179 -401.3037)
			(xy 3.350006 -401.31111) (xy 3.839718 -401.800822) (xy 3.847114 -401.807674) (xy 3.865713 -401.815414)
			(xy 3.875786 -401.815808) (xy 17.396714 -401.815808) (xy 17.406783 -401.815383) (xy 17.425385 -401.807666)
			(xy 17.432782 -401.800822) (xy 17.723104 -401.5105) (xy 17.72995 -401.503101) (xy 17.737684 -401.484503)
			(xy 17.73809 -401.474432) (xy 17.73809 -395.350746) (xy 17.737657 -395.34068) (xy 17.729927 -395.322091)
			(xy 17.723104 -395.314678) (xy 17.562576 -395.15415) (xy 17.555178 -395.147302) (xy 17.53658 -395.139569)
			(xy 17.526508 -395.139164) (xy 14.677898 -395.139164) (xy 14.667829 -395.139589) (xy 14.649231 -395.147311)
			(xy 14.64183 -395.15415) (xy 12.710668 -397.085312) (xy 12.703272 -397.092163) (xy 12.684673 -397.0999)
			(xy 12.6746 -397.100298) (xy 11.38809 -397.100298) (xy 11.378021 -397.099873) (xy 11.359419 -397.092156)
			(xy 11.352022 -397.085312) (xy 9.67232 -395.40561) (xy 9.66547 -395.398213) (xy 9.657728 -395.379615)
			(xy 9.657334 -395.369542) (xy 9.657334 -393.558776) (xy 9.657762 -393.548708) (xy 9.665487 -393.530113)
			(xy 9.67232 -393.522708) (xy 9.67613 -393.518898) (xy 9.68375 -393.500356) (xy 9.68375 -390.98093)
			(xy 9.684187 -390.970867) (xy 9.691925 -390.952285) (xy 9.698736 -390.944862) (xy 11.839194 -388.804404)
			(xy 11.846592 -388.797556) (xy 11.86519 -388.789819) (xy 11.875262 -388.789418) (xy 12.50188 -388.789418)
			(xy 12.511943 -388.789856) (xy 12.530525 -388.797593) (xy 12.537948 -388.804404) (xy 12.595098 -388.861554)
			(xy 12.602494 -388.868406) (xy 12.621093 -388.876148) (xy 12.631166 -388.87654) (xy 13.302488 -388.87654)
			(xy 13.321284 -388.86892) (xy 13.328396 -388.861554) (xy 13.388086 -388.801864) (xy 13.394928 -388.794464)
			(xy 13.402652 -388.775866) (xy 13.403072 -388.765796) (xy 13.403072 -388.182866) (xy 13.403501 -388.172798)
			(xy 13.41122 -388.1542) (xy 13.418058 -388.146798) (xy 13.489432 -388.075424) (xy 13.496831 -388.06858)
			(xy 13.515429 -388.060853) (xy 13.5255 -388.060438) (xy 14.038326 -388.060438) (xy 14.03985 -388.058914)
			(xy 15.593568 -388.058914) (xy 15.603632 -388.05935) (xy 15.622218 -388.067083) (xy 15.629636 -388.0739)
			(xy 15.650464 -388.094728) (xy 15.65731 -388.102126) (xy 15.66504 -388.120725) (xy 15.66545 -388.130796)
			(xy 15.66545 -388.2771) (xy 15.665196 -388.277354) (xy 15.665196 -388.922768) (xy 15.66476 -388.932833)
			(xy 15.657028 -388.951419) (xy 15.65021 -388.958836) (xy 15.522702 -389.086344) (xy 15.515306 -389.093197)
			(xy 15.496708 -389.100941) (xy 15.486634 -389.10133) (xy 15.451836 -389.136128) (xy 15.444438 -389.142972)
			(xy 15.425838 -389.150695) (xy 15.415768 -389.151114) (xy 14.848078 -389.151114) (xy 14.838074 -389.151606)
			(xy 14.819592 -389.15927) (xy 14.80545 -389.173423) (xy 14.797799 -389.19191) (xy 14.797278 -389.201914)
			(xy 14.797278 -390.47039) (xy 14.796856 -390.480461) (xy 14.789142 -390.499066) (xy 14.782292 -390.506458)
			(xy 14.740382 -390.548368) (xy 14.732984 -390.555215) (xy 14.714386 -390.562948) (xy 14.704314 -390.563354)
			(xy 13.908278 -390.563354) (xy 13.898211 -390.563783) (xy 13.879617 -390.571509) (xy 13.87221 -390.57834)
			(xy 13.851382 -390.599168) (xy 13.844537 -390.606566) (xy 13.836815 -390.625165) (xy 13.836396 -390.635236)
			(xy 13.836396 -390.745472) (xy 13.836832 -390.755536) (xy 13.844565 -390.774122) (xy 13.851382 -390.78154)
			(xy 13.854176 -390.784334) (xy 13.872718 -390.791954) (xy 14.658086 -390.791954) (xy 14.668148 -390.792394)
			(xy 14.686725 -390.800137) (xy 14.694154 -390.80694) (xy 14.78661 -390.899396) (xy 14.793467 -390.90679)
			(xy 14.801217 -390.925389) (xy 14.801596 -390.935464) (xy 14.801596 -391.075672) (xy 14.802032 -391.085736)
			(xy 14.809765 -391.104322) (xy 14.816582 -391.11174) (xy 14.819376 -391.114534) (xy 14.837918 -391.122154)
			(xy 16.531082 -391.122154) (xy 16.541145 -391.121715) (xy 16.559723 -391.113974) (xy 16.56715 -391.107168)
			(xy 16.571976 -391.102342) (xy 16.579596 -391.0838) (xy 16.579596 -388.882636) (xy 16.580031 -388.872571)
			(xy 16.587761 -388.853983) (xy 16.594582 -388.846568) (xy 16.681704 -388.759446) (xy 16.688308 -388.758938)
			(xy 19.313906 -388.758938) (xy 19.323975 -388.759363) (xy 19.342574 -388.767083) (xy 19.349974 -388.773924)
			(xy 19.446494 -388.870444) (xy 19.453889 -388.877297) (xy 19.472488 -388.885043) (xy 19.482562 -388.88543)
			(xy 20.757388 -388.88543) (xy 20.767459 -388.885852) (xy 20.786063 -388.893566) (xy 20.793456 -388.900416)
			(xy 20.903438 -389.010398) (xy 20.910839 -389.017239) (xy 20.929437 -389.02496) (xy 20.939506 -389.025384)
			(xy 22.308312 -389.025384) (xy 22.318381 -389.024958) (xy 22.336981 -389.017239) (xy 22.34438 -389.010398)
			(xy 22.466808 -388.88797) (xy 22.473649 -388.880569) (xy 22.481371 -388.861971) (xy 22.481794 -388.851902)
			(xy 22.481794 -388.182866) (xy 22.482223 -388.172798) (xy 22.489945 -388.154202) (xy 22.49678 -388.146798)
			(xy 22.568154 -388.075424) (xy 22.575554 -388.068584) (xy 22.594153 -388.060865) (xy 22.604222 -388.060438)
			(xy 23.117048 -388.060438) (xy 23.118572 -388.058914) (xy 24.67229 -388.058914) (xy 24.682361 -388.059336)
			(xy 24.700966 -388.067049) (xy 24.708358 -388.0739) (xy 24.729186 -388.094728) (xy 24.73603 -388.102127)
			(xy 24.743756 -388.120726) (xy 24.744172 -388.130796) (xy 24.744172 -388.2771) (xy 24.743918 -388.277354)
			(xy 24.743918 -388.922768) (xy 24.743483 -388.932833) (xy 24.735753 -388.951421) (xy 24.728932 -388.958836)
			(xy 24.601424 -389.086344) (xy 24.594024 -389.093185) (xy 24.575425 -389.1009) (xy 24.565356 -389.10133)
			(xy 24.530558 -389.136128) (xy 24.523161 -389.142976) (xy 24.504562 -389.150706) (xy 24.49449 -389.151114)
			(xy 23.9268 -389.151114) (xy 23.91678 -389.151534) (xy 23.898265 -389.159204) (xy 23.884096 -389.173377)
			(xy 23.876431 -389.191894) (xy 23.876 -389.201914) (xy 23.876 -390.470136) (xy 23.87219 -390.474454)
			(xy 23.854664 -390.491726) (xy 23.847725 -390.499155) (xy 23.839884 -390.517891) (xy 23.839424 -390.528048)
			(xy 23.819104 -390.548368) (xy 23.811707 -390.555218) (xy 23.793109 -390.562959) (xy 23.783036 -390.563354)
			(xy 22.987 -390.563354) (xy 22.976931 -390.563779) (xy 22.958332 -390.571499) (xy 22.950932 -390.57834)
			(xy 22.930104 -390.599168) (xy 22.923268 -390.60657) (xy 22.915557 -390.625168) (xy 22.915118 -390.635236)
			(xy 22.915118 -390.745472) (xy 22.915555 -390.755536) (xy 22.92329 -390.77412) (xy 22.930104 -390.78154)
			(xy 22.932898 -390.784334) (xy 22.95144 -390.791954) (xy 23.736808 -390.791954) (xy 23.746876 -390.79238)
			(xy 23.765474 -390.800103) (xy 23.772876 -390.80694) (xy 23.865332 -390.899396) (xy 23.872187 -390.906791)
			(xy 23.879933 -390.92539) (xy 23.880318 -390.935464) (xy 23.880318 -391.071354) (xy 23.88073 -391.08138)
			(xy 23.888392 -391.09991) (xy 23.902567 -391.114092) (xy 23.921092 -391.121765) (xy 23.931118 -391.122154)
			(xy 25.609804 -391.122154) (xy 25.619873 -391.121729) (xy 25.638472 -391.114008) (xy 25.645872 -391.107168)
			(xy 25.650698 -391.102342) (xy 25.658318 -391.0838) (xy 25.658318 -388.882636) (xy 25.658753 -388.872571)
			(xy 25.666486 -388.853985) (xy 25.673304 -388.846568) (xy 25.760426 -388.759446) (xy 25.76703 -388.758938)
			(xy 30.118558 -388.758938) (xy 30.128623 -388.759372) (xy 30.147208 -388.767106) (xy 30.154626 -388.773924)
			(xy 30.878018 -389.497316) (xy 31.30296 -389.922004) (xy 31.30296 -389.949436) (xy 31.30296 -395.257782)
			(xy 35.127436 -395.257782) (xy 35.131509 -395.202123) (xy 35.143644 -395.14765) (xy 35.16358 -395.095524)
			(xy 35.190894 -395.046856) (xy 35.225002 -395.002684) (xy 35.265179 -394.963949) (xy 35.310567 -394.931477)
			(xy 35.360199 -394.905959) (xy 35.413019 -394.88794) (xy 35.467898 -394.877803) (xy 35.523669 -394.875765)
			(xy 35.579143 -394.881868) (xy 35.633136 -394.895984) (xy 35.684499 -394.917811) (xy 35.732137 -394.946884)
			(xy 35.775033 -394.982583) (xy 35.812275 -395.024147) (xy 35.843069 -395.070691) (xy 35.866757 -395.121222)
			(xy 35.882835 -395.174664) (xy 35.890961 -395.229878) (xy 35.89147 -395.257782) (xy 35.890961 -395.285686)
			(xy 35.882835 -395.3409) (xy 35.866757 -395.394342) (xy 35.843069 -395.444873) (xy 35.812275 -395.491417)
			(xy 35.775033 -395.532981) (xy 35.732137 -395.56868) (xy 35.684499 -395.597753) (xy 35.633136 -395.61958)
			(xy 35.579143 -395.633696) (xy 35.523669 -395.639799) (xy 35.467898 -395.637761) (xy 35.413019 -395.627624)
			(xy 35.360199 -395.609605) (xy 35.310567 -395.584087) (xy 35.265179 -395.551615) (xy 35.225002 -395.51288)
			(xy 35.190894 -395.468708) (xy 35.16358 -395.42004) (xy 35.143644 -395.367914) (xy 35.131509 -395.313441)
			(xy 35.127436 -395.257782) (xy 31.30296 -395.257782) (xy 31.30296 -402.35124) (xy 31.302528 -402.361306)
			(xy 31.294799 -402.379896) (xy 31.287974 -402.387308) (xy 30.912816 -402.762466) (xy 30.905415 -402.769303)
			(xy 30.886816 -402.777012) (xy 30.876748 -402.777452) (xy 27.396186 -402.777452) (xy 27.386118 -402.777879)
			(xy 27.367522 -402.785603) (xy 27.360118 -402.792438) (xy 27.092148 -403.060408) (xy 27.085298 -403.067805)
			(xy 27.077558 -403.086403) (xy 27.077162 -403.096476) (xy 27.077162 -407.198576) (xy 27.077601 -407.208639)
			(xy 27.085341 -407.227217) (xy 27.092148 -407.234644) (xy 27.14625 -407.288746) (xy 27.153649 -407.29559)
			(xy 27.172247 -407.303315) (xy 27.182318 -407.303732)
		)
		(stroke
			(width 0)
			(type solid)
		)
		(fill yes)
		(layer "F.Cu")
		(net "GND")
	)
	(gr_poly
		(pts
			(xy 162.052254 -400.987006) (xy 162.06232 -400.986573) (xy 162.080911 -400.978846) (xy 162.088322 -400.97202)
			(xy 163.680902 -399.37944) (xy 164.623496 -398.436592) (xy 164.630895 -398.429746) (xy 164.649492 -398.422011)
			(xy 164.659564 -398.421606) (xy 165.097206 -398.421606) (xy 165.108741 -398.421063) (xy 165.129511 -398.411019)
			(xy 165.137084 -398.402302) (xy 165.193726 -398.330674) (xy 165.198806 -398.308322) (xy 165.196012 -398.296638)
			(xy 165.191258 -398.275043) (xy 165.186163 -398.231118) (xy 165.185852 -398.209008) (xy 165.186338 -398.181757)
			(xy 165.194094 -398.127809) (xy 165.209449 -398.075514) (xy 165.232091 -398.025937) (xy 165.261557 -397.980087)
			(xy 165.297248 -397.938896) (xy 165.338439 -397.903205) (xy 165.384289 -397.873739) (xy 165.433866 -397.851097)
			(xy 165.486161 -397.835742) (xy 165.540109 -397.827986) (xy 165.594611 -397.827986) (xy 165.648559 -397.835742)
			(xy 165.700854 -397.851097) (xy 165.750431 -397.873739) (xy 165.796281 -397.903205) (xy 165.837472 -397.938896)
			(xy 165.873163 -397.980087) (xy 165.902629 -398.025937) (xy 165.925271 -398.075514) (xy 165.940626 -398.127809)
			(xy 165.948382 -398.181757) (xy 165.948868 -398.209008) (xy 165.948564 -398.231118) (xy 165.943466 -398.275043)
			(xy 165.938708 -398.296638) (xy 165.935914 -398.308322) (xy 165.940994 -398.330674) (xy 165.997636 -398.402302)
			(xy 166.005209 -398.411027) (xy 166.025974 -398.4211) (xy 166.037514 -398.421606) (xy 171.724574 -398.421606)
			(xy 171.736741 -398.420921) (xy 171.75838 -398.409796) (xy 171.765976 -398.40027) (xy 171.821348 -398.322546)
			(xy 171.82465 -398.298416) (xy 171.820586 -398.286732) (xy 171.811642 -398.259787) (xy 171.799096 -398.204413)
			(xy 171.792783 -398.147988) (xy 171.792392 -398.1196) (xy 171.792894 -398.087639) (xy 171.800905 -398.024221)
			(xy 171.816802 -397.962307) (xy 171.840334 -397.902874) (xy 171.871128 -397.846859) (xy 171.908701 -397.795144)
			(xy 171.952458 -397.748547) (xy 172.001711 -397.707802) (xy 172.055682 -397.673551) (xy 172.113521 -397.646334)
			(xy 172.174314 -397.626581) (xy 172.237104 -397.614603) (xy 172.3009 -397.61059) (xy 172.364696 -397.614603)
			(xy 172.427486 -397.626581) (xy 172.488279 -397.646334) (xy 172.546118 -397.673551) (xy 172.600089 -397.707802)
			(xy 172.649342 -397.748547) (xy 172.693099 -397.795144) (xy 172.730672 -397.846859) (xy 172.761466 -397.902874)
			(xy 172.784998 -397.962307) (xy 172.800895 -398.024221) (xy 172.808906 -398.087639) (xy 172.809408 -398.1196)
			(xy 172.809031 -398.147989) (xy 172.802726 -398.204416) (xy 172.790161 -398.259786) (xy 172.781214 -398.286732)
			(xy 172.77715 -398.298416) (xy 172.780452 -398.322546) (xy 172.835824 -398.40027) (xy 172.843436 -398.409787)
			(xy 172.865059 -398.420948) (xy 172.877226 -398.421606) (xy 175.05553 -398.421606) (xy 175.065598 -398.421178)
			(xy 175.084195 -398.413456) (xy 175.091598 -398.40662) (xy 176.206658 -397.29156) (xy 176.213503 -397.284161)
			(xy 176.221229 -397.265563) (xy 176.221644 -397.255492) (xy 176.221644 -396.22603) (xy 176.222081 -396.215966)
			(xy 176.229818 -396.197385) (xy 176.23663 -396.189962) (xy 177.690018 -394.736574) (xy 177.696869 -394.729178)
			(xy 177.704607 -394.710579) (xy 177.705004 -394.700506) (xy 177.705004 -388.706614) (xy 177.705443 -388.696551)
			(xy 177.71318 -388.67797) (xy 177.71999 -388.670546) (xy 177.899568 -388.490968) (xy 177.906967 -388.484125)
			(xy 177.925566 -388.476404) (xy 177.935636 -388.475982) (xy 179.404518 -388.475982) (xy 179.414586 -388.475555)
			(xy 179.433184 -388.467834) (xy 179.440586 -388.460996) (xy 185.145934 -382.755648) (xy 185.15278 -382.74825)
			(xy 185.160505 -382.729651) (xy 185.16092 -382.71958) (xy 185.16092 -373.991632) (xy 185.147204 -373.968264)
			(xy 185.135012 -373.961406) (xy 185.116857 -373.950814) (xy 185.083335 -373.925456) (xy 185.06821 -373.91086)
			(xy 183.514238 -372.356634) (xy 183.506838 -372.349794) (xy 183.488239 -372.342076) (xy 183.47817 -372.341648)
			(xy 179.127404 -372.341648) (xy 179.11565 -372.342227) (xy 179.094581 -372.352646) (xy 179.080351 -372.371353)
			(xy 179.07762 -372.382796) (xy 179.055014 -372.498874) (xy 179.07254 -372.530878) (xy 179.089558 -372.537482)
			(xy 179.176472 -372.573027) (xy 179.347427 -372.650766) (xy 179.514797 -372.735949) (xy 179.678259 -372.828412)
			(xy 179.837494 -372.927976) (xy 179.992197 -373.034447) (xy 180.142066 -373.147621) (xy 180.286812 -373.267277)
			(xy 180.426154 -373.393184) (xy 180.559824 -373.525099) (xy 180.687561 -373.662765) (xy 180.809119 -373.805918)
			(xy 180.924263 -373.954278) (xy 181.032769 -374.10756) (xy 181.134428 -374.265467) (xy 181.229042 -374.427692)
			(xy 181.31643 -374.593922) (xy 181.39642 -374.763835) (xy 181.468859 -374.937103) (xy 181.533607 -375.113389)
			(xy 181.590537 -375.292352) (xy 181.639541 -375.473646) (xy 181.680522 -375.656921) (xy 181.713402 -375.84182)
			(xy 181.738117 -376.027987) (xy 181.754619 -376.215061) (xy 181.762877 -376.40268) (xy 181.763416 -376.49658)
			(xy 181.762922 -376.588421) (xy 181.755019 -376.771931) (xy 181.739229 -376.954933) (xy 181.715581 -377.137085)
			(xy 181.684117 -377.318051) (xy 181.644898 -377.497496) (xy 181.597994 -377.675088) (xy 181.543494 -377.850497)
			(xy 181.481497 -378.023399) (xy 181.412119 -378.193474) (xy 181.335489 -378.360407) (xy 181.251747 -378.523888)
			(xy 181.16105 -378.683615) (xy 181.063565 -378.839292) (xy 180.959473 -378.990631) (xy 180.848966 -379.137352)
			(xy 180.732249 -379.279182) (xy 180.609538 -379.41586) (xy 180.481061 -379.547132) (xy 180.347055 -379.672755)
			(xy 180.207769 -379.792496) (xy 180.06346 -379.906135) (xy 179.914396 -380.013459) (xy 179.760852 -380.114271)
			(xy 179.603113 -380.208384) (xy 179.441472 -380.295624) (xy 179.276227 -380.375828) (xy 179.107684 -380.448849)
			(xy 178.936156 -380.514552) (xy 178.76196 -380.572814) (xy 178.585418 -380.623527) (xy 178.406859 -380.666599)
			(xy 178.226611 -380.701949) (xy 178.04501 -380.729511) (xy 177.862391 -380.749235) (xy 177.679093 -380.761084)
			(xy 177.495454 -380.765036) (xy 177.311815 -380.761084) (xy 177.128517 -380.749235) (xy 176.945898 -380.729511)
			(xy 176.764297 -380.701949) (xy 176.584049 -380.666599) (xy 176.40549 -380.623527) (xy 176.228948 -380.572814)
			(xy 176.054752 -380.514552) (xy 175.883224 -380.448849) (xy 175.714681 -380.375828) (xy 175.549436 -380.295624)
			(xy 175.387795 -380.208384) (xy 175.230056 -380.114271) (xy 175.076512 -380.013459) (xy 174.927448 -379.906135)
			(xy 174.783139 -379.792496) (xy 174.643853 -379.672755) (xy 174.509847 -379.547132) (xy 174.38137 -379.41586)
			(xy 174.258659 -379.279182) (xy 174.141942 -379.137352) (xy 174.031435 -378.990631) (xy 173.927343 -378.839292)
			(xy 173.829858 -378.683615) (xy 173.739161 -378.523888) (xy 173.655419 -378.360407) (xy 173.578789 -378.193474)
			(xy 173.509411 -378.023399) (xy 173.447414 -377.850497) (xy 173.392914 -377.675088) (xy 173.34601 -377.497496)
			(xy 173.306791 -377.318051) (xy 173.275327 -377.137085) (xy 173.251679 -376.954933) (xy 173.235889 -376.771931)
			(xy 173.227986 -376.588421) (xy 173.227492 -376.49658) (xy 173.228003 -376.40268) (xy 173.236264 -376.215061)
			(xy 173.25277 -376.027988) (xy 173.277489 -375.841822) (xy 173.310372 -375.656923) (xy 173.351357 -375.473649)
			(xy 173.400363 -375.292355) (xy 173.457296 -375.113393) (xy 173.522046 -374.937108) (xy 173.594487 -374.763842)
			(xy 173.674479 -374.59393) (xy 173.761868 -374.4277) (xy 173.856484 -374.265476) (xy 173.958144 -374.10757)
			(xy 174.066651 -373.954289) (xy 174.181795 -373.805929) (xy 174.303354 -373.662777) (xy 174.431091 -373.52511)
			(xy 174.56476 -373.393196) (xy 174.704103 -373.267288) (xy 174.848848 -373.147632) (xy 174.998717 -373.034458)
			(xy 175.153419 -372.927986) (xy 175.312654 -372.828421) (xy 175.476114 -372.735957) (xy 175.643484 -372.650773)
			(xy 175.814438 -372.573032) (xy 175.90135 -372.537482) (xy 175.918368 -372.530878) (xy 175.935894 -372.498874)
			(xy 175.913288 -372.382796) (xy 175.910456 -372.371399) (xy 175.896233 -372.352743) (xy 175.875231 -372.342293)
			(xy 175.863504 -372.341648) (xy 175.264826 -372.341648) (xy 175.240648 -372.341186) (xy 175.192882 -372.333649)
			(xy 175.146881 -372.318742) (xy 175.103774 -372.29683) (xy 175.06462 -372.268452) (xy 175.047148 -372.251732)
			(xy 175.044862 -372.249446) (xy 175.037517 -372.242637) (xy 175.019054 -372.234911) (xy 175.009048 -372.23446)
			(xy 173.221142 -372.23446) (xy 173.211078 -372.234895) (xy 173.192494 -372.242631) (xy 173.185074 -372.249446)
			(xy 172.171106 -373.263414) (xy 172.164261 -373.270813) (xy 172.156531 -373.289411) (xy 172.15612 -373.299482)
			(xy 172.15612 -381.888238) (xy 172.155691 -381.898306) (xy 172.147969 -381.916902) (xy 172.141134 -381.924306)
			(xy 171.512484 -382.552956) (xy 171.509182 -382.558798) (xy 171.500419 -382.572853) (xy 171.477014 -382.596272)
			(xy 171.462954 -382.605026) (xy 171.457112 -382.608328) (xy 171.191174 -382.874266) (xy 171.183776 -382.881112)
			(xy 171.165177 -382.888843) (xy 171.155106 -382.889252) (xy 171.130976 -382.889252) (xy 171.120909 -382.889681)
			(xy 171.102316 -382.897407) (xy 171.094908 -382.904238) (xy 171.085002 -382.914144) (xy 171.078162 -382.921545)
			(xy 171.070444 -382.940143) (xy 171.070016 -382.950212) (xy 171.070016 -383.637028) (xy 171.069588 -383.647096)
			(xy 171.061869 -383.665695) (xy 171.05503 -383.673096) (xy 170.68419 -384.043936) (xy 170.677339 -384.051332)
			(xy 170.669604 -384.069931) (xy 170.669204 -384.080004) (xy 170.669204 -385.295394) (xy 170.669626 -385.305465)
			(xy 170.67734 -385.32407) (xy 170.68419 -385.331462) (xy 170.806364 -385.453636) (xy 170.813763 -385.460479)
			(xy 170.832362 -385.468201) (xy 170.842432 -385.468622) (xy 171.517564 -385.468622) (xy 171.527629 -385.469057)
			(xy 171.546214 -385.476791) (xy 171.553632 -385.483608) (xy 171.807886 -385.737862) (xy 171.814724 -385.745263)
			(xy 171.822438 -385.763862) (xy 171.822872 -385.77393) (xy 171.822872 -387.154166) (xy 171.822436 -387.16423)
			(xy 171.814702 -387.182815) (xy 171.807886 -387.190234) (xy 171.413424 -387.584696) (xy 171.406574 -387.592093)
			(xy 171.398835 -387.610691) (xy 171.398438 -387.620764) (xy 171.398438 -388.892034) (xy 171.398868 -388.902101)
			(xy 171.406595 -388.920693) (xy 171.413424 -388.928102) (xy 171.415964 -388.930896) (xy 173.041818 -388.930896)
			(xy 173.051823 -388.930405) (xy 173.070308 -388.922742) (xy 173.084454 -388.908589) (xy 173.092109 -388.890101)
			(xy 173.092618 -388.880096) (xy 173.092618 -387.516624) (xy 173.092182 -387.50656) (xy 173.08445 -387.487973)
			(xy 173.077632 -387.480556) (xy 172.649896 -387.05282) (xy 172.635164 -387.045454) (xy 172.626782 -387.044438)
			(xy 172.611812 -387.041988) (xy 172.583556 -387.030977) (xy 172.558695 -387.01361) (xy 172.538633 -386.990869)
			(xy 172.524503 -386.964037) (xy 172.517101 -386.934629) (xy 172.516546 -386.91947) (xy 172.516292 -386.909564)
			(xy 172.508926 -386.89153) (xy 172.503846 -386.886196) (xy 172.503846 -385.74218) (xy 172.504274 -385.732112)
			(xy 172.511999 -385.713518) (xy 172.518832 -385.706112) (xy 172.741336 -385.483608) (xy 172.748736 -385.476766)
			(xy 172.767334 -385.469044) (xy 172.777404 -385.468622) (xy 174.982124 -385.468622) (xy 174.992192 -385.46905)
			(xy 175.010788 -385.476773) (xy 175.018192 -385.483608) (xy 175.36795 -385.833366) (xy 175.374792 -385.840766)
			(xy 175.38251 -385.859364) (xy 175.382936 -385.869434) (xy 175.382936 -391.478262) (xy 175.383371 -391.488326)
			(xy 175.391105 -391.506911) (xy 175.397922 -391.51433) (xy 175.404526 -391.520934) (xy 175.404526 -391.563098)
			(xy 175.238664 -391.728706) (xy 175.231811 -391.736102) (xy 175.224069 -391.7547) (xy 175.223678 -391.764774)
			(xy 175.223678 -394.58392) (xy 175.223251 -394.593988) (xy 175.215529 -394.612585) (xy 175.208692 -394.619988)
			(xy 173.590966 -396.237714) (xy 173.58357 -396.244565) (xy 173.564971 -396.2523) (xy 173.554898 -396.2527)
			(xy 171.328842 -396.2527) (xy 171.317644 -396.253282) (xy 171.297353 -396.262768) (xy 171.289726 -396.270988)
			(xy 171.232322 -396.34033) (xy 171.226734 -396.36192) (xy 171.22902 -396.37335) (xy 171.233206 -396.396875)
			(xy 171.237661 -396.444453) (xy 171.23791 -396.468346) (xy 171.237443 -396.499075) (xy 171.23003 -396.560085)
			(xy 171.215318 -396.619757) (xy 171.19352 -396.67722) (xy 171.164956 -396.731637) (xy 171.13004 -396.782214)
			(xy 171.089284 -396.828215) (xy 171.04328 -396.868968) (xy 170.992699 -396.903878) (xy 170.93828 -396.932438)
			(xy 170.880815 -396.954231) (xy 170.821142 -396.968938) (xy 170.760131 -396.976346) (xy 170.729402 -396.976854)
			(xy 170.695774 -396.97631) (xy 170.629107 -396.967436) (xy 170.564193 -396.949844) (xy 170.502167 -396.923841)
			(xy 170.444115 -396.889881) (xy 170.417236 -396.869666) (xy 170.408271 -396.86334) (xy 170.38694 -396.858298)
			(xy 170.365455 -396.862637) (xy 170.356276 -396.86865) (xy 170.330219 -396.886788) (xy 170.274463 -396.917158)
			(xy 170.215364 -396.940357) (xy 170.153838 -396.956026) (xy 170.090841 -396.963921) (xy 170.059096 -396.964408)
			(xy 170.029625 -396.963988) (xy 169.971079 -396.957172) (xy 169.913717 -396.943622) (xy 169.85831 -396.923518)
			(xy 169.805604 -396.897133) (xy 169.780712 -396.88135) (xy 169.771629 -396.875976) (xy 169.75085 -396.872419)
			(xy 169.730403 -396.877549) (xy 169.721784 -396.883636) (xy 169.695044 -396.903436) (xy 169.637401 -396.936668)
			(xy 169.575919 -396.962104) (xy 169.511647 -396.979312) (xy 169.44568 -396.987997) (xy 169.412412 -396.988538)
			(xy 169.379559 -396.988024) (xy 169.3144 -396.979566) (xy 169.250871 -396.962789) (xy 169.190032 -396.937973)
			(xy 169.132894 -396.90553) (xy 169.106342 -396.886176) (xy 169.096909 -396.87976) (xy 169.074601 -396.875132)
			(xy 169.052491 -396.880625) (xy 169.04335 -396.887446) (xy 169.020489 -396.905901) (xy 168.971272 -396.937993)
			(xy 168.918682 -396.964193) (xy 168.863421 -396.984152) (xy 168.806226 -396.997603) (xy 168.747862 -397.004368)
			(xy 168.718484 -397.004794) (xy 168.689047 -397.004372) (xy 168.630568 -396.997571) (xy 168.573266 -396.984062)
			(xy 168.517907 -396.964026) (xy 168.465233 -396.93773) (xy 168.440354 -396.92199) (xy 168.431439 -396.916775)
			(xy 168.411106 -396.91326) (xy 168.391031 -396.91803) (xy 168.382442 -396.923768) (xy 168.356065 -396.942655)
			(xy 168.299435 -396.974308) (xy 168.239242 -396.998507) (xy 168.176462 -397.01486) (xy 168.112112 -397.023102)
			(xy 168.079674 -397.02359) (xy 168.048944 -397.023124) (xy 167.987934 -397.015713) (xy 167.928261 -397.001002)
			(xy 167.870797 -396.979206) (xy 167.816379 -396.950642) (xy 167.7658 -396.915727) (xy 167.719799 -396.87497)
			(xy 167.679046 -396.828965) (xy 167.644136 -396.778384) (xy 167.615576 -396.723963) (xy 167.593785 -396.666497)
			(xy 167.579079 -396.606823) (xy 167.571673 -396.545812) (xy 167.571166 -396.515082) (xy 167.571704 -396.481137)
			(xy 167.580755 -396.413852) (xy 167.5892 -396.38097) (xy 167.592248 -396.36954) (xy 167.587676 -396.346426)
			(xy 167.531542 -396.272766) (xy 167.523948 -396.263782) (xy 167.502903 -396.253329) (xy 167.491156 -396.2527)
			(xy 166.987474 -396.2527) (xy 166.977406 -396.252272) (xy 166.958808 -396.244551) (xy 166.951406 -396.237714)
			(xy 166.39032 -395.676628) (xy 166.382919 -395.669791) (xy 166.36432 -395.662081) (xy 166.354252 -395.661642)
			(xy 166.257986 -395.661642) (xy 166.252144 -395.662912) (xy 166.234569 -395.666899) (xy 166.198789 -395.671226)
			(xy 166.18077 -395.671548) (xy 165.937946 -395.671548) (xy 165.929259 -395.671842) (xy 165.912855 -395.677555)
			(xy 165.899317 -395.688438) (xy 165.894512 -395.695678) (xy 165.875254 -395.726166) (xy 165.830874 -395.783007)
			(xy 165.780342 -395.834456) (xy 165.724309 -395.879852) (xy 165.663494 -395.918609) (xy 165.598682 -395.950229)
			(xy 165.530705 -395.974305) (xy 165.460439 -395.990527) (xy 165.388787 -395.998686) (xy 165.35273 -395.999208)
			(xy 165.317721 -395.998728) (xy 165.248128 -395.991034) (xy 165.179803 -395.975735) (xy 165.113573 -395.953016)
			(xy 165.081712 -395.938502) (xy 165.076596 -395.936268) (xy 165.065702 -395.933843) (xy 165.060122 -395.933676)
			(xy 160.843214 -395.933676) (xy 160.833164 -395.934183) (xy 160.814605 -395.941906) (xy 160.807146 -395.948662)
			(xy 160.280096 -396.475712) (xy 160.272701 -396.482567) (xy 160.254102 -396.490314) (xy 160.244028 -396.490698)
			(xy 146.463512 -396.490698) (xy 146.454114 -396.494508) (xy 146.442424 -396.498994) (xy 146.417864 -396.503855)
			(xy 146.405346 -396.50416) (xy 146.34337 -396.50416) (xy 146.333972 -396.508224) (xy 146.305464 -396.519375)
			(xy 146.24545 -396.531393) (xy 146.214846 -396.5321) (xy 146.184242 -396.531399) (xy 146.124227 -396.519379)
			(xy 146.09572 -396.508224) (xy 146.086322 -396.50416) (xy 146.053302 -396.50416) (xy 146.023838 -396.531846)
			(xy 146.022822 -396.552166) (xy 146.020055 -396.589005) (xy 146.00707 -396.661732) (xy 145.985745 -396.732464)
			(xy 145.956367 -396.800249) (xy 145.919331 -396.864172) (xy 145.875138 -396.923373) (xy 145.824381 -396.977053)
			(xy 145.767746 -397.02449) (xy 145.705994 -397.065044) (xy 145.63996 -397.098169) (xy 145.570531 -397.123418)
			(xy 145.498645 -397.140451) (xy 145.425268 -397.149039) (xy 145.38833 -397.149574) (xy 145.352667 -397.149094)
			(xy 145.28179 -397.141111) (xy 145.212252 -397.125242) (xy 145.144929 -397.101686) (xy 145.080666 -397.070741)
			(xy 145.020273 -397.032794) (xy 144.964508 -396.988323) (xy 144.914074 -396.937889) (xy 144.869604 -396.882124)
			(xy 144.831658 -396.82173) (xy 144.800712 -396.757467) (xy 144.777157 -396.690144) (xy 144.761288 -396.620606)
			(xy 144.753306 -396.549729) (xy 144.752822 -396.514066) (xy 144.753336 -396.477422) (xy 144.761761 -396.404621)
			(xy 144.778505 -396.333273) (xy 144.803348 -396.264325) (xy 144.835958 -396.198693) (xy 144.875903 -396.137249)
			(xy 144.922652 -396.080809) (xy 144.975584 -396.030122) (xy 145.033997 -395.985862) (xy 145.097114 -395.948616)
			(xy 145.164097 -395.91888) (xy 145.234056 -395.897048) (xy 145.269966 -395.889734) (xy 145.288 -395.886178)
			(xy 145.311368 -395.858238) (xy 145.311368 -395.623034) (xy 145.310836 -395.613044) (xy 145.303128 -395.594606)
			(xy 145.296382 -395.58722) (xy 145.271998 -395.562836) (xy 145.264601 -395.555986) (xy 145.246003 -395.548247)
			(xy 145.23593 -395.54785) (xy 143.980916 -395.54785) (xy 143.970854 -395.54829) (xy 143.952276 -395.556031)
			(xy 143.944848 -395.562836) (xy 143.473424 -396.03426) (xy 143.466023 -396.041099) (xy 143.447425 -396.048812)
			(xy 143.437356 -396.049246) (xy 143.281908 -396.049246) (xy 143.271889 -396.049665) (xy 143.253377 -396.057335)
			(xy 143.239214 -396.071509) (xy 143.231557 -396.090027) (xy 143.231108 -396.100046) (xy 143.231108 -396.624048)
			(xy 143.231545 -396.634081) (xy 143.239119 -396.652656) (xy 143.24584 -396.660116) (xy 144.751044 -398.16532)
			(xy 144.758494 -398.172204) (xy 144.777229 -398.179937) (xy 144.787366 -398.180306) (xy 144.869916 -398.179798)
			(xy 144.888458 -398.171924) (xy 144.89557 -398.164558) (xy 144.92122 -398.139082) (xy 144.977327 -398.093491)
			(xy 145.038246 -398.05456) (xy 145.103188 -398.022792) (xy 145.171315 -397.998598) (xy 145.241747 -397.98229)
			(xy 145.313574 -397.974079) (xy 145.349722 -397.97355) (xy 145.385385 -397.974051) (xy 145.456262 -397.98204)
			(xy 145.525799 -397.997913) (xy 145.593121 -398.021472) (xy 145.657383 -398.052421) (xy 145.717775 -398.09037)
			(xy 145.773539 -398.134842) (xy 145.823973 -398.185278) (xy 145.868443 -398.241043) (xy 145.90639 -398.301437)
			(xy 145.937336 -398.365699) (xy 145.960893 -398.433022) (xy 145.976764 -398.50256) (xy 145.98475 -398.573437)
			(xy 145.98475 -398.644763) (xy 145.976764 -398.71564) (xy 145.960893 -398.785178) (xy 145.937336 -398.852501)
			(xy 145.90639 -398.916763) (xy 145.868443 -398.977157) (xy 145.823973 -399.032922) (xy 145.773539 -399.083358)
			(xy 145.717775 -399.12783) (xy 145.657383 -399.165779) (xy 145.593121 -399.196728) (xy 145.525799 -399.220287)
			(xy 145.456262 -399.23616) (xy 145.385385 -399.244149) (xy 145.349722 -399.244566) (xy 145.313663 -399.244063)
			(xy 145.24201 -399.2359) (xy 145.171741 -399.219675) (xy 145.103761 -399.195599) (xy 145.038945 -399.16398)
			(xy 144.978126 -399.125226) (xy 144.922086 -399.079833) (xy 144.871546 -399.028388) (xy 144.827157 -398.971551)
			(xy 144.80794 -398.941036) (xy 144.800828 -398.929606) (xy 144.777968 -398.916652) (xy 144.75968 -398.916652)
			(xy 144.731133 -398.916052) (xy 144.675012 -398.905571) (xy 144.648174 -398.895824) (xy 144.63395 -398.89049)
			(xy 144.604486 -398.896586) (xy 144.593818 -398.907254) (xy 144.586974 -398.914618) (xy 144.579226 -398.933152)
			(xy 144.579224 -398.953241) (xy 144.58697 -398.971776) (xy 144.593818 -398.979136) (xy 145.18894 -399.574258)
			(xy 161.83102 -399.574258) (xy 161.83147 -399.543486) (xy 161.838913 -399.482393) (xy 161.853672 -399.422644)
			(xy 161.875532 -399.365113) (xy 161.904173 -399.310639) (xy 161.939178 -399.260019) (xy 161.980034 -399.213992)
			(xy 162.026145 -399.17323) (xy 162.051238 -399.155412) (xy 162.060603 -399.14832) (xy 162.07212 -399.127877)
			(xy 162.073367 -399.104446) (xy 162.069272 -399.093436) (xy 162.056193 -399.061571) (xy 162.037752 -398.995208)
			(xy 162.028445 -398.926961) (xy 162.02787 -398.892522) (xy 162.028372 -398.860561) (xy 162.036383 -398.797143)
			(xy 162.05228 -398.735229) (xy 162.075812 -398.675796) (xy 162.106606 -398.619781) (xy 162.144179 -398.568066)
			(xy 162.187936 -398.521469) (xy 162.237189 -398.480724) (xy 162.29116 -398.446473) (xy 162.348999 -398.419256)
			(xy 162.409792 -398.399503) (xy 162.472582 -398.387525) (xy 162.536378 -398.383512) (xy 162.600174 -398.387525)
			(xy 162.662964 -398.399503) (xy 162.723757 -398.419256) (xy 162.781596 -398.446473) (xy 162.835567 -398.480724)
			(xy 162.88482 -398.521469) (xy 162.928577 -398.568066) (xy 162.96615 -398.619781) (xy 162.996944 -398.675796)
			(xy 163.020476 -398.735229) (xy 163.036373 -398.797143) (xy 163.044384 -398.860561) (xy 163.044886 -398.892522)
			(xy 163.044461 -398.923295) (xy 163.03702 -398.984391) (xy 163.02226 -399.044141) (xy 163.000398 -399.101675)
			(xy 162.971752 -399.156149) (xy 162.936743 -399.206769) (xy 162.895881 -399.252794) (xy 162.849764 -399.293552)
			(xy 162.824668 -399.311368) (xy 162.815319 -399.318477) (xy 162.803798 -399.338911) (xy 162.802544 -399.362335)
			(xy 162.806634 -399.373344) (xy 162.819738 -399.405199) (xy 162.838169 -399.471568) (xy 162.847466 -399.539818)
			(xy 162.848036 -399.574258) (xy 162.847534 -399.606219) (xy 162.839523 -399.669637) (xy 162.823626 -399.731551)
			(xy 162.800094 -399.790984) (xy 162.7693 -399.846999) (xy 162.731727 -399.898714) (xy 162.68797 -399.945311)
			(xy 162.638717 -399.986056) (xy 162.584746 -400.020307) (xy 162.526907 -400.047524) (xy 162.466114 -400.067277)
			(xy 162.403324 -400.079255) (xy 162.339528 -400.083269) (xy 162.275732 -400.079255) (xy 162.212942 -400.067277)
			(xy 162.152149 -400.047524) (xy 162.09431 -400.020307) (xy 162.040339 -399.986056) (xy 161.991086 -399.945311)
			(xy 161.947329 -399.898714) (xy 161.909756 -399.846999) (xy 161.878962 -399.790984) (xy 161.85543 -399.731551)
			(xy 161.839533 -399.669637) (xy 161.831522 -399.606219) (xy 161.83102 -399.574258) (xy 145.18894 -399.574258)
			(xy 146.586702 -400.97202) (xy 146.594097 -400.978875) (xy 146.612696 -400.986621) (xy 146.62277 -400.987006)
		)
		(stroke
			(width 0)
			(type solid)
		)
		(fill yes)
		(layer "F.Cu")
		(net "P1V8_CPU1_RT_1D")
	)
	(gr_poly
		(pts
			(xy 115.718336 -345.291664) (xy 115.718336 -342.490044) (xy 115.725181 -342.482646) (xy 115.732905 -342.464047)
			(xy 115.733322 -342.453976) (xy 115.733322 -333.1083) (xy 115.725702 -333.089504) (xy 115.718336 -333.082392)
			(xy 115.44808 -332.812136) (xy 115.440682 -332.805289) (xy 115.422084 -332.797556) (xy 115.412012 -332.79715)
			(xy 101.280722 -332.79715) (xy 101.270659 -332.796711) (xy 101.25208 -332.788971) (xy 101.244654 -332.782164)
			(xy 100.807774 -332.345284) (xy 100.800922 -332.337888) (xy 100.793182 -332.319289) (xy 100.792788 -332.309216)
			(xy 100.792788 -330.796646) (xy 100.785168 -330.77785) (xy 100.777802 -330.770738) (xy 100.655628 -330.648564)
			(xy 100.648229 -330.641722) (xy 100.62963 -330.634003) (xy 100.61956 -330.633578) (xy 99.863402 -330.633578)
			(xy 99.853332 -330.633155) (xy 99.834729 -330.625438) (xy 99.827334 -330.618592) (xy 99.023424 -329.814682)
			(xy 99.023424 -328.534776) (xy 98.34499 -327.856342) (xy 98.337593 -327.849493) (xy 98.318995 -327.841755)
			(xy 98.308922 -327.841356) (xy 68.18249 -327.841356) (xy 68.163694 -327.848976) (xy 68.156582 -327.856342)
			(xy 66.656966 -329.355704) (xy 66.41846 -329.59421) (xy 66.411608 -329.601606) (xy 66.403868 -329.620205)
			(xy 66.403474 -329.630278) (xy 66.403474 -331.01534) (xy 66.411094 -331.034136) (xy 66.41846 -331.041248)
			(xy 66.642488 -331.265276) (xy 66.649885 -331.272127) (xy 66.668483 -331.279869) (xy 66.678556 -331.280262)
			(xy 67.594226 -331.280262) (xy 67.613022 -331.272642) (xy 67.620134 -331.265276) (xy 67.93738 -330.94803)
			(xy 67.944217 -330.940629) (xy 67.95193 -330.92203) (xy 67.952366 -330.911962) (xy 67.952366 -328.672952)
			(xy 67.9528 -328.662887) (xy 67.960534 -328.644302) (xy 67.967352 -328.636884) (xy 68.156836 -328.4474)
			(xy 68.164237 -328.440559) (xy 68.182835 -328.432838) (xy 68.192904 -328.432414) (xy 72.90816 -328.432414)
			(xy 72.918225 -328.432848) (xy 72.936812 -328.44058) (xy 72.944228 -328.4474) (xy 73.065894 -328.569066)
			(xy 73.072731 -328.576468) (xy 73.080442 -328.595066) (xy 73.08088 -328.605134) (xy 73.08088 -332.593442)
			(xy 72.88403 -332.790292) (xy 67.72021 -332.790292) (xy 67.701414 -332.797912) (xy 67.694302 -332.805278)
			(xy 67.67449 -332.82509) (xy 74.182986 -332.82509) (xy 74.182986 -331.498194) (xy 74.183386 -331.488121)
			(xy 74.191122 -331.469522) (xy 74.197972 -331.462126) (xy 74.31786 -331.342238) (xy 74.325284 -331.335428)
			(xy 74.343865 -331.32769) (xy 74.353928 -331.327252) (xy 75.870054 -331.327252) (xy 75.880122 -331.326815)
			(xy 75.898721 -331.319104) (xy 75.906122 -331.312266) (xy 76.3016 -330.916788) (xy 76.308966 -330.909676)
			(xy 76.316586 -330.89088) (xy 76.316586 -328.69886) (xy 76.32319 -328.692256) (xy 76.330556 -328.685144)
			(xy 76.338176 -328.666348) (xy 76.338176 -328.638916) (xy 76.33859 -328.628845) (xy 76.346316 -328.610246)
			(xy 76.353162 -328.602848) (xy 76.530962 -328.425048) (xy 76.538387 -328.418239) (xy 76.556967 -328.4105)
			(xy 76.56703 -328.410062) (xy 81.235804 -328.410062) (xy 81.245876 -328.410469) (xy 81.264474 -328.418201)
			(xy 81.271872 -328.425048) (xy 81.42224 -328.575416) (xy 81.429085 -328.582812) (xy 81.436801 -328.601415)
			(xy 81.437226 -328.611484) (xy 81.437226 -332.406498) (xy 81.436464 -332.40726) (xy 81.436464 -332.52029)
			(xy 81.435194 -332.53172) (xy 81.435194 -332.577694) (xy 81.229708 -332.78318) (xy 76.041758 -332.78318)
			(xy 76.031683 -332.783562) (xy 76.013085 -332.791311) (xy 76.00569 -332.798166) (xy 75.978512 -332.825344)
			(xy 82.53984 -332.825344) (xy 82.53984 -331.38491) (xy 82.705194 -331.219556) (xy 84.352638 -331.219556)
			(xy 84.35467 -331.221334) (xy 84.659216 -330.916788) (xy 84.666582 -330.909676) (xy 84.674202 -330.89088)
			(xy 84.674202 -328.684382) (xy 84.680806 -328.677778) (xy 84.688172 -328.670666) (xy 84.695792 -328.65187)
			(xy 84.695792 -328.638916) (xy 84.696201 -328.628844) (xy 84.70393 -328.610245) (xy 84.710778 -328.602848)
			(xy 84.888578 -328.425048) (xy 84.895997 -328.418232) (xy 84.914582 -328.410497) (xy 84.924646 -328.410062)
			(xy 89.61247 -328.410062) (xy 89.614248 -328.410824) (xy 89.779348 -328.575924) (xy 89.782765 -328.579482)
			(xy 89.788262 -328.587674) (xy 89.79027 -328.59218) (xy 89.79027 -328.592434) (xy 89.791032 -328.594212)
			(xy 89.79281 -328.598838) (xy 89.794725 -328.608561) (xy 89.794842 -328.613516) (xy 89.794842 -332.406498)
			(xy 89.79408 -332.40726) (xy 89.79408 -332.572614) (xy 89.793667 -332.582685) (xy 89.785938 -332.601283)
			(xy 89.779094 -332.608682) (xy 89.63406 -332.753716) (xy 89.62667 -332.760568) (xy 89.608063 -332.76828)
			(xy 89.597992 -332.768702) (xy 84.413852 -332.768702) (xy 84.403782 -332.769127) (xy 84.385183 -332.776845)
			(xy 84.377784 -332.783688) (xy 84.285328 -332.876144) (xy 90.87104 -332.876144) (xy 90.87104 -331.614272)
			(xy 90.87144 -331.6042) (xy 90.879177 -331.585602) (xy 90.886026 -331.578204) (xy 91.14536 -331.31887)
			(xy 92.639896 -331.31887) (xy 92.89034 -331.068426) (xy 92.897167 -331.061016) (xy 92.904893 -331.042424)
			(xy 92.905326 -331.032358) (xy 92.905326 -328.610976) (xy 92.905732 -328.600905) (xy 92.913466 -328.582307)
			(xy 92.920312 -328.574908) (xy 93.01861 -328.47661) (xy 93.026014 -328.469774) (xy 93.04461 -328.462052)
			(xy 93.054678 -328.461624) (xy 97.924366 -328.461624) (xy 97.934434 -328.462061) (xy 97.953032 -328.469773)
			(xy 97.960434 -328.47661) (xy 98.110294 -328.62647) (xy 98.117113 -328.633887) (xy 98.124845 -328.652473)
			(xy 98.12528 -328.662538) (xy 98.12528 -332.537054) (xy 98.125029 -332.544379) (xy 98.12089 -332.558434)
			(xy 98.117152 -332.56474) (xy 98.117152 -332.626208) (xy 97.923858 -332.819502) (xy 97.842832 -332.819502)
			(xy 92.745052 -332.819502) (xy 92.734982 -332.819927) (xy 92.716383 -332.827645) (xy 92.708984 -332.834488)
			(xy 92.317316 -333.226156) (xy 92.317316 -333.227172) (xy 92.139516 -333.404972) (xy 92.132101 -333.411793)
			(xy 92.113513 -333.419525) (xy 92.103448 -333.419958) (xy 91.414854 -333.419958) (xy 91.404786 -333.419516)
			(xy 91.386188 -333.411808) (xy 91.378786 -333.404972) (xy 90.886026 -332.912212) (xy 90.879203 -332.904799)
			(xy 90.871472 -332.88621) (xy 90.87104 -332.876144) (xy 84.285328 -332.876144) (xy 83.986116 -333.175356)
			(xy 83.986116 -333.176372) (xy 83.808316 -333.354172) (xy 83.800901 -333.360993) (xy 83.782313 -333.368725)
			(xy 83.772248 -333.369158) (xy 83.083654 -333.369158) (xy 83.073586 -333.368716) (xy 83.054988 -333.361008)
			(xy 83.047586 -333.354172) (xy 82.554826 -332.861412) (xy 82.548003 -332.853999) (xy 82.540272 -332.83541)
			(xy 82.53984 -332.825344) (xy 75.978512 -332.825344) (xy 75.450446 -333.35341) (xy 75.443025 -333.360224)
			(xy 75.424442 -333.367958) (xy 75.414378 -333.368396) (xy 74.726292 -333.368396) (xy 74.716219 -333.368002)
			(xy 74.697619 -333.360263) (xy 74.690224 -333.35341) (xy 74.197972 -332.861158) (xy 74.191117 -332.85377)
			(xy 74.183407 -332.835161) (xy 74.182986 -332.82509) (xy 67.67449 -332.82509) (xy 67.12458 -333.375)
			(xy 67.11718 -333.381843) (xy 67.098582 -333.38957) (xy 67.088512 -333.389986) (xy 66.454274 -333.389986)
			(xy 66.444269 -333.390478) (xy 66.425783 -333.398142) (xy 66.411635 -333.412293) (xy 66.403976 -333.430781)
			(xy 66.403474 -333.440786) (xy 66.403474 -334.608678) (xy 66.411094 -334.627474) (xy 66.41846 -334.634586)
			(xy 66.464688 -334.680814) (xy 66.472082 -334.687672) (xy 66.490681 -334.695424) (xy 66.500756 -334.6958)
			(xy 67.438778 -334.6958) (xy 67.92214 -334.212438) (xy 69.445378 -334.212438) (xy 69.455399 -334.212854)
			(xy 69.473917 -334.220522) (xy 69.488087 -334.234696) (xy 69.495749 -334.253216) (xy 69.496178 -334.263238)
			(xy 69.496178 -334.897222) (xy 69.49575 -334.90729) (xy 69.488028 -334.925887) (xy 69.481192 -334.93329)
			(xy 69.152262 -335.26222) (xy 68.645532 -335.26222) (xy 68.598542 -335.30921) (xy 68.598542 -335.312766)
			(xy 68.565268 -335.34604) (xy 68.557871 -335.352888) (xy 68.539272 -335.36062) (xy 68.5292 -335.361026)
			(xy 67.811904 -335.361026) (xy 67.793108 -335.368646) (xy 67.785996 -335.376012) (xy 67.765168 -335.39684)
			(xy 67.75832 -335.404237) (xy 67.75059 -335.422836) (xy 67.750182 -335.432908) (xy 67.750182 -335.538826)
			(xy 67.750674 -335.548832) (xy 67.758338 -335.567318) (xy 67.772489 -335.581467) (xy 67.790976 -335.589128)
			(xy 67.800982 -335.589626) (xy 68.311522 -335.589626) (xy 68.314062 -335.587086) (xy 68.581016 -335.587086)
			(xy 68.591085 -335.587511) (xy 68.609687 -335.595228) (xy 68.617084 -335.602072) (xy 68.645532 -335.63052)
			(xy 68.652383 -335.637916) (xy 68.66012 -335.656515) (xy 68.660518 -335.666588) (xy 68.660518 -335.764886)
			(xy 68.66255 -335.769966) (xy 68.66255 -336.612738) (xy 68.660518 -336.618072) (xy 68.660518 -336.637884)
			(xy 68.66008 -336.647948) (xy 68.652346 -336.666532) (xy 68.645532 -336.673952) (xy 68.629022 -336.690462)
			(xy 68.629022 -336.691986) (xy 68.623942 -336.697066) (xy 68.614798 -336.700876) (xy 68.61048 -336.7024)
			(xy 68.599558 -336.713322) (xy 67.782948 -336.713322) (xy 67.772876 -336.720831) (xy 67.761006 -336.742941)
			(xy 67.760342 -336.755486) (xy 67.760342 -336.896964) (xy 67.767962 -336.91576) (xy 67.775328 -336.922872)
			(xy 67.778376 -336.92592) (xy 67.785488 -336.933286) (xy 68.596256 -336.933286) (xy 68.603876 -336.940906)
			(xy 68.61394 -336.941343) (xy 68.632524 -336.949078) (xy 68.639944 -336.955892) (xy 68.645532 -336.96148)
			(xy 68.652373 -336.96888) (xy 68.660089 -336.987479) (xy 68.660518 -336.997548) (xy 68.660518 -337.034886)
			(xy 68.66255 -337.039966) (xy 68.66255 -337.216496) (xy 68.662695 -337.221527) (xy 68.66475 -337.231378)
			(xy 68.666614 -337.236054) (xy 68.67779 -337.262724) (xy 68.691252 -337.276186) (xy 68.694914 -337.279704)
			(xy 68.703359 -337.285338) (xy 68.708016 -337.287362) (xy 68.726812 -337.294982) (xy 68.738496 -337.29168)
			(xy 68.754683 -337.286914) (xy 68.787466 -337.278907) (xy 68.804028 -337.275678) (xy 68.832651 -337.270573)
			(xy 68.890527 -337.264977) (xy 68.919598 -337.264502) (xy 68.925948 -337.264502) (xy 68.958632 -337.265129)
			(xy 69.023616 -337.272254) (xy 69.087526 -337.286014) (xy 69.118734 -337.295744) (xy 69.126608 -337.298284)
			(xy 70.409562 -337.298284) (xy 70.43166 -337.276186) (xy 70.43166 -335.2546) (xy 70.75932 -334.92694)
			(xy 73.087738 -334.92694) (xy 73.13676 -334.975962) (xy 74.284586 -334.975962) (xy 74.301858 -334.97647)
			(xy 74.386694 -334.97647) (xy 74.40549 -334.96885) (xy 74.412602 -334.961484) (xy 74.493882 -334.880204)
			(xy 74.501285 -334.87337) (xy 74.519883 -334.865665) (xy 74.52995 -334.865218) (xy 75.626468 -334.865218)
			(xy 76.284328 -334.207358) (xy 77.801978 -334.207358) (xy 77.811992 -334.207842) (xy 77.830498 -334.215496)
			(xy 77.844668 -334.229648) (xy 77.852346 -334.248145) (xy 77.852778 -334.258158) (xy 77.852778 -334.886046)
			(xy 77.852346 -334.896112) (xy 77.844617 -334.914702) (xy 77.837792 -334.922114) (xy 77.53477 -335.225136)
			(xy 77.527373 -335.231985) (xy 77.508774 -335.239718) (xy 77.498702 -335.240122) (xy 77.027024 -335.240122)
			(xy 77.008228 -335.247742) (xy 77.001116 -335.255108) (xy 76.954126 -335.302098) (xy 76.954126 -335.305654)
			(xy 76.920852 -335.338928) (xy 76.913454 -335.345775) (xy 76.894855 -335.353503) (xy 76.884784 -335.353914)
			(xy 76.167488 -335.353914) (xy 76.148692 -335.361534) (xy 76.14158 -335.3689) (xy 76.120752 -335.389728)
			(xy 76.113904 -335.397126) (xy 76.106172 -335.415724) (xy 76.105766 -335.425796) (xy 76.105766 -335.531714)
			(xy 76.106256 -335.541722) (xy 76.113917 -335.560215) (xy 76.128068 -335.574372) (xy 76.146558 -335.58204)
			(xy 76.156566 -335.582514) (xy 76.667106 -335.582514) (xy 76.669646 -335.579974) (xy 76.9366 -335.579974)
			(xy 76.946671 -335.580396) (xy 76.965278 -335.588108) (xy 76.972668 -335.59496) (xy 77.001116 -335.623408)
			(xy 77.00797 -335.630803) (xy 77.015715 -335.649402) (xy 77.016102 -335.659476) (xy 77.016102 -335.757774)
			(xy 77.018134 -335.762854) (xy 77.018134 -336.605626) (xy 77.016102 -336.61096) (xy 77.016102 -336.630772)
			(xy 77.015666 -336.640836) (xy 77.007933 -336.659422) (xy 77.001116 -336.66684) (xy 76.984606 -336.68335)
			(xy 76.984606 -336.684874) (xy 76.979526 -336.689954) (xy 76.970382 -336.693764) (xy 76.965754 -336.695536)
			(xy 76.956032 -336.697452) (xy 76.951078 -336.697574) (xy 76.941934 -336.706718) (xy 76.13777 -336.706718)
			(xy 76.124816 -336.719672) (xy 76.120711 -336.726126) (xy 76.116189 -336.74073) (xy 76.115926 -336.748374)
			(xy 76.115926 -336.889852) (xy 76.123546 -336.908648) (xy 76.130912 -336.91576) (xy 76.13396 -336.918808)
			(xy 76.141072 -336.926174) (xy 76.152248 -336.930746) (xy 76.956412 -336.930746) (xy 76.95946 -336.933794)
			(xy 76.969526 -336.934228) (xy 76.988115 -336.941957) (xy 76.995528 -336.94878) (xy 77.001116 -336.954368)
			(xy 77.007961 -336.961766) (xy 77.015684 -336.980365) (xy 77.016102 -336.990436) (xy 77.016102 -337.027774)
			(xy 77.018134 -337.032854) (xy 77.018134 -337.209384) (xy 77.018278 -337.214415) (xy 77.020334 -337.224266)
			(xy 77.022198 -337.228942) (xy 77.033374 -337.255612) (xy 77.046836 -337.269074) (xy 77.050496 -337.272594)
			(xy 77.058941 -337.278231) (xy 77.0636 -337.28025) (xy 77.082396 -337.28787) (xy 77.09408 -337.284568)
			(xy 77.110267 -337.279801) (xy 77.14305 -337.271794) (xy 77.159612 -337.268566) (xy 77.188235 -337.26346)
			(xy 77.246111 -337.257863) (xy 77.275182 -337.25739) (xy 77.281532 -337.25739) (xy 77.314216 -337.258016)
			(xy 77.379201 -337.26514) (xy 77.443111 -337.278898) (xy 77.474318 -337.288632) (xy 77.482192 -337.291172)
			(xy 78.743048 -337.291172) (xy 78.80096 -337.23326) (xy 78.80096 -335.22412) (xy 79.11084 -334.91424)
			(xy 81.345532 -334.91424) (xy 81.42478 -334.993488) (xy 82.721958 -334.993488) (xy 82.845402 -334.870044)
			(xy 82.852799 -334.863193) (xy 82.871397 -334.855452) (xy 82.88147 -334.855058) (xy 83.98002 -334.855058)
			(xy 84.64423 -334.190848) (xy 86.157308 -334.190848) (xy 86.167325 -334.19127) (xy 86.185831 -334.198943)
			(xy 86.199989 -334.213116) (xy 86.207641 -334.231631) (xy 86.208108 -334.241648) (xy 86.208108 -334.885792)
			(xy 85.85327 -335.24063) (xy 85.358732 -335.24063) (xy 85.311742 -335.28762) (xy 85.311742 -335.291176)
			(xy 85.278468 -335.32445) (xy 85.27107 -335.331297) (xy 85.252471 -335.339027) (xy 85.2424 -335.339436)
			(xy 84.525104 -335.339436) (xy 84.506308 -335.347056) (xy 84.499196 -335.354422) (xy 84.478368 -335.37525)
			(xy 84.471522 -335.382648) (xy 84.463795 -335.401247) (xy 84.463382 -335.411318) (xy 84.463382 -335.517236)
			(xy 84.463876 -335.52724) (xy 84.471541 -335.545723) (xy 84.485692 -335.559869) (xy 84.504178 -335.567528)
			(xy 84.514182 -335.568036) (xy 85.024722 -335.568036) (xy 85.027262 -335.565496) (xy 85.294216 -335.565496)
			(xy 85.304285 -335.565922) (xy 85.322885 -335.57364) (xy 85.330284 -335.580482) (xy 85.358732 -335.60893)
			(xy 85.365581 -335.616327) (xy 85.373315 -335.634926) (xy 85.373718 -335.644998) (xy 85.373718 -335.743296)
			(xy 85.37575 -335.748376) (xy 85.37575 -336.591148) (xy 85.373718 -336.596482) (xy 85.373718 -336.616294)
			(xy 85.373297 -336.626365) (xy 85.365586 -336.644973) (xy 85.358732 -336.652362) (xy 85.342222 -336.668872)
			(xy 85.342222 -336.670396) (xy 85.337142 -336.675476) (xy 85.327998 -336.679286) (xy 85.32337 -336.681059)
			(xy 85.313648 -336.682977) (xy 85.308694 -336.683096) (xy 85.212936 -336.683096) (xy 85.204046 -336.691986)
			(xy 84.49564 -336.691986) (xy 84.485752 -336.699516) (xy 84.474184 -336.721483) (xy 84.473542 -336.733896)
			(xy 84.473542 -336.875374) (xy 84.481162 -336.89417) (xy 84.488528 -336.901282) (xy 84.491576 -336.90433)
			(xy 84.498688 -336.911696) (xy 84.510626 -336.916522) (xy 85.314282 -336.916522) (xy 85.317076 -336.919316)
			(xy 85.32714 -336.919753) (xy 85.345723 -336.927489) (xy 85.353144 -336.934302) (xy 85.358732 -336.93989)
			(xy 85.365587 -336.947285) (xy 85.373336 -336.965883) (xy 85.373718 -336.975958) (xy 85.373718 -337.013296)
			(xy 85.37575 -337.018376) (xy 85.37575 -337.194906) (xy 85.375886 -337.199939) (xy 85.377925 -337.209797)
			(xy 85.379814 -337.214464) (xy 85.39099 -337.241134) (xy 85.404452 -337.254596) (xy 85.408114 -337.258113)
			(xy 85.41656 -337.263746) (xy 85.421216 -337.265772) (xy 85.440012 -337.273392) (xy 85.451696 -337.27009)
			(xy 85.467883 -337.265323) (xy 85.500666 -337.257317) (xy 85.517228 -337.254088) (xy 85.545851 -337.248983)
			(xy 85.603727 -337.243387) (xy 85.632798 -337.242912) (xy 85.639148 -337.242912) (xy 85.671832 -337.243539)
			(xy 85.736816 -337.250665) (xy 85.800726 -337.264424) (xy 85.831934 -337.274154) (xy 85.839808 -337.276694)
			(xy 87.116666 -337.276694) (xy 87.15756 -337.2358) (xy 87.15756 -335.19618) (xy 87.44966 -334.90408)
			(xy 89.695782 -334.90408) (xy 89.7636 -334.971898) (xy 91.049348 -334.971898) (xy 91.110562 -334.910684)
			(xy 91.11796 -334.903838) (xy 91.136559 -334.896113) (xy 91.14663 -334.895698) (xy 92.274136 -334.895698)
			(xy 92.292932 -334.888078) (xy 92.300044 -334.880712) (xy 92.925392 -334.255364) (xy 92.932787 -334.248509)
			(xy 92.951386 -334.240762) (xy 92.96146 -334.240378) (xy 94.488508 -334.240378) (xy 94.498516 -334.240867)
			(xy 94.517009 -334.248527) (xy 94.531165 -334.262679) (xy 94.53883 -334.28117) (xy 94.539308 -334.291178)
			(xy 94.539308 -334.949292) (xy 94.204536 -335.284064) (xy 93.697044 -335.284064) (xy 93.689932 -335.29143)
			(xy 93.642942 -335.33842) (xy 93.642942 -335.341976) (xy 93.609668 -335.37525) (xy 93.60227 -335.382097)
			(xy 93.583671 -335.389827) (xy 93.5736 -335.390236) (xy 92.856304 -335.390236) (xy 92.837508 -335.397856)
			(xy 92.830396 -335.405222) (xy 92.809568 -335.42605) (xy 92.802722 -335.433448) (xy 92.794995 -335.452047)
			(xy 92.794582 -335.462118) (xy 92.794582 -335.568036) (xy 92.795076 -335.57804) (xy 92.802741 -335.596523)
			(xy 92.816892 -335.610669) (xy 92.835378 -335.618328) (xy 92.845382 -335.618836) (xy 93.355922 -335.618836)
			(xy 93.358462 -335.616296) (xy 93.625416 -335.616296) (xy 93.635485 -335.616722) (xy 93.654085 -335.62444)
			(xy 93.661484 -335.631282) (xy 93.689932 -335.65973) (xy 93.696781 -335.667127) (xy 93.704515 -335.685726)
			(xy 93.704918 -335.695798) (xy 93.704918 -335.794096) (xy 93.70695 -335.799176) (xy 93.70695 -336.641948)
			(xy 93.704918 -336.647282) (xy 93.704918 -336.667094) (xy 93.704497 -336.677165) (xy 93.696786 -336.695773)
			(xy 93.689932 -336.703162) (xy 93.673422 -336.719672) (xy 93.673422 -336.721196) (xy 93.668342 -336.726276)
			(xy 93.659198 -336.730086) (xy 93.65457 -336.731859) (xy 93.644848 -336.733777) (xy 93.639894 -336.733896)
			(xy 92.855542 -336.733896) (xy 92.845515 -336.734308) (xy 92.826983 -336.741971) (xy 92.812796 -336.756144)
			(xy 92.805117 -336.774669) (xy 92.804742 -336.784696) (xy 92.804742 -336.926174) (xy 92.812362 -336.94497)
			(xy 92.819728 -336.952082) (xy 92.822776 -336.95513) (xy 92.829888 -336.962496) (xy 92.848684 -336.970116)
			(xy 93.648276 -336.970116) (xy 93.65834 -336.970553) (xy 93.676923 -336.978289) (xy 93.684344 -336.985102)
			(xy 93.689932 -336.99069) (xy 93.696787 -336.998085) (xy 93.704536 -337.016683) (xy 93.704918 -337.026758)
			(xy 93.704918 -337.064096) (xy 93.70695 -337.069176) (xy 93.70695 -337.245706) (xy 93.707086 -337.250739)
			(xy 93.709125 -337.260597) (xy 93.711014 -337.265264) (xy 93.72219 -337.291934) (xy 93.735652 -337.305396)
			(xy 93.739314 -337.308913) (xy 93.74776 -337.314546) (xy 93.752416 -337.316572) (xy 93.771212 -337.324192)
			(xy 93.782896 -337.32089) (xy 93.799083 -337.316123) (xy 93.831866 -337.308117) (xy 93.848428 -337.304888)
			(xy 93.877051 -337.299783) (xy 93.934927 -337.294187) (xy 93.963998 -337.293712) (xy 93.970348 -337.293712)
			(xy 94.003032 -337.294339) (xy 94.068016 -337.301465) (xy 94.131926 -337.315224) (xy 94.163134 -337.324954)
			(xy 94.171008 -337.327494) (xy 95.42272 -337.327494) (xy 95.48876 -337.261454) (xy 95.48876 -335.24952)
			(xy 95.78848 -334.9498) (xy 98.080068 -334.9498) (xy 98.15068 -335.020412) (xy 99.423982 -335.020412)
			(xy 99.444302 -335.040732) (xy 100.764086 -335.040732) (xy 100.782882 -335.033112) (xy 100.789994 -335.025746)
			(xy 100.938076 -334.877664) (xy 100.944919 -334.870265) (xy 100.952645 -334.851666) (xy 100.953062 -334.841596)
			(xy 100.953062 -333.60106) (xy 100.953494 -333.590994) (xy 100.961226 -333.572406) (xy 100.968048 -333.564992)
			(xy 101.174296 -333.358744) (xy 101.181692 -333.351892) (xy 101.200291 -333.344149) (xy 101.210364 -333.343758)
			(xy 106.382058 -333.343758) (xy 106.392074 -333.344238) (xy 106.410588 -333.351889) (xy 106.424764 -333.366042)
			(xy 106.432445 -333.384542) (xy 106.432858 -333.394558) (xy 106.432858 -337.49488) (xy 106.21264 -337.715098)
			(xy 101.0539 -337.715098) (xy 101.035104 -337.722718) (xy 101.027992 -337.730084) (xy 100.443284 -338.314792)
			(xy 100.435885 -338.321637) (xy 100.417287 -338.329367) (xy 100.407216 -338.329778) (xy 99.81946 -338.329778)
			(xy 99.800664 -338.337398) (xy 99.793552 -338.344764) (xy 99.744784 -338.393532) (xy 99.737933 -338.400928)
			(xy 99.730197 -338.419527) (xy 99.729798 -338.4296) (xy 99.729798 -338.889594) (xy 99.736148 -338.895944)
			(xy 99.736148 -339.764624) (xy 99.737418 -339.767672) (xy 99.744784 -339.774784) (xy 99.783392 -339.813392)
			(xy 99.79079 -339.820241) (xy 99.809388 -339.827979) (xy 99.81946 -339.828378) (xy 100.341176 -339.828378)
			(xy 100.359972 -339.820758) (xy 100.367084 -339.813392) (xy 101.015292 -339.165184) (xy 101.022686 -339.158327)
			(xy 101.041285 -339.150577) (xy 101.05136 -339.150198) (xy 102.777798 -339.150198) (xy 102.787806 -339.150686)
			(xy 102.806299 -339.158345) (xy 102.820453 -339.172498) (xy 102.828113 -339.19099) (xy 102.828598 -339.200998)
			(xy 102.828598 -339.835236) (xy 102.828168 -339.845303) (xy 102.820444 -339.863898) (xy 102.813612 -339.871304)
			(xy 102.475284 -340.209632) (xy 102.467888 -340.216483) (xy 102.449289 -340.224223) (xy 102.439216 -340.224618)
			(xy 101.823774 -340.224618) (xy 101.748336 -340.300056) (xy 100.975668 -340.300056) (xy 100.934774 -340.34095)
			(xy 100.934774 -340.486238) (xy 100.970334 -340.521798) (xy 101.891338 -340.521798) (xy 101.94544 -340.5759)
			(xy 101.94544 -341.60206) (xy 101.897434 -341.650066) (xy 101.008942 -341.650066) (xy 100.954078 -341.70493)
			(xy 100.954078 -341.832438) (xy 101.000306 -341.878666) (xy 101.863906 -341.878666) (xy 101.94798 -341.96274)
			(xy 101.94798 -342.213438) (xy 101.97084 -342.236298) (xy 103.691436 -342.236298) (xy 103.710232 -342.228678)
			(xy 103.717344 -342.221312) (xy 103.728012 -342.210644) (xy 103.734859 -342.203247) (xy 103.742587 -342.184647)
			(xy 103.742998 -342.174576) (xy 103.742998 -340.203282) (xy 104.06888 -339.8774) (xy 106.265726 -339.8774)
			(xy 106.3371 -339.948774) (xy 108.799884 -339.948774) (xy 108.834428 -339.983318) (xy 108.970318 -339.983318)
			(xy 109.347 -340.36) (xy 109.347 -345.186) (xy 109.9185 -345.7575) (xy 110.93196 -345.7575) (xy 112.439958 -345.7575)
			(xy 115.2525 -345.7575)
		)
		(stroke
			(width 0)
			(type solid)
		)
		(fill yes)
		(layer "F.Cu")
		(net "GND")
	)
	(gr_poly
		(pts
			(xy 295.475914 -405.51608) (xy 295.485983 -405.515654) (xy 295.504582 -405.507934) (xy 295.511982 -405.501094)
			(xy 296.096182 -404.916894) (xy 296.103029 -404.909496) (xy 296.110764 -404.890898) (xy 296.111168 -404.880826)
			(xy 296.111168 -401.987766) (xy 296.111597 -401.977698) (xy 296.119316 -401.959099) (xy 296.126154 -401.951698)
			(xy 296.694352 -401.3835) (xy 296.701204 -401.376104) (xy 296.708946 -401.357505) (xy 296.709338 -401.347432)
			(xy 296.709338 -400.243548) (xy 296.708927 -400.233518) (xy 296.701267 -400.214978) (xy 296.687095 -400.200781)
			(xy 296.668568 -400.193089) (xy 296.658538 -400.192748) (xy 296.385742 -400.192748) (xy 296.355126 -400.191997)
			(xy 296.29511 -400.179842) (xy 296.266616 -400.168618) (xy 296.257218 -400.164808) (xy 296.195242 -400.164808)
			(xy 296.17858 -400.164271) (xy 296.146387 -400.155664) (xy 296.117515 -400.139024) (xy 296.093928 -400.115484)
			(xy 296.077232 -400.086645) (xy 296.068562 -400.054469) (xy 296.067988 -400.037808) (xy 296.067988 -399.7325)
			(xy 296.068531 -399.715806) (xy 296.077161 -399.683553) (xy 296.093836 -399.654626) (xy 296.117421 -399.630994)
			(xy 296.146313 -399.614261) (xy 296.178549 -399.605565) (xy 296.195242 -399.604992) (xy 296.257218 -399.604992)
			(xy 296.266616 -399.601182) (xy 296.295117 -399.58998) (xy 296.355128 -399.577819) (xy 296.385742 -399.577052)
			(xy 296.658538 -399.577052) (xy 296.668551 -399.576625) (xy 296.687046 -399.568947) (xy 296.701195 -399.554774)
			(xy 296.708842 -399.536266) (xy 296.709338 -399.526252) (xy 296.709338 -399.405348) (xy 296.708927 -399.395318)
			(xy 296.701267 -399.376778) (xy 296.687095 -399.362581) (xy 296.668568 -399.354889) (xy 296.658538 -399.354548)
			(xy 296.385742 -399.354548) (xy 296.355126 -399.353797) (xy 296.29511 -399.341642) (xy 296.266616 -399.330418)
			(xy 296.257218 -399.326608) (xy 296.195242 -399.326608) (xy 296.17858 -399.326071) (xy 296.146387 -399.317464)
			(xy 296.117515 -399.300824) (xy 296.093928 -399.277284) (xy 296.077232 -399.248445) (xy 296.068562 -399.216269)
			(xy 296.067988 -399.199608) (xy 296.067988 -398.8943) (xy 296.068531 -398.877606) (xy 296.077161 -398.845353)
			(xy 296.093836 -398.816426) (xy 296.117421 -398.792794) (xy 296.146313 -398.776061) (xy 296.178549 -398.767365)
			(xy 296.195242 -398.766792) (xy 296.257218 -398.766792) (xy 296.266616 -398.762982) (xy 296.295117 -398.75178)
			(xy 296.355128 -398.739619) (xy 296.385742 -398.738852) (xy 296.658538 -398.738852) (xy 296.668551 -398.738425)
			(xy 296.687046 -398.730747) (xy 296.701195 -398.716574) (xy 296.708842 -398.698066) (xy 296.709338 -398.688052)
			(xy 296.709338 -397.568928) (xy 296.7089 -397.558865) (xy 296.70116 -397.540285) (xy 296.694352 -397.53286)
			(xy 296.625772 -397.46428) (xy 296.618345 -397.457509) (xy 296.599748 -397.449929) (xy 296.589704 -397.449548)
			(xy 296.385742 -397.449548) (xy 296.355126 -397.448797) (xy 296.29511 -397.436642) (xy 296.266616 -397.425418)
			(xy 296.257218 -397.421608) (xy 296.195242 -397.421608) (xy 296.17858 -397.421071) (xy 296.146387 -397.412464)
			(xy 296.117515 -397.395824) (xy 296.093928 -397.372284) (xy 296.077232 -397.343445) (xy 296.068562 -397.311269)
			(xy 296.067988 -397.294608) (xy 296.067988 -397.024098) (xy 296.067496 -397.013257) (xy 296.058551 -396.993507)
			(xy 296.050716 -396.985998) (xy 296.027744 -396.96527) (xy 295.986485 -396.919156) (xy 295.951126 -396.868377)
			(xy 295.922189 -396.813684) (xy 295.900102 -396.755884) (xy 295.88519 -396.695831) (xy 295.877674 -396.634412)
			(xy 295.877234 -396.603474) (xy 295.877681 -396.572744) (xy 295.885093 -396.511732) (xy 295.899804 -396.452058)
			(xy 295.921602 -396.394593) (xy 295.950167 -396.340174) (xy 295.985084 -396.289596) (xy 296.025843 -396.243595)
			(xy 296.071849 -396.202842) (xy 296.122433 -396.167932) (xy 296.176855 -396.139374) (xy 296.234323 -396.117584)
			(xy 296.293999 -396.10288) (xy 296.355012 -396.095477) (xy 296.385742 -396.094966) (xy 296.417295 -396.095438)
			(xy 296.479916 -396.103238) (xy 296.541092 -396.118724) (xy 296.570654 -396.129764) (xy 296.58254 -396.133795)
			(xy 296.607451 -396.13099) (xy 296.618152 -396.12443) (xy 296.68724 -396.077186) (xy 296.697126 -396.069656)
			(xy 296.708688 -396.047688) (xy 296.709338 -396.035276) (xy 296.709338 -395.74978) (xy 296.708771 -395.737296)
			(xy 296.697183 -395.715187) (xy 296.68724 -395.707616) (xy 296.617898 -395.660372) (xy 296.607252 -395.654059)
			(xy 296.582699 -395.651274) (xy 296.570908 -395.655038) (xy 296.570654 -395.655038) (xy 296.533704 -395.668861)
			(xy 296.457242 -395.688295) (xy 296.37896 -395.6981) (xy 296.339514 -395.698726) (xy 296.30385 -395.698245)
			(xy 296.232971 -395.69026) (xy 296.163431 -395.67439) (xy 296.096106 -395.650833) (xy 296.031841 -395.619886)
			(xy 295.971446 -395.581938) (xy 295.915679 -395.537467) (xy 295.865242 -395.487031) (xy 295.82077 -395.431265)
			(xy 295.782821 -395.370871) (xy 295.751872 -395.306607) (xy 295.728314 -395.239282) (xy 295.712442 -395.169743)
			(xy 295.704456 -395.098864) (xy 295.704456 -395.027536) (xy 295.712442 -394.956657) (xy 295.728314 -394.887118)
			(xy 295.751872 -394.819793) (xy 295.782821 -394.755529) (xy 295.82077 -394.695135) (xy 295.865242 -394.639369)
			(xy 295.915679 -394.588933) (xy 295.971446 -394.544462) (xy 296.031841 -394.506514) (xy 296.096106 -394.475567)
			(xy 296.163431 -394.45201) (xy 296.232971 -394.43614) (xy 296.30385 -394.428155) (xy 296.339514 -394.42771)
			(xy 296.380035 -394.428362) (xy 296.460418 -394.438674) (xy 296.499788 -394.448284) (xy 296.509681 -394.450369)
			(xy 296.529692 -394.447635) (xy 296.53865 -394.44295) (xy 296.562479 -394.429531) (xy 296.613714 -394.410423)
			(xy 296.66752 -394.400668) (xy 296.69486 -394.400024) (xy 296.899838 -394.400024) (xy 296.904857 -394.399933)
			(xy 296.91471 -394.398016) (xy 296.919396 -394.396214) (xy 297.62704 -394.103098) (xy 297.65525 -394.092085)
			(xy 297.714621 -394.080185) (xy 297.744896 -394.079476) (xy 297.800776 -394.079476) (xy 297.810799 -394.07906)
			(xy 297.82932 -394.071394) (xy 297.843494 -394.05722) (xy 297.85116 -394.038699) (xy 297.851576 -394.028676)
			(xy 297.851576 -393.596114) (xy 297.850928 -393.58418) (xy 297.840196 -393.562858) (xy 297.831002 -393.55522)
			(xy 297.803939 -393.534603) (xy 297.753927 -393.488477) (xy 297.709128 -393.437271) (xy 297.670055 -393.381574)
			(xy 297.653202 -393.35202) (xy 297.646598 -393.340082) (xy 297.623738 -393.326366) (xy 297.522392 -393.32408)
			(xy 297.513462 -393.324194) (xy 297.496541 -393.329872) (xy 297.482584 -393.340997) (xy 297.477688 -393.348464)
			(xy 297.458433 -393.379064) (xy 297.414031 -393.436124) (xy 297.363443 -393.487779) (xy 297.307323 -393.533363)
			(xy 297.246395 -393.572288) (xy 297.181445 -393.60405) (xy 297.113311 -393.62824) (xy 297.042873 -393.644546)
			(xy 296.97104 -393.652757) (xy 296.93489 -393.653264) (xy 296.899232 -393.652763) (xy 296.828363 -393.644777)
			(xy 296.758835 -393.628907) (xy 296.69152 -393.605352) (xy 296.627266 -393.574408) (xy 296.566881 -393.536464)
			(xy 296.511123 -393.491998) (xy 296.460695 -393.441569) (xy 296.41623 -393.385811) (xy 296.378287 -393.325425)
			(xy 296.347344 -393.261171) (xy 296.32379 -393.193856) (xy 296.307921 -393.124327) (xy 296.299936 -393.053458)
			(xy 296.299936 -392.982142) (xy 296.307921 -392.911273) (xy 296.32379 -392.841744) (xy 296.347344 -392.774429)
			(xy 296.378287 -392.710175) (xy 296.41623 -392.649789) (xy 296.460695 -392.594031) (xy 296.511123 -392.543602)
			(xy 296.566881 -392.499136) (xy 296.627266 -392.461192) (xy 296.69152 -392.430248) (xy 296.758835 -392.406693)
			(xy 296.828363 -392.390823) (xy 296.899232 -392.382837) (xy 296.93489 -392.382248) (xy 296.968851 -392.382708)
			(xy 297.036384 -392.389985) (xy 297.102756 -392.404414) (xy 297.167214 -392.425832) (xy 297.229024 -392.453994)
			(xy 297.258486 -392.470894) (xy 297.268451 -392.476043) (xy 297.290762 -392.478082) (xy 297.31184 -392.470492)
			(xy 297.320208 -392.46302) (xy 297.692572 -392.090656) (xy 297.697695 -392.085198) (xy 297.704797 -392.072028)
			(xy 297.706542 -392.064748) (xy 297.709764 -392.049714) (xy 297.718799 -392.020323) (xy 297.724576 -392.006074)
			(xy 297.72864 -391.996676) (xy 297.72864 -391.95883) (xy 297.728202 -391.948767) (xy 297.720463 -391.930186)
			(xy 297.713654 -391.922762) (xy 297.576748 -391.785856) (xy 297.550078 -391.778998) (xy 297.536616 -391.782808)
			(xy 297.510621 -391.789725) (xy 297.45734 -391.797124) (xy 297.430444 -391.79754) (xy 297.402877 -391.797052)
			(xy 297.348302 -391.789214) (xy 297.295398 -391.773691) (xy 297.245241 -391.750799) (xy 297.19885 -391.721004)
			(xy 297.157171 -391.684911) (xy 297.121051 -391.643256) (xy 297.091225 -391.596886) (xy 297.068299 -391.546744)
			(xy 297.052741 -391.49385) (xy 297.044867 -391.439281) (xy 297.044364 -391.411714) (xy 297.044364 -391.411206)
			(xy 297.044872 -391.388346) (xy 297.045634 -391.375392) (xy 297.034712 -391.352024) (xy 296.955718 -391.293858)
			(xy 296.9487 -391.289068) (xy 296.932488 -391.28401) (xy 296.915515 -391.284549) (xy 296.907458 -391.287254)
			(xy 296.885566 -391.295218) (xy 296.840342 -391.306403) (xy 296.794099 -391.312049) (xy 296.770806 -391.3124)
			(xy 296.770044 -391.3124) (xy 296.742462 -391.311935) (xy 296.687859 -391.30409) (xy 296.634928 -391.288554)
			(xy 296.584746 -391.265643) (xy 296.538337 -391.235823) (xy 296.496644 -391.199702) (xy 296.460515 -391.158015)
			(xy 296.430688 -391.11161) (xy 296.407769 -391.061433) (xy 296.392224 -391.008504) (xy 296.38437 -390.953902)
			(xy 296.383964 -390.92632) (xy 296.383964 -390.925812) (xy 296.384513 -390.896773) (xy 296.393251 -390.839355)
			(xy 296.410473 -390.783888) (xy 296.435791 -390.731618) (xy 296.451782 -390.707372) (xy 296.456564 -390.699909)
			(xy 296.461098 -390.682785) (xy 296.459497 -390.665143) (xy 296.451956 -390.649114) (xy 296.44594 -390.642602)
			(xy 296.239946 -390.436608) (xy 296.233093 -390.429212) (xy 296.225349 -390.410614) (xy 296.22496 -390.40054)
			(xy 296.22496 -378.714762) (xy 296.224529 -378.704696) (xy 296.2168 -378.686105) (xy 296.209974 -378.678694)
			(xy 295.712642 -378.181362) (xy 295.705243 -378.174518) (xy 295.686644 -378.166795) (xy 295.676574 -378.166376)
			(xy 289.342322 -378.166376) (xy 289.332271 -378.166881) (xy 289.31371 -378.174602) (xy 289.306254 -378.181362)
			(xy 287.774634 -379.712982) (xy 287.752055 -379.73493) (xy 287.702819 -379.774185) (xy 287.649499 -379.807685)
			(xy 287.592766 -379.835009) (xy 287.533332 -379.855813) (xy 287.471943 -379.869837) (xy 287.409371 -379.876903)
			(xy 287.377886 -379.87732) (xy 284.3022 -379.87732) (xy 284.29213 -379.877744) (xy 284.273528 -379.88546)
			(xy 284.266132 -379.892306) (xy 282.547314 -381.611378) (xy 282.540478 -381.61878) (xy 282.53277 -381.637378)
			(xy 282.532328 -381.647446) (xy 282.532328 -384.973576) (xy 283.18841 -384.973576) (xy 283.18841 -384.973322)
			(xy 283.188853 -384.943114) (xy 283.195991 -384.883122) (xy 283.210191 -384.8244) (xy 283.231253 -384.767776)
			(xy 283.258881 -384.714048) (xy 283.292685 -384.663975) (xy 283.312108 -384.640836) (xy 283.317763 -384.633772)
			(xy 283.324146 -384.616855) (xy 283.324554 -384.607816) (xy 283.324554 -384.577336) (xy 283.324139 -384.568299)
			(xy 283.317758 -384.551382) (xy 283.312108 -384.544316) (xy 283.292674 -384.521187) (xy 283.258888 -384.471103)
			(xy 283.231271 -384.41737) (xy 283.210209 -384.360746) (xy 283.196 -384.302026) (xy 283.188843 -384.242037)
			(xy 283.18841 -384.21183) (xy 283.18841 -384.211576) (xy 283.189016 -384.177336) (xy 283.198238 -384.109479)
			(xy 283.216472 -384.04347) (xy 283.243389 -383.980501) (xy 283.278504 -383.921709) (xy 283.299408 -383.894584)
			(xy 283.306024 -383.88519) (xy 283.311131 -383.862827) (xy 283.306047 -383.840458) (xy 283.299408 -383.831084)
			(xy 283.278483 -383.80397) (xy 283.243325 -383.745193) (xy 283.216386 -383.682225) (xy 283.198155 -383.616206)
			(xy 283.188964 -383.548337) (xy 283.18841 -383.514092) (xy 283.188894 -383.482926) (xy 283.19651 -383.42106)
			(xy 283.211627 -383.360587) (xy 283.234019 -383.302415) (xy 283.26335 -383.247414) (xy 283.299181 -383.196409)
			(xy 283.319728 -383.17297) (xy 283.325806 -383.165814) (xy 283.332581 -383.148317) (xy 283.332936 -383.138934)
			(xy 283.332936 -383.1082) (xy 283.332494 -383.098839) (xy 283.325701 -383.081387) (xy 283.319728 -383.074164)
			(xy 283.299156 -383.050745) (xy 283.263323 -382.999737) (xy 283.233992 -382.944733) (xy 283.211602 -382.886557)
			(xy 283.196488 -382.82608) (xy 283.188878 -382.76421) (xy 283.18841 -382.733042) (xy 283.188877 -382.70231)
			(xy 283.196281 -382.641294) (xy 283.210987 -382.581615) (xy 283.232779 -382.524144) (xy 283.26134 -382.46972)
			(xy 283.296253 -382.419135) (xy 283.33701 -382.373127) (xy 283.383016 -382.332368) (xy 283.433599 -382.297452)
			(xy 283.488022 -382.268889) (xy 283.545492 -382.247094) (xy 283.60517 -382.232386) (xy 283.666186 -382.224979)
			(xy 283.696918 -382.224534) (xy 283.728714 -382.225071) (xy 283.791809 -382.232994) (xy 283.853427 -382.248715)
			(xy 283.912606 -382.271989) (xy 283.968426 -382.302453) (xy 284.020016 -382.339633) (xy 284.043628 -382.360932)
			(xy 284.050506 -382.366907) (xy 284.067311 -382.373919) (xy 284.076394 -382.374648) (xy 284.10662 -382.375664)
			(xy 284.115679 -382.375582) (xy 284.132854 -382.36986) (xy 284.140148 -382.364488) (xy 284.167291 -382.343503)
			(xy 284.226149 -382.308247) (xy 284.289219 -382.281239) (xy 284.355352 -382.262972) (xy 284.423343 -382.253778)
			(xy 284.457648 -382.253236) (xy 284.488382 -382.253611) (xy 284.5494 -382.261025) (xy 284.60908 -382.275741)
			(xy 284.666552 -382.297543) (xy 284.720976 -382.326114) (xy 284.771559 -382.361036) (xy 284.817565 -382.4018)
			(xy 284.858321 -382.447813) (xy 284.893234 -382.498403) (xy 284.921795 -382.552832) (xy 284.943586 -382.610307)
			(xy 284.958291 -382.66999) (xy 284.965695 -382.73101) (xy 284.966156 -382.761744) (xy 284.965734 -382.791403)
			(xy 284.958803 -382.850314) (xy 284.945065 -382.90802) (xy 284.924705 -382.963734) (xy 284.898001 -383.016701)
			(xy 284.865315 -383.066201) (xy 284.846522 -383.08915) (xy 284.841106 -383.096247) (xy 284.834985 -383.112999)
			(xy 284.834584 -383.121916) (xy 284.834584 -383.152142) (xy 284.834911 -383.161075) (xy 284.841025 -383.17786)
			(xy 284.846522 -383.184908) (xy 284.865303 -383.207866) (xy 284.897986 -383.257365) (xy 284.924689 -383.310331)
			(xy 284.945048 -383.366044) (xy 284.958788 -383.423747) (xy 284.965722 -383.482656) (xy 284.966156 -383.512314)
			(xy 284.966156 -383.512568) (xy 284.96556 -383.546904) (xy 284.956323 -383.614951) (xy 284.938012 -383.681136)
			(xy 284.910961 -383.744256) (xy 284.875661 -383.80316) (xy 284.85465 -383.830322) (xy 284.847905 -383.839657)
			(xy 284.842762 -383.862078) (xy 284.847886 -383.884504) (xy 284.85465 -383.893822) (xy 284.875648 -383.920995)
			(xy 284.91096 -383.979894) (xy 284.938022 -384.043009) (xy 284.956343 -384.109193) (xy 284.965589 -384.17724)
			(xy 284.966156 -384.211576) (xy 284.966156 -384.21183) (xy 284.965752 -384.242039) (xy 284.958608 -384.302033)
			(xy 284.944401 -384.360756) (xy 284.923331 -384.417381) (xy 284.895696 -384.471107) (xy 284.861885 -384.521178)
			(xy 284.842458 -384.544316) (xy 284.836819 -384.551391) (xy 284.830428 -384.5683) (xy 284.830012 -384.577336)
			(xy 284.830012 -384.607816) (xy 284.830457 -384.61685) (xy 284.836818 -384.633766) (xy 284.842458 -384.640836)
			(xy 284.861864 -384.663988) (xy 284.895654 -384.714067) (xy 284.923276 -384.767794) (xy 284.944343 -384.824414)
			(xy 284.957456 -384.87858) (xy 286.799027 -384.87858) (xy 286.803034 -384.693676) (xy 286.815047 -384.509118)
			(xy 286.835043 -384.325254) (xy 286.862985 -384.14243) (xy 286.898821 -383.960987) (xy 286.942483 -383.781266)
			(xy 286.99389 -383.603606) (xy 287.052944 -383.42834) (xy 287.119535 -383.255796) (xy 287.193538 -383.086299)
			(xy 287.274814 -382.920167) (xy 287.36321 -382.757711) (xy 287.458561 -382.599237) (xy 287.560687 -382.445042)
			(xy 287.669396 -382.295416) (xy 287.784485 -382.15064) (xy 287.905738 -382.010985) (xy 288.032927 -381.876714)
			(xy 288.165812 -381.748078) (xy 288.304146 -381.625319) (xy 288.447667 -381.508669) (xy 288.596106 -381.398345)
			(xy 288.749186 -381.294554) (xy 288.906617 -381.197492) (xy 289.068106 -381.107342) (xy 289.233348 -381.024271)
			(xy 289.402034 -380.948436) (xy 289.573846 -380.87998) (xy 289.748462 -380.81903) (xy 289.925555 -380.765703)
			(xy 290.104792 -380.720096) (xy 290.285836 -380.682297) (xy 290.468347 -380.652376) (xy 290.651984 -380.630389)
			(xy 290.8364 -380.616377) (xy 291.02125 -380.610367) (xy 291.206187 -380.612371) (xy 291.390864 -380.622384)
			(xy 291.574934 -380.640387) (xy 291.75805 -380.666348) (xy 291.939871 -380.700216) (xy 292.120054 -380.741928)
			(xy 292.29826 -380.791407) (xy 292.474156 -380.848559) (xy 292.647411 -380.913277) (xy 292.8177 -380.98544)
			(xy 292.984703 -381.064911) (xy 293.148107 -381.151542) (xy 293.307604 -381.245171) (xy 293.462896 -381.34562)
			(xy 293.613691 -381.452703) (xy 293.759706 -381.566217) (xy 293.900666 -381.685949) (xy 294.036307 -381.811676)
			(xy 294.166375 -381.94316) (xy 294.290625 -382.080156) (xy 294.408823 -382.222405) (xy 294.520749 -382.36964)
			(xy 294.626192 -382.521586) (xy 294.724953 -382.677957) (xy 294.816848 -382.83846) (xy 294.901704 -383.002792)
			(xy 294.979362 -383.170647) (xy 295.049675 -383.341707) (xy 295.112512 -383.515653) (xy 295.167756 -383.692158)
			(xy 295.215301 -383.87089) (xy 295.255059 -384.051514) (xy 295.286956 -384.233691) (xy 295.310931 -384.417078)
			(xy 295.326939 -384.601332) (xy 295.334951 -384.786106) (xy 295.335452 -384.87858) (xy 295.334951 -384.971054)
			(xy 295.326939 -385.155828) (xy 295.310931 -385.340082) (xy 295.286956 -385.523469) (xy 295.255059 -385.705646)
			(xy 295.215301 -385.88627) (xy 295.167756 -386.065002) (xy 295.112512 -386.241507) (xy 295.049675 -386.415453)
			(xy 294.979362 -386.586513) (xy 294.901704 -386.754368) (xy 294.816848 -386.9187) (xy 294.724953 -387.079203)
			(xy 294.626192 -387.235574) (xy 294.520749 -387.38752) (xy 294.408823 -387.534755) (xy 294.290625 -387.677004)
			(xy 294.166375 -387.814) (xy 294.036307 -387.945484) (xy 293.900666 -388.071211) (xy 293.759706 -388.190943)
			(xy 293.613691 -388.304457) (xy 293.462896 -388.41154) (xy 293.307604 -388.511989) (xy 293.148107 -388.605618)
			(xy 292.984703 -388.692249) (xy 292.8177 -388.77172) (xy 292.647411 -388.843883) (xy 292.474156 -388.908601)
			(xy 292.29826 -388.965753) (xy 292.120054 -389.015232) (xy 291.939871 -389.056944) (xy 291.75805 -389.090812)
			(xy 291.574934 -389.116773) (xy 291.390864 -389.134776) (xy 291.206187 -389.144789) (xy 291.02125 -389.146793)
			(xy 290.8364 -389.140783) (xy 290.651984 -389.126771) (xy 290.468347 -389.104784) (xy 290.285836 -389.074863)
			(xy 290.104792 -389.037064) (xy 289.925555 -388.991457) (xy 289.748462 -388.93813) (xy 289.573846 -388.87718)
			(xy 289.402034 -388.808724) (xy 289.233348 -388.732889) (xy 289.068106 -388.649818) (xy 288.906617 -388.559668)
			(xy 288.749186 -388.462606) (xy 288.596106 -388.358815) (xy 288.447667 -388.248491) (xy 288.304146 -388.131841)
			(xy 288.165812 -388.009082) (xy 288.032927 -387.880446) (xy 287.905738 -387.746175) (xy 287.784485 -387.60652)
			(xy 287.669396 -387.461744) (xy 287.560687 -387.312118) (xy 287.458561 -387.157923) (xy 287.36321 -386.999449)
			(xy 287.274814 -386.836993) (xy 287.193538 -386.670861) (xy 287.119535 -386.501364) (xy 287.052944 -386.32882)
			(xy 286.99389 -386.153554) (xy 286.942483 -385.975894) (xy 286.898821 -385.796173) (xy 286.862985 -385.61473)
			(xy 286.835043 -385.431906) (xy 286.815047 -385.248042) (xy 286.803034 -385.063484) (xy 286.799027 -384.87858)
			(xy 284.957456 -384.87858) (xy 284.958558 -384.88313) (xy 284.96572 -384.943116) (xy 284.966156 -384.973322)
			(xy 284.966156 -384.973576) (xy 284.965621 -385.004305) (xy 284.958217 -385.065314) (xy 284.943512 -385.124986)
			(xy 284.921723 -385.182451) (xy 284.893165 -385.236871) (xy 284.858257 -385.287451) (xy 284.817506 -385.333455)
			(xy 284.771508 -385.374212) (xy 284.720932 -385.409128) (xy 284.666517 -385.437693) (xy 284.609055 -385.459491)
			(xy 284.549385 -385.474204) (xy 284.488377 -385.481617) (xy 284.457648 -385.482084) (xy 284.427501 -385.481652)
			(xy 284.367629 -385.474522) (xy 284.309018 -385.460369) (xy 284.252491 -385.43939) (xy 284.198837 -385.411879)
			(xy 284.14881 -385.378223) (xy 284.12567 -385.358894) (xy 284.118596 -385.353253) (xy 284.101687 -385.346862)
			(xy 284.09265 -385.346448) (xy 284.061916 -385.346448) (xy 284.052878 -385.346853) (xy 284.035961 -385.353241)
			(xy 284.028896 -385.358894) (xy 284.005791 -385.37827) (xy 283.95577 -385.41195) (xy 283.902114 -385.439472)
			(xy 283.845577 -385.460447) (xy 283.786954 -385.474581) (xy 283.72707 -385.481676) (xy 283.696918 -385.482084)
			(xy 283.666185 -385.481645) (xy 283.605168 -385.474238) (xy 283.545488 -385.45953) (xy 283.488017 -385.437735)
			(xy 283.433592 -385.409171) (xy 283.383007 -385.374255) (xy 283.337 -385.333496) (xy 283.296241 -385.287488)
			(xy 283.261326 -385.236903) (xy 283.232762 -385.182477) (xy 283.210968 -385.125006) (xy 283.196261 -385.065326)
			(xy 283.188854 -385.004309) (xy 283.18841 -384.973576) (xy 282.532328 -384.973576) (xy 282.532328 -386.872988)
			(xy 282.53275 -386.883059) (xy 282.540464 -386.901664) (xy 282.547314 -386.909056) (xy 282.848304 -387.2103)
			(xy 282.855901 -387.217192) (xy 282.874917 -387.224834) (xy 282.895409 -387.224485) (xy 282.904946 -387.220714)
			(xy 282.93776 -387.206658) (xy 283.006343 -387.186852) (xy 283.077025 -387.176852) (xy 283.112718 -387.176264)
			(xy 283.143449 -387.176729) (xy 283.204462 -387.184139) (xy 283.264138 -387.198849) (xy 283.321605 -387.220645)
			(xy 283.376027 -387.249208) (xy 283.426609 -387.284122) (xy 283.472614 -387.324879) (xy 283.513372 -387.370883)
			(xy 283.548287 -387.421464) (xy 283.576851 -387.475885) (xy 283.598648 -387.533352) (xy 283.613359 -387.593028)
			(xy 283.62077 -387.654041) (xy 283.621226 -387.684772) (xy 283.620764 -387.715417) (xy 283.613393 -387.776261)
			(xy 283.598767 -387.835779) (xy 283.577096 -387.89311) (xy 283.563314 -387.920484) (xy 283.56064 -387.925955)
			(xy 283.557687 -387.937766) (xy 283.557472 -387.943852) (xy 283.557472 -388.316978) (xy 283.556943 -388.34767)
			(xy 283.548474 -388.408467) (xy 283.531721 -388.467521) (xy 283.507002 -388.523708) (xy 283.474789 -388.57596)
			(xy 283.455618 -388.599934) (xy 283.442918 -388.615174) (xy 283.44495 -388.65429) (xy 283.509974 -388.719314)
			(xy 283.53192 -388.741893) (xy 283.571172 -388.791131) (xy 283.604668 -388.844451) (xy 283.631987 -388.901184)
			(xy 283.652787 -388.960618) (xy 283.666805 -389.022007) (xy 283.673866 -389.084578) (xy 283.674312 -389.116062)
			(xy 283.674312 -389.14705) (xy 283.674745 -389.157116) (xy 283.682473 -389.175706) (xy 283.689298 -389.183118)
			(xy 283.820108 -389.313928) (xy 283.84754 -389.320786) (xy 283.861002 -389.316468) (xy 283.881491 -389.310325)
			(xy 283.923192 -389.30079) (xy 283.944314 -389.297418) (xy 283.948551 -389.296681) (xy 283.956724 -389.294008)
			(xy 283.96057 -389.292084) (xy 283.995166 -389.274322) (xy 284.067754 -389.246407) (xy 284.143204 -389.227548)
			(xy 284.220389 -389.218028) (xy 284.259274 -389.217408) (xy 284.298775 -389.218002) (xy 284.377167 -389.227793)
			(xy 284.453737 -389.247238) (xy 284.527302 -389.276038) (xy 284.562296 -389.29437) (xy 284.565957 -389.296256)
			(xy 284.573744 -389.298937) (xy 284.57779 -389.299704) (xy 284.611505 -389.306178) (xy 284.677156 -389.326258)
			(xy 284.739875 -389.354181) (xy 284.798729 -389.389532) (xy 284.852841 -389.431784) (xy 284.87751 -389.45566)
			(xy 286.590486 -391.168636) (xy 286.612431 -391.191216) (xy 286.65168 -391.240454) (xy 286.685173 -391.293775)
			(xy 286.71249 -391.350508) (xy 286.733286 -391.409942) (xy 286.747302 -391.47133) (xy 286.754361 -391.5339)
			(xy 286.754824 -391.565384) (xy 286.754824 -392.227562) (xy 286.755259 -392.237627) (xy 286.762992 -392.256213)
			(xy 286.76981 -392.26363) (xy 287.213294 -392.707114) (xy 287.220688 -392.713971) (xy 287.239287 -392.721721)
			(xy 287.249362 -392.7221) (xy 289.307524 -392.7221) (xy 289.317592 -392.722528) (xy 289.33619 -392.730248)
			(xy 289.343592 -392.737086) (xy 290.014152 -392.737086) (xy 290.024218 -392.736653) (xy 290.042807 -392.728924)
			(xy 290.05022 -392.7221) (xy 290.090098 -392.682222) (xy 290.112677 -392.660275) (xy 290.161914 -392.621022)
			(xy 290.215234 -392.587525) (xy 290.271968 -392.560204) (xy 290.331402 -392.539403) (xy 290.39279 -392.525383)
			(xy 290.455362 -392.51832) (xy 290.486846 -392.517884) (xy 293.072566 -392.517884) (xy 293.082631 -392.517448)
			(xy 293.101216 -392.509715) (xy 293.108634 -392.502898) (xy 293.686484 -391.924794) (xy 293.709063 -391.902848)
			(xy 293.758301 -391.863595) (xy 293.811621 -391.830098) (xy 293.868354 -391.802778) (xy 293.927788 -391.781976)
			(xy 293.989176 -391.767956) (xy 294.051748 -391.760891) (xy 294.083232 -391.760456) (xy 294.493188 -391.760456)
			(xy 294.525665 -391.760918) (xy 294.590185 -391.768407) (xy 294.653412 -391.783286) (xy 294.714501 -391.805357)
			(xy 294.772637 -391.834326) (xy 294.827045 -391.869805) (xy 294.876998 -391.911322) (xy 294.921831 -391.958323)
			(xy 294.941752 -391.983976) (xy 294.949305 -391.993042) (xy 294.970357 -392.003638) (xy 294.982138 -392.004296)
			(xy 295.178988 -392.004296) (xy 295.195683 -392.004837) (xy 295.227938 -392.013466) (xy 295.256866 -392.03014)
			(xy 295.2805 -392.053726) (xy 295.297233 -392.082619) (xy 295.305928 -392.114856) (xy 295.306496 -392.13155)
			(xy 295.306496 -392.142218) (xy 295.336214 -392.171936) (xy 295.52519 -392.171936) (xy 295.559129 -392.172427)
			(xy 295.626512 -392.180608) (xy 295.692418 -392.196851) (xy 295.755885 -392.22092) (xy 295.815989 -392.252464)
			(xy 295.871852 -392.291023) (xy 295.922659 -392.336034) (xy 295.967671 -392.386841) (xy 296.006231 -392.442703)
			(xy 296.037776 -392.502806) (xy 296.061846 -392.566272) (xy 296.07809 -392.632178) (xy 296.086272 -392.699561)
			(xy 296.086272 -392.767439) (xy 296.07809 -392.834822) (xy 296.061846 -392.900728) (xy 296.037776 -392.964194)
			(xy 296.006231 -393.024297) (xy 295.967671 -393.080159) (xy 295.922659 -393.130966) (xy 295.871852 -393.175977)
			(xy 295.815989 -393.214536) (xy 295.755885 -393.24608) (xy 295.692418 -393.270149) (xy 295.626512 -393.286392)
			(xy 295.559129 -393.294573) (xy 295.52519 -393.295124) (xy 295.395396 -393.295124) (xy 295.384059 -393.295722)
			(xy 295.363588 -393.305469) (xy 295.34933 -393.323097) (xy 295.34612 -393.333986) (xy 295.339395 -393.359853)
			(xy 295.319769 -393.409565) (xy 295.307004 -393.433046) (xy 295.302636 -393.44149) (xy 295.299879 -393.460287)
			(xy 295.30167 -393.469622) (xy 295.308782 -393.499848) (xy 295.311323 -393.509192) (xy 295.322295 -393.525128)
			(xy 295.330118 -393.530836) (xy 295.358594 -393.550405) (xy 295.411006 -393.595432) (xy 295.457499 -393.646547)
			(xy 295.497371 -393.702979) (xy 295.53002 -393.763875) (xy 295.554953 -393.828316) (xy 295.571794 -393.895329)
			(xy 295.580287 -393.963902) (xy 295.580816 -393.99845) (xy 295.580334 -394.031851) (xy 295.572409 -394.098181)
			(xy 295.556677 -394.163104) (xy 295.53336 -394.225704) (xy 295.502787 -394.285098) (xy 295.465388 -394.34045)
			(xy 295.421692 -394.390978) (xy 295.372314 -394.43597) (xy 295.31795 -394.474791) (xy 295.259368 -394.506894)
			(xy 295.197394 -394.531826) (xy 295.165272 -394.540994) (xy 295.154677 -394.54443) (xy 295.137639 -394.558736)
			(xy 295.128223 -394.578893) (xy 295.12768 -394.590016) (xy 295.12768 -394.912342) (xy 295.127133 -394.929)
			(xy 295.118513 -394.961182) (xy 295.10187 -394.990044) (xy 295.078333 -395.013624) (xy 295.049503 -395.030322)
			(xy 295.017337 -395.039002) (xy 295.00068 -395.039596) (xy 294.811958 -395.039596) (xy 294.801891 -395.040027)
			(xy 294.783297 -395.047752) (xy 294.77589 -395.054582) (xy 294.711628 -395.119098) (xy 294.685588 -395.144306)
			(xy 294.628145 -395.188498) (xy 294.565492 -395.224931) (xy 294.532304 -395.239494) (xy 294.524093 -395.243386)
			(xy 294.510904 -395.255865) (xy 294.502888 -395.272158) (xy 294.50157 -395.28115) (xy 294.497525 -395.315622)
			(xy 294.482009 -395.383274) (xy 294.458275 -395.448499) (xy 294.426686 -395.510302) (xy 294.387722 -395.567743)
			(xy 294.341977 -395.619944) (xy 294.290149 -395.666112) (xy 294.233027 -395.705542) (xy 294.171483 -395.737633)
			(xy 294.106453 -395.761896) (xy 294.038929 -395.777962) (xy 294.004492 -395.782292) (xy 293.99528 -395.783717)
			(xy 293.978718 -395.792234) (xy 293.966304 -395.806117) (xy 293.959683 -395.823525) (xy 293.95928 -395.832838)
			(xy 293.95928 -404.18265) (xy 294.26688 -404.18265) (xy 294.26688 -404.12815) (xy 294.274635 -404.074205)
			(xy 294.289989 -404.021912) (xy 294.312628 -403.972337) (xy 294.342092 -403.926488) (xy 294.377781 -403.885299)
			(xy 294.418968 -403.849608) (xy 294.464814 -403.820141) (xy 294.514388 -403.797498) (xy 294.566679 -403.782141)
			(xy 294.620624 -403.774382) (xy 294.647874 -403.773894) (xy 294.677925 -403.774465) (xy 294.737284 -403.783898)
			(xy 294.79443 -403.80252) (xy 294.84795 -403.829869) (xy 294.896521 -403.86527) (xy 294.91813 -403.886162)
			(xy 294.925242 -403.893274) (xy 294.943784 -403.901148) (xy 295.021762 -403.901148) (xy 295.028719 -403.900937)
			(xy 295.042122 -403.897211) (xy 295.048178 -403.893782) (xy 295.063259 -403.885437) (xy 295.096482 -403.876302)
			(xy 295.11371 -403.875748) (xy 295.49471 -403.875748) (xy 295.511392 -403.876282) (xy 295.543619 -403.884919)
			(xy 295.572513 -403.901603) (xy 295.596104 -403.925197) (xy 295.612785 -403.954092) (xy 295.62142 -403.98632)
			(xy 295.621964 -404.003002) (xy 295.621964 -404.307802) (xy 295.621411 -404.324483) (xy 295.612777 -404.356708)
			(xy 295.596096 -404.3856) (xy 295.572507 -404.409191) (xy 295.543615 -404.425874) (xy 295.511391 -404.43451)
			(xy 295.49471 -404.435056) (xy 295.11371 -404.435056) (xy 295.096481 -404.434525) (xy 295.063261 -404.425369)
			(xy 295.048178 -404.417022) (xy 295.042105 -404.413631) (xy 295.028713 -404.409895) (xy 295.021762 -404.409656)
			(xy 294.943784 -404.409656) (xy 294.925242 -404.41753) (xy 294.91813 -404.424642) (xy 294.896517 -404.445531)
			(xy 294.847953 -404.480945) (xy 294.794435 -404.508301) (xy 294.737287 -404.526923) (xy 294.677926 -404.536348)
			(xy 294.647874 -404.53691) (xy 294.620624 -404.536418) (xy 294.566679 -404.528659) (xy 294.514388 -404.513302)
			(xy 294.464814 -404.490659) (xy 294.418968 -404.461192) (xy 294.377781 -404.425501) (xy 294.342092 -404.384312)
			(xy 294.312628 -404.338463) (xy 294.289989 -404.288888) (xy 294.274635 -404.236595) (xy 294.26688 -404.18265)
			(xy 293.95928 -404.18265) (xy 293.95928 -404.255224) (xy 293.958852 -404.265292) (xy 293.951129 -404.283888)
			(xy 293.944294 -404.291292) (xy 293.716202 -404.519384) (xy 293.708804 -404.526232) (xy 293.690206 -404.53397)
			(xy 293.680134 -404.53437) (xy 292.289738 -404.53437) (xy 292.279686 -404.534872) (xy 292.26112 -404.542589)
			(xy 292.25367 -404.549356) (xy 292.177216 -404.62581) (xy 292.17037 -404.633208) (xy 292.162636 -404.651806)
			(xy 292.16223 -404.661878) (xy 292.16223 -405.47036) (xy 292.162665 -405.480425) (xy 292.170398 -405.499011)
			(xy 292.177216 -405.506428) (xy 292.179248 -405.50846) (xy 292.19779 -405.51608)
		)
		(stroke
			(width 0)
			(type solid)
		)
		(fill yes)
		(layer "F.Cu")
		(net "P1V8_CPU0_RT_1D")
	)
	(gr_poly
		(pts
			(xy 170.737784 -193.37909) (xy 170.743118 -193.378328) (xy 170.744642 -193.378328) (xy 170.74769 -193.378074)
			(xy 170.764702 -193.376079) (xy 170.798889 -193.373922) (xy 170.816016 -193.373756) (xy 171.97197 -193.373756)
			(xy 171.991528 -193.3739) (xy 172.030552 -193.376573) (xy 172.049948 -193.37909) (xy 172.05071 -193.37909)
			(xy 172.052996 -193.379852) (xy 172.699172 -193.379852) (xy 172.708824 -193.378836) (xy 172.716069 -193.37721)
			(xy 172.72924 -193.370371) (xy 172.734732 -193.365374) (xy 172.74032 -193.359786) (xy 172.745172 -193.355172)
			(xy 172.756757 -193.348467) (xy 172.76318 -193.346578) (xy 172.763434 -193.346578) (xy 172.773594 -193.343784)
			(xy 172.78096 -193.338196) (xy 172.785004 -193.334967) (xy 172.791791 -193.327158) (xy 172.794422 -193.322702)
			(xy 172.811948 -193.291968) (xy 172.815353 -193.284042) (xy 172.817188 -193.266899) (xy 172.815504 -193.25844)
			(xy 172.815504 -193.258186) (xy 172.812964 -193.24701) (xy 172.810678 -193.24193) (xy 172.810424 -193.241676)
			(xy 172.79945 -193.217111) (xy 172.783947 -193.165592) (xy 172.776108 -193.112366) (xy 172.775626 -193.085466)
			(xy 172.775626 -193.085212) (xy 172.776142 -193.057612) (xy 172.784369 -193.003029) (xy 172.800639 -192.950282)
			(xy 172.824589 -192.90055) (xy 172.855684 -192.854942) (xy 172.893229 -192.814478) (xy 172.936386 -192.780061)
			(xy 172.98419 -192.752462) (xy 173.035574 -192.732295) (xy 173.089389 -192.720012) (xy 173.144434 -192.715887)
			(xy 173.199479 -192.720012) (xy 173.253294 -192.732295) (xy 173.304678 -192.752462) (xy 173.352482 -192.780061)
			(xy 173.395639 -192.814478) (xy 173.433184 -192.854942) (xy 173.464279 -192.90055) (xy 173.488229 -192.950282)
			(xy 173.504499 -193.003029) (xy 173.512726 -193.057612) (xy 173.513242 -193.085212) (xy 173.513242 -193.085466)
			(xy 173.512565 -193.117361) (xy 173.501574 -193.180198) (xy 173.491398 -193.210434) (xy 173.489874 -193.214752)
			(xy 173.487757 -193.224974) (xy 173.491044 -193.245566) (xy 173.496224 -193.25463) (xy 173.520608 -193.289682)
			(xy 173.520608 -193.29019) (xy 173.543976 -193.32321) (xy 173.547606 -193.328054) (xy 173.556719 -193.336017)
			(xy 173.56201 -193.338958) (xy 173.567541 -193.341653) (xy 173.579482 -193.344603) (xy 173.585632 -193.3448)
			(xy 175.145192 -193.3448) (xy 175.155061 -193.344387) (xy 175.173297 -193.336833) (xy 175.18725 -193.322871)
			(xy 175.194793 -193.304632) (xy 175.19523 -193.294762) (xy 175.19523 -192.825116) (xy 175.19581 -192.808428)
			(xy 175.20451 -192.776202) (xy 175.221246 -192.747322) (xy 175.244878 -192.723749) (xy 175.273801 -192.707086)
			(xy 175.306048 -192.698467) (xy 175.322738 -192.697862) (xy 176.821338 -192.697862) (xy 176.83803 -192.698409)
			(xy 176.870278 -192.707045) (xy 176.899199 -192.723722) (xy 176.922828 -192.747305) (xy 176.93956 -192.776194)
			(xy 176.948259 -192.808425) (xy 176.948846 -192.825116) (xy 176.948846 -193.294762) (xy 176.949253 -193.304639)
			(xy 176.9568 -193.322894) (xy 176.970761 -193.33687) (xy 176.989007 -193.344437) (xy 176.998884 -193.3448)
			(xy 178.211734 -193.3448) (xy 178.216688 -193.344922) (xy 178.226407 -193.346847) (xy 178.231038 -193.34861)
			(xy 178.24831 -193.355722) (xy 178.252938 -193.357495) (xy 178.262659 -193.359414) (xy 178.267614 -193.359532)
			(xy 180.24602 -193.359532) (xy 180.259482 -193.3575) (xy 180.275992 -193.35242) (xy 180.287168 -193.350134)
			(xy 180.297074 -193.349118) (xy 180.30698 -193.344038) (xy 180.309774 -193.34226) (xy 180.314875 -193.33877)
			(xy 180.323347 -193.329774) (xy 180.326538 -193.32448) (xy 180.34 -193.300858) (xy 180.340508 -193.299842)
			(xy 180.341016 -193.298826) (xy 180.34487 -193.29056) (xy 180.347092 -193.272469) (xy 180.345334 -193.26352)
			(xy 180.342286 -193.251582) (xy 180.341016 -193.249042) (xy 180.34 -193.246756) (xy 180.32838 -193.221775)
			(xy 180.311853 -193.169218) (xy 180.303327 -193.114788) (xy 180.302662 -193.087244) (xy 180.302916 -193.07556)
			(xy 180.30422 -193.047089) (xy 180.314508 -192.991035) (xy 180.33329 -192.937227) (xy 180.360118 -192.886946)
			(xy 180.394356 -192.841385) (xy 180.43519 -192.801629) (xy 180.481649 -192.768621) (xy 180.532629 -192.743146)
			(xy 180.586919 -192.725809) (xy 180.643229 -192.717022) (xy 180.671724 -192.716404) (xy 180.698067 -192.716876)
			(xy 180.750215 -192.724377) (xy 180.800766 -192.739223) (xy 180.848689 -192.761112) (xy 180.893009 -192.789598)
			(xy 180.932824 -192.824102) (xy 180.967324 -192.86392) (xy 180.995805 -192.908243) (xy 181.01769 -192.956168)
			(xy 181.032531 -193.00672) (xy 181.040027 -193.058869) (xy 181.040532 -193.085212) (xy 181.040532 -193.086228)
			(xy 181.039713 -193.118952) (xy 181.027963 -193.183342) (xy 181.017164 -193.214244) (xy 181.017164 -193.214498)
			(xy 181.01691 -193.215006) (xy 181.013555 -193.226094) (xy 181.016065 -193.249101) (xy 181.021736 -193.259202)
			(xy 181.04612 -193.294508) (xy 181.069234 -193.328036) (xy 181.073552 -193.33337) (xy 181.076566 -193.336532)
			(xy 181.08346 -193.341898) (xy 181.087268 -193.344038) (xy 181.092266 -193.346529) (xy 181.103035 -193.349473)
			(xy 181.108604 -193.34988) (xy 182.6895 -193.34988) (xy 182.698899 -193.349468) (xy 182.716382 -193.342552)
			(xy 182.73012 -193.329718) (xy 182.738207 -193.312746) (xy 182.739284 -193.303398) (xy 182.739284 -192.825116)
			(xy 182.739779 -192.808393) (xy 182.748431 -192.776085) (xy 182.765151 -192.747118) (xy 182.788799 -192.723466)
			(xy 182.817763 -192.706741) (xy 182.850069 -192.698082) (xy 182.866792 -192.697608) (xy 184.365392 -192.697608)
			(xy 184.382113 -192.698104) (xy 184.414417 -192.706758) (xy 184.443379 -192.723479) (xy 184.467025 -192.747128)
			(xy 184.483745 -192.776091) (xy 184.492397 -192.808395) (xy 184.4929 -192.825116) (xy 184.4929 -193.303398)
			(xy 184.49391 -193.31277) (xy 184.501965 -193.329797) (xy 184.51573 -193.342655) (xy 184.533265 -193.349533)
			(xy 184.542684 -193.34988) (xy 185.758074 -193.34988) (xy 185.763029 -193.349996) (xy 185.772753 -193.35191)
			(xy 185.777378 -193.35369) (xy 185.79465 -193.360802) (xy 185.799279 -193.36257) (xy 185.809 -193.364478)
			(xy 185.813954 -193.364612) (xy 187.619894 -193.364612) (xy 187.624974 -193.369692) (xy 187.775596 -193.369692)
			(xy 187.7822 -193.369184) (xy 187.791212 -193.367606) (xy 187.807344 -193.359006) (xy 187.813696 -193.35242)
			(xy 187.815728 -193.350134) (xy 187.816236 -193.349372) (xy 187.865004 -193.279268) (xy 187.869576 -193.269616)
			(xy 187.869576 -193.235072) (xy 187.866782 -193.227198) (xy 187.857773 -193.19908) (xy 187.847812 -193.140887)
			(xy 187.84697 -193.111374) (xy 187.84697 -193.106294) (xy 187.847576 -193.078756) (xy 187.855955 -193.024319)
			(xy 187.872336 -192.971732) (xy 187.896356 -192.922167) (xy 187.92748 -192.876725) (xy 187.965016 -192.836416)
			(xy 188.008129 -192.802139) (xy 188.05586 -192.774654) (xy 188.107148 -192.754574) (xy 188.160852 -192.742344)
			(xy 188.215778 -192.738237) (xy 188.270704 -192.742344) (xy 188.324408 -192.754574) (xy 188.375696 -192.774654)
			(xy 188.423427 -192.802139) (xy 188.46654 -192.836416) (xy 188.504076 -192.876725) (xy 188.5352 -192.922167)
			(xy 188.55922 -192.971732) (xy 188.575601 -193.024319) (xy 188.58398 -193.078756) (xy 188.584586 -193.106294)
			(xy 188.584586 -193.108326) (xy 188.583811 -193.140633) (xy 188.57245 -193.204245) (xy 188.56198 -193.234818)
			(xy 188.56198 -193.235072) (xy 188.558497 -193.246762) (xy 188.56169 -193.270906) (xy 188.568076 -193.2813)
			(xy 188.59373 -193.318384) (xy 188.61532 -193.349372) (xy 188.615828 -193.350134) (xy 188.61786 -193.35242)
			(xy 188.624188 -193.359034) (xy 188.640335 -193.367627) (xy 188.649356 -193.369184) (xy 188.65596 -193.369692)
			(xy 190.2333 -193.369692) (xy 190.243168 -193.369278) (xy 190.261399 -193.361722) (xy 190.275347 -193.34776)
			(xy 190.282887 -193.329522) (xy 190.283338 -193.319654) (xy 190.283338 -192.825116) (xy 190.283918 -192.808428)
			(xy 190.292619 -192.776204) (xy 190.309354 -192.747324) (xy 190.332987 -192.723752) (xy 190.36191 -192.707092)
			(xy 190.394157 -192.698474) (xy 190.410846 -192.697862) (xy 191.909446 -192.697862) (xy 191.926137 -192.69841)
			(xy 191.958383 -192.707048) (xy 191.987302 -192.723725) (xy 192.01093 -192.747308) (xy 192.027661 -192.776196)
			(xy 192.036359 -192.808426) (xy 192.036954 -192.825116) (xy 192.036954 -193.319654) (xy 192.037359 -193.329532)
			(xy 192.044906 -193.347788) (xy 192.058867 -193.361764) (xy 192.077115 -193.36933) (xy 192.086992 -193.369692)
			(xy 195.31965 -193.369692) (xy 195.326254 -193.369184) (xy 195.33527 -193.367613) (xy 195.351414 -193.359023)
			(xy 195.35775 -193.35242) (xy 195.359782 -193.350134) (xy 195.36029 -193.349372) (xy 195.409058 -193.279268)
			(xy 195.41363 -193.269616) (xy 195.41363 -193.235072) (xy 195.410836 -193.227198) (xy 195.401826 -193.199081)
			(xy 195.391863 -193.140887) (xy 195.391024 -193.111374) (xy 195.391024 -193.106294) (xy 195.39163 -193.078756)
			(xy 195.400009 -193.024319) (xy 195.41639 -192.971732) (xy 195.44041 -192.922167) (xy 195.471534 -192.876725)
			(xy 195.50907 -192.836416) (xy 195.552183 -192.802139) (xy 195.599914 -192.774654) (xy 195.651202 -192.754574)
			(xy 195.704906 -192.742344) (xy 195.759832 -192.738237) (xy 195.814758 -192.742344) (xy 195.868462 -192.754574)
			(xy 195.91975 -192.774654) (xy 195.967481 -192.802139) (xy 196.010594 -192.836416) (xy 196.04813 -192.876725)
			(xy 196.079254 -192.922167) (xy 196.103274 -192.971732) (xy 196.119655 -193.024319) (xy 196.128034 -193.078756)
			(xy 196.12864 -193.106294) (xy 196.12864 -193.108326) (xy 196.127865 -193.140633) (xy 196.116506 -193.204246)
			(xy 196.106034 -193.234818) (xy 196.106034 -193.235072) (xy 196.102553 -193.246762) (xy 196.105743 -193.270907)
			(xy 196.11213 -193.2813) (xy 196.137784 -193.318384) (xy 196.159374 -193.349372) (xy 196.159882 -193.350134)
			(xy 196.161914 -193.35242) (xy 196.16824 -193.35904) (xy 196.184385 -193.367647) (xy 196.19341 -193.369184)
			(xy 196.200014 -193.369692) (xy 197.777608 -193.369692) (xy 197.787007 -193.369278) (xy 197.804489 -193.362362)
			(xy 197.818227 -193.349528) (xy 197.826317 -193.332558) (xy 197.827392 -193.32321) (xy 197.827392 -192.825116)
			(xy 197.827887 -192.808393) (xy 197.836539 -192.776087) (xy 197.85326 -192.747121) (xy 197.876908 -192.72347)
			(xy 197.905872 -192.706746) (xy 197.938177 -192.698089) (xy 197.9549 -192.697608) (xy 199.4535 -192.697608)
			(xy 199.470221 -192.698105) (xy 199.502522 -192.70676) (xy 199.531482 -192.723482) (xy 199.555128 -192.74713)
			(xy 199.571846 -192.776093) (xy 199.580498 -192.808395) (xy 199.581008 -192.825116) (xy 199.581008 -193.32321)
			(xy 199.58202 -193.33258) (xy 199.590077 -193.349601) (xy 199.603842 -193.362454) (xy 199.621375 -193.369327)
			(xy 199.630792 -193.369692) (xy 202.864974 -193.369692) (xy 202.866244 -193.371216) (xy 202.913996 -193.371216)
			(xy 202.926244 -193.370491) (xy 202.947989 -193.35921) (xy 202.955652 -193.349626) (xy 202.957938 -193.34607)
			(xy 202.957938 -193.345816) (xy 202.958192 -193.345562) (xy 202.9714 -193.322448) (xy 202.976734 -193.309748)
			(xy 202.978093 -193.303598) (xy 202.978093 -193.291006) (xy 202.976734 -193.284856) (xy 202.97394 -193.273172)
			(xy 202.972416 -193.269616) (xy 202.9714 -193.267838) (xy 202.95989 -193.242746) (xy 202.94361 -193.19)
			(xy 202.935355 -193.135418) (xy 202.934824 -193.107818) (xy 202.934824 -193.107564) (xy 202.93534 -193.079964)
			(xy 202.943567 -193.025381) (xy 202.959837 -192.972634) (xy 202.983787 -192.922902) (xy 203.014882 -192.877294)
			(xy 203.052427 -192.83683) (xy 203.095584 -192.802413) (xy 203.143388 -192.774814) (xy 203.194772 -192.754647)
			(xy 203.248587 -192.742364) (xy 203.303632 -192.738239) (xy 203.358677 -192.742364) (xy 203.412492 -192.754647)
			(xy 203.463876 -192.774814) (xy 203.51168 -192.802413) (xy 203.554837 -192.83683) (xy 203.592382 -192.877294)
			(xy 203.623477 -192.922902) (xy 203.647427 -192.972634) (xy 203.663697 -193.025381) (xy 203.671924 -193.079964)
			(xy 203.67244 -193.107564) (xy 203.67244 -193.108072) (xy 203.671715 -193.140306) (xy 203.660479 -193.203788)
			(xy 203.650088 -193.23431) (xy 203.64958 -193.236088) (xy 203.646532 -193.253868) (xy 203.64676 -193.261139)
			(xy 203.650886 -193.275082) (xy 203.65466 -193.2813) (xy 203.665582 -193.297048) (xy 203.665582 -193.297556)
			(xy 203.70165 -193.349372) (xy 203.705277 -193.354269) (xy 203.71439 -193.362355) (xy 203.719684 -193.365374)
			(xy 203.724682 -193.367862) (xy 203.735451 -193.3708) (xy 203.74102 -193.371216) (xy 205.321408 -193.371216)
			(xy 205.330809 -193.370803) (xy 205.348294 -193.363887) (xy 205.362038 -193.351055) (xy 205.370135 -193.334084)
			(xy 205.371192 -193.324734) (xy 205.371192 -192.825116) (xy 205.371687 -192.808393) (xy 205.380339 -192.776087)
			(xy 205.39706 -192.747121) (xy 205.420708 -192.72347) (xy 205.449672 -192.706746) (xy 205.481977 -192.698089)
			(xy 205.4987 -192.697608) (xy 206.82712 -192.697862) (xy 206.836989 -192.6972) (xy 206.855129 -192.68936)
			(xy 206.868956 -192.675242) (xy 206.876416 -192.656943) (xy 206.876904 -192.647062) (xy 206.876904 -190.557658)
			(xy 206.876815 -190.553714) (xy 206.875537 -190.545931) (xy 206.874364 -190.542164) (xy 206.05115 -188.554614)
			(xy 206.045344 -188.544949) (xy 206.027273 -188.531516) (xy 206.016352 -188.528706) (xy 206.006192 -188.52769)
			(xy 171.80814 -188.52769) (xy 171.798074 -188.528124) (xy 171.779485 -188.535852) (xy 171.772072 -188.542676)
			(xy 171.607988 -188.70676) (xy 171.573084 -188.741012) (xy 171.498723 -188.804537) (xy 171.419606 -188.862032)
			(xy 171.336222 -188.913141) (xy 171.249084 -188.957549) (xy 171.15873 -188.994982) (xy 171.065718 -189.025211)
			(xy 170.97062 -189.048047) (xy 170.874024 -189.06335) (xy 170.776525 -189.071027) (xy 170.727624 -189.071504)
			(xy 163.223956 -189.071504) (xy 163.213889 -189.071935) (xy 163.195297 -189.079661) (xy 163.187888 -189.08649)
			(xy 163.017962 -189.256416) (xy 163.015256 -189.259267) (xy 163.010662 -189.265645) (xy 163.008818 -189.269116)
			(xy 163.006231 -189.274542) (xy 163.0034 -189.286222) (xy 163.00323 -189.29223) (xy 163.00323 -192.218564)
			(xy 165.214315 -192.218564) (xy 165.21825 -192.164793) (xy 165.229973 -192.112169) (xy 165.249233 -192.061812)
			(xy 165.275619 -192.014795) (xy 165.308571 -191.972122) (xy 165.347384 -191.934701) (xy 165.391232 -191.903331)
			(xy 165.43918 -191.878679) (xy 165.490207 -191.861271) (xy 165.543225 -191.851478) (xy 165.597104 -191.849509)
			(xy 165.650695 -191.855406) (xy 165.702856 -191.869042) (xy 165.752476 -191.890129) (xy 165.798497 -191.918215)
			(xy 165.839939 -191.952703) (xy 165.875917 -191.992857) (xy 165.905665 -192.037821) (xy 165.92855 -192.086638)
			(xy 165.944082 -192.138267) (xy 165.951932 -192.191607) (xy 165.952424 -192.218564) (xy 167.002983 -192.218564)
			(xy 167.006918 -192.164793) (xy 167.018641 -192.112169) (xy 167.037901 -192.061812) (xy 167.064287 -192.014795)
			(xy 167.097239 -191.972122) (xy 167.136052 -191.934701) (xy 167.1799 -191.903331) (xy 167.227848 -191.878679)
			(xy 167.278875 -191.861271) (xy 167.331893 -191.851478) (xy 167.385772 -191.849509) (xy 167.439363 -191.855406)
			(xy 167.491524 -191.869042) (xy 167.541144 -191.890129) (xy 167.587165 -191.918215) (xy 167.628607 -191.952703)
			(xy 167.664585 -191.992857) (xy 167.694333 -192.037821) (xy 167.717218 -192.086638) (xy 167.73275 -192.138267)
			(xy 167.7406 -192.191607) (xy 167.741092 -192.218564) (xy 172.758369 -192.218564) (xy 172.762304 -192.164793)
			(xy 172.774027 -192.112169) (xy 172.793287 -192.061812) (xy 172.819673 -192.014795) (xy 172.852625 -191.972122)
			(xy 172.891438 -191.934701) (xy 172.935286 -191.903331) (xy 172.983234 -191.878679) (xy 173.034261 -191.861271)
			(xy 173.087279 -191.851478) (xy 173.141158 -191.849509) (xy 173.194749 -191.855406) (xy 173.24691 -191.869042)
			(xy 173.29653 -191.890129) (xy 173.342551 -191.918215) (xy 173.383993 -191.952703) (xy 173.419971 -191.992857)
			(xy 173.449719 -192.037821) (xy 173.472604 -192.086638) (xy 173.488136 -192.138267) (xy 173.495986 -192.191607)
			(xy 173.496478 -192.218564) (xy 174.547037 -192.218564) (xy 174.550972 -192.164793) (xy 174.562695 -192.112169)
			(xy 174.581955 -192.061812) (xy 174.608341 -192.014795) (xy 174.641293 -191.972122) (xy 174.680106 -191.934701)
			(xy 174.723954 -191.903331) (xy 174.771902 -191.878679) (xy 174.822929 -191.861271) (xy 174.875947 -191.851478)
			(xy 174.929826 -191.849509) (xy 174.983417 -191.855406) (xy 175.035578 -191.869042) (xy 175.085198 -191.890129)
			(xy 175.131219 -191.918215) (xy 175.172661 -191.952703) (xy 175.208639 -191.992857) (xy 175.238387 -192.037821)
			(xy 175.261272 -192.086638) (xy 175.276804 -192.138267) (xy 175.284654 -192.191607) (xy 175.285146 -192.218564)
			(xy 180.302423 -192.218564) (xy 180.306358 -192.164793) (xy 180.318081 -192.112169) (xy 180.337341 -192.061812)
			(xy 180.363727 -192.014795) (xy 180.396679 -191.972122) (xy 180.435492 -191.934701) (xy 180.47934 -191.903331)
			(xy 180.527288 -191.878679) (xy 180.578315 -191.861271) (xy 180.631333 -191.851478) (xy 180.685212 -191.849509)
			(xy 180.738803 -191.855406) (xy 180.790964 -191.869042) (xy 180.840584 -191.890129) (xy 180.886605 -191.918215)
			(xy 180.928047 -191.952703) (xy 180.964025 -191.992857) (xy 180.993773 -192.037821) (xy 181.016658 -192.086638)
			(xy 181.03219 -192.138267) (xy 181.04004 -192.191607) (xy 181.040532 -192.218564) (xy 182.091091 -192.218564)
			(xy 182.095026 -192.164793) (xy 182.106749 -192.112169) (xy 182.126009 -192.061812) (xy 182.152395 -192.014795)
			(xy 182.185347 -191.972122) (xy 182.22416 -191.934701) (xy 182.268008 -191.903331) (xy 182.315956 -191.878679)
			(xy 182.366983 -191.861271) (xy 182.420001 -191.851478) (xy 182.47388 -191.849509) (xy 182.527471 -191.855406)
			(xy 182.579632 -191.869042) (xy 182.629252 -191.890129) (xy 182.675273 -191.918215) (xy 182.716715 -191.952703)
			(xy 182.752693 -191.992857) (xy 182.782441 -192.037821) (xy 182.805326 -192.086638) (xy 182.820858 -192.138267)
			(xy 182.828708 -192.191607) (xy 182.8292 -192.218564) (xy 187.846477 -192.218564) (xy 187.850412 -192.164793)
			(xy 187.862135 -192.112169) (xy 187.881395 -192.061812) (xy 187.907781 -192.014795) (xy 187.940733 -191.972122)
			(xy 187.979546 -191.934701) (xy 188.023394 -191.903331) (xy 188.071342 -191.878679) (xy 188.122369 -191.861271)
			(xy 188.175387 -191.851478) (xy 188.229266 -191.849509) (xy 188.282857 -191.855406) (xy 188.335018 -191.869042)
			(xy 188.384638 -191.890129) (xy 188.430659 -191.918215) (xy 188.472101 -191.952703) (xy 188.508079 -191.992857)
			(xy 188.537827 -192.037821) (xy 188.560712 -192.086638) (xy 188.576244 -192.138267) (xy 188.584094 -192.191607)
			(xy 188.584586 -192.218564) (xy 189.635145 -192.218564) (xy 189.63908 -192.164793) (xy 189.650803 -192.112169)
			(xy 189.670063 -192.061812) (xy 189.696449 -192.014795) (xy 189.729401 -191.972122) (xy 189.768214 -191.934701)
			(xy 189.812062 -191.903331) (xy 189.86001 -191.878679) (xy 189.911037 -191.861271) (xy 189.964055 -191.851478)
			(xy 190.017934 -191.849509) (xy 190.071525 -191.855406) (xy 190.123686 -191.869042) (xy 190.173306 -191.890129)
			(xy 190.219327 -191.918215) (xy 190.260769 -191.952703) (xy 190.296747 -191.992857) (xy 190.326495 -192.037821)
			(xy 190.34938 -192.086638) (xy 190.364912 -192.138267) (xy 190.372762 -192.191607) (xy 190.373254 -192.218564)
			(xy 195.390531 -192.218564) (xy 195.394466 -192.164793) (xy 195.406189 -192.112169) (xy 195.425449 -192.061812)
			(xy 195.451835 -192.014795) (xy 195.484787 -191.972122) (xy 195.5236 -191.934701) (xy 195.567448 -191.903331)
			(xy 195.615396 -191.878679) (xy 195.666423 -191.861271) (xy 195.719441 -191.851478) (xy 195.77332 -191.849509)
			(xy 195.826911 -191.855406) (xy 195.879072 -191.869042) (xy 195.928692 -191.890129) (xy 195.974713 -191.918215)
			(xy 196.016155 -191.952703) (xy 196.052133 -191.992857) (xy 196.081881 -192.037821) (xy 196.104766 -192.086638)
			(xy 196.120298 -192.138267) (xy 196.128148 -192.191607) (xy 196.12864 -192.218564) (xy 197.217299 -192.218564)
			(xy 197.221234 -192.164793) (xy 197.232957 -192.112169) (xy 197.252217 -192.061812) (xy 197.278603 -192.014795)
			(xy 197.311555 -191.972122) (xy 197.350368 -191.934701) (xy 197.394216 -191.903331) (xy 197.442164 -191.878679)
			(xy 197.493191 -191.861271) (xy 197.546209 -191.851478) (xy 197.600088 -191.849509) (xy 197.653679 -191.855406)
			(xy 197.70584 -191.869042) (xy 197.75546 -191.890129) (xy 197.801481 -191.918215) (xy 197.842923 -191.952703)
			(xy 197.878901 -191.992857) (xy 197.908649 -192.037821) (xy 197.931534 -192.086638) (xy 197.947066 -192.138267)
			(xy 197.954916 -192.191607) (xy 197.955408 -192.218564) (xy 202.934331 -192.218564) (xy 202.938266 -192.164793)
			(xy 202.949989 -192.112169) (xy 202.969249 -192.061812) (xy 202.995635 -192.014795) (xy 203.028587 -191.972122)
			(xy 203.0674 -191.934701) (xy 203.111248 -191.903331) (xy 203.159196 -191.878679) (xy 203.210223 -191.861271)
			(xy 203.263241 -191.851478) (xy 203.31712 -191.849509) (xy 203.370711 -191.855406) (xy 203.422872 -191.869042)
			(xy 203.472492 -191.890129) (xy 203.518513 -191.918215) (xy 203.559955 -191.952703) (xy 203.595933 -191.992857)
			(xy 203.625681 -192.037821) (xy 203.648566 -192.086638) (xy 203.664098 -192.138267) (xy 203.671948 -192.191607)
			(xy 203.67244 -192.218564) (xy 204.722999 -192.218564) (xy 204.726934 -192.164793) (xy 204.738657 -192.112169)
			(xy 204.757917 -192.061812) (xy 204.784303 -192.014795) (xy 204.817255 -191.972122) (xy 204.856068 -191.934701)
			(xy 204.899916 -191.903331) (xy 204.947864 -191.878679) (xy 204.998891 -191.861271) (xy 205.051909 -191.851478)
			(xy 205.105788 -191.849509) (xy 205.159379 -191.855406) (xy 205.21154 -191.869042) (xy 205.26116 -191.890129)
			(xy 205.307181 -191.918215) (xy 205.348623 -191.952703) (xy 205.384601 -191.992857) (xy 205.414349 -192.037821)
			(xy 205.437234 -192.086638) (xy 205.452766 -192.138267) (xy 205.460616 -192.191607) (xy 205.461108 -192.218564)
			(xy 205.460616 -192.245521) (xy 205.452766 -192.298861) (xy 205.437234 -192.35049) (xy 205.414349 -192.399307)
			(xy 205.384601 -192.444271) (xy 205.348623 -192.484425) (xy 205.307181 -192.518913) (xy 205.26116 -192.546999)
			(xy 205.21154 -192.568086) (xy 205.159379 -192.581722) (xy 205.105788 -192.587619) (xy 205.051909 -192.58565)
			(xy 204.998891 -192.575857) (xy 204.947864 -192.558449) (xy 204.899916 -192.533797) (xy 204.856068 -192.502427)
			(xy 204.817255 -192.465006) (xy 204.784303 -192.422333) (xy 204.757917 -192.375316) (xy 204.738657 -192.324959)
			(xy 204.726934 -192.272335) (xy 204.722999 -192.218564) (xy 203.67244 -192.218564) (xy 203.671948 -192.245521)
			(xy 203.664098 -192.298861) (xy 203.648566 -192.35049) (xy 203.625681 -192.399307) (xy 203.595933 -192.444271)
			(xy 203.559955 -192.484425) (xy 203.518513 -192.518913) (xy 203.472492 -192.546999) (xy 203.422872 -192.568086)
			(xy 203.370711 -192.581722) (xy 203.31712 -192.587619) (xy 203.263241 -192.58565) (xy 203.210223 -192.575857)
			(xy 203.159196 -192.558449) (xy 203.111248 -192.533797) (xy 203.0674 -192.502427) (xy 203.028587 -192.465006)
			(xy 202.995635 -192.422333) (xy 202.969249 -192.375316) (xy 202.949989 -192.324959) (xy 202.938266 -192.272335)
			(xy 202.934331 -192.218564) (xy 197.955408 -192.218564) (xy 197.954916 -192.245521) (xy 197.947066 -192.298861)
			(xy 197.931534 -192.35049) (xy 197.908649 -192.399307) (xy 197.878901 -192.444271) (xy 197.842923 -192.484425)
			(xy 197.801481 -192.518913) (xy 197.75546 -192.546999) (xy 197.70584 -192.568086) (xy 197.653679 -192.581722)
			(xy 197.600088 -192.587619) (xy 197.546209 -192.58565) (xy 197.493191 -192.575857) (xy 197.442164 -192.558449)
			(xy 197.394216 -192.533797) (xy 197.350368 -192.502427) (xy 197.311555 -192.465006) (xy 197.278603 -192.422333)
			(xy 197.252217 -192.375316) (xy 197.232957 -192.324959) (xy 197.221234 -192.272335) (xy 197.217299 -192.218564)
			(xy 196.12864 -192.218564) (xy 196.128148 -192.245521) (xy 196.120298 -192.298861) (xy 196.104766 -192.35049)
			(xy 196.081881 -192.399307) (xy 196.052133 -192.444271) (xy 196.016155 -192.484425) (xy 195.974713 -192.518913)
			(xy 195.928692 -192.546999) (xy 195.879072 -192.568086) (xy 195.826911 -192.581722) (xy 195.77332 -192.587619)
			(xy 195.719441 -192.58565) (xy 195.666423 -192.575857) (xy 195.615396 -192.558449) (xy 195.567448 -192.533797)
			(xy 195.5236 -192.502427) (xy 195.484787 -192.465006) (xy 195.451835 -192.422333) (xy 195.425449 -192.375316)
			(xy 195.406189 -192.324959) (xy 195.394466 -192.272335) (xy 195.390531 -192.218564) (xy 190.373254 -192.218564)
			(xy 190.372762 -192.245521) (xy 190.364912 -192.298861) (xy 190.34938 -192.35049) (xy 190.326495 -192.399307)
			(xy 190.296747 -192.444271) (xy 190.260769 -192.484425) (xy 190.219327 -192.518913) (xy 190.173306 -192.546999)
			(xy 190.123686 -192.568086) (xy 190.071525 -192.581722) (xy 190.017934 -192.587619) (xy 189.964055 -192.58565)
			(xy 189.911037 -192.575857) (xy 189.86001 -192.558449) (xy 189.812062 -192.533797) (xy 189.768214 -192.502427)
			(xy 189.729401 -192.465006) (xy 189.696449 -192.422333) (xy 189.670063 -192.375316) (xy 189.650803 -192.324959)
			(xy 189.63908 -192.272335) (xy 189.635145 -192.218564) (xy 188.584586 -192.218564) (xy 188.584094 -192.245521)
			(xy 188.576244 -192.298861) (xy 188.560712 -192.35049) (xy 188.537827 -192.399307) (xy 188.508079 -192.444271)
			(xy 188.472101 -192.484425) (xy 188.430659 -192.518913) (xy 188.384638 -192.546999) (xy 188.335018 -192.568086)
			(xy 188.282857 -192.581722) (xy 188.229266 -192.587619) (xy 188.175387 -192.58565) (xy 188.122369 -192.575857)
			(xy 188.071342 -192.558449) (xy 188.023394 -192.533797) (xy 187.979546 -192.502427) (xy 187.940733 -192.465006)
			(xy 187.907781 -192.422333) (xy 187.881395 -192.375316) (xy 187.862135 -192.324959) (xy 187.850412 -192.272335)
			(xy 187.846477 -192.218564) (xy 182.8292 -192.218564) (xy 182.828708 -192.245521) (xy 182.820858 -192.298861)
			(xy 182.805326 -192.35049) (xy 182.782441 -192.399307) (xy 182.752693 -192.444271) (xy 182.716715 -192.484425)
			(xy 182.675273 -192.518913) (xy 182.629252 -192.546999) (xy 182.579632 -192.568086) (xy 182.527471 -192.581722)
			(xy 182.47388 -192.587619) (xy 182.420001 -192.58565) (xy 182.366983 -192.575857) (xy 182.315956 -192.558449)
			(xy 182.268008 -192.533797) (xy 182.22416 -192.502427) (xy 182.185347 -192.465006) (xy 182.152395 -192.422333)
			(xy 182.126009 -192.375316) (xy 182.106749 -192.324959) (xy 182.095026 -192.272335) (xy 182.091091 -192.218564)
			(xy 181.040532 -192.218564) (xy 181.04004 -192.245521) (xy 181.03219 -192.298861) (xy 181.016658 -192.35049)
			(xy 180.993773 -192.399307) (xy 180.964025 -192.444271) (xy 180.928047 -192.484425) (xy 180.886605 -192.518913)
			(xy 180.840584 -192.546999) (xy 180.790964 -192.568086) (xy 180.738803 -192.581722) (xy 180.685212 -192.587619)
			(xy 180.631333 -192.58565) (xy 180.578315 -192.575857) (xy 180.527288 -192.558449) (xy 180.47934 -192.533797)
			(xy 180.435492 -192.502427) (xy 180.396679 -192.465006) (xy 180.363727 -192.422333) (xy 180.337341 -192.375316)
			(xy 180.318081 -192.324959) (xy 180.306358 -192.272335) (xy 180.302423 -192.218564) (xy 175.285146 -192.218564)
			(xy 175.284654 -192.245521) (xy 175.276804 -192.298861) (xy 175.261272 -192.35049) (xy 175.238387 -192.399307)
			(xy 175.208639 -192.444271) (xy 175.172661 -192.484425) (xy 175.131219 -192.518913) (xy 175.085198 -192.546999)
			(xy 175.035578 -192.568086) (xy 174.983417 -192.581722) (xy 174.929826 -192.587619) (xy 174.875947 -192.58565)
			(xy 174.822929 -192.575857) (xy 174.771902 -192.558449) (xy 174.723954 -192.533797) (xy 174.680106 -192.502427)
			(xy 174.641293 -192.465006) (xy 174.608341 -192.422333) (xy 174.581955 -192.375316) (xy 174.562695 -192.324959)
			(xy 174.550972 -192.272335) (xy 174.547037 -192.218564) (xy 173.496478 -192.218564) (xy 173.495986 -192.245521)
			(xy 173.488136 -192.298861) (xy 173.472604 -192.35049) (xy 173.449719 -192.399307) (xy 173.419971 -192.444271)
			(xy 173.383993 -192.484425) (xy 173.342551 -192.518913) (xy 173.29653 -192.546999) (xy 173.24691 -192.568086)
			(xy 173.194749 -192.581722) (xy 173.141158 -192.587619) (xy 173.087279 -192.58565) (xy 173.034261 -192.575857)
			(xy 172.983234 -192.558449) (xy 172.935286 -192.533797) (xy 172.891438 -192.502427) (xy 172.852625 -192.465006)
			(xy 172.819673 -192.422333) (xy 172.793287 -192.375316) (xy 172.774027 -192.324959) (xy 172.762304 -192.272335)
			(xy 172.758369 -192.218564) (xy 167.741092 -192.218564) (xy 167.7406 -192.245521) (xy 167.73275 -192.298861)
			(xy 167.717218 -192.35049) (xy 167.694333 -192.399307) (xy 167.664585 -192.444271) (xy 167.628607 -192.484425)
			(xy 167.587165 -192.518913) (xy 167.541144 -192.546999) (xy 167.491524 -192.568086) (xy 167.439363 -192.581722)
			(xy 167.385772 -192.587619) (xy 167.331893 -192.58565) (xy 167.278875 -192.575857) (xy 167.227848 -192.558449)
			(xy 167.1799 -192.533797) (xy 167.136052 -192.502427) (xy 167.097239 -192.465006) (xy 167.064287 -192.422333)
			(xy 167.037901 -192.375316) (xy 167.018641 -192.324959) (xy 167.006918 -192.272335) (xy 167.002983 -192.218564)
			(xy 165.952424 -192.218564) (xy 165.951932 -192.245521) (xy 165.944082 -192.298861) (xy 165.92855 -192.35049)
			(xy 165.905665 -192.399307) (xy 165.875917 -192.444271) (xy 165.839939 -192.484425) (xy 165.798497 -192.518913)
			(xy 165.752476 -192.546999) (xy 165.702856 -192.568086) (xy 165.650695 -192.581722) (xy 165.597104 -192.587619)
			(xy 165.543225 -192.58565) (xy 165.490207 -192.575857) (xy 165.43918 -192.558449) (xy 165.391232 -192.533797)
			(xy 165.347384 -192.502427) (xy 165.308571 -192.465006) (xy 165.275619 -192.422333) (xy 165.249233 -192.375316)
			(xy 165.229973 -192.324959) (xy 165.21825 -192.272335) (xy 165.214315 -192.218564) (xy 163.00323 -192.218564)
			(xy 163.00323 -192.734946) (xy 163.00323 -192.737232) (xy 163.004177 -192.747581) (xy 163.013221 -192.766268)
			(xy 163.028921 -192.779851) (xy 163.048714 -192.786114) (xy 163.06937 -192.784034) (xy 163.078668 -192.779396)
			(xy 163.08197 -192.777364) (xy 163.104676 -192.762973) (xy 163.153371 -192.740204) (xy 163.204856 -192.724743)
			(xy 163.258038 -192.716917) (xy 163.284916 -192.716404) (xy 163.311259 -192.716875) (xy 163.363408 -192.724375)
			(xy 163.41396 -192.739221) (xy 163.461884 -192.761109) (xy 163.506205 -192.789595) (xy 163.546021 -192.824099)
			(xy 163.580522 -192.863917) (xy 163.609004 -192.908241) (xy 163.630889 -192.956167) (xy 163.645731 -193.006719)
			(xy 163.653227 -193.058869) (xy 163.653724 -193.085212) (xy 163.653292 -193.109803) (xy 163.646711 -193.158543)
			(xy 163.633722 -193.205979) (xy 163.614553 -193.251272) (xy 163.602416 -193.272664) (xy 163.597501 -193.281978)
			(xy 163.594919 -193.302857) (xy 163.600908 -193.323024) (xy 163.614468 -193.339109) (xy 163.633332 -193.348423)
			(xy 163.643818 -193.349372) (xy 165.099746 -193.349372) (xy 165.106719 -193.349635) (xy 165.120126 -193.353492)
			(xy 165.126162 -193.356992) (xy 165.126416 -193.357246) (xy 165.132766 -193.361056) (xy 165.139116 -193.362834)
			(xy 165.142712 -193.363873) (xy 165.150107 -193.365026) (xy 165.153848 -193.36512) (xy 165.190678 -193.36512)
			(xy 165.19779 -193.364612) (xy 165.204961 -193.363371) (xy 165.218244 -193.357442) (xy 165.223952 -193.352928)
			(xy 165.229286 -193.347594) (xy 165.235128 -193.339466) (xy 165.248082 -193.316352) (xy 165.248336 -193.316098)
			(xy 165.253416 -193.306954) (xy 165.25621 -193.288412) (xy 165.255194 -193.284348) (xy 165.251384 -193.267838)
			(xy 165.249352 -193.263266) (xy 165.238446 -193.238773) (xy 165.223048 -193.187418) (xy 165.21527 -193.134371)
			(xy 165.214808 -193.107564) (xy 165.215324 -193.079964) (xy 165.223551 -193.025381) (xy 165.239821 -192.972634)
			(xy 165.263771 -192.922902) (xy 165.294866 -192.877294) (xy 165.332411 -192.83683) (xy 165.375568 -192.802413)
			(xy 165.423372 -192.774814) (xy 165.474756 -192.754647) (xy 165.528571 -192.742364) (xy 165.583616 -192.738239)
			(xy 165.638661 -192.742364) (xy 165.692476 -192.754647) (xy 165.74386 -192.774814) (xy 165.791664 -192.802413)
			(xy 165.834821 -192.83683) (xy 165.872366 -192.877294) (xy 165.903461 -192.922902) (xy 165.927411 -192.972634)
			(xy 165.943681 -193.025381) (xy 165.951908 -193.079964) (xy 165.952424 -193.107564) (xy 165.952424 -193.109088)
			(xy 165.951644 -193.140258) (xy 165.94092 -193.201674) (xy 165.931088 -193.231262) (xy 165.930326 -193.233548)
			(xy 165.927792 -193.243608) (xy 165.930162 -193.264195) (xy 165.934898 -193.273426) (xy 165.937438 -193.27749)
			(xy 165.984174 -193.34353) (xy 165.991746 -193.353122) (xy 166.013377 -193.364406) (xy 166.025576 -193.36512)
			(xy 167.601392 -193.36512) (xy 167.610795 -193.36471) (xy 167.628286 -193.357797) (xy 167.642035 -193.344965)
			(xy 167.650137 -193.327992) (xy 167.651176 -193.318638) (xy 167.651176 -192.825116) (xy 167.65172 -192.808399)
			(xy 167.660369 -192.776103) (xy 167.677082 -192.747146) (xy 167.700721 -192.723502) (xy 167.729673 -192.706781)
			(xy 167.761967 -192.698124) (xy 167.778684 -192.697608) (xy 169.277284 -192.697608) (xy 169.294006 -192.698103)
			(xy 169.326311 -192.706756) (xy 169.355275 -192.723477) (xy 169.378923 -192.747125) (xy 169.395644 -192.776089)
			(xy 169.404297 -192.808394) (xy 169.404792 -192.825116) (xy 169.404792 -193.318638) (xy 169.405808 -193.328006)
			(xy 169.41387 -193.345021) (xy 169.427632 -193.357869) (xy 169.445161 -193.364743) (xy 169.454576 -193.36512)
			(xy 170.670474 -193.36512) (xy 170.675429 -193.365236) (xy 170.685153 -193.367147) (xy 170.689778 -193.36893)
			(xy 170.70705 -193.376042) (xy 170.711679 -193.377811) (xy 170.7214 -193.379722) (xy 170.726354 -193.379852)
			(xy 170.73372 -193.379852)
		)
		(stroke
			(width 0)
			(type solid)
		)
		(fill yes)
		(layer "F.Cu")
		(net "P12V_MEM_CPU1")
	)
	(gr_poly
		(pts
			(xy 411.212284 -193.373248) (xy 412.367984 -193.373248) (xy 412.39821 -193.374264) (xy 413.083502 -193.374264)
			(xy 413.095831 -193.373676) (xy 413.117666 -193.362228) (xy 413.125158 -193.35242) (xy 413.179768 -193.273426)
			(xy 413.182816 -193.248788) (xy 413.178498 -193.23685) (xy 413.167535 -193.20559) (xy 413.155647 -193.140428)
			(xy 413.154876 -193.10731) (xy 413.155392 -193.07971) (xy 413.163619 -193.025127) (xy 413.179889 -192.97238)
			(xy 413.203839 -192.922648) (xy 413.234934 -192.87704) (xy 413.272479 -192.836576) (xy 413.315636 -192.802159)
			(xy 413.36344 -192.77456) (xy 413.414824 -192.754393) (xy 413.468639 -192.74211) (xy 413.523684 -192.737985)
			(xy 413.578729 -192.74211) (xy 413.632544 -192.754393) (xy 413.683928 -192.77456) (xy 413.731732 -192.802159)
			(xy 413.774889 -192.836576) (xy 413.812434 -192.87704) (xy 413.843529 -192.922648) (xy 413.867479 -192.97238)
			(xy 413.883749 -193.025127) (xy 413.891976 -193.07971) (xy 413.892492 -193.10731) (xy 413.891771 -193.140433)
			(xy 413.879882 -193.205603) (xy 413.86887 -193.23685) (xy 413.864552 -193.248788) (xy 413.8676 -193.273426)
			(xy 413.92221 -193.35242) (xy 413.929823 -193.362089) (xy 413.951583 -193.373505) (xy 413.963866 -193.374264)
			(xy 415.540444 -193.374264) (xy 415.550443 -193.373768) (xy 415.568914 -193.366099) (xy 415.583044 -193.351947)
			(xy 415.590684 -193.333464) (xy 415.591244 -193.323464) (xy 415.591244 -192.825116) (xy 415.591787 -192.808397)
			(xy 415.600436 -192.776098) (xy 415.617148 -192.747137) (xy 415.640786 -192.723487) (xy 415.669739 -192.70676)
			(xy 415.702034 -192.698095) (xy 415.718752 -192.697608) (xy 417.217352 -192.697608) (xy 417.234077 -192.698099)
			(xy 417.266389 -192.706747) (xy 417.29536 -192.723465) (xy 417.319015 -192.747114) (xy 417.335741 -192.776082)
			(xy 417.344397 -192.808391) (xy 417.34486 -192.825116) (xy 417.34486 -193.323464) (xy 417.345341 -193.333479)
			(xy 417.352993 -193.35199) (xy 417.367146 -193.366164) (xy 417.385645 -193.373844) (xy 417.39566 -193.374264)
			(xy 418.726112 -193.374264) (xy 418.756338 -193.373248) (xy 419.912038 -193.373248) (xy 419.942264 -193.374264)
			(xy 420.627556 -193.374264) (xy 420.639878 -193.373665) (xy 420.661694 -193.362204) (xy 420.669212 -193.35242)
			(xy 420.723822 -193.273426) (xy 420.72687 -193.248788) (xy 420.722552 -193.23685) (xy 420.711588 -193.20559)
			(xy 420.699698 -193.140428) (xy 420.69893 -193.10731) (xy 420.699446 -193.07971) (xy 420.707673 -193.025127)
			(xy 420.723943 -192.97238) (xy 420.747893 -192.922648) (xy 420.778988 -192.87704) (xy 420.816533 -192.836576)
			(xy 420.85969 -192.802159) (xy 420.907494 -192.77456) (xy 420.958878 -192.754393) (xy 421.012693 -192.74211)
			(xy 421.067738 -192.737985) (xy 421.122783 -192.74211) (xy 421.176598 -192.754393) (xy 421.227982 -192.77456)
			(xy 421.275786 -192.802159) (xy 421.318943 -192.836576) (xy 421.356488 -192.87704) (xy 421.387583 -192.922648)
			(xy 421.411533 -192.97238) (xy 421.427803 -193.025127) (xy 421.43603 -193.07971) (xy 421.436546 -193.10731)
			(xy 421.435824 -193.140432) (xy 421.423934 -193.205602) (xy 421.412924 -193.23685) (xy 421.408606 -193.248788)
			(xy 421.411654 -193.273426) (xy 421.466264 -193.35242) (xy 421.473881 -193.36208) (xy 421.495642 -193.373473)
			(xy 421.50792 -193.374264) (xy 423.084752 -193.374264) (xy 423.094777 -193.373852) (xy 423.113304 -193.366189)
			(xy 423.127483 -193.352014) (xy 423.13515 -193.333489) (xy 423.135552 -193.323464) (xy 423.135552 -192.824608)
			(xy 423.136131 -192.807952) (xy 423.144816 -192.77579) (xy 423.161517 -192.746964) (xy 423.185102 -192.723435)
			(xy 423.213966 -192.706801) (xy 423.246149 -192.698192) (xy 423.262806 -192.697608) (xy 424.761406 -192.697608)
			(xy 424.778068 -192.69815) (xy 424.810259 -192.706764) (xy 424.83913 -192.723405) (xy 424.86272 -192.746942)
			(xy 424.879426 -192.775776) (xy 424.888112 -192.807947) (xy 424.88866 -192.824608) (xy 424.88866 -193.323464)
			(xy 424.889141 -193.333479) (xy 424.896793 -193.35199) (xy 424.910946 -193.366164) (xy 424.929445 -193.373844)
			(xy 424.93946 -193.374264) (xy 426.270166 -193.374264) (xy 426.300392 -193.373248) (xy 427.456092 -193.373248)
			(xy 427.486318 -193.374264) (xy 428.17161 -193.374264) (xy 428.183938 -193.373675) (xy 428.20577 -193.362225)
			(xy 428.213266 -193.35242) (xy 428.267876 -193.273426) (xy 428.270924 -193.248788) (xy 428.266606 -193.23685)
			(xy 428.255643 -193.20559) (xy 428.243755 -193.140428) (xy 428.242984 -193.10731) (xy 428.2435 -193.07971)
			(xy 428.251727 -193.025127) (xy 428.267997 -192.97238) (xy 428.291947 -192.922648) (xy 428.323042 -192.87704)
			(xy 428.360587 -192.836576) (xy 428.403744 -192.802159) (xy 428.451548 -192.77456) (xy 428.502932 -192.754393)
			(xy 428.556747 -192.74211) (xy 428.611792 -192.737985) (xy 428.666837 -192.74211) (xy 428.720652 -192.754393)
			(xy 428.772036 -192.77456) (xy 428.81984 -192.802159) (xy 428.862997 -192.836576) (xy 428.900542 -192.87704)
			(xy 428.931637 -192.922648) (xy 428.955587 -192.97238) (xy 428.971857 -193.025127) (xy 428.980084 -193.07971)
			(xy 428.9806 -193.10731) (xy 428.979879 -193.140433) (xy 428.96799 -193.205603) (xy 428.956978 -193.23685)
			(xy 428.95266 -193.248788) (xy 428.955708 -193.273426) (xy 429.010318 -193.35242) (xy 429.017932 -193.362088)
			(xy 429.039692 -193.3735) (xy 429.051974 -193.374264) (xy 430.628552 -193.374264) (xy 430.638577 -193.373852)
			(xy 430.657104 -193.366189) (xy 430.671283 -193.352014) (xy 430.67895 -193.333489) (xy 430.679352 -193.323464)
			(xy 430.679352 -192.825116) (xy 430.679895 -192.808398) (xy 430.688544 -192.776099) (xy 430.705257 -192.747139)
			(xy 430.728895 -192.723491) (xy 430.757847 -192.706765) (xy 430.790142 -192.698102) (xy 430.80686 -192.697608)
			(xy 432.30546 -192.697608) (xy 432.322184 -192.6981) (xy 432.354494 -192.706749) (xy 432.383464 -192.723468)
			(xy 432.407117 -192.747117) (xy 432.423842 -192.776083) (xy 432.432497 -192.808392) (xy 432.432968 -192.825116)
			(xy 432.432968 -193.323464) (xy 432.433381 -193.333492) (xy 432.441043 -193.352027) (xy 432.455216 -193.366219)
			(xy 432.47374 -193.373906) (xy 432.483768 -193.374264) (xy 433.81422 -193.374264) (xy 433.844446 -193.373248)
			(xy 435.000146 -193.373248) (xy 435.030372 -193.374264) (xy 435.715664 -193.374264) (xy 435.727985 -193.373663)
			(xy 435.749798 -193.3622) (xy 435.75732 -193.35242) (xy 435.81193 -193.273426) (xy 435.814978 -193.248788)
			(xy 435.81066 -193.23685) (xy 435.799696 -193.20559) (xy 435.787806 -193.140428) (xy 435.787038 -193.10731)
			(xy 435.787554 -193.07971) (xy 435.795781 -193.025127) (xy 435.812051 -192.97238) (xy 435.836001 -192.922648)
			(xy 435.867096 -192.87704) (xy 435.904641 -192.836576) (xy 435.947798 -192.802159) (xy 435.995602 -192.77456)
			(xy 436.046986 -192.754393) (xy 436.100801 -192.74211) (xy 436.155846 -192.737985) (xy 436.210891 -192.74211)
			(xy 436.264706 -192.754393) (xy 436.31609 -192.77456) (xy 436.363894 -192.802159) (xy 436.407051 -192.836576)
			(xy 436.444596 -192.87704) (xy 436.475691 -192.922648) (xy 436.499641 -192.97238) (xy 436.515911 -193.025127)
			(xy 436.524138 -193.07971) (xy 436.524654 -193.10731) (xy 436.523932 -193.140432) (xy 436.512042 -193.205602)
			(xy 436.501032 -193.23685) (xy 436.496714 -193.248788) (xy 436.499762 -193.273426) (xy 436.554372 -193.35242)
			(xy 436.56199 -193.362079) (xy 436.58375 -193.373468) (xy 436.596028 -193.374264) (xy 438.17286 -193.374264)
			(xy 438.182884 -193.373851) (xy 438.201408 -193.366187) (xy 438.215584 -193.352012) (xy 438.22325 -193.333488)
			(xy 438.22366 -193.323464) (xy 438.22366 -192.824608) (xy 438.224239 -192.807952) (xy 438.232924 -192.775791)
			(xy 438.249626 -192.746966) (xy 438.27321 -192.723439) (xy 438.302075 -192.706806) (xy 438.334257 -192.698199)
			(xy 438.350914 -192.697608) (xy 439.849514 -192.697608) (xy 439.866175 -192.698151) (xy 439.898365 -192.706766)
			(xy 439.927234 -192.723408) (xy 439.950822 -192.746944) (xy 439.967527 -192.775777) (xy 439.976212 -192.807948)
			(xy 439.976768 -192.824608) (xy 439.976768 -193.323464) (xy 439.977181 -193.333492) (xy 439.984843 -193.352027)
			(xy 439.999016 -193.366219) (xy 440.01754 -193.373906) (xy 440.027568 -193.374264) (xy 441.358274 -193.374264)
			(xy 441.3885 -193.373248) (xy 442.5442 -193.373248) (xy 442.574426 -193.374264) (xy 443.259718 -193.374264)
			(xy 443.272045 -193.373673) (xy 443.293874 -193.362221) (xy 443.301374 -193.35242) (xy 443.355984 -193.273426)
			(xy 443.359032 -193.248788) (xy 443.354714 -193.23685) (xy 443.343751 -193.20559) (xy 443.331862 -193.140428)
			(xy 443.331092 -193.10731) (xy 443.331608 -193.07971) (xy 443.339835 -193.025127) (xy 443.356105 -192.97238)
			(xy 443.380055 -192.922648) (xy 443.41115 -192.87704) (xy 443.448695 -192.836576) (xy 443.491852 -192.802159)
			(xy 443.539656 -192.77456) (xy 443.59104 -192.754393) (xy 443.644855 -192.74211) (xy 443.6999 -192.737985)
			(xy 443.754945 -192.74211) (xy 443.80876 -192.754393) (xy 443.860144 -192.77456) (xy 443.907948 -192.802159)
			(xy 443.951105 -192.836576) (xy 443.98865 -192.87704) (xy 444.019745 -192.922648) (xy 444.043695 -192.97238)
			(xy 444.059965 -193.025127) (xy 444.068192 -193.07971) (xy 444.068708 -193.10731) (xy 444.067987 -193.140433)
			(xy 444.056098 -193.205603) (xy 444.045086 -193.23685) (xy 444.040768 -193.248788) (xy 444.043816 -193.273426)
			(xy 444.098426 -193.35242) (xy 444.106041 -193.362086) (xy 444.127801 -193.373495) (xy 444.140082 -193.374264)
			(xy 445.71666 -193.374264) (xy 445.726684 -193.373851) (xy 445.745208 -193.366187) (xy 445.759384 -193.352012)
			(xy 445.76705 -193.333488) (xy 445.76746 -193.323464) (xy 445.76746 -192.825116) (xy 445.768003 -192.808398)
			(xy 445.776652 -192.7761) (xy 445.793365 -192.747142) (xy 445.817003 -192.723494) (xy 445.845956 -192.706771)
			(xy 445.87825 -192.698109) (xy 445.894968 -192.697608) (xy 447.393568 -192.697608) (xy 447.410291 -192.698101)
			(xy 447.4426 -192.706751) (xy 447.471568 -192.723471) (xy 447.495219 -192.74712) (xy 447.511943 -192.776085)
			(xy 447.520597 -192.808393) (xy 447.521076 -192.825116) (xy 447.521076 -193.323464) (xy 447.521489 -193.333492)
			(xy 447.529152 -193.352025) (xy 447.543324 -193.366214) (xy 447.561849 -193.373899) (xy 447.571876 -193.374264)
			(xy 448.902074 -193.374264) (xy 448.9323 -193.373248) (xy 450.088 -193.373248) (xy 450.118226 -193.374264)
			(xy 450.803518 -193.374264) (xy 450.815845 -193.373673) (xy 450.837674 -193.362221) (xy 450.845174 -193.35242)
			(xy 450.899784 -193.273426) (xy 450.902832 -193.248788) (xy 450.898514 -193.23685) (xy 450.887551 -193.20559)
			(xy 450.875662 -193.140428) (xy 450.874892 -193.10731) (xy 450.875408 -193.07971) (xy 450.883635 -193.025127)
			(xy 450.899905 -192.97238) (xy 450.923855 -192.922648) (xy 450.95495 -192.87704) (xy 450.992495 -192.836576)
			(xy 451.035652 -192.802159) (xy 451.083456 -192.77456) (xy 451.13484 -192.754393) (xy 451.188655 -192.74211)
			(xy 451.2437 -192.737985) (xy 451.298745 -192.74211) (xy 451.35256 -192.754393) (xy 451.403944 -192.77456)
			(xy 451.451748 -192.802159) (xy 451.494905 -192.836576) (xy 451.53245 -192.87704) (xy 451.563545 -192.922648)
			(xy 451.587495 -192.97238) (xy 451.603765 -193.025127) (xy 451.611992 -193.07971) (xy 451.612508 -193.10731)
			(xy 451.611787 -193.140433) (xy 451.599898 -193.205603) (xy 451.588886 -193.23685) (xy 451.584568 -193.248788)
			(xy 451.587616 -193.273426) (xy 451.642226 -193.35242) (xy 451.649841 -193.362086) (xy 451.671601 -193.373495)
			(xy 451.683882 -193.374264) (xy 452.825104 -193.374264) (xy 452.835173 -193.373839) (xy 452.853773 -193.36612)
			(xy 452.861172 -193.359278) (xy 453.296528 -192.923922) (xy 453.303213 -192.916512) (xy 453.310799 -192.898077)
			(xy 453.31126 -192.888108) (xy 453.31126 -192.825116) (xy 453.311803 -192.808398) (xy 453.320452 -192.7761)
			(xy 453.337165 -192.747142) (xy 453.360803 -192.723494) (xy 453.389756 -192.706771) (xy 453.42205 -192.698109)
			(xy 453.438768 -192.697608) (xy 455.50074 -192.697608) (xy 456.89012 -191.308228) (xy 456.89012 -186.92876)
			(xy 454.80732 -184.84596) (xy 452.91756 -184.84596) (xy 448.67068 -180.59908) (xy 447.36512 -180.59908)
			(xy 447.3194 -180.55336) (xy 447.3194 -179.65674) (xy 447.36258 -179.61356) (xy 448.53098 -179.61356)
			(xy 448.888104 -179.256436) (xy 448.888104 -176.965864) (xy 448.63512 -176.71288) (xy 427.13656 -176.71288)
			(xy 423.8625 -179.98694) (xy 426.944796 -179.98694) (xy 426.948814 -179.885938) (xy 426.960845 -179.785574)
			(xy 426.980811 -179.686484) (xy 427.008587 -179.589293) (xy 427.043998 -179.494616) (xy 427.086818 -179.403052)
			(xy 427.136778 -179.315179) (xy 427.193561 -179.231553) (xy 427.256809 -179.152704) (xy 427.326121 -179.079128)
			(xy 427.40106 -179.011292) (xy 427.481152 -178.949624) (xy 427.56589 -178.894515) (xy 427.654739 -178.846312)
			(xy 427.747136 -178.805321) (xy 427.842499 -178.7718) (xy 427.940223 -178.745962) (xy 428.03969 -178.727969)
			(xy 428.140273 -178.717937) (xy 428.241336 -178.715927) (xy 428.342238 -178.721953) (xy 428.442342 -178.735976)
			(xy 428.541016 -178.757909) (xy 428.637636 -178.787612) (xy 428.73159 -178.824898) (xy 428.822285 -178.86953)
			(xy 428.909147 -178.921227) (xy 428.991627 -178.979662) (xy 429.069204 -179.044465) (xy 429.141386 -179.115227)
			(xy 429.207719 -179.1915) (xy 429.267782 -179.272802) (xy 429.321196 -179.358619) (xy 429.367623 -179.448408)
			(xy 429.406769 -179.541602) (xy 429.438387 -179.637612) (xy 429.462277 -179.73583) (xy 429.478288 -179.835636)
			(xy 429.486319 -179.936399) (xy 429.486822 -179.98694) (xy 429.486319 -180.037481) (xy 429.478288 -180.138244)
			(xy 429.462277 -180.23805) (xy 429.438387 -180.336268) (xy 429.406769 -180.432278) (xy 429.367623 -180.525472)
			(xy 429.321196 -180.615261) (xy 429.267782 -180.701078) (xy 429.207719 -180.78238) (xy 429.141386 -180.858653)
			(xy 429.069204 -180.929415) (xy 428.991627 -180.994218) (xy 428.909147 -181.052653) (xy 428.822285 -181.10435)
			(xy 428.73159 -181.148982) (xy 428.637636 -181.186268) (xy 428.541016 -181.215971) (xy 428.442342 -181.237904)
			(xy 428.342238 -181.251927) (xy 428.241336 -181.257953) (xy 428.140273 -181.255943) (xy 428.03969 -181.245911)
			(xy 427.940223 -181.227918) (xy 427.842499 -181.20208) (xy 427.747136 -181.168559) (xy 427.654739 -181.127568)
			(xy 427.56589 -181.079365) (xy 427.481152 -181.024256) (xy 427.40106 -180.962588) (xy 427.326121 -180.894752)
			(xy 427.256809 -180.821176) (xy 427.193561 -180.742327) (xy 427.136778 -180.658701) (xy 427.086818 -180.570828)
			(xy 427.043998 -180.479264) (xy 427.008587 -180.384587) (xy 426.980811 -180.287396) (xy 426.960845 -180.188306)
			(xy 426.948814 -180.087942) (xy 426.944796 -179.98694) (xy 423.8625 -179.98694) (xy 419.38702 -184.46242)
			(xy 419.38702 -186.5851) (xy 420.093936 -186.5851) (xy 420.097929 -186.496192) (xy 420.109876 -186.407999)
			(xy 420.129679 -186.321232) (xy 420.157181 -186.23659) (xy 420.192158 -186.154754) (xy 420.234331 -186.076382)
			(xy 420.283359 -186.002106) (xy 420.338847 -185.932524) (xy 420.40035 -185.868196) (xy 420.467371 -185.80964)
			(xy 420.539371 -185.757327) (xy 420.61577 -185.711679) (xy 420.695954 -185.673062) (xy 420.779276 -185.641789)
			(xy 420.865066 -185.61811) (xy 420.952634 -185.602217) (xy 421.041273 -185.594236) (xy 421.085772 -185.593736)
			(xy 422.838372 -185.593736) (xy 422.882873 -185.594224) (xy 422.971517 -185.602199) (xy 423.059089 -185.618089)
			(xy 423.144885 -185.641765) (xy 423.228212 -185.673036) (xy 423.308401 -185.711651) (xy 423.384806 -185.757299)
			(xy 423.456811 -185.809612) (xy 423.523837 -185.868169) (xy 423.585344 -185.932498) (xy 423.640836 -186.002082)
			(xy 423.689868 -186.07636) (xy 423.732044 -186.154735) (xy 423.767025 -186.236574) (xy 423.794528 -186.32122)
			(xy 423.814334 -186.407991) (xy 423.826281 -186.496188) (xy 423.830274 -186.5851) (xy 427.63843 -186.5851)
			(xy 427.642421 -186.496233) (xy 427.654362 -186.408081) (xy 427.674157 -186.321355) (xy 427.701647 -186.236752)
			(xy 427.73661 -186.154954) (xy 427.778764 -186.076619) (xy 427.827771 -186.002379) (xy 427.883235 -185.93283)
			(xy 427.944711 -185.868534) (xy 428.011703 -185.810006) (xy 428.083671 -185.75772) (xy 428.160037 -185.712096)
			(xy 428.240185 -185.6735) (xy 428.32347 -185.642245) (xy 428.409221 -185.618581) (xy 428.496749 -185.602699)
			(xy 428.585348 -185.594727) (xy 428.629826 -185.594244) (xy 430.382426 -185.594244) (xy 430.426902 -185.594748)
			(xy 430.515496 -185.602724) (xy 430.603018 -185.618609) (xy 430.688764 -185.642275) (xy 430.772044 -185.673532)
			(xy 430.852186 -185.712129) (xy 430.928546 -185.757754) (xy 431.000509 -185.810039) (xy 431.067496 -185.868565)
			(xy 431.128966 -185.93286) (xy 431.184426 -186.002407) (xy 431.233429 -186.076644) (xy 431.27558 -186.154975)
			(xy 431.31054 -186.23677) (xy 431.338027 -186.321368) (xy 431.357821 -186.40809) (xy 431.369761 -186.496237)
			(xy 431.373752 -186.5851) (xy 435.182544 -186.5851) (xy 435.186535 -186.496237) (xy 435.198476 -186.408089)
			(xy 435.218269 -186.321366) (xy 435.245757 -186.236767) (xy 435.280717 -186.154972) (xy 435.322869 -186.07664)
			(xy 435.371872 -186.002402) (xy 435.427332 -185.932856) (xy 435.488804 -185.86856) (xy 435.555791 -185.810034)
			(xy 435.627755 -185.757748) (xy 435.704116 -185.712123) (xy 435.784259 -185.673527) (xy 435.867539 -185.64227)
			(xy 435.953286 -185.618604) (xy 436.040809 -185.602719) (xy 436.129404 -185.594744) (xy 436.17388 -185.594244)
			(xy 437.92648 -185.594244) (xy 437.970958 -185.594731) (xy 438.059556 -185.602704) (xy 438.147083 -185.618586)
			(xy 438.232834 -185.64225) (xy 438.316118 -185.673506) (xy 438.396265 -185.712101) (xy 438.47263 -185.757726)
			(xy 438.544598 -185.810012) (xy 438.611589 -185.868539) (xy 438.673063 -185.932835) (xy 438.728527 -186.002383)
			(xy 438.777533 -186.076623) (xy 438.819687 -186.154957) (xy 438.85465 -186.236755) (xy 438.882139 -186.321357)
			(xy 438.901934 -186.408083) (xy 438.913875 -186.496233) (xy 438.917866 -186.5851) (xy 442.72653 -186.5851)
			(xy 442.730521 -186.496232) (xy 442.742462 -186.40808) (xy 442.762258 -186.321353) (xy 442.789748 -186.23675)
			(xy 442.824711 -186.154952) (xy 442.866866 -186.076617) (xy 442.915873 -186.002376) (xy 442.971338 -185.932828)
			(xy 443.032814 -185.868531) (xy 443.099806 -185.810004) (xy 443.171775 -185.757717) (xy 443.248141 -185.712093)
			(xy 443.32829 -185.673498) (xy 443.411576 -185.642243) (xy 443.497328 -185.618579) (xy 443.584856 -185.602698)
			(xy 443.673455 -185.594727) (xy 443.717934 -185.594244) (xy 445.470534 -185.594244) (xy 445.51501 -185.594748)
			(xy 445.603603 -185.602725) (xy 445.691125 -185.61861) (xy 445.77687 -185.642277) (xy 445.860149 -185.673535)
			(xy 445.940291 -185.712131) (xy 446.01665 -185.757756) (xy 446.088613 -185.810042) (xy 446.155599 -185.868568)
			(xy 446.217069 -185.932863) (xy 446.272528 -186.002409) (xy 446.32153 -186.076647) (xy 446.363681 -186.154977)
			(xy 446.398641 -186.236771) (xy 446.426128 -186.32137) (xy 446.445921 -186.408091) (xy 446.457861 -186.496238)
			(xy 446.461852 -186.5851) (xy 450.27033 -186.5851) (xy 450.274321 -186.496232) (xy 450.286262 -186.40808)
			(xy 450.306058 -186.321353) (xy 450.333548 -186.23675) (xy 450.368511 -186.154952) (xy 450.410666 -186.076617)
			(xy 450.459673 -186.002376) (xy 450.515138 -185.932828) (xy 450.576614 -185.868531) (xy 450.643606 -185.810004)
			(xy 450.715575 -185.757717) (xy 450.791941 -185.712093) (xy 450.87209 -185.673498) (xy 450.955376 -185.642243)
			(xy 451.041128 -185.618579) (xy 451.128656 -185.602698) (xy 451.217255 -185.594727) (xy 451.261734 -185.594244)
			(xy 453.014334 -185.594244) (xy 453.05881 -185.594748) (xy 453.147403 -185.602725) (xy 453.234925 -185.61861)
			(xy 453.32067 -185.642277) (xy 453.403949 -185.673535) (xy 453.484091 -185.712131) (xy 453.56045 -185.757756)
			(xy 453.632413 -185.810042) (xy 453.699399 -185.868568) (xy 453.760869 -185.932863) (xy 453.816328 -186.002409)
			(xy 453.86533 -186.076647) (xy 453.907481 -186.154977) (xy 453.942441 -186.236771) (xy 453.969928 -186.32137)
			(xy 453.989721 -186.408091) (xy 454.001661 -186.496238) (xy 454.005652 -186.5851) (xy 454.001661 -186.673962)
			(xy 453.989721 -186.762109) (xy 453.969928 -186.84883) (xy 453.942441 -186.933429) (xy 453.907481 -187.015223)
			(xy 453.86533 -187.093553) (xy 453.816328 -187.167791) (xy 453.760869 -187.237337) (xy 453.699399 -187.301632)
			(xy 453.632413 -187.360158) (xy 453.56045 -187.412444) (xy 453.484091 -187.458069) (xy 453.403949 -187.496665)
			(xy 453.32067 -187.527923) (xy 453.234925 -187.55159) (xy 453.147403 -187.567475) (xy 453.05881 -187.575452)
			(xy 453.014334 -187.575952) (xy 451.261734 -187.575952) (xy 451.217255 -187.575473) (xy 451.128656 -187.567502)
			(xy 451.041128 -187.551621) (xy 450.955376 -187.527957) (xy 450.87209 -187.496702) (xy 450.791941 -187.458107)
			(xy 450.715575 -187.412483) (xy 450.643606 -187.360196) (xy 450.576614 -187.301669) (xy 450.515138 -187.237372)
			(xy 450.459673 -187.167824) (xy 450.410666 -187.093583) (xy 450.368511 -187.015248) (xy 450.333548 -186.93345)
			(xy 450.306058 -186.848847) (xy 450.286262 -186.76212) (xy 450.274321 -186.673968) (xy 450.27033 -186.5851)
			(xy 446.461852 -186.5851) (xy 446.457861 -186.673962) (xy 446.445921 -186.762109) (xy 446.426128 -186.84883)
			(xy 446.398641 -186.933429) (xy 446.363681 -187.015223) (xy 446.32153 -187.093553) (xy 446.272528 -187.167791)
			(xy 446.217069 -187.237337) (xy 446.155599 -187.301632) (xy 446.088613 -187.360158) (xy 446.01665 -187.412444)
			(xy 445.940291 -187.458069) (xy 445.860149 -187.496665) (xy 445.77687 -187.527923) (xy 445.691125 -187.55159)
			(xy 445.603603 -187.567475) (xy 445.51501 -187.575452) (xy 445.470534 -187.575952) (xy 443.717934 -187.575952)
			(xy 443.673455 -187.575473) (xy 443.584856 -187.567502) (xy 443.497328 -187.551621) (xy 443.411576 -187.527957)
			(xy 443.32829 -187.496702) (xy 443.248141 -187.458107) (xy 443.171775 -187.412483) (xy 443.099806 -187.360196)
			(xy 443.032814 -187.301669) (xy 442.971338 -187.237372) (xy 442.915873 -187.167824) (xy 442.866866 -187.093583)
			(xy 442.824711 -187.015248) (xy 442.789748 -186.93345) (xy 442.762258 -186.848847) (xy 442.742462 -186.76212)
			(xy 442.730521 -186.673968) (xy 442.72653 -186.5851) (xy 438.917866 -186.5851) (xy 438.913875 -186.673967)
			(xy 438.901934 -186.762117) (xy 438.882139 -186.848843) (xy 438.85465 -186.933445) (xy 438.819687 -187.015243)
			(xy 438.777533 -187.093577) (xy 438.728527 -187.167817) (xy 438.673063 -187.237365) (xy 438.611589 -187.301661)
			(xy 438.544598 -187.360188) (xy 438.47263 -187.412474) (xy 438.396265 -187.458099) (xy 438.316118 -187.496694)
			(xy 438.232834 -187.52795) (xy 438.147083 -187.551614) (xy 438.059556 -187.567496) (xy 437.970958 -187.575469)
			(xy 437.92648 -187.575952) (xy 436.17388 -187.575952) (xy 436.129404 -187.575456) (xy 436.040809 -187.567481)
			(xy 435.953286 -187.551596) (xy 435.867539 -187.52793) (xy 435.784259 -187.496673) (xy 435.704116 -187.458077)
			(xy 435.627755 -187.412452) (xy 435.555791 -187.360166) (xy 435.488804 -187.30164) (xy 435.427332 -187.237344)
			(xy 435.371872 -187.167798) (xy 435.322869 -187.09356) (xy 435.280717 -187.015228) (xy 435.245757 -186.933433)
			(xy 435.218269 -186.848834) (xy 435.198476 -186.762111) (xy 435.186535 -186.673963) (xy 435.182544 -186.5851)
			(xy 431.373752 -186.5851) (xy 431.369761 -186.673963) (xy 431.357821 -186.76211) (xy 431.338027 -186.848832)
			(xy 431.31054 -186.93343) (xy 431.27558 -187.015225) (xy 431.233429 -187.093556) (xy 431.184426 -187.167793)
			(xy 431.128966 -187.23734) (xy 431.067496 -187.301635) (xy 431.000509 -187.360161) (xy 430.928546 -187.412446)
			(xy 430.852186 -187.458071) (xy 430.772044 -187.496668) (xy 430.688764 -187.527925) (xy 430.603018 -187.551591)
			(xy 430.515496 -187.567476) (xy 430.426902 -187.575452) (xy 430.382426 -187.575952) (xy 428.629826 -187.575952)
			(xy 428.585348 -187.575473) (xy 428.496749 -187.567501) (xy 428.409221 -187.551619) (xy 428.32347 -187.527955)
			(xy 428.240185 -187.4967) (xy 428.160037 -187.458104) (xy 428.083671 -187.41248) (xy 428.011703 -187.360194)
			(xy 427.944711 -187.301666) (xy 427.883235 -187.23737) (xy 427.827771 -187.167821) (xy 427.778764 -187.093581)
			(xy 427.73661 -187.015246) (xy 427.701647 -186.933448) (xy 427.674157 -186.848845) (xy 427.654362 -186.762119)
			(xy 427.642421 -186.673967) (xy 427.63843 -186.5851) (xy 423.830274 -186.5851) (xy 423.826281 -186.674012)
			(xy 423.814334 -186.762209) (xy 423.794528 -186.84898) (xy 423.767025 -186.933626) (xy 423.732044 -187.015465)
			(xy 423.689868 -187.09384) (xy 423.640836 -187.168118) (xy 423.585344 -187.237702) (xy 423.523837 -187.302031)
			(xy 423.456811 -187.360588) (xy 423.384806 -187.412901) (xy 423.308401 -187.458549) (xy 423.228212 -187.497164)
			(xy 423.144885 -187.528435) (xy 423.059089 -187.552111) (xy 422.971517 -187.568001) (xy 422.882873 -187.575976)
			(xy 422.838372 -187.57646) (xy 421.085772 -187.57646) (xy 421.041273 -187.575964) (xy 420.952634 -187.567983)
			(xy 420.865066 -187.55209) (xy 420.779276 -187.528411) (xy 420.695954 -187.497138) (xy 420.61577 -187.458521)
			(xy 420.539371 -187.412873) (xy 420.467371 -187.36056) (xy 420.40035 -187.302004) (xy 420.338847 -187.237676)
			(xy 420.283359 -187.168094) (xy 420.234331 -187.093818) (xy 420.192158 -187.015446) (xy 420.157181 -186.93361)
			(xy 420.129679 -186.848968) (xy 420.109876 -186.762201) (xy 420.097929 -186.674008) (xy 420.093936 -186.5851)
			(xy 419.38702 -186.5851) (xy 419.38702 -187.23102) (xy 416.86988 -189.74816) (xy 411.72384 -189.74816)
			(xy 411.220158 -190.251842) (xy 450.08318 -190.251842) (xy 450.087198 -190.15084) (xy 450.099229 -190.050476)
			(xy 450.119195 -189.951386) (xy 450.146971 -189.854195) (xy 450.182382 -189.759518) (xy 450.225202 -189.667954)
			(xy 450.275162 -189.580081) (xy 450.331945 -189.496455) (xy 450.395193 -189.417606) (xy 450.464505 -189.34403)
			(xy 450.539444 -189.276194) (xy 450.619536 -189.214526) (xy 450.704274 -189.159417) (xy 450.793123 -189.111214)
			(xy 450.88552 -189.070223) (xy 450.980883 -189.036702) (xy 451.078607 -189.010864) (xy 451.178074 -188.992871)
			(xy 451.278657 -188.982839) (xy 451.37972 -188.980829) (xy 451.480622 -188.986855) (xy 451.580726 -189.000878)
			(xy 451.6794 -189.022811) (xy 451.77602 -189.052514) (xy 451.869974 -189.0898) (xy 451.960669 -189.134432)
			(xy 452.047531 -189.186129) (xy 452.130011 -189.244564) (xy 452.207588 -189.309367) (xy 452.27977 -189.380129)
			(xy 452.346103 -189.456402) (xy 452.406166 -189.537704) (xy 452.45958 -189.623521) (xy 452.506007 -189.71331)
			(xy 452.545153 -189.806504) (xy 452.576771 -189.902514) (xy 452.600661 -190.000732) (xy 452.616672 -190.100538)
			(xy 452.624703 -190.201301) (xy 452.625206 -190.251842) (xy 452.624703 -190.302383) (xy 452.616672 -190.403146)
			(xy 452.600661 -190.502952) (xy 452.576771 -190.60117) (xy 452.545153 -190.69718) (xy 452.506007 -190.790374)
			(xy 452.45958 -190.880163) (xy 452.406166 -190.96598) (xy 452.346103 -191.047282) (xy 452.27977 -191.123555)
			(xy 452.207588 -191.194317) (xy 452.130011 -191.25912) (xy 452.047531 -191.317555) (xy 451.960669 -191.369252)
			(xy 451.869974 -191.413884) (xy 451.77602 -191.45117) (xy 451.6794 -191.480873) (xy 451.580726 -191.502806)
			(xy 451.480622 -191.516829) (xy 451.37972 -191.522855) (xy 451.278657 -191.520845) (xy 451.178074 -191.510813)
			(xy 451.078607 -191.49282) (xy 450.980883 -191.466982) (xy 450.88552 -191.433461) (xy 450.793123 -191.39247)
			(xy 450.704274 -191.344267) (xy 450.619536 -191.289158) (xy 450.539444 -191.22749) (xy 450.464505 -191.159654)
			(xy 450.395193 -191.086078) (xy 450.331945 -191.007229) (xy 450.275162 -190.923603) (xy 450.225202 -190.83573)
			(xy 450.182382 -190.744166) (xy 450.146971 -190.649489) (xy 450.119195 -190.552298) (xy 450.099229 -190.453208)
			(xy 450.087198 -190.352844) (xy 450.08318 -190.251842) (xy 411.220158 -190.251842) (xy 410.61132 -190.86068)
			(xy 410.61132 -192.21831) (xy 413.154383 -192.21831) (xy 413.158318 -192.164539) (xy 413.170041 -192.111915)
			(xy 413.189301 -192.061558) (xy 413.215687 -192.014541) (xy 413.248639 -191.971868) (xy 413.287452 -191.934447)
			(xy 413.3313 -191.903077) (xy 413.379248 -191.878425) (xy 413.430275 -191.861017) (xy 413.483293 -191.851224)
			(xy 413.537172 -191.849255) (xy 413.590763 -191.855152) (xy 413.642924 -191.868788) (xy 413.692544 -191.889875)
			(xy 413.738565 -191.917961) (xy 413.780007 -191.952449) (xy 413.815985 -191.992603) (xy 413.845733 -192.037567)
			(xy 413.868618 -192.086384) (xy 413.88415 -192.138013) (xy 413.892 -192.191353) (xy 413.892492 -192.21831)
			(xy 414.943051 -192.21831) (xy 414.946986 -192.164539) (xy 414.958709 -192.111915) (xy 414.977969 -192.061558)
			(xy 415.004355 -192.014541) (xy 415.037307 -191.971868) (xy 415.07612 -191.934447) (xy 415.119968 -191.903077)
			(xy 415.167916 -191.878425) (xy 415.218943 -191.861017) (xy 415.271961 -191.851224) (xy 415.32584 -191.849255)
			(xy 415.379431 -191.855152) (xy 415.431592 -191.868788) (xy 415.481212 -191.889875) (xy 415.527233 -191.917961)
			(xy 415.568675 -191.952449) (xy 415.604653 -191.992603) (xy 415.634401 -192.037567) (xy 415.657286 -192.086384)
			(xy 415.672818 -192.138013) (xy 415.680668 -192.191353) (xy 415.68116 -192.21831) (xy 420.698437 -192.21831)
			(xy 420.702372 -192.164539) (xy 420.714095 -192.111915) (xy 420.733355 -192.061558) (xy 420.759741 -192.014541)
			(xy 420.792693 -191.971868) (xy 420.831506 -191.934447) (xy 420.875354 -191.903077) (xy 420.923302 -191.878425)
			(xy 420.974329 -191.861017) (xy 421.027347 -191.851224) (xy 421.081226 -191.849255) (xy 421.134817 -191.855152)
			(xy 421.186978 -191.868788) (xy 421.236598 -191.889875) (xy 421.282619 -191.917961) (xy 421.324061 -191.952449)
			(xy 421.360039 -191.992603) (xy 421.389787 -192.037567) (xy 421.412672 -192.086384) (xy 421.428204 -192.138013)
			(xy 421.436054 -192.191353) (xy 421.436546 -192.21831) (xy 422.487105 -192.21831) (xy 422.49104 -192.164539)
			(xy 422.502763 -192.111915) (xy 422.522023 -192.061558) (xy 422.548409 -192.014541) (xy 422.581361 -191.971868)
			(xy 422.620174 -191.934447) (xy 422.664022 -191.903077) (xy 422.71197 -191.878425) (xy 422.762997 -191.861017)
			(xy 422.816015 -191.851224) (xy 422.869894 -191.849255) (xy 422.923485 -191.855152) (xy 422.975646 -191.868788)
			(xy 423.025266 -191.889875) (xy 423.071287 -191.917961) (xy 423.112729 -191.952449) (xy 423.148707 -191.992603)
			(xy 423.178455 -192.037567) (xy 423.20134 -192.086384) (xy 423.216872 -192.138013) (xy 423.224722 -192.191353)
			(xy 423.225214 -192.21831) (xy 428.242491 -192.21831) (xy 428.246426 -192.164539) (xy 428.258149 -192.111915)
			(xy 428.277409 -192.061558) (xy 428.303795 -192.014541) (xy 428.336747 -191.971868) (xy 428.37556 -191.934447)
			(xy 428.419408 -191.903077) (xy 428.467356 -191.878425) (xy 428.518383 -191.861017) (xy 428.571401 -191.851224)
			(xy 428.62528 -191.849255) (xy 428.678871 -191.855152) (xy 428.731032 -191.868788) (xy 428.780652 -191.889875)
			(xy 428.826673 -191.917961) (xy 428.868115 -191.952449) (xy 428.904093 -191.992603) (xy 428.933841 -192.037567)
			(xy 428.956726 -192.086384) (xy 428.972258 -192.138013) (xy 428.980108 -192.191353) (xy 428.9806 -192.21831)
			(xy 430.031159 -192.21831) (xy 430.035094 -192.164539) (xy 430.046817 -192.111915) (xy 430.066077 -192.061558)
			(xy 430.092463 -192.014541) (xy 430.125415 -191.971868) (xy 430.164228 -191.934447) (xy 430.208076 -191.903077)
			(xy 430.256024 -191.878425) (xy 430.307051 -191.861017) (xy 430.360069 -191.851224) (xy 430.413948 -191.849255)
			(xy 430.467539 -191.855152) (xy 430.5197 -191.868788) (xy 430.56932 -191.889875) (xy 430.615341 -191.917961)
			(xy 430.656783 -191.952449) (xy 430.692761 -191.992603) (xy 430.722509 -192.037567) (xy 430.745394 -192.086384)
			(xy 430.760926 -192.138013) (xy 430.768776 -192.191353) (xy 430.769268 -192.21831) (xy 435.786545 -192.21831)
			(xy 435.79048 -192.164539) (xy 435.802203 -192.111915) (xy 435.821463 -192.061558) (xy 435.847849 -192.014541)
			(xy 435.880801 -191.971868) (xy 435.919614 -191.934447) (xy 435.963462 -191.903077) (xy 436.01141 -191.878425)
			(xy 436.062437 -191.861017) (xy 436.115455 -191.851224) (xy 436.169334 -191.849255) (xy 436.222925 -191.855152)
			(xy 436.275086 -191.868788) (xy 436.324706 -191.889875) (xy 436.370727 -191.917961) (xy 436.412169 -191.952449)
			(xy 436.448147 -191.992603) (xy 436.477895 -192.037567) (xy 436.50078 -192.086384) (xy 436.516312 -192.138013)
			(xy 436.524162 -192.191353) (xy 436.524654 -192.21831) (xy 437.575213 -192.21831) (xy 437.579148 -192.164539)
			(xy 437.590871 -192.111915) (xy 437.610131 -192.061558) (xy 437.636517 -192.014541) (xy 437.669469 -191.971868)
			(xy 437.708282 -191.934447) (xy 437.75213 -191.903077) (xy 437.800078 -191.878425) (xy 437.851105 -191.861017)
			(xy 437.904123 -191.851224) (xy 437.958002 -191.849255) (xy 438.011593 -191.855152) (xy 438.063754 -191.868788)
			(xy 438.113374 -191.889875) (xy 438.159395 -191.917961) (xy 438.200837 -191.952449) (xy 438.236815 -191.992603)
			(xy 438.266563 -192.037567) (xy 438.289448 -192.086384) (xy 438.30498 -192.138013) (xy 438.31283 -192.191353)
			(xy 438.313322 -192.21831) (xy 443.330599 -192.21831) (xy 443.334534 -192.164539) (xy 443.346257 -192.111915)
			(xy 443.365517 -192.061558) (xy 443.391903 -192.014541) (xy 443.424855 -191.971868) (xy 443.463668 -191.934447)
			(xy 443.507516 -191.903077) (xy 443.555464 -191.878425) (xy 443.606491 -191.861017) (xy 443.659509 -191.851224)
			(xy 443.713388 -191.849255) (xy 443.766979 -191.855152) (xy 443.81914 -191.868788) (xy 443.86876 -191.889875)
			(xy 443.914781 -191.917961) (xy 443.956223 -191.952449) (xy 443.992201 -191.992603) (xy 444.021949 -192.037567)
			(xy 444.044834 -192.086384) (xy 444.060366 -192.138013) (xy 444.068216 -192.191353) (xy 444.068708 -192.21831)
			(xy 445.119267 -192.21831) (xy 445.123202 -192.164539) (xy 445.134925 -192.111915) (xy 445.154185 -192.061558)
			(xy 445.180571 -192.014541) (xy 445.213523 -191.971868) (xy 445.252336 -191.934447) (xy 445.296184 -191.903077)
			(xy 445.344132 -191.878425) (xy 445.395159 -191.861017) (xy 445.448177 -191.851224) (xy 445.502056 -191.849255)
			(xy 445.555647 -191.855152) (xy 445.607808 -191.868788) (xy 445.657428 -191.889875) (xy 445.703449 -191.917961)
			(xy 445.744891 -191.952449) (xy 445.780869 -191.992603) (xy 445.810617 -192.037567) (xy 445.833502 -192.086384)
			(xy 445.849034 -192.138013) (xy 445.856884 -192.191353) (xy 445.857376 -192.21831) (xy 450.874399 -192.21831)
			(xy 450.878334 -192.164539) (xy 450.890057 -192.111915) (xy 450.909317 -192.061558) (xy 450.935703 -192.014541)
			(xy 450.968655 -191.971868) (xy 451.007468 -191.934447) (xy 451.051316 -191.903077) (xy 451.099264 -191.878425)
			(xy 451.150291 -191.861017) (xy 451.203309 -191.851224) (xy 451.257188 -191.849255) (xy 451.310779 -191.855152)
			(xy 451.36294 -191.868788) (xy 451.41256 -191.889875) (xy 451.458581 -191.917961) (xy 451.500023 -191.952449)
			(xy 451.536001 -191.992603) (xy 451.565749 -192.037567) (xy 451.588634 -192.086384) (xy 451.604166 -192.138013)
			(xy 451.612016 -192.191353) (xy 451.612508 -192.21831) (xy 452.663067 -192.21831) (xy 452.667002 -192.164539)
			(xy 452.678725 -192.111915) (xy 452.697985 -192.061558) (xy 452.724371 -192.014541) (xy 452.757323 -191.971868)
			(xy 452.796136 -191.934447) (xy 452.839984 -191.903077) (xy 452.887932 -191.878425) (xy 452.938959 -191.861017)
			(xy 452.991977 -191.851224) (xy 453.045856 -191.849255) (xy 453.099447 -191.855152) (xy 453.151608 -191.868788)
			(xy 453.201228 -191.889875) (xy 453.247249 -191.917961) (xy 453.288691 -191.952449) (xy 453.324669 -191.992603)
			(xy 453.354417 -192.037567) (xy 453.377302 -192.086384) (xy 453.392834 -192.138013) (xy 453.400684 -192.191353)
			(xy 453.401176 -192.21831) (xy 453.400684 -192.245267) (xy 453.392834 -192.298607) (xy 453.377302 -192.350236)
			(xy 453.354417 -192.399053) (xy 453.324669 -192.444017) (xy 453.288691 -192.484171) (xy 453.247249 -192.518659)
			(xy 453.201228 -192.546745) (xy 453.151608 -192.567832) (xy 453.099447 -192.581468) (xy 453.045856 -192.587365)
			(xy 452.991977 -192.585396) (xy 452.938959 -192.575603) (xy 452.887932 -192.558195) (xy 452.839984 -192.533543)
			(xy 452.796136 -192.502173) (xy 452.757323 -192.464752) (xy 452.724371 -192.422079) (xy 452.697985 -192.375062)
			(xy 452.678725 -192.324705) (xy 452.667002 -192.272081) (xy 452.663067 -192.21831) (xy 451.612508 -192.21831)
			(xy 451.612016 -192.245267) (xy 451.604166 -192.298607) (xy 451.588634 -192.350236) (xy 451.565749 -192.399053)
			(xy 451.536001 -192.444017) (xy 451.500023 -192.484171) (xy 451.458581 -192.518659) (xy 451.41256 -192.546745)
			(xy 451.36294 -192.567832) (xy 451.310779 -192.581468) (xy 451.257188 -192.587365) (xy 451.203309 -192.585396)
			(xy 451.150291 -192.575603) (xy 451.099264 -192.558195) (xy 451.051316 -192.533543) (xy 451.007468 -192.502173)
			(xy 450.968655 -192.464752) (xy 450.935703 -192.422079) (xy 450.909317 -192.375062) (xy 450.890057 -192.324705)
			(xy 450.878334 -192.272081) (xy 450.874399 -192.21831) (xy 445.857376 -192.21831) (xy 445.856884 -192.245267)
			(xy 445.849034 -192.298607) (xy 445.833502 -192.350236) (xy 445.810617 -192.399053) (xy 445.780869 -192.444017)
			(xy 445.744891 -192.484171) (xy 445.703449 -192.518659) (xy 445.657428 -192.546745) (xy 445.607808 -192.567832)
			(xy 445.555647 -192.581468) (xy 445.502056 -192.587365) (xy 445.448177 -192.585396) (xy 445.395159 -192.575603)
			(xy 445.344132 -192.558195) (xy 445.296184 -192.533543) (xy 445.252336 -192.502173) (xy 445.213523 -192.464752)
			(xy 445.180571 -192.422079) (xy 445.154185 -192.375062) (xy 445.134925 -192.324705) (xy 445.123202 -192.272081)
			(xy 445.119267 -192.21831) (xy 444.068708 -192.21831) (xy 444.068216 -192.245267) (xy 444.060366 -192.298607)
			(xy 444.044834 -192.350236) (xy 444.021949 -192.399053) (xy 443.992201 -192.444017) (xy 443.956223 -192.484171)
			(xy 443.914781 -192.518659) (xy 443.86876 -192.546745) (xy 443.81914 -192.567832) (xy 443.766979 -192.581468)
			(xy 443.713388 -192.587365) (xy 443.659509 -192.585396) (xy 443.606491 -192.575603) (xy 443.555464 -192.558195)
			(xy 443.507516 -192.533543) (xy 443.463668 -192.502173) (xy 443.424855 -192.464752) (xy 443.391903 -192.422079)
			(xy 443.365517 -192.375062) (xy 443.346257 -192.324705) (xy 443.334534 -192.272081) (xy 443.330599 -192.21831)
			(xy 438.313322 -192.21831) (xy 438.31283 -192.245267) (xy 438.30498 -192.298607) (xy 438.289448 -192.350236)
			(xy 438.266563 -192.399053) (xy 438.236815 -192.444017) (xy 438.200837 -192.484171) (xy 438.159395 -192.518659)
			(xy 438.113374 -192.546745) (xy 438.063754 -192.567832) (xy 438.011593 -192.581468) (xy 437.958002 -192.587365)
			(xy 437.904123 -192.585396) (xy 437.851105 -192.575603) (xy 437.800078 -192.558195) (xy 437.75213 -192.533543)
			(xy 437.708282 -192.502173) (xy 437.669469 -192.464752) (xy 437.636517 -192.422079) (xy 437.610131 -192.375062)
			(xy 437.590871 -192.324705) (xy 437.579148 -192.272081) (xy 437.575213 -192.21831) (xy 436.524654 -192.21831)
			(xy 436.524162 -192.245267) (xy 436.516312 -192.298607) (xy 436.50078 -192.350236) (xy 436.477895 -192.399053)
			(xy 436.448147 -192.444017) (xy 436.412169 -192.484171) (xy 436.370727 -192.518659) (xy 436.324706 -192.546745)
			(xy 436.275086 -192.567832) (xy 436.222925 -192.581468) (xy 436.169334 -192.587365) (xy 436.115455 -192.585396)
			(xy 436.062437 -192.575603) (xy 436.01141 -192.558195) (xy 435.963462 -192.533543) (xy 435.919614 -192.502173)
			(xy 435.880801 -192.464752) (xy 435.847849 -192.422079) (xy 435.821463 -192.375062) (xy 435.802203 -192.324705)
			(xy 435.79048 -192.272081) (xy 435.786545 -192.21831) (xy 430.769268 -192.21831) (xy 430.768776 -192.245267)
			(xy 430.760926 -192.298607) (xy 430.745394 -192.350236) (xy 430.722509 -192.399053) (xy 430.692761 -192.444017)
			(xy 430.656783 -192.484171) (xy 430.615341 -192.518659) (xy 430.56932 -192.546745) (xy 430.5197 -192.567832)
			(xy 430.467539 -192.581468) (xy 430.413948 -192.587365) (xy 430.360069 -192.585396) (xy 430.307051 -192.575603)
			(xy 430.256024 -192.558195) (xy 430.208076 -192.533543) (xy 430.164228 -192.502173) (xy 430.125415 -192.464752)
			(xy 430.092463 -192.422079) (xy 430.066077 -192.375062) (xy 430.046817 -192.324705) (xy 430.035094 -192.272081)
			(xy 430.031159 -192.21831) (xy 428.9806 -192.21831) (xy 428.980108 -192.245267) (xy 428.972258 -192.298607)
			(xy 428.956726 -192.350236) (xy 428.933841 -192.399053) (xy 428.904093 -192.444017) (xy 428.868115 -192.484171)
			(xy 428.826673 -192.518659) (xy 428.780652 -192.546745) (xy 428.731032 -192.567832) (xy 428.678871 -192.581468)
			(xy 428.62528 -192.587365) (xy 428.571401 -192.585396) (xy 428.518383 -192.575603) (xy 428.467356 -192.558195)
			(xy 428.419408 -192.533543) (xy 428.37556 -192.502173) (xy 428.336747 -192.464752) (xy 428.303795 -192.422079)
			(xy 428.277409 -192.375062) (xy 428.258149 -192.324705) (xy 428.246426 -192.272081) (xy 428.242491 -192.21831)
			(xy 423.225214 -192.21831) (xy 423.224722 -192.245267) (xy 423.216872 -192.298607) (xy 423.20134 -192.350236)
			(xy 423.178455 -192.399053) (xy 423.148707 -192.444017) (xy 423.112729 -192.484171) (xy 423.071287 -192.518659)
			(xy 423.025266 -192.546745) (xy 422.975646 -192.567832) (xy 422.923485 -192.581468) (xy 422.869894 -192.587365)
			(xy 422.816015 -192.585396) (xy 422.762997 -192.575603) (xy 422.71197 -192.558195) (xy 422.664022 -192.533543)
			(xy 422.620174 -192.502173) (xy 422.581361 -192.464752) (xy 422.548409 -192.422079) (xy 422.522023 -192.375062)
			(xy 422.502763 -192.324705) (xy 422.49104 -192.272081) (xy 422.487105 -192.21831) (xy 421.436546 -192.21831)
			(xy 421.436054 -192.245267) (xy 421.428204 -192.298607) (xy 421.412672 -192.350236) (xy 421.389787 -192.399053)
			(xy 421.360039 -192.444017) (xy 421.324061 -192.484171) (xy 421.282619 -192.518659) (xy 421.236598 -192.546745)
			(xy 421.186978 -192.567832) (xy 421.134817 -192.581468) (xy 421.081226 -192.587365) (xy 421.027347 -192.585396)
			(xy 420.974329 -192.575603) (xy 420.923302 -192.558195) (xy 420.875354 -192.533543) (xy 420.831506 -192.502173)
			(xy 420.792693 -192.464752) (xy 420.759741 -192.422079) (xy 420.733355 -192.375062) (xy 420.714095 -192.324705)
			(xy 420.702372 -192.272081) (xy 420.698437 -192.21831) (xy 415.68116 -192.21831) (xy 415.680668 -192.245267)
			(xy 415.672818 -192.298607) (xy 415.657286 -192.350236) (xy 415.634401 -192.399053) (xy 415.604653 -192.444017)
			(xy 415.568675 -192.484171) (xy 415.527233 -192.518659) (xy 415.481212 -192.546745) (xy 415.431592 -192.567832)
			(xy 415.379431 -192.581468) (xy 415.32584 -192.587365) (xy 415.271961 -192.585396) (xy 415.218943 -192.575603)
			(xy 415.167916 -192.558195) (xy 415.119968 -192.533543) (xy 415.07612 -192.502173) (xy 415.037307 -192.464752)
			(xy 415.004355 -192.422079) (xy 414.977969 -192.375062) (xy 414.958709 -192.324705) (xy 414.946986 -192.272081)
			(xy 414.943051 -192.21831) (xy 413.892492 -192.21831) (xy 413.892 -192.245267) (xy 413.88415 -192.298607)
			(xy 413.868618 -192.350236) (xy 413.845733 -192.399053) (xy 413.815985 -192.444017) (xy 413.780007 -192.484171)
			(xy 413.738565 -192.518659) (xy 413.692544 -192.546745) (xy 413.642924 -192.567832) (xy 413.590763 -192.581468)
			(xy 413.537172 -192.587365) (xy 413.483293 -192.585396) (xy 413.430275 -192.575603) (xy 413.379248 -192.558195)
			(xy 413.3313 -192.533543) (xy 413.287452 -192.502173) (xy 413.248639 -192.464752) (xy 413.215687 -192.422079)
			(xy 413.189301 -192.375062) (xy 413.170041 -192.324705) (xy 413.158318 -192.272081) (xy 413.154383 -192.21831)
			(xy 410.61132 -192.21831) (xy 410.61132 -193.285364) (xy 410.70022 -193.374264) (xy 411.182058 -193.374264)
		)
		(stroke
			(width 0)
			(type solid)
		)
		(fill yes)
		(layer "F.Cu")
		(net "P12V_MEM_CPU0")
	)
	(gr_poly
		(pts
			(xy 18.308066 -193.325242) (xy 18.319621 -193.324622) (xy 18.340373 -193.314436) (xy 18.347944 -193.305684)
			(xy 18.404586 -193.232786) (xy 18.409158 -193.21018) (xy 18.406364 -193.198496) (xy 18.401019 -193.176144)
			(xy 18.395281 -193.130544) (xy 18.394934 -193.107564) (xy 18.39545 -193.079964) (xy 18.403677 -193.025381)
			(xy 18.419947 -192.972634) (xy 18.443897 -192.922902) (xy 18.474992 -192.877294) (xy 18.512537 -192.83683)
			(xy 18.555694 -192.802413) (xy 18.603498 -192.774814) (xy 18.654882 -192.754647) (xy 18.708697 -192.742364)
			(xy 18.763742 -192.738239) (xy 18.818787 -192.742364) (xy 18.872602 -192.754647) (xy 18.923986 -192.774814)
			(xy 18.97179 -192.802413) (xy 19.014947 -192.83683) (xy 19.052492 -192.877294) (xy 19.083587 -192.922902)
			(xy 19.107537 -192.972634) (xy 19.123807 -193.025381) (xy 19.132034 -193.079964) (xy 19.13255 -193.107564)
			(xy 19.13218 -193.130542) (xy 19.126444 -193.17614) (xy 19.12112 -193.198496) (xy 19.118326 -193.21018)
			(xy 19.122898 -193.232786) (xy 19.17954 -193.305684) (xy 19.187076 -193.314482) (xy 19.207848 -193.324681)
			(xy 19.219418 -193.325242) (xy 20.780756 -193.325242) (xy 20.790786 -193.324831) (xy 20.809325 -193.31717)
			(xy 20.823522 -193.302998) (xy 20.831214 -193.284472) (xy 20.831556 -193.274442) (xy 20.831556 -192.825116)
			(xy 20.83205 -192.808427) (xy 20.840686 -192.776186) (xy 20.857373 -192.747279) (xy 20.880974 -192.723677)
			(xy 20.90988 -192.706988) (xy 20.942121 -192.698351) (xy 20.95881 -192.697862) (xy 22.45741 -192.697862)
			(xy 22.474096 -192.698359) (xy 22.506331 -192.706999) (xy 22.535232 -192.723689) (xy 22.558827 -192.747289)
			(xy 22.575511 -192.776193) (xy 22.584144 -192.808429) (xy 22.584664 -192.825116) (xy 22.584664 -193.274442)
			(xy 22.585159 -193.284447) (xy 22.592824 -193.30293) (xy 22.606975 -193.317079) (xy 22.625459 -193.324742)
			(xy 22.635464 -193.325242) (xy 25.85212 -193.325242) (xy 25.863679 -193.324631) (xy 25.884447 -193.314457)
			(xy 25.891998 -193.305684) (xy 25.94864 -193.232786) (xy 25.953212 -193.21018) (xy 25.950418 -193.198496)
			(xy 25.945074 -193.176144) (xy 25.939337 -193.130544) (xy 25.938988 -193.107564) (xy 25.939504 -193.079964)
			(xy 25.947731 -193.025381) (xy 25.964001 -192.972634) (xy 25.987951 -192.922902) (xy 26.019046 -192.877294)
			(xy 26.056591 -192.83683) (xy 26.099748 -192.802413) (xy 26.147552 -192.774814) (xy 26.198936 -192.754647)
			(xy 26.252751 -192.742364) (xy 26.307796 -192.738239) (xy 26.362841 -192.742364) (xy 26.416656 -192.754647)
			(xy 26.46804 -192.774814) (xy 26.515844 -192.802413) (xy 26.559001 -192.83683) (xy 26.596546 -192.877294)
			(xy 26.627641 -192.922902) (xy 26.651591 -192.972634) (xy 26.667861 -193.025381) (xy 26.676088 -193.079964)
			(xy 26.676604 -193.107564) (xy 26.676234 -193.130542) (xy 26.670497 -193.17614) (xy 26.665174 -193.198496)
			(xy 26.66238 -193.21018) (xy 26.666952 -193.232786) (xy 26.723594 -193.305684) (xy 26.731134 -193.314473)
			(xy 26.751906 -193.32465) (xy 26.763472 -193.325242) (xy 28.324556 -193.325242) (xy 28.334586 -193.324831)
			(xy 28.353125 -193.31717) (xy 28.367322 -193.302998) (xy 28.375014 -193.284472) (xy 28.375356 -193.274442)
			(xy 28.375356 -192.825116) (xy 28.375935 -192.808424) (xy 28.384634 -192.776191) (xy 28.401368 -192.747301)
			(xy 28.424998 -192.723716) (xy 28.453921 -192.707039) (xy 28.486171 -192.698402) (xy 28.502864 -192.697862)
			(xy 30.001464 -192.697862) (xy 30.018162 -192.6984) (xy 30.050426 -192.707024) (xy 30.079364 -192.723695)
			(xy 30.103009 -192.747281) (xy 30.119753 -192.776177) (xy 30.128458 -192.808419) (xy 30.128972 -192.825116)
			(xy 30.128972 -193.274442) (xy 30.129467 -193.284446) (xy 30.137133 -193.302928) (xy 30.151283 -193.317075)
			(xy 30.169768 -193.324736) (xy 30.179772 -193.325242) (xy 33.35782 -193.325242) (xy 33.369379 -193.324631)
			(xy 33.390147 -193.314457) (xy 33.397698 -193.305684) (xy 33.45434 -193.232786) (xy 33.458912 -193.21018)
			(xy 33.456118 -193.198496) (xy 33.450774 -193.176144) (xy 33.445037 -193.130544) (xy 33.444688 -193.107564)
			(xy 33.445204 -193.079964) (xy 33.453431 -193.025381) (xy 33.469701 -192.972634) (xy 33.493651 -192.922902)
			(xy 33.524746 -192.877294) (xy 33.562291 -192.83683) (xy 33.605448 -192.802413) (xy 33.653252 -192.774814)
			(xy 33.704636 -192.754647) (xy 33.758451 -192.742364) (xy 33.813496 -192.738239) (xy 33.868541 -192.742364)
			(xy 33.922356 -192.754647) (xy 33.97374 -192.774814) (xy 34.021544 -192.802413) (xy 34.064701 -192.83683)
			(xy 34.102246 -192.877294) (xy 34.133341 -192.922902) (xy 34.157291 -192.972634) (xy 34.173561 -193.025381)
			(xy 34.181788 -193.079964) (xy 34.182304 -193.107564) (xy 34.181934 -193.130542) (xy 34.176197 -193.17614)
			(xy 34.170874 -193.198496) (xy 34.16808 -193.21018) (xy 34.172652 -193.232786) (xy 34.229294 -193.305684)
			(xy 34.236834 -193.314473) (xy 34.257606 -193.32465) (xy 34.269172 -193.325242) (xy 35.868356 -193.325242)
			(xy 35.878386 -193.324831) (xy 35.896925 -193.31717) (xy 35.911122 -193.302998) (xy 35.918814 -193.284472)
			(xy 35.919156 -193.274442) (xy 35.919156 -192.825116) (xy 35.919735 -192.808424) (xy 35.928434 -192.776191)
			(xy 35.945168 -192.747301) (xy 35.968798 -192.723716) (xy 35.997721 -192.707039) (xy 36.029971 -192.698402)
			(xy 36.046664 -192.697862) (xy 37.545264 -192.697862) (xy 37.561962 -192.6984) (xy 37.594226 -192.707024)
			(xy 37.623164 -192.723695) (xy 37.646809 -192.747281) (xy 37.663553 -192.776177) (xy 37.672258 -192.808419)
			(xy 37.672772 -192.825116) (xy 37.672772 -193.274442) (xy 37.673267 -193.284446) (xy 37.680933 -193.302928)
			(xy 37.695083 -193.317075) (xy 37.713568 -193.324736) (xy 37.723572 -193.325242) (xy 40.939974 -193.325242)
			(xy 40.951538 -193.32464) (xy 40.972321 -193.314477) (xy 40.979852 -193.305684) (xy 41.036494 -193.232786)
			(xy 41.041066 -193.21018) (xy 41.038272 -193.198496) (xy 41.032927 -193.176144) (xy 41.027189 -193.130544)
			(xy 41.026842 -193.107564) (xy 41.027358 -193.079964) (xy 41.035585 -193.025381) (xy 41.051855 -192.972634)
			(xy 41.075805 -192.922902) (xy 41.1069 -192.877294) (xy 41.144445 -192.83683) (xy 41.187602 -192.802413)
			(xy 41.235406 -192.774814) (xy 41.28679 -192.754647) (xy 41.340605 -192.742364) (xy 41.39565 -192.738239)
			(xy 41.450695 -192.742364) (xy 41.50451 -192.754647) (xy 41.555894 -192.774814) (xy 41.603698 -192.802413)
			(xy 41.646855 -192.83683) (xy 41.6844 -192.877294) (xy 41.715495 -192.922902) (xy 41.739445 -192.972634)
			(xy 41.755715 -193.025381) (xy 41.763942 -193.079964) (xy 41.764458 -193.107564) (xy 41.764088 -193.130542)
			(xy 41.758352 -193.17614) (xy 41.753028 -193.198496) (xy 41.750234 -193.21018) (xy 41.754806 -193.232786)
			(xy 41.811448 -193.305684) (xy 41.818985 -193.314481) (xy 41.839757 -193.324677) (xy 41.851326 -193.325242)
			(xy 43.412664 -193.325242) (xy 43.42268 -193.324761) (xy 43.441191 -193.317109) (xy 43.455365 -193.302956)
			(xy 43.463045 -193.284457) (xy 43.463464 -193.274442) (xy 43.463464 -192.825116) (xy 43.463958 -192.808427)
			(xy 43.472594 -192.776187) (xy 43.489281 -192.747281) (xy 43.512883 -192.72368) (xy 43.541789 -192.706993)
			(xy 43.574029 -192.698358) (xy 43.590718 -192.697862) (xy 45.089318 -192.697862) (xy 45.105997 -192.698409)
			(xy 45.138218 -192.707047) (xy 45.167105 -192.72373) (xy 45.190691 -192.747322) (xy 45.207366 -192.776213)
			(xy 45.215996 -192.808437) (xy 45.216572 -192.825116) (xy 45.216572 -193.274442) (xy 45.217067 -193.284446)
			(xy 45.224733 -193.302928) (xy 45.238883 -193.317075) (xy 45.257368 -193.324736) (xy 45.267372 -193.325242)
			(xy 48.484028 -193.325242) (xy 48.495587 -193.324629) (xy 48.516352 -193.314453) (xy 48.523906 -193.305684)
			(xy 48.580548 -193.232786) (xy 48.58512 -193.21018) (xy 48.582326 -193.198496) (xy 48.576981 -193.176144)
			(xy 48.571245 -193.130544) (xy 48.570896 -193.107564) (xy 48.571412 -193.079964) (xy 48.579639 -193.025381)
			(xy 48.595909 -192.972634) (xy 48.619859 -192.922902) (xy 48.650954 -192.877294) (xy 48.688499 -192.83683)
			(xy 48.731656 -192.802413) (xy 48.77946 -192.774814) (xy 48.830844 -192.754647) (xy 48.884659 -192.742364)
			(xy 48.939704 -192.738239) (xy 48.994749 -192.742364) (xy 49.048564 -192.754647) (xy 49.099948 -192.774814)
			(xy 49.147752 -192.802413) (xy 49.190909 -192.83683) (xy 49.228454 -192.877294) (xy 49.259549 -192.922902)
			(xy 49.283499 -192.972634) (xy 49.299769 -193.025381) (xy 49.307996 -193.079964) (xy 49.308512 -193.107564)
			(xy 49.308142 -193.130542) (xy 49.302406 -193.17614) (xy 49.297082 -193.198496) (xy 49.294288 -193.21018)
			(xy 49.29886 -193.232786) (xy 49.355502 -193.305684) (xy 49.363042 -193.314472) (xy 49.383815 -193.324646)
			(xy 49.39538 -193.325242) (xy 50.956464 -193.325242) (xy 50.96648 -193.324761) (xy 50.984991 -193.317109)
			(xy 50.999165 -193.302956) (xy 51.006845 -193.284457) (xy 51.007264 -193.274442) (xy 51.007264 -192.825116)
			(xy 51.007843 -192.808424) (xy 51.016543 -192.776192) (xy 51.033276 -192.747303) (xy 51.056907 -192.72372)
			(xy 51.08583 -192.707044) (xy 51.118079 -192.698409) (xy 51.134772 -192.697862) (xy 52.633372 -192.697862)
			(xy 52.65007 -192.698401) (xy 52.682332 -192.707026) (xy 52.711268 -192.723698) (xy 52.734911 -192.747283)
			(xy 52.751654 -192.776179) (xy 52.760358 -192.808419) (xy 52.76088 -192.825116) (xy 52.76088 -193.274442)
			(xy 52.761375 -193.284446) (xy 52.769041 -193.302927) (xy 52.783192 -193.317071) (xy 52.801676 -193.32473)
			(xy 52.81168 -193.325242) (xy 56.028082 -193.325242) (xy 56.039645 -193.324639) (xy 56.060426 -193.314474)
			(xy 56.06796 -193.305684) (xy 56.124602 -193.232786) (xy 56.129174 -193.21018) (xy 56.12638 -193.198496)
			(xy 56.121035 -193.176144) (xy 56.115297 -193.130544) (xy 56.11495 -193.107564) (xy 56.115466 -193.079964)
			(xy 56.123693 -193.025381) (xy 56.139963 -192.972634) (xy 56.163913 -192.922902) (xy 56.195008 -192.877294)
			(xy 56.232553 -192.83683) (xy 56.27571 -192.802413) (xy 56.323514 -192.774814) (xy 56.374898 -192.754647)
			(xy 56.428713 -192.742364) (xy 56.483758 -192.738239) (xy 56.538803 -192.742364) (xy 56.592618 -192.754647)
			(xy 56.644002 -192.774814) (xy 56.691806 -192.802413) (xy 56.734963 -192.83683) (xy 56.772508 -192.877294)
			(xy 56.803603 -192.922902) (xy 56.827553 -192.972634) (xy 56.843823 -193.025381) (xy 56.85205 -193.079964)
			(xy 56.852566 -193.107564) (xy 56.852196 -193.130542) (xy 56.846461 -193.17614) (xy 56.841136 -193.198496)
			(xy 56.838342 -193.21018) (xy 56.842914 -193.232786) (xy 56.899556 -193.305684) (xy 56.907093 -193.314479)
			(xy 56.927866 -193.324672) (xy 56.939434 -193.325242) (xy 58.500772 -193.325242) (xy 58.510786 -193.324759)
			(xy 58.529295 -193.317106) (xy 58.543467 -193.302954) (xy 58.551146 -193.284456) (xy 58.551572 -193.274442)
			(xy 58.551572 -192.825116) (xy 58.552066 -192.808428) (xy 58.560702 -192.776188) (xy 58.57739 -192.747283)
			(xy 58.600991 -192.723684) (xy 58.629897 -192.706998) (xy 58.662138 -192.698365) (xy 58.678826 -192.697862)
			(xy 60.177426 -192.697862) (xy 60.194105 -192.69841) (xy 60.226324 -192.707049) (xy 60.255209 -192.723733)
			(xy 60.278793 -192.747324) (xy 60.295467 -192.776215) (xy 60.304096 -192.808437) (xy 60.30468 -192.825116)
			(xy 60.30468 -193.106548) (xy 60.305113 -193.116589) (xy 60.312828 -193.135132) (xy 60.327061 -193.149301)
			(xy 60.336176 -193.153538) (xy 60.350654 -193.15938) (xy 60.380372 -193.153538) (xy 60.779914 -192.753996)
			(xy 60.786769 -192.746601) (xy 60.794516 -192.728002) (xy 60.7949 -192.717928) (xy 60.7949 -192.124584)
			(xy 60.794474 -192.114515) (xy 60.786755 -192.095915) (xy 60.779914 -192.088516) (xy 60.690252 -191.998854)
			(xy 60.682907 -191.992045) (xy 60.664444 -191.984322) (xy 60.654438 -191.983868) (xy 58.72353 -191.983868)
			(xy 58.711655 -191.984548) (xy 58.690454 -191.995265) (xy 58.68289 -192.004442) (xy 58.62701 -192.079372)
			(xy 58.622692 -192.102486) (xy 58.626248 -192.114424) (xy 58.633254 -192.139822) (xy 58.64077 -192.191968)
			(xy 58.641234 -192.21831) (xy 58.641234 -192.218564) (xy 58.640718 -192.246164) (xy 58.632491 -192.300747)
			(xy 58.616221 -192.353494) (xy 58.592271 -192.403227) (xy 58.561176 -192.448834) (xy 58.523631 -192.489298)
			(xy 58.480474 -192.523715) (xy 58.43267 -192.551314) (xy 58.381286 -192.571481) (xy 58.327471 -192.583764)
			(xy 58.272426 -192.587889) (xy 58.217381 -192.583764) (xy 58.163566 -192.571481) (xy 58.112182 -192.551314)
			(xy 58.064378 -192.523715) (xy 58.021221 -192.489298) (xy 57.983676 -192.448834) (xy 57.952581 -192.403227)
			(xy 57.928631 -192.353494) (xy 57.912361 -192.300747) (xy 57.904134 -192.246164) (xy 57.903618 -192.218564)
			(xy 57.903618 -192.21831) (xy 57.904104 -192.191969) (xy 57.91162 -192.139826) (xy 57.918604 -192.114424)
			(xy 57.92216 -192.102486) (xy 57.917842 -192.079372) (xy 57.861962 -192.004442) (xy 57.8544 -191.995256)
			(xy 57.833202 -191.984517) (xy 57.821322 -191.983868) (xy 56.934862 -191.983868) (xy 56.922995 -191.984562)
			(xy 56.901817 -191.995296) (xy 56.894222 -192.004442) (xy 56.838342 -192.079372) (xy 56.834024 -192.102486)
			(xy 56.83758 -192.114424) (xy 56.844588 -192.139821) (xy 56.852105 -192.191967) (xy 56.852566 -192.21831)
			(xy 56.852566 -192.218564) (xy 56.85205 -192.246164) (xy 56.843823 -192.300747) (xy 56.827553 -192.353494)
			(xy 56.803603 -192.403227) (xy 56.772508 -192.448834) (xy 56.734963 -192.489298) (xy 56.691806 -192.523715)
			(xy 56.644002 -192.551314) (xy 56.592618 -192.571481) (xy 56.538803 -192.583764) (xy 56.483758 -192.587889)
			(xy 56.428713 -192.583764) (xy 56.374898 -192.571481) (xy 56.323514 -192.551314) (xy 56.27571 -192.523715)
			(xy 56.232553 -192.489298) (xy 56.195008 -192.448834) (xy 56.163913 -192.403227) (xy 56.139963 -192.353494)
			(xy 56.123693 -192.300747) (xy 56.115466 -192.246164) (xy 56.11495 -192.218564) (xy 56.115488 -192.190357)
			(xy 56.124082 -192.134601) (xy 56.141063 -192.080804) (xy 56.166036 -192.030219) (xy 56.198419 -191.984025)
			(xy 56.237457 -191.943299) (xy 56.282239 -191.90899) (xy 56.30672 -191.894968) (xy 56.316445 -191.888908)
			(xy 56.32978 -191.870313) (xy 56.332374 -191.859154) (xy 56.342026 -191.802004) (xy 56.337962 -191.79794)
			(xy 53.000656 -188.460634) (xy 52.974134 -188.433325) (xy 52.927119 -188.373448) (xy 52.887602 -188.308379)
			(xy 52.87137 -188.273944) (xy 52.86121 -188.259212) (xy 52.695856 -188.093858) (xy 52.68901 -188.08646)
			(xy 52.681282 -188.067861) (xy 52.68087 -188.05779) (xy 52.68087 -187.878212) (xy 52.680397 -187.867969)
			(xy 52.672398 -187.849109) (xy 52.665376 -187.841636) (xy 52.605686 -187.783724) (xy 52.586636 -187.776358)
			(xy 52.576222 -187.776612) (xy 52.560982 -187.776866) (xy 52.529024 -187.776363) (xy 52.465613 -187.76835)
			(xy 52.403706 -187.752453) (xy 52.34428 -187.728923) (xy 52.288271 -187.69813) (xy 52.236563 -187.660561)
			(xy 52.189972 -187.616807) (xy 52.149232 -187.567558) (xy 52.114985 -187.513592) (xy 52.087771 -187.45576)
			(xy 52.068021 -187.394973) (xy 52.056045 -187.332189) (xy 52.052031 -187.2684) (xy 52.056045 -187.204611)
			(xy 52.068021 -187.141827) (xy 52.087771 -187.08104) (xy 52.114985 -187.023208) (xy 52.149232 -186.969242)
			(xy 52.189972 -186.919993) (xy 52.236563 -186.876239) (xy 52.288271 -186.83867) (xy 52.34428 -186.807877)
			(xy 52.403706 -186.784347) (xy 52.465613 -186.76845) (xy 52.529024 -186.760437) (xy 52.560982 -186.75985)
			(xy 52.576222 -186.760104) (xy 52.586636 -186.760358) (xy 52.605686 -186.752992) (xy 52.665376 -186.69508)
			(xy 52.67244 -186.687633) (xy 52.680455 -186.668758) (xy 52.68087 -186.658504) (xy 52.68087 -186.508136)
			(xy 52.680203 -186.495489) (xy 52.668213 -186.473218) (xy 52.65801 -186.465718) (xy 52.576476 -186.412124)
			(xy 52.551076 -186.409838) (xy 52.539138 -186.414918) (xy 52.51525 -186.424721) (xy 52.465496 -186.438527)
			(xy 52.414333 -186.445495) (xy 52.388516 -186.445906) (xy 52.361263 -186.445444) (xy 52.30731 -186.437689)
			(xy 52.255011 -186.422334) (xy 52.205429 -186.399693) (xy 52.159574 -186.370225) (xy 52.11838 -186.334532)
			(xy 52.082684 -186.293339) (xy 52.053215 -186.247485) (xy 52.030571 -186.197904) (xy 52.015215 -186.145605)
			(xy 52.007457 -186.091653) (xy 52.007457 -186.037147) (xy 52.015215 -185.983195) (xy 52.030571 -185.930896)
			(xy 52.053215 -185.881315) (xy 52.082684 -185.835461) (xy 52.11838 -185.794268) (xy 52.159574 -185.758575)
			(xy 52.205429 -185.729107) (xy 52.255011 -185.706466) (xy 52.30731 -185.691111) (xy 52.361263 -185.683356)
			(xy 52.388516 -185.68289) (xy 52.414332 -185.683318) (xy 52.465494 -185.690282) (xy 52.515249 -185.704081)
			(xy 52.539138 -185.713878) (xy 52.551076 -185.718958) (xy 52.576476 -185.716672) (xy 52.65801 -185.663078)
			(xy 52.668196 -185.655559) (xy 52.680197 -185.633302) (xy 52.68087 -185.62066) (xy 52.68087 -185.53557)
			(xy 50.4952 -183.3499) (xy 50.4952 -179.44338) (xy 47.93742 -176.8856) (xy 17.8943 -176.8856) (xy 11.808341 -182.971559)
			(xy 20.552388 -182.971559) (xy 20.552388 -182.871761) (xy 20.560218 -182.77227) (xy 20.57583 -182.6737)
			(xy 20.599127 -182.576659) (xy 20.629967 -182.481745) (xy 20.668158 -182.389543) (xy 20.713466 -182.300621)
			(xy 20.76561 -182.215529) (xy 20.824271 -182.13479) (xy 20.889085 -182.058903) (xy 20.959653 -181.988335)
			(xy 21.03554 -181.923521) (xy 21.116279 -181.86486) (xy 21.201371 -181.812716) (xy 21.290293 -181.767408)
			(xy 21.382495 -181.729217) (xy 21.477409 -181.698377) (xy 21.57445 -181.67508) (xy 21.67302 -181.659468)
			(xy 21.772511 -181.651638) (xy 21.82241 -181.651148) (xy 21.873807 -181.651673) (xy 21.976263 -181.660012)
			(xy 22.077709 -181.676609) (xy 22.127718 -181.688486) (xy 22.133745 -181.689799) (xy 22.146075 -181.689799)
			(xy 22.152102 -181.688486) (xy 22.202113 -181.676619) (xy 22.303559 -181.660028) (xy 22.406013 -181.651681)
			(xy 22.45741 -181.651148) (xy 22.507309 -181.651646) (xy 22.606799 -181.659476) (xy 22.705369 -181.675088)
			(xy 22.802409 -181.698385) (xy 22.897323 -181.729224) (xy 22.989524 -181.767415) (xy 23.078445 -181.812723)
			(xy 23.163536 -181.864867) (xy 23.244275 -181.923527) (xy 23.320162 -181.98834) (xy 23.39073 -182.058908)
			(xy 23.455543 -182.134795) (xy 23.514203 -182.215534) (xy 23.566347 -182.300625) (xy 23.611655 -182.389546)
			(xy 23.649846 -182.481747) (xy 23.680685 -182.576661) (xy 23.703982 -182.673701) (xy 23.719594 -182.772271)
			(xy 23.727424 -182.871761) (xy 23.727424 -182.971559) (xy 23.719594 -183.071049) (xy 23.703982 -183.169619)
			(xy 23.680685 -183.266659) (xy 23.649846 -183.361573) (xy 23.611655 -183.453774) (xy 23.566347 -183.542695)
			(xy 23.514203 -183.627786) (xy 23.455543 -183.708525) (xy 23.39073 -183.784412) (xy 23.320162 -183.85498)
			(xy 23.244275 -183.919793) (xy 23.163536 -183.978453) (xy 23.078445 -184.030597) (xy 22.989524 -184.075905)
			(xy 22.897323 -184.114096) (xy 22.802409 -184.144935) (xy 22.705369 -184.168232) (xy 22.606799 -184.183844)
			(xy 22.507309 -184.191674) (xy 22.45741 -184.192164) (xy 22.406013 -184.191635) (xy 22.303557 -184.183298)
			(xy 22.202111 -184.166702) (xy 22.152102 -184.154826) (xy 22.146075 -184.153513) (xy 22.133745 -184.153513)
			(xy 22.127718 -184.154826) (xy 22.077706 -184.16669) (xy 21.976261 -184.183282) (xy 21.873807 -184.19163)
			(xy 21.82241 -184.192164) (xy 21.772511 -184.191682) (xy 21.67302 -184.183852) (xy 21.57445 -184.16824)
			(xy 21.477409 -184.144943) (xy 21.382495 -184.114103) (xy 21.290293 -184.075912) (xy 21.201371 -184.030604)
			(xy 21.116279 -183.97846) (xy 21.03554 -183.919799) (xy 20.959653 -183.854985) (xy 20.889085 -183.784417)
			(xy 20.824271 -183.70853) (xy 20.76561 -183.627791) (xy 20.713466 -183.542699) (xy 20.668158 -183.453777)
			(xy 20.629967 -183.361575) (xy 20.599127 -183.266661) (xy 20.57583 -183.16962) (xy 20.560218 -183.07105)
			(xy 20.552388 -182.971559) (xy 11.808341 -182.971559) (xy 10.724642 -184.055258) (xy 10.724642 -184.837832)
			(xy 10.717796 -184.84523) (xy 10.710067 -184.863829) (xy 10.709656 -184.8739) (xy 10.709656 -187.305188)
			(xy 13.780522 -187.305188) (xy 13.78454 -187.204186) (xy 13.796571 -187.103822) (xy 13.816537 -187.004732)
			(xy 13.844313 -186.907541) (xy 13.879724 -186.812864) (xy 13.922544 -186.7213) (xy 13.972504 -186.633427)
			(xy 14.029287 -186.549801) (xy 14.092535 -186.470952) (xy 14.161847 -186.397376) (xy 14.236786 -186.32954)
			(xy 14.316878 -186.267872) (xy 14.401616 -186.212763) (xy 14.490465 -186.16456) (xy 14.582862 -186.123569)
			(xy 14.678225 -186.090048) (xy 14.775949 -186.06421) (xy 14.875416 -186.046217) (xy 14.975999 -186.036185)
			(xy 15.077062 -186.034175) (xy 15.177964 -186.040201) (xy 15.278068 -186.054224) (xy 15.376742 -186.076157)
			(xy 15.473362 -186.10586) (xy 15.567316 -186.143146) (xy 15.658011 -186.187778) (xy 15.744873 -186.239475)
			(xy 15.827353 -186.29791) (xy 15.90493 -186.362713) (xy 15.977112 -186.433475) (xy 16.043445 -186.509748)
			(xy 16.099297 -186.58535) (xy 17.790174 -186.58535) (xy 17.794166 -186.496463) (xy 17.80611 -186.408292)
			(xy 17.825909 -186.321547) (xy 17.853404 -186.236926) (xy 17.888374 -186.15511) (xy 17.930537 -186.076757)
			(xy 17.979553 -186.0025) (xy 18.035029 -185.932936) (xy 18.096517 -185.868624) (xy 18.163522 -185.810083)
			(xy 18.235505 -185.757784) (xy 18.311887 -185.712148) (xy 18.392051 -185.673542) (xy 18.475354 -185.642278)
			(xy 18.561124 -185.618607) (xy 18.64867 -185.602719) (xy 18.737288 -185.594743) (xy 18.781776 -185.594244)
			(xy 20.534376 -185.594244) (xy 20.578865 -185.594724) (xy 20.667485 -185.6027) (xy 20.755034 -185.618587)
			(xy 20.840806 -185.642259) (xy 20.92411 -185.673523) (xy 21.004277 -185.712129) (xy 21.080661 -185.757766)
			(xy 21.152646 -185.810066) (xy 21.219653 -185.868608) (xy 21.281143 -185.932921) (xy 21.33662 -186.002487)
			(xy 21.385638 -186.076746) (xy 21.427802 -186.155099) (xy 21.462773 -186.236917) (xy 21.490269 -186.321541)
			(xy 21.510068 -186.408288) (xy 21.522012 -186.496461) (xy 21.526004 -186.58535) (xy 25.334225 -186.58535)
			(xy 25.338216 -186.496463) (xy 25.35016 -186.408292) (xy 25.369959 -186.321546) (xy 25.397454 -186.236925)
			(xy 25.432424 -186.155108) (xy 25.474587 -186.076756) (xy 25.523604 -186.002499) (xy 25.57908 -185.932934)
			(xy 25.640568 -185.868623) (xy 25.707574 -185.810082) (xy 25.779558 -185.757783) (xy 25.855939 -185.712147)
			(xy 25.936104 -185.673541) (xy 26.019407 -185.642277) (xy 26.105177 -185.618606) (xy 26.192724 -185.602719)
			(xy 26.281342 -185.594743) (xy 26.32583 -185.594244) (xy 28.07843 -185.594244) (xy 28.122918 -185.594739)
			(xy 28.211537 -185.602715) (xy 28.299084 -185.618602) (xy 28.384854 -185.642273) (xy 28.468157 -185.673538)
			(xy 28.548323 -185.712143) (xy 28.624705 -185.757779) (xy 28.696688 -185.810078) (xy 28.763694 -185.86862)
			(xy 28.825183 -185.932932) (xy 28.880659 -186.002497) (xy 28.929676 -186.076754) (xy 28.971839 -186.155107)
			(xy 29.006809 -186.236923) (xy 29.034305 -186.321545) (xy 29.054104 -186.408291) (xy 29.066048 -186.496463)
			(xy 29.07004 -186.58535) (xy 32.878025 -186.58535) (xy 32.882016 -186.496463) (xy 32.89396 -186.408292)
			(xy 32.913759 -186.321546) (xy 32.941254 -186.236925) (xy 32.976224 -186.155108) (xy 33.018387 -186.076756)
			(xy 33.067404 -186.002499) (xy 33.12288 -185.932934) (xy 33.184368 -185.868623) (xy 33.251374 -185.810082)
			(xy 33.323358 -185.757783) (xy 33.399739 -185.712147) (xy 33.479904 -185.673541) (xy 33.563207 -185.642277)
			(xy 33.648977 -185.618606) (xy 33.736524 -185.602719) (xy 33.825142 -185.594743) (xy 33.86963 -185.594244)
			(xy 35.62223 -185.594244) (xy 35.666718 -185.594739) (xy 35.755337 -185.602715) (xy 35.842884 -185.618602)
			(xy 35.928654 -185.642273) (xy 36.011957 -185.673538) (xy 36.092123 -185.712143) (xy 36.168505 -185.757779)
			(xy 36.240488 -185.810078) (xy 36.307494 -185.86862) (xy 36.368983 -185.932932) (xy 36.424459 -186.002497)
			(xy 36.473476 -186.076754) (xy 36.515639 -186.155107) (xy 36.550609 -186.236923) (xy 36.578105 -186.321545)
			(xy 36.597904 -186.408291) (xy 36.609848 -186.496463) (xy 36.61384 -186.58535) (xy 40.42206 -186.58535)
			(xy 40.426052 -186.496462) (xy 40.437996 -186.408289) (xy 40.457795 -186.321542) (xy 40.485291 -186.236919)
			(xy 40.520262 -186.155101) (xy 40.562426 -186.076748) (xy 40.611444 -186.002489) (xy 40.66692 -185.932923)
			(xy 40.72841 -185.868611) (xy 40.795417 -185.810069) (xy 40.867402 -185.757769) (xy 40.943785 -185.712133)
			(xy 41.023951 -185.673527) (xy 41.107256 -185.642262) (xy 41.193027 -185.618591) (xy 41.280575 -185.602704)
			(xy 41.369195 -185.594728) (xy 41.413684 -185.594244) (xy 43.166284 -185.594244) (xy 43.210772 -185.594739)
			(xy 43.299391 -185.602715) (xy 43.386937 -185.618603) (xy 43.472707 -185.642274) (xy 43.55601 -185.673539)
			(xy 43.636175 -185.712144) (xy 43.712557 -185.757781) (xy 43.78454 -185.81008) (xy 43.851546 -185.868621)
			(xy 43.869737 -185.887647) (xy 47.385014 -185.887647) (xy 47.385014 -185.833153) (xy 47.392769 -185.779213)
			(xy 47.408121 -185.726925) (xy 47.430758 -185.677355) (xy 47.460219 -185.63151) (xy 47.495904 -185.590325)
			(xy 47.537086 -185.554637) (xy 47.582929 -185.525172) (xy 47.632497 -185.502532) (xy 47.684783 -185.487175)
			(xy 47.738723 -185.479416) (xy 47.76597 -185.478928) (xy 47.794951 -185.479404) (xy 47.85225 -185.488155)
			(xy 47.907565 -185.505474) (xy 47.959622 -185.530962) (xy 48.007224 -185.564034) (xy 48.049274 -185.603928)
			(xy 48.084803 -185.649724) (xy 48.112995 -185.700369) (xy 48.133199 -185.754696) (xy 48.139604 -185.782966)
			(xy 48.142398 -185.796428) (xy 48.160178 -185.816494) (xy 48.269144 -185.853324) (xy 48.29556 -185.84799)
			(xy 48.305974 -185.838846) (xy 48.339804 -185.809988) (xy 48.411762 -185.757737) (xy 48.48811 -185.712139)
			(xy 48.568234 -185.673562) (xy 48.651491 -185.642314) (xy 48.737212 -185.618648) (xy 48.824707 -185.602753)
			(xy 48.913274 -185.594758) (xy 48.957738 -185.594244) (xy 50.710338 -185.594244) (xy 50.754827 -185.594724)
			(xy 50.843447 -185.6027) (xy 50.930995 -185.618588) (xy 51.016767 -185.642259) (xy 51.100072 -185.673524)
			(xy 51.180238 -185.71213) (xy 51.256622 -185.757766) (xy 51.328607 -185.810066) (xy 51.395614 -185.868609)
			(xy 51.457103 -185.932921) (xy 51.51258 -186.002487) (xy 51.561598 -186.076746) (xy 51.603762 -186.1551)
			(xy 51.638733 -186.236918) (xy 51.666229 -186.321541) (xy 51.686028 -186.408288) (xy 51.697972 -186.496461)
			(xy 51.701964 -186.58535) (xy 51.697972 -186.674239) (xy 51.686028 -186.762412) (xy 51.666229 -186.849159)
			(xy 51.638733 -186.933782) (xy 51.603762 -187.0156) (xy 51.561598 -187.093954) (xy 51.51258 -187.168213)
			(xy 51.457103 -187.237779) (xy 51.395614 -187.302091) (xy 51.328607 -187.360634) (xy 51.256622 -187.412934)
			(xy 51.180238 -187.45857) (xy 51.100072 -187.497176) (xy 51.016767 -187.528441) (xy 50.930995 -187.552112)
			(xy 50.843447 -187.568) (xy 50.754827 -187.575976) (xy 50.710338 -187.57646) (xy 48.957738 -187.57646)
			(xy 48.911945 -187.575905) (xy 48.82075 -187.567456) (xy 48.730723 -187.550628) (xy 48.642634 -187.525563)
			(xy 48.557234 -187.492476) (xy 48.475252 -187.451649) (xy 48.397387 -187.40343) (xy 48.324304 -187.348231)
			(xy 48.256628 -187.286524) (xy 48.194934 -187.218834) (xy 48.139751 -187.14574) (xy 48.091549 -187.067865)
			(xy 48.050739 -186.985874) (xy 48.01767 -186.900467) (xy 47.992624 -186.812372) (xy 47.975815 -186.722342)
			(xy 47.967386 -186.631145) (xy 47.966884 -186.585352) (xy 47.967237 -186.545686) (xy 47.973498 -186.466601)
			(xy 47.986064 -186.38827) (xy 47.995078 -186.34964) (xy 47.99838 -186.336432) (xy 47.991014 -186.310524)
			(xy 47.90821 -186.230768) (xy 47.882302 -186.224164) (xy 47.869094 -186.22772) (xy 47.843833 -186.234372)
			(xy 47.792088 -186.241514) (xy 47.76597 -186.241944) (xy 47.738723 -186.241384) (xy 47.684783 -186.233625)
			(xy 47.632497 -186.218268) (xy 47.582929 -186.195628) (xy 47.537086 -186.166163) (xy 47.495904 -186.130475)
			(xy 47.460219 -186.08929) (xy 47.430758 -186.043445) (xy 47.408121 -185.993875) (xy 47.392769 -185.941587)
			(xy 47.385014 -185.887647) (xy 43.869737 -185.887647) (xy 43.913034 -185.932933) (xy 43.96851 -186.002498)
			(xy 44.017527 -186.076755) (xy 44.05969 -186.155108) (xy 44.09466 -186.236924) (xy 44.122155 -186.321546)
			(xy 44.141954 -186.408292) (xy 44.153898 -186.496463) (xy 44.15789 -186.58535) (xy 44.153898 -186.674237)
			(xy 44.141954 -186.762408) (xy 44.122155 -186.849154) (xy 44.09466 -186.933776) (xy 44.05969 -187.015592)
			(xy 44.017527 -187.093945) (xy 43.96851 -187.168202) (xy 43.913034 -187.237767) (xy 43.851546 -187.302079)
			(xy 43.78454 -187.36062) (xy 43.712557 -187.412919) (xy 43.636175 -187.458556) (xy 43.55601 -187.497161)
			(xy 43.472707 -187.528426) (xy 43.386937 -187.552097) (xy 43.299391 -187.567985) (xy 43.210772 -187.575961)
			(xy 43.166284 -187.57646) (xy 41.413684 -187.57646) (xy 41.369195 -187.575972) (xy 41.280575 -187.567996)
			(xy 41.193027 -187.552109) (xy 41.107256 -187.528438) (xy 41.023951 -187.497173) (xy 40.943785 -187.458567)
			(xy 40.867402 -187.412931) (xy 40.795417 -187.360631) (xy 40.72841 -187.302089) (xy 40.66692 -187.237777)
			(xy 40.611444 -187.168211) (xy 40.562426 -187.093952) (xy 40.520262 -187.015599) (xy 40.485291 -186.933781)
			(xy 40.457795 -186.849158) (xy 40.437996 -186.762411) (xy 40.426052 -186.674238) (xy 40.42206 -186.58535)
			(xy 36.61384 -186.58535) (xy 36.609848 -186.674237) (xy 36.597904 -186.762409) (xy 36.578105 -186.849155)
			(xy 36.550609 -186.933777) (xy 36.515639 -187.015593) (xy 36.473476 -187.093946) (xy 36.424459 -187.168203)
			(xy 36.368983 -187.237768) (xy 36.307494 -187.30208) (xy 36.240488 -187.360622) (xy 36.168505 -187.412921)
			(xy 36.092123 -187.458557) (xy 36.011957 -187.497162) (xy 35.928654 -187.528427) (xy 35.842884 -187.552098)
			(xy 35.755337 -187.567985) (xy 35.666718 -187.575961) (xy 35.62223 -187.57646) (xy 33.86963 -187.57646)
			(xy 33.825142 -187.575957) (xy 33.736524 -187.567981) (xy 33.648977 -187.552094) (xy 33.563207 -187.528423)
			(xy 33.479904 -187.497159) (xy 33.399739 -187.458553) (xy 33.323358 -187.412917) (xy 33.251374 -187.360618)
			(xy 33.184368 -187.302077) (xy 33.12288 -187.237766) (xy 33.067404 -187.168201) (xy 33.018387 -187.093944)
			(xy 32.976224 -187.015592) (xy 32.941254 -186.933775) (xy 32.913759 -186.849154) (xy 32.89396 -186.762408)
			(xy 32.882016 -186.674237) (xy 32.878025 -186.58535) (xy 29.07004 -186.58535) (xy 29.066048 -186.674237)
			(xy 29.054104 -186.762409) (xy 29.034305 -186.849155) (xy 29.006809 -186.933777) (xy 28.971839 -187.015593)
			(xy 28.929676 -187.093946) (xy 28.880659 -187.168203) (xy 28.825183 -187.237768) (xy 28.763694 -187.30208)
			(xy 28.696688 -187.360622) (xy 28.624705 -187.412921) (xy 28.548323 -187.458557) (xy 28.468157 -187.497162)
			(xy 28.384854 -187.528427) (xy 28.299084 -187.552098) (xy 28.211537 -187.567985) (xy 28.122918 -187.575961)
			(xy 28.07843 -187.57646) (xy 26.32583 -187.57646) (xy 26.281342 -187.575957) (xy 26.192724 -187.567981)
			(xy 26.105177 -187.552094) (xy 26.019407 -187.528423) (xy 25.936104 -187.497159) (xy 25.855939 -187.458553)
			(xy 25.779558 -187.412917) (xy 25.707574 -187.360618) (xy 25.640568 -187.302077) (xy 25.57908 -187.237766)
			(xy 25.523604 -187.168201) (xy 25.474587 -187.093944) (xy 25.432424 -187.015592) (xy 25.397454 -186.933775)
			(xy 25.369959 -186.849154) (xy 25.35016 -186.762408) (xy 25.338216 -186.674237) (xy 25.334225 -186.58535)
			(xy 21.526004 -186.58535) (xy 21.522012 -186.674239) (xy 21.510068 -186.762412) (xy 21.490269 -186.849159)
			(xy 21.462773 -186.933783) (xy 21.427802 -187.015601) (xy 21.385638 -187.093954) (xy 21.33662 -187.168213)
			(xy 21.281143 -187.237779) (xy 21.219653 -187.302092) (xy 21.152646 -187.360634) (xy 21.080661 -187.412934)
			(xy 21.004277 -187.458571) (xy 20.92411 -187.497177) (xy 20.840806 -187.528441) (xy 20.755034 -187.552113)
			(xy 20.667485 -187.568) (xy 20.578865 -187.575976) (xy 20.534376 -187.57646) (xy 18.781776 -187.57646)
			(xy 18.737288 -187.575957) (xy 18.64867 -187.567981) (xy 18.561124 -187.552093) (xy 18.475354 -187.528422)
			(xy 18.392051 -187.497158) (xy 18.311887 -187.458552) (xy 18.235505 -187.412916) (xy 18.163522 -187.360617)
			(xy 18.096517 -187.302076) (xy 18.035029 -187.237764) (xy 17.979553 -187.1682) (xy 17.930537 -187.093943)
			(xy 17.888374 -187.01559) (xy 17.853404 -186.933774) (xy 17.825909 -186.849153) (xy 17.80611 -186.762408)
			(xy 17.794166 -186.674237) (xy 17.790174 -186.58535) (xy 16.099297 -186.58535) (xy 16.103508 -186.59105)
			(xy 16.156922 -186.676867) (xy 16.203349 -186.766656) (xy 16.242495 -186.85985) (xy 16.274113 -186.95586)
			(xy 16.298003 -187.054078) (xy 16.314014 -187.153884) (xy 16.322045 -187.254647) (xy 16.322548 -187.305188)
			(xy 16.322045 -187.355729) (xy 16.314014 -187.456492) (xy 16.298003 -187.556298) (xy 16.274113 -187.654516)
			(xy 16.242495 -187.750526) (xy 16.203349 -187.84372) (xy 16.156922 -187.933509) (xy 16.103508 -188.019326)
			(xy 16.043445 -188.100628) (xy 15.977112 -188.176901) (xy 15.90493 -188.247663) (xy 15.827353 -188.312466)
			(xy 15.744873 -188.370901) (xy 15.658011 -188.422598) (xy 15.567316 -188.46723) (xy 15.473362 -188.504516)
			(xy 15.376742 -188.534219) (xy 15.278068 -188.556152) (xy 15.177964 -188.570175) (xy 15.077062 -188.576201)
			(xy 14.975999 -188.574191) (xy 14.875416 -188.564159) (xy 14.775949 -188.546166) (xy 14.678225 -188.520328)
			(xy 14.582862 -188.486807) (xy 14.490465 -188.445816) (xy 14.401616 -188.397613) (xy 14.316878 -188.342504)
			(xy 14.236786 -188.280836) (xy 14.161847 -188.213) (xy 14.092535 -188.139424) (xy 14.029287 -188.060575)
			(xy 13.972504 -187.976949) (xy 13.922544 -187.889076) (xy 13.879724 -187.797512) (xy 13.844313 -187.702835)
			(xy 13.816537 -187.605644) (xy 13.796571 -187.506554) (xy 13.78454 -187.40619) (xy 13.780522 -187.305188)
			(xy 10.709656 -187.305188) (xy 10.709656 -191.81318) (xy 10.915396 -192.01892) (xy 12.2301 -192.01892)
			(xy 12.3571 -191.89192) (xy 12.3571 -190.86322) (xy 12.42314 -190.79718) (xy 13.37056 -190.79718)
			(xy 13.404596 -190.831216) (xy 13.404596 -192.218564) (xy 18.394441 -192.218564) (xy 18.398376 -192.164793)
			(xy 18.410099 -192.112169) (xy 18.429359 -192.061812) (xy 18.455745 -192.014795) (xy 18.488697 -191.972122)
			(xy 18.52751 -191.934701) (xy 18.571358 -191.903331) (xy 18.619306 -191.878679) (xy 18.670333 -191.861271)
			(xy 18.723351 -191.851478) (xy 18.77723 -191.849509) (xy 18.830821 -191.855406) (xy 18.882982 -191.869042)
			(xy 18.932602 -191.890129) (xy 18.978623 -191.918215) (xy 19.020065 -191.952703) (xy 19.056043 -191.992857)
			(xy 19.085791 -192.037821) (xy 19.108676 -192.086638) (xy 19.124208 -192.138267) (xy 19.132058 -192.191607)
			(xy 19.13255 -192.218564) (xy 20.183109 -192.218564) (xy 20.187044 -192.164793) (xy 20.198767 -192.112169)
			(xy 20.218027 -192.061812) (xy 20.244413 -192.014795) (xy 20.277365 -191.972122) (xy 20.316178 -191.934701)
			(xy 20.360026 -191.903331) (xy 20.407974 -191.878679) (xy 20.459001 -191.861271) (xy 20.512019 -191.851478)
			(xy 20.565898 -191.849509) (xy 20.619489 -191.855406) (xy 20.67165 -191.869042) (xy 20.72127 -191.890129)
			(xy 20.767291 -191.918215) (xy 20.808733 -191.952703) (xy 20.844711 -191.992857) (xy 20.874459 -192.037821)
			(xy 20.897344 -192.086638) (xy 20.912876 -192.138267) (xy 20.920726 -192.191607) (xy 20.921218 -192.218564)
			(xy 25.938495 -192.218564) (xy 25.94243 -192.164793) (xy 25.954153 -192.112169) (xy 25.973413 -192.061812)
			(xy 25.999799 -192.014795) (xy 26.032751 -191.972122) (xy 26.071564 -191.934701) (xy 26.115412 -191.903331)
			(xy 26.16336 -191.878679) (xy 26.214387 -191.861271) (xy 26.267405 -191.851478) (xy 26.321284 -191.849509)
			(xy 26.374875 -191.855406) (xy 26.427036 -191.869042) (xy 26.476656 -191.890129) (xy 26.522677 -191.918215)
			(xy 26.564119 -191.952703) (xy 26.600097 -191.992857) (xy 26.629845 -192.037821) (xy 26.65273 -192.086638)
			(xy 26.668262 -192.138267) (xy 26.676112 -192.191607) (xy 26.676604 -192.218564) (xy 27.727163 -192.218564)
			(xy 27.731098 -192.164793) (xy 27.742821 -192.112169) (xy 27.762081 -192.061812) (xy 27.788467 -192.014795)
			(xy 27.821419 -191.972122) (xy 27.860232 -191.934701) (xy 27.90408 -191.903331) (xy 27.952028 -191.878679)
			(xy 28.003055 -191.861271) (xy 28.056073 -191.851478) (xy 28.109952 -191.849509) (xy 28.163543 -191.855406)
			(xy 28.215704 -191.869042) (xy 28.265324 -191.890129) (xy 28.311345 -191.918215) (xy 28.352787 -191.952703)
			(xy 28.388765 -191.992857) (xy 28.418513 -192.037821) (xy 28.441398 -192.086638) (xy 28.45693 -192.138267)
			(xy 28.46478 -192.191607) (xy 28.465272 -192.218564) (xy 33.444195 -192.218564) (xy 33.44813 -192.164793)
			(xy 33.459853 -192.112169) (xy 33.479113 -192.061812) (xy 33.505499 -192.014795) (xy 33.538451 -191.972122)
			(xy 33.577264 -191.934701) (xy 33.621112 -191.903331) (xy 33.66906 -191.878679) (xy 33.720087 -191.861271)
			(xy 33.773105 -191.851478) (xy 33.826984 -191.849509) (xy 33.880575 -191.855406) (xy 33.932736 -191.869042)
			(xy 33.982356 -191.890129) (xy 34.028377 -191.918215) (xy 34.069819 -191.952703) (xy 34.105797 -191.992857)
			(xy 34.135545 -192.037821) (xy 34.15843 -192.086638) (xy 34.173962 -192.138267) (xy 34.181812 -192.191607)
			(xy 34.182304 -192.218564) (xy 35.270963 -192.218564) (xy 35.274898 -192.164793) (xy 35.286621 -192.112169)
			(xy 35.305881 -192.061812) (xy 35.332267 -192.014795) (xy 35.365219 -191.972122) (xy 35.404032 -191.934701)
			(xy 35.44788 -191.903331) (xy 35.495828 -191.878679) (xy 35.546855 -191.861271) (xy 35.599873 -191.851478)
			(xy 35.653752 -191.849509) (xy 35.707343 -191.855406) (xy 35.759504 -191.869042) (xy 35.809124 -191.890129)
			(xy 35.855145 -191.918215) (xy 35.896587 -191.952703) (xy 35.932565 -191.992857) (xy 35.962313 -192.037821)
			(xy 35.985198 -192.086638) (xy 36.00073 -192.138267) (xy 36.00858 -192.191607) (xy 36.009072 -192.218564)
			(xy 41.026349 -192.218564) (xy 41.030284 -192.164793) (xy 41.042007 -192.112169) (xy 41.061267 -192.061812)
			(xy 41.087653 -192.014795) (xy 41.120605 -191.972122) (xy 41.159418 -191.934701) (xy 41.203266 -191.903331)
			(xy 41.251214 -191.878679) (xy 41.302241 -191.861271) (xy 41.355259 -191.851478) (xy 41.409138 -191.849509)
			(xy 41.462729 -191.855406) (xy 41.51489 -191.869042) (xy 41.56451 -191.890129) (xy 41.610531 -191.918215)
			(xy 41.651973 -191.952703) (xy 41.687951 -191.992857) (xy 41.717699 -192.037821) (xy 41.740584 -192.086638)
			(xy 41.756116 -192.138267) (xy 41.763966 -192.191607) (xy 41.764458 -192.218564) (xy 42.815017 -192.218564)
			(xy 42.818952 -192.164793) (xy 42.830675 -192.112169) (xy 42.849935 -192.061812) (xy 42.876321 -192.014795)
			(xy 42.909273 -191.972122) (xy 42.948086 -191.934701) (xy 42.991934 -191.903331) (xy 43.039882 -191.878679)
			(xy 43.090909 -191.861271) (xy 43.143927 -191.851478) (xy 43.197806 -191.849509) (xy 43.251397 -191.855406)
			(xy 43.303558 -191.869042) (xy 43.353178 -191.890129) (xy 43.399199 -191.918215) (xy 43.440641 -191.952703)
			(xy 43.476619 -191.992857) (xy 43.506367 -192.037821) (xy 43.529252 -192.086638) (xy 43.544784 -192.138267)
			(xy 43.552634 -192.191607) (xy 43.553126 -192.218564) (xy 48.570403 -192.218564) (xy 48.574338 -192.164793)
			(xy 48.586061 -192.112169) (xy 48.605321 -192.061812) (xy 48.631707 -192.014795) (xy 48.664659 -191.972122)
			(xy 48.703472 -191.934701) (xy 48.74732 -191.903331) (xy 48.795268 -191.878679) (xy 48.846295 -191.861271)
			(xy 48.899313 -191.851478) (xy 48.953192 -191.849509) (xy 49.006783 -191.855406) (xy 49.058944 -191.869042)
			(xy 49.108564 -191.890129) (xy 49.154585 -191.918215) (xy 49.196027 -191.952703) (xy 49.232005 -191.992857)
			(xy 49.261753 -192.037821) (xy 49.284638 -192.086638) (xy 49.30017 -192.138267) (xy 49.30802 -192.191607)
			(xy 49.308512 -192.218564) (xy 50.359071 -192.218564) (xy 50.363006 -192.164793) (xy 50.374729 -192.112169)
			(xy 50.393989 -192.061812) (xy 50.420375 -192.014795) (xy 50.453327 -191.972122) (xy 50.49214 -191.934701)
			(xy 50.535988 -191.903331) (xy 50.583936 -191.878679) (xy 50.634963 -191.861271) (xy 50.687981 -191.851478)
			(xy 50.74186 -191.849509) (xy 50.795451 -191.855406) (xy 50.847612 -191.869042) (xy 50.897232 -191.890129)
			(xy 50.943253 -191.918215) (xy 50.984695 -191.952703) (xy 51.020673 -191.992857) (xy 51.050421 -192.037821)
			(xy 51.073306 -192.086638) (xy 51.088838 -192.138267) (xy 51.096688 -192.191607) (xy 51.09718 -192.218564)
			(xy 51.096688 -192.245521) (xy 51.088838 -192.298861) (xy 51.073306 -192.35049) (xy 51.050421 -192.399307)
			(xy 51.020673 -192.444271) (xy 50.984695 -192.484425) (xy 50.943253 -192.518913) (xy 50.897232 -192.546999)
			(xy 50.847612 -192.568086) (xy 50.795451 -192.581722) (xy 50.74186 -192.587619) (xy 50.687981 -192.58565)
			(xy 50.634963 -192.575857) (xy 50.583936 -192.558449) (xy 50.535988 -192.533797) (xy 50.49214 -192.502427)
			(xy 50.453327 -192.465006) (xy 50.420375 -192.422333) (xy 50.393989 -192.375316) (xy 50.374729 -192.324959)
			(xy 50.363006 -192.272335) (xy 50.359071 -192.218564) (xy 49.308512 -192.218564) (xy 49.30802 -192.245521)
			(xy 49.30017 -192.298861) (xy 49.284638 -192.35049) (xy 49.261753 -192.399307) (xy 49.232005 -192.444271)
			(xy 49.196027 -192.484425) (xy 49.154585 -192.518913) (xy 49.108564 -192.546999) (xy 49.058944 -192.568086)
			(xy 49.006783 -192.581722) (xy 48.953192 -192.587619) (xy 48.899313 -192.58565) (xy 48.846295 -192.575857)
			(xy 48.795268 -192.558449) (xy 48.74732 -192.533797) (xy 48.703472 -192.502427) (xy 48.664659 -192.465006)
			(xy 48.631707 -192.422333) (xy 48.605321 -192.375316) (xy 48.586061 -192.324959) (xy 48.574338 -192.272335)
			(xy 48.570403 -192.218564) (xy 43.553126 -192.218564) (xy 43.552634 -192.245521) (xy 43.544784 -192.298861)
			(xy 43.529252 -192.35049) (xy 43.506367 -192.399307) (xy 43.476619 -192.444271) (xy 43.440641 -192.484425)
			(xy 43.399199 -192.518913) (xy 43.353178 -192.546999) (xy 43.303558 -192.568086) (xy 43.251397 -192.581722)
			(xy 43.197806 -192.587619) (xy 43.143927 -192.58565) (xy 43.090909 -192.575857) (xy 43.039882 -192.558449)
			(xy 42.991934 -192.533797) (xy 42.948086 -192.502427) (xy 42.909273 -192.465006) (xy 42.876321 -192.422333)
			(xy 42.849935 -192.375316) (xy 42.830675 -192.324959) (xy 42.818952 -192.272335) (xy 42.815017 -192.218564)
			(xy 41.764458 -192.218564) (xy 41.763966 -192.245521) (xy 41.756116 -192.298861) (xy 41.740584 -192.35049)
			(xy 41.717699 -192.399307) (xy 41.687951 -192.444271) (xy 41.651973 -192.484425) (xy 41.610531 -192.518913)
			(xy 41.56451 -192.546999) (xy 41.51489 -192.568086) (xy 41.462729 -192.581722) (xy 41.409138 -192.587619)
			(xy 41.355259 -192.58565) (xy 41.302241 -192.575857) (xy 41.251214 -192.558449) (xy 41.203266 -192.533797)
			(xy 41.159418 -192.502427) (xy 41.120605 -192.465006) (xy 41.087653 -192.422333) (xy 41.061267 -192.375316)
			(xy 41.042007 -192.324959) (xy 41.030284 -192.272335) (xy 41.026349 -192.218564) (xy 36.009072 -192.218564)
			(xy 36.00858 -192.245521) (xy 36.00073 -192.298861) (xy 35.985198 -192.35049) (xy 35.962313 -192.399307)
			(xy 35.932565 -192.444271) (xy 35.896587 -192.484425) (xy 35.855145 -192.518913) (xy 35.809124 -192.546999)
			(xy 35.759504 -192.568086) (xy 35.707343 -192.581722) (xy 35.653752 -192.587619) (xy 35.599873 -192.58565)
			(xy 35.546855 -192.575857) (xy 35.495828 -192.558449) (xy 35.44788 -192.533797) (xy 35.404032 -192.502427)
			(xy 35.365219 -192.465006) (xy 35.332267 -192.422333) (xy 35.305881 -192.375316) (xy 35.286621 -192.324959)
			(xy 35.274898 -192.272335) (xy 35.270963 -192.218564) (xy 34.182304 -192.218564) (xy 34.181812 -192.245521)
			(xy 34.173962 -192.298861) (xy 34.15843 -192.35049) (xy 34.135545 -192.399307) (xy 34.105797 -192.444271)
			(xy 34.069819 -192.484425) (xy 34.028377 -192.518913) (xy 33.982356 -192.546999) (xy 33.932736 -192.568086)
			(xy 33.880575 -192.581722) (xy 33.826984 -192.587619) (xy 33.773105 -192.58565) (xy 33.720087 -192.575857)
			(xy 33.66906 -192.558449) (xy 33.621112 -192.533797) (xy 33.577264 -192.502427) (xy 33.538451 -192.465006)
			(xy 33.505499 -192.422333) (xy 33.479113 -192.375316) (xy 33.459853 -192.324959) (xy 33.44813 -192.272335)
			(xy 33.444195 -192.218564) (xy 28.465272 -192.218564) (xy 28.46478 -192.245521) (xy 28.45693 -192.298861)
			(xy 28.441398 -192.35049) (xy 28.418513 -192.399307) (xy 28.388765 -192.444271) (xy 28.352787 -192.484425)
			(xy 28.311345 -192.518913) (xy 28.265324 -192.546999) (xy 28.215704 -192.568086) (xy 28.163543 -192.581722)
			(xy 28.109952 -192.587619) (xy 28.056073 -192.58565) (xy 28.003055 -192.575857) (xy 27.952028 -192.558449)
			(xy 27.90408 -192.533797) (xy 27.860232 -192.502427) (xy 27.821419 -192.465006) (xy 27.788467 -192.422333)
			(xy 27.762081 -192.375316) (xy 27.742821 -192.324959) (xy 27.731098 -192.272335) (xy 27.727163 -192.218564)
			(xy 26.676604 -192.218564) (xy 26.676112 -192.245521) (xy 26.668262 -192.298861) (xy 26.65273 -192.35049)
			(xy 26.629845 -192.399307) (xy 26.600097 -192.444271) (xy 26.564119 -192.484425) (xy 26.522677 -192.518913)
			(xy 26.476656 -192.546999) (xy 26.427036 -192.568086) (xy 26.374875 -192.581722) (xy 26.321284 -192.587619)
			(xy 26.267405 -192.58565) (xy 26.214387 -192.575857) (xy 26.16336 -192.558449) (xy 26.115412 -192.533797)
			(xy 26.071564 -192.502427) (xy 26.032751 -192.465006) (xy 25.999799 -192.422333) (xy 25.973413 -192.375316)
			(xy 25.954153 -192.324959) (xy 25.94243 -192.272335) (xy 25.938495 -192.218564) (xy 20.921218 -192.218564)
			(xy 20.920726 -192.245521) (xy 20.912876 -192.298861) (xy 20.897344 -192.35049) (xy 20.874459 -192.399307)
			(xy 20.844711 -192.444271) (xy 20.808733 -192.484425) (xy 20.767291 -192.518913) (xy 20.72127 -192.546999)
			(xy 20.67165 -192.568086) (xy 20.619489 -192.581722) (xy 20.565898 -192.587619) (xy 20.512019 -192.58565)
			(xy 20.459001 -192.575857) (xy 20.407974 -192.558449) (xy 20.360026 -192.533797) (xy 20.316178 -192.502427)
			(xy 20.277365 -192.465006) (xy 20.244413 -192.422333) (xy 20.218027 -192.375316) (xy 20.198767 -192.324959)
			(xy 20.187044 -192.272335) (xy 20.183109 -192.218564) (xy 19.13255 -192.218564) (xy 19.132058 -192.245521)
			(xy 19.124208 -192.298861) (xy 19.108676 -192.35049) (xy 19.085791 -192.399307) (xy 19.056043 -192.444271)
			(xy 19.020065 -192.484425) (xy 18.978623 -192.518913) (xy 18.932602 -192.546999) (xy 18.882982 -192.568086)
			(xy 18.830821 -192.581722) (xy 18.77723 -192.587619) (xy 18.723351 -192.58565) (xy 18.670333 -192.575857)
			(xy 18.619306 -192.558449) (xy 18.571358 -192.533797) (xy 18.52751 -192.502427) (xy 18.488697 -192.465006)
			(xy 18.455745 -192.422333) (xy 18.429359 -192.375316) (xy 18.410099 -192.324959) (xy 18.398376 -192.272335)
			(xy 18.394441 -192.218564) (xy 13.404596 -192.218564) (xy 13.404596 -193.023998) (xy 13.70584 -193.325242)
		)
		(stroke
			(width 0)
			(type solid)
		)
		(fill yes)
		(layer "F.Cu")
		(net "P12V_MEM_CPU1")
	)
	(gr_line
		(start 10.394188 -421.200326)
		(end 10.664698 -420.929816)
		(stroke
			(width 0.06477)
			(type default)
		)
		(layer "F.Cu")
	)
	(gr_line
		(start 10.394188 -420.336726)
		(end 10.664698 -420.607236)
		(stroke
			(width 0.06477)
			(type default)
		)
		(layer "F.Cu")
	)
	(gr_line
		(start 10.856976 -425.617132)
		(end 10.586466 -425.887642)
		(stroke
			(width 0.06477)
			(type default)
		)
		(layer "F.Cu")
	)
	(gr_line
		(start 10.856976 -425.294552)
		(end 10.586466 -425.024042)
		(stroke
			(width 0.06477)
			(type default)
		)
		(layer "F.Cu")
	)
	(gr_line
		(start 11.421618 -105.88244)
		(end 11.669268 -105.88244)
		(stroke
			(width 0.06477)
			(type default)
		)
		(layer "F.Cu")
	)
	(gr_line
		(start 11.421618 -104.740456)
		(end 11.421618 -105.08234)
		(stroke
			(width 0.06477)
			(type default)
		)
		(layer "F.Cu")
	)
	(gr_line
		(start 11.669268 -105.88244)
		(end 12.094972 -105.456736)
		(stroke
			(width 0.06477)
			(type default)
		)
		(layer "F.Cu")
	)
	(gr_line
		(start 11.948668 -104.213406)
		(end 11.421618 -104.740456)
		(stroke
			(width 0.06477)
			(type default)
		)
		(layer "F.Cu")
	)
	(gr_line
		(start 12.095226 -106.447336)
		(end 12.638532 -105.90403)
		(stroke
			(width 0.06477)
			(type default)
		)
		(layer "F.Cu")
	)
	(gr_line
		(start 12.272518 -104.243632)
		(end 12.272518 -104.212136)
		(stroke
			(width 0.06477)
			(type default)
		)
		(layer "F.Cu")
	)
	(gr_line
		(start 12.272518 -104.243632)
		(end 12.786106 -104.75722)
		(stroke
			(width 0.06477)
			(type default)
		)
		(layer "F.Cu")
	)
	(gr_line
		(start 12.272518 -104.212136)
		(end 12.272518 -104.243632)
		(stroke
			(width 0.06477)
			(type default)
		)
		(layer "F.Cu")
	)
	(gr_line
		(start 12.638532 -105.90403)
		(end 12.095226 -106.447336)
		(stroke
			(width 0.06477)
			(type default)
		)
		(layer "F.Cu")
	)
	(gr_line
		(start 12.638532 -105.90403)
		(end 12.786106 -105.90403)
		(stroke
			(width 0.06477)
			(type default)
		)
		(layer "F.Cu")
	)
	(gr_line
		(start 12.786106 -105.90403)
		(end 12.638532 -105.90403)
		(stroke
			(width 0.06477)
			(type default)
		)
		(layer "F.Cu")
	)
	(gr_line
		(start 12.786106 -105.10393)
		(end 12.786106 -104.75722)
		(stroke
			(width 0.06477)
			(type default)
		)
		(layer "F.Cu")
	)
	(gr_line
		(start 12.786106 -104.75722)
		(end 12.272518 -104.243632)
		(stroke
			(width 0.06477)
			(type default)
		)
		(layer "F.Cu")
	)
	(gr_line
		(start 12.786106 -104.75722)
		(end 12.786106 -105.10393)
		(stroke
			(width 0.06477)
			(type default)
		)
		(layer "F.Cu")
	)
	(gr_line
		(start 13.493496 -103.315516)
		(end 15.855188 -103.35768)
		(stroke
			(width 0.2)
			(type default)
		)
		(layer "F.Cu")
	)
	(gr_line
		(start 13.92555 -103.726488)
		(end 14.314932 -102.384098)
		(stroke
			(width 0.19304)
			(type default)
		)
		(layer "F.Cu")
	)
	(gr_line
		(start 14.064996 -101.84511)
		(end 14.153642 -101.933756)
		(stroke
			(width 0.06477)
			(type default)
		)
		(layer "F.Cu")
	)
	(gr_line
		(start 14.064996 -101.548946)
		(end 14.064996 -101.84511)
		(stroke
			(width 0.06477)
			(type default)
		)
		(layer "F.Cu")
	)
	(gr_line
		(start 14.265402 -105.137712)
		(end 15.288006 -105.13568)
		(stroke
			(width 0.06477)
			(type default)
		)
		(layer "F.Cu")
	)
	(gr_line
		(start 14.314932 -102.384098)
		(end 12.993116 -103.315516)
		(stroke
			(width 0.19304)
			(type default)
		)
		(layer "F.Cu")
	)
	(gr_line
		(start 14.314932 -102.384098)
		(end 13.92555 -103.726488)
		(stroke
			(width 0.19304)
			(type default)
		)
		(layer "F.Cu")
	)
	(gr_line
		(start 14.389608 -421.972232)
		(end 14.428216 -421.972232)
		(stroke
			(width 0.06477)
			(type default)
		)
		(layer "F.Cu")
	)
	(gr_line
		(start 14.390878 -422.296082)
		(end 14.478254 -422.383458)
		(stroke
			(width 0.06477)
			(type default)
		)
		(layer "F.Cu")
	)
	(gr_line
		(start 14.428216 -421.972232)
		(end 14.516862 -421.883586)
		(stroke
			(width 0.06477)
			(type default)
		)
		(layer "F.Cu")
	)
	(gr_line
		(start 14.450568 -424.294808)
		(end 14.410944 -424.294808)
		(stroke
			(width 0.06477)
			(type default)
		)
		(layer "F.Cu")
	)
	(gr_line
		(start 14.476222 -101.933756)
		(end 14.564868 -101.84511)
		(stroke
			(width 0.06477)
			(type default)
		)
		(layer "F.Cu")
	)
	(gr_line
		(start 14.478254 -422.383458)
		(end 14.723364 -422.383458)
		(stroke
			(width 0.06477)
			(type default)
		)
		(layer "F.Cu")
	)
	(gr_line
		(start 14.49959 -423.883582)
		(end 14.412214 -423.970958)
		(stroke
			(width 0.06477)
			(type default)
		)
		(layer "F.Cu")
	)
	(gr_line
		(start 14.516862 -421.883586)
		(end 14.723364 -421.883586)
		(stroke
			(width 0.06477)
			(type default)
		)
		(layer "F.Cu")
	)
	(gr_line
		(start 14.539214 -424.383454)
		(end 14.450568 -424.294808)
		(stroke
			(width 0.06477)
			(type default)
		)
		(layer "F.Cu")
	)
	(gr_line
		(start 14.564868 -101.84511)
		(end 14.476222 -101.933756)
		(stroke
			(width 0.06477)
			(type default)
		)
		(layer "F.Cu")
	)
	(gr_line
		(start 14.564868 -101.84511)
		(end 14.564868 -101.548946)
		(stroke
			(width 0.06477)
			(type default)
		)
		(layer "F.Cu")
	)
	(gr_line
		(start 14.564868 -101.548946)
		(end 14.564868 -101.84511)
		(stroke
			(width 0.06477)
			(type default)
		)
		(layer "F.Cu")
	)
	(gr_line
		(start 14.723364 -424.383454)
		(end 14.539214 -424.383454)
		(stroke
			(width 0.06477)
			(type default)
		)
		(layer "F.Cu")
	)
	(gr_line
		(start 14.723364 -423.883582)
		(end 14.49959 -423.883582)
		(stroke
			(width 0.06477)
			(type default)
		)
		(layer "F.Cu")
	)
	(gr_line
		(start 15.064994 -101.84511)
		(end 15.064994 -101.548946)
		(stroke
			(width 0.06477)
			(type default)
		)
		(layer "F.Cu")
	)
	(gr_line
		(start 15.15364 -101.933756)
		(end 15.064994 -101.84511)
		(stroke
			(width 0.06477)
			(type default)
		)
		(layer "F.Cu")
	)
	(gr_line
		(start 15.286228 -107.631484)
		(end 15.627096 -107.631484)
		(stroke
			(width 0.06477)
			(type default)
		)
		(layer "F.Cu")
	)
	(gr_line
		(start 15.288006 -106.415586)
		(end 15.288006 -105.93578)
		(stroke
			(width 0.06477)
			(type default)
		)
		(layer "F.Cu")
	)
	(gr_line
		(start 15.288006 -104.33558)
		(end 15.288006 -103.99522)
		(stroke
			(width 0.06477)
			(type default)
		)
		(layer "F.Cu")
	)
	(gr_line
		(start 15.288006 -103.99522)
		(end 15.823692 -103.459534)
		(stroke
			(width 0.06477)
			(type default)
		)
		(layer "F.Cu")
	)
	(gr_line
		(start 15.42161 -135.289036)
		(end 15.56893 -135.289036)
		(stroke
			(width 0.06477)
			(type default)
		)
		(layer "F.Cu")
	)
	(gr_line
		(start 15.42161 -134.789164)
		(end 15.587218 -134.789164)
		(stroke
			(width 0.06477)
			(type default)
		)
		(layer "F.Cu")
	)
	(gr_line
		(start 15.42161 -133.28904)
		(end 15.589758 -133.28904)
		(stroke
			(width 0.06477)
			(type default)
		)
		(layer "F.Cu")
	)
	(gr_line
		(start 15.42161 -132.789168)
		(end 15.586202 -132.789168)
		(stroke
			(width 0.06477)
			(type default)
		)
		(layer "F.Cu")
	)
	(gr_line
		(start 15.441422 -105.13568)
		(end 15.288006 -105.13568)
		(stroke
			(width 0.06477)
			(type default)
		)
		(layer "F.Cu")
	)
	(gr_line
		(start 15.47622 -101.933756)
		(end 15.56512 -101.844856)
		(stroke
			(width 0.06477)
			(type default)
		)
		(layer "F.Cu")
	)
	(gr_line
		(start 15.508478 -16.366236)
		(end 15.804388 -16.662146)
		(stroke
			(width 0.06477)
			(type default)
		)
		(layer "F.Cu")
	)
	(gr_line
		(start 15.56512 -101.844856)
		(end 15.47622 -101.933756)
		(stroke
			(width 0.06477)
			(type default)
		)
		(layer "F.Cu")
	)
	(gr_line
		(start 15.56512 -101.844856)
		(end 15.56512 -101.548946)
		(stroke
			(width 0.06477)
			(type default)
		)
		(layer "F.Cu")
	)
	(gr_line
		(start 15.56512 -101.548946)
		(end 15.56512 -101.844856)
		(stroke
			(width 0.06477)
			(type default)
		)
		(layer "F.Cu")
	)
	(gr_line
		(start 15.56893 -135.289036)
		(end 15.657576 -135.20039)
		(stroke
			(width 0.06477)
			(type default)
		)
		(layer "F.Cu")
	)
	(gr_line
		(start 15.586202 -132.789168)
		(end 15.674848 -132.877814)
		(stroke
			(width 0.06477)
			(type default)
		)
		(layer "F.Cu")
	)
	(gr_line
		(start 15.587218 -134.789164)
		(end 15.674594 -134.87654)
		(stroke
			(width 0.06477)
			(type default)
		)
		(layer "F.Cu")
	)
	(gr_line
		(start 15.589758 -133.28904)
		(end 15.677134 -133.201664)
		(stroke
			(width 0.06477)
			(type default)
		)
		(layer "F.Cu")
	)
	(gr_line
		(start 15.627096 -107.631484)
		(end 15.79372 -107.46486)
		(stroke
			(width 0.06477)
			(type default)
		)
		(layer "F.Cu")
	)
	(gr_line
		(start 15.657576 -135.20039)
		(end 15.675864 -135.20039)
		(stroke
			(width 0.06477)
			(type default)
		)
		(layer "F.Cu")
	)
	(gr_line
		(start 15.674848 -132.877814)
		(end 15.678404 -132.877814)
		(stroke
			(width 0.06477)
			(type default)
		)
		(layer "F.Cu")
	)
	(gr_line
		(start 15.79372 -107.46486)
		(end 15.79372 -107.431586)
		(stroke
			(width 0.06477)
			(type default)
		)
		(layer "F.Cu")
	)
	(gr_line
		(start 15.79372 -106.948986)
		(end 15.79372 -106.9213)
		(stroke
			(width 0.06477)
			(type default)
		)
		(layer "F.Cu")
	)
	(gr_line
		(start 15.79372 -106.9213)
		(end 15.288006 -106.415586)
		(stroke
			(width 0.06477)
			(type default)
		)
		(layer "F.Cu")
	)
	(gr_line
		(start 15.804388 -17.34185)
		(end 15.533878 -17.61236)
		(stroke
			(width 0.06477)
			(type default)
		)
		(layer "F.Cu")
	)
	(gr_line
		(start 15.804388 -15.536926)
		(end 15.508478 -15.832836)
		(stroke
			(width 0.06477)
			(type default)
		)
		(layer "F.Cu")
	)
	(gr_line
		(start 15.855188 -103.35768)
		(end 13.493496 -103.315516)
		(stroke
			(width 0.2)
			(type default)
		)
		(layer "F.Cu")
	)
	(gr_line
		(start 15.954248 -104.6734)
		(end 16.447008 -105.16616)
		(stroke
			(width 0.06477)
			(type default)
		)
		(layer "F.Cu")
	)
	(gr_line
		(start 15.954502 -105.664)
		(end 15.954502 -105.64876)
		(stroke
			(width 0.06477)
			(type default)
		)
		(layer "F.Cu")
	)
	(gr_line
		(start 15.954502 -105.64876)
		(end 15.441422 -105.13568)
		(stroke
			(width 0.06477)
			(type default)
		)
		(layer "F.Cu")
	)
	(gr_line
		(start 16.11757 -107.432856)
		(end 16.316198 -107.631484)
		(stroke
			(width 0.06477)
			(type default)
		)
		(layer "F.Cu")
	)
	(gr_line
		(start 16.126968 -17.34185)
		(end 16.397478 -17.61236)
		(stroke
			(width 0.06477)
			(type default)
		)
		(layer "F.Cu")
	)
	(gr_line
		(start 16.126968 -15.536926)
		(end 16.422878 -15.832836)
		(stroke
			(width 0.06477)
			(type default)
		)
		(layer "F.Cu")
	)
	(gr_line
		(start 16.147542 -103.515668)
		(end 16.147542 -103.458264)
		(stroke
			(width 0.06477)
			(type default)
		)
		(layer "F.Cu")
	)
	(gr_line
		(start 16.147542 -103.515668)
		(end 16.645382 -104.013508)
		(stroke
			(width 0.06477)
			(type default)
		)
		(layer "F.Cu")
	)
	(gr_line
		(start 16.147542 -103.458264)
		(end 16.147542 -103.515668)
		(stroke
			(width 0.06477)
			(type default)
		)
		(layer "F.Cu")
	)
	(gr_line
		(start 16.316198 -107.631484)
		(end 16.645382 -107.631484)
		(stroke
			(width 0.06477)
			(type default)
		)
		(layer "F.Cu")
	)
	(gr_line
		(start 16.422878 -16.366236)
		(end 16.126968 -16.662146)
		(stroke
			(width 0.06477)
			(type default)
		)
		(layer "F.Cu")
	)
	(gr_line
		(start 16.447008 -105.16616)
		(end 16.645382 -105.16616)
		(stroke
			(width 0.06477)
			(type default)
		)
		(layer "F.Cu")
	)
	(gr_line
		(start 16.645382 -106.419904)
		(end 16.11757 -106.947716)
		(stroke
			(width 0.06477)
			(type default)
		)
		(layer "F.Cu")
	)
	(gr_line
		(start 16.645382 -105.96626)
		(end 16.645382 -106.419904)
		(stroke
			(width 0.06477)
			(type default)
		)
		(layer "F.Cu")
	)
	(gr_line
		(start 16.645382 -105.16616)
		(end 17.630394 -105.16616)
		(stroke
			(width 0.06477)
			(type default)
		)
		(layer "F.Cu")
	)
	(gr_line
		(start 16.645382 -104.36606)
		(end 16.645382 -104.013508)
		(stroke
			(width 0.06477)
			(type default)
		)
		(layer "F.Cu")
	)
	(gr_line
		(start 16.645382 -104.013508)
		(end 16.147542 -103.515668)
		(stroke
			(width 0.06477)
			(type default)
		)
		(layer "F.Cu")
	)
	(gr_line
		(start 16.645382 -104.013508)
		(end 16.645382 -104.36606)
		(stroke
			(width 0.06477)
			(type default)
		)
		(layer "F.Cu")
	)
	(gr_line
		(start 17.630394 -105.16616)
		(end 17.658842 -105.137712)
		(stroke
			(width 0.06477)
			(type default)
		)
		(layer "F.Cu")
	)
	(gr_line
		(start 17.91462 -133.200394)
		(end 18.022824 -133.200394)
		(stroke
			(width 0.06477)
			(type default)
		)
		(layer "F.Cu")
	)
	(gr_line
		(start 17.91589 -132.876544)
		(end 18.302732 -132.489702)
		(stroke
			(width 0.06477)
			(type default)
		)
		(layer "F.Cu")
	)
	(gr_line
		(start 17.968722 -137.642092)
		(end 18.302732 -137.976102)
		(stroke
			(width 0.06477)
			(type default)
		)
		(layer "F.Cu")
	)
	(gr_line
		(start 17.968722 -137.319512)
		(end 18.302732 -136.985502)
		(stroke
			(width 0.06477)
			(type default)
		)
		(layer "F.Cu")
	)
	(gr_line
		(start 18.022824 -133.200394)
		(end 18.302732 -133.480302)
		(stroke
			(width 0.06477)
			(type default)
		)
		(layer "F.Cu")
	)
	(gr_line
		(start 18.302478 -17.890236)
		(end 18.598388 -18.186146)
		(stroke
			(width 0.06477)
			(type default)
		)
		(layer "F.Cu")
	)
	(gr_line
		(start 18.523204 -422.383458)
		(end 18.746978 -422.383458)
		(stroke
			(width 0.06477)
			(type default)
		)
		(layer "F.Cu")
	)
	(gr_line
		(start 18.523204 -421.883586)
		(end 18.707354 -421.883586)
		(stroke
			(width 0.06477)
			(type default)
		)
		(layer "F.Cu")
	)
	(gr_line
		(start 18.597118 -18.866866)
		(end 18.326862 -19.137122)
		(stroke
			(width 0.06477)
			(type default)
		)
		(layer "F.Cu")
	)
	(gr_line
		(start 18.598388 -17.060926)
		(end 18.302478 -17.356836)
		(stroke
			(width 0.06477)
			(type default)
		)
		(layer "F.Cu")
	)
	(gr_line
		(start 18.707354 -423.883582)
		(end 18.523204 -423.883582)
		(stroke
			(width 0.06477)
			(type default)
		)
		(layer "F.Cu")
	)
	(gr_line
		(start 18.707354 -421.883586)
		(end 18.796 -421.972232)
		(stroke
			(width 0.06477)
			(type default)
		)
		(layer "F.Cu")
	)
	(gr_line
		(start 18.746978 -424.383454)
		(end 18.523204 -424.383454)
		(stroke
			(width 0.06477)
			(type default)
		)
		(layer "F.Cu")
	)
	(gr_line
		(start 18.746978 -422.383458)
		(end 18.834354 -422.296082)
		(stroke
			(width 0.06477)
			(type default)
		)
		(layer "F.Cu")
	)
	(gr_line
		(start 18.796 -423.972228)
		(end 18.707354 -423.883582)
		(stroke
			(width 0.06477)
			(type default)
		)
		(layer "F.Cu")
	)
	(gr_line
		(start 18.796 -421.972232)
		(end 18.835624 -421.972232)
		(stroke
			(width 0.06477)
			(type default)
		)
		(layer "F.Cu")
	)
	(gr_line
		(start 18.834354 -424.296078)
		(end 18.746978 -424.383454)
		(stroke
			(width 0.06477)
			(type default)
		)
		(layer "F.Cu")
	)
	(gr_line
		(start 18.835624 -423.972228)
		(end 18.796 -423.972228)
		(stroke
			(width 0.06477)
			(type default)
		)
		(layer "F.Cu")
	)
	(gr_line
		(start 18.920968 -18.867628)
		(end 19.190462 -19.137122)
		(stroke
			(width 0.06477)
			(type default)
		)
		(layer "F.Cu")
	)
	(gr_line
		(start 18.920968 -18.865596)
		(end 18.920968 -18.867628)
		(stroke
			(width 0.06477)
			(type default)
		)
		(layer "F.Cu")
	)
	(gr_line
		(start 18.920968 -17.060926)
		(end 19.216878 -17.356836)
		(stroke
			(width 0.06477)
			(type default)
		)
		(layer "F.Cu")
	)
	(gr_line
		(start 19.102832 -137.976102)
		(end 19.436842 -137.642092)
		(stroke
			(width 0.06477)
			(type default)
		)
		(layer "F.Cu")
	)
	(gr_line
		(start 19.102832 -136.985502)
		(end 19.436842 -137.319512)
		(stroke
			(width 0.06477)
			(type default)
		)
		(layer "F.Cu")
	)
	(gr_line
		(start 19.102832 -133.480302)
		(end 19.436842 -133.146292)
		(stroke
			(width 0.06477)
			(type default)
		)
		(layer "F.Cu")
	)
	(gr_line
		(start 19.102832 -132.489702)
		(end 19.436842 -132.823712)
		(stroke
			(width 0.06477)
			(type default)
		)
		(layer "F.Cu")
	)
	(gr_line
		(start 19.147028 -11.881104)
		(end 19.285712 -12.019788)
		(stroke
			(width 0.06477)
			(type default)
		)
		(layer "F.Cu")
	)
	(gr_line
		(start 19.147028 -11.26998)
		(end 19.147028 -11.881104)
		(stroke
			(width 0.06477)
			(type default)
		)
		(layer "F.Cu")
	)
	(gr_line
		(start 19.216878 -17.890236)
		(end 18.920968 -18.186146)
		(stroke
			(width 0.06477)
			(type default)
		)
		(layer "F.Cu")
	)
	(gr_line
		(start 19.746976 -11.881104)
		(end 19.608292 -12.019788)
		(stroke
			(width 0.06477)
			(type default)
		)
		(layer "F.Cu")
	)
	(gr_line
		(start 19.746976 -11.26998)
		(end 19.746976 -11.881104)
		(stroke
			(width 0.06477)
			(type default)
		)
		(layer "F.Cu")
	)
	(gr_line
		(start 20.041362 -137.319512)
		(end 20.092162 -137.319512)
		(stroke
			(width 0.06477)
			(type default)
		)
		(layer "F.Cu")
	)
	(gr_line
		(start 20.042632 -137.643362)
		(end 20.400772 -138.001502)
		(stroke
			(width 0.06477)
			(type default)
		)
		(layer "F.Cu")
	)
	(gr_line
		(start 20.092162 -137.319512)
		(end 20.400772 -137.010902)
		(stroke
			(width 0.06477)
			(type default)
		)
		(layer "F.Cu")
	)
	(gr_line
		(start 20.226782 -133.146292)
		(end 20.560792 -133.480302)
		(stroke
			(width 0.06477)
			(type default)
		)
		(layer "F.Cu")
	)
	(gr_line
		(start 20.226782 -132.823712)
		(end 20.560792 -132.489702)
		(stroke
			(width 0.06477)
			(type default)
		)
		(layer "F.Cu")
	)
	(gr_line
		(start 20.946872 -11.881104)
		(end 21.085556 -12.019788)
		(stroke
			(width 0.06477)
			(type default)
		)
		(layer "F.Cu")
	)
	(gr_line
		(start 20.946872 -11.26998)
		(end 20.946872 -11.881104)
		(stroke
			(width 0.06477)
			(type default)
		)
		(layer "F.Cu")
	)
	(gr_line
		(start 21.096478 -16.366236)
		(end 21.392388 -16.662146)
		(stroke
			(width 0.06477)
			(type default)
		)
		(layer "F.Cu")
	)
	(gr_line
		(start 21.392388 -17.34185)
		(end 21.121878 -17.61236)
		(stroke
			(width 0.06477)
			(type default)
		)
		(layer "F.Cu")
	)
	(gr_line
		(start 21.392388 -15.536926)
		(end 21.096478 -15.832836)
		(stroke
			(width 0.06477)
			(type default)
		)
		(layer "F.Cu")
	)
	(gr_line
		(start 21.531834 -420.999412)
		(end 21.802344 -421.269922)
		(stroke
			(width 0.06477)
			(type default)
		)
		(layer "F.Cu")
	)
	(gr_line
		(start 21.531834 -420.676832)
		(end 21.802344 -420.406322)
		(stroke
			(width 0.06477)
			(type default)
		)
		(layer "F.Cu")
	)
	(gr_line
		(start 21.547074 -11.88085)
		(end 21.408136 -12.019788)
		(stroke
			(width 0.06477)
			(type default)
		)
		(layer "F.Cu")
	)
	(gr_line
		(start 21.547074 -11.26998)
		(end 21.547074 -11.88085)
		(stroke
			(width 0.06477)
			(type default)
		)
		(layer "F.Cu")
	)
	(gr_line
		(start 21.714968 -17.34185)
		(end 21.985478 -17.61236)
		(stroke
			(width 0.06477)
			(type default)
		)
		(layer "F.Cu")
	)
	(gr_line
		(start 21.714968 -15.536926)
		(end 22.010878 -15.832836)
		(stroke
			(width 0.06477)
			(type default)
		)
		(layer "F.Cu")
	)
	(gr_line
		(start 22.010878 -16.366236)
		(end 21.714968 -16.662146)
		(stroke
			(width 0.06477)
			(type default)
		)
		(layer "F.Cu")
	)
	(gr_line
		(start 22.324314 -425.328334)
		(end 22.053804 -425.057824)
		(stroke
			(width 0.06477)
			(type default)
		)
		(layer "F.Cu")
	)
	(gr_line
		(start 22.324314 -424.464734)
		(end 22.053804 -424.735244)
		(stroke
			(width 0.06477)
			(type default)
		)
		(layer "F.Cu")
	)
	(gr_line
		(start 22.74697 -11.881104)
		(end 22.885654 -12.019788)
		(stroke
			(width 0.06477)
			(type default)
		)
		(layer "F.Cu")
	)
	(gr_line
		(start 22.74697 -11.26998)
		(end 22.74697 -11.881104)
		(stroke
			(width 0.06477)
			(type default)
		)
		(layer "F.Cu")
	)
	(gr_line
		(start 23.346918 -11.881104)
		(end 23.208234 -12.019788)
		(stroke
			(width 0.06477)
			(type default)
		)
		(layer "F.Cu")
	)
	(gr_line
		(start 23.346918 -11.26998)
		(end 23.346918 -11.881104)
		(stroke
			(width 0.06477)
			(type default)
		)
		(layer "F.Cu")
	)
	(gr_line
		(start 23.890478 -17.890236)
		(end 24.186388 -18.186146)
		(stroke
			(width 0.06477)
			(type default)
		)
		(layer "F.Cu")
	)
	(gr_line
		(start 24.186388 -18.86585)
		(end 23.915878 -19.13636)
		(stroke
			(width 0.06477)
			(type default)
		)
		(layer "F.Cu")
	)
	(gr_line
		(start 24.186388 -17.060926)
		(end 23.890478 -17.356836)
		(stroke
			(width 0.06477)
			(type default)
		)
		(layer "F.Cu")
	)
	(gr_line
		(start 24.508968 -18.86585)
		(end 24.779478 -19.13636)
		(stroke
			(width 0.06477)
			(type default)
		)
		(layer "F.Cu")
	)
	(gr_line
		(start 24.508968 -17.060926)
		(end 24.804878 -17.356836)
		(stroke
			(width 0.06477)
			(type default)
		)
		(layer "F.Cu")
	)
	(gr_line
		(start 24.547068 -11.881104)
		(end 24.685752 -12.019788)
		(stroke
			(width 0.06477)
			(type default)
		)
		(layer "F.Cu")
	)
	(gr_line
		(start 24.547068 -11.26998)
		(end 24.547068 -11.881104)
		(stroke
			(width 0.06477)
			(type default)
		)
		(layer "F.Cu")
	)
	(gr_line
		(start 24.804878 -17.890236)
		(end 24.508968 -18.186146)
		(stroke
			(width 0.06477)
			(type default)
		)
		(layer "F.Cu")
	)
	(gr_line
		(start 25.147016 -11.881104)
		(end 25.008332 -12.019788)
		(stroke
			(width 0.06477)
			(type default)
		)
		(layer "F.Cu")
	)
	(gr_line
		(start 25.147016 -11.26998)
		(end 25.147016 -11.881104)
		(stroke
			(width 0.06477)
			(type default)
		)
		(layer "F.Cu")
	)
	(gr_line
		(start 25.258522 -422.130474)
		(end 25.528778 -421.860218)
		(stroke
			(width 0.06477)
			(type default)
		)
		(layer "F.Cu")
	)
	(gr_line
		(start 25.258522 -421.266874)
		(end 25.528778 -421.53713)
		(stroke
			(width 0.06477)
			(type default)
		)
		(layer "F.Cu")
	)
	(gr_line
		(start 25.528778 -421.860218)
		(end 25.529286 -421.860218)
		(stroke
			(width 0.06477)
			(type default)
		)
		(layer "F.Cu")
	)
	(gr_line
		(start 25.783032 -428.345092)
		(end 25.512522 -428.615602)
		(stroke
			(width 0.06477)
			(type default)
		)
		(layer "F.Cu")
	)
	(gr_line
		(start 25.783032 -428.022512)
		(end 25.512522 -427.752002)
		(stroke
			(width 0.06477)
			(type default)
		)
		(layer "F.Cu")
	)
	(gr_line
		(start 26.216864 -427.987714)
		(end 26.182066 -428.022512)
		(stroke
			(width 0.06477)
			(type default)
		)
		(layer "F.Cu")
	)
	(gr_line
		(start 26.217118 -427.987714)
		(end 26.216864 -427.987714)
		(stroke
			(width 0.06477)
			(type default)
		)
		(layer "F.Cu")
	)
	(gr_line
		(start 26.346912 -11.881104)
		(end 26.485596 -12.019788)
		(stroke
			(width 0.06477)
			(type default)
		)
		(layer "F.Cu")
	)
	(gr_line
		(start 26.346912 -11.26998)
		(end 26.346912 -11.881104)
		(stroke
			(width 0.06477)
			(type default)
		)
		(layer "F.Cu")
	)
	(gr_line
		(start 26.38044 -421.860472)
		(end 26.380186 -421.860218)
		(stroke
			(width 0.06477)
			(type default)
		)
		(layer "F.Cu")
	)
	(gr_line
		(start 26.509726 -421.537638)
		(end 26.510488 -421.537638)
		(stroke
			(width 0.06477)
			(type default)
		)
		(layer "F.Cu")
	)
	(gr_line
		(start 26.510488 -421.861234)
		(end 26.97988 -422.330626)
		(stroke
			(width 0.06477)
			(type default)
		)
		(layer "F.Cu")
	)
	(gr_line
		(start 26.510488 -421.537638)
		(end 26.979118 -421.069008)
		(stroke
			(width 0.06477)
			(type default)
		)
		(layer "F.Cu")
	)
	(gr_line
		(start 26.59253 -428.755302)
		(end 26.18232 -428.345092)
		(stroke
			(width 0.06477)
			(type default)
		)
		(layer "F.Cu")
	)
	(gr_line
		(start 26.59253 -427.612302)
		(end 26.217118 -427.987714)
		(stroke
			(width 0.06477)
			(type default)
		)
		(layer "F.Cu")
	)
	(gr_line
		(start 26.684478 -16.366236)
		(end 26.980388 -16.662146)
		(stroke
			(width 0.06477)
			(type default)
		)
		(layer "F.Cu")
	)
	(gr_line
		(start 26.94686 -11.881104)
		(end 26.808176 -12.019788)
		(stroke
			(width 0.06477)
			(type default)
		)
		(layer "F.Cu")
	)
	(gr_line
		(start 26.94686 -11.26998)
		(end 26.94686 -11.881104)
		(stroke
			(width 0.06477)
			(type default)
		)
		(layer "F.Cu")
	)
	(gr_line
		(start 26.979118 -421.069008)
		(end 27.33675 -421.069008)
		(stroke
			(width 0.06477)
			(type default)
		)
		(layer "F.Cu")
	)
	(gr_line
		(start 26.97988 -422.330626)
		(end 27.33548 -422.330626)
		(stroke
			(width 0.06477)
			(type default)
		)
		(layer "F.Cu")
	)
	(gr_line
		(start 26.980388 -17.34185)
		(end 26.709878 -17.61236)
		(stroke
			(width 0.06477)
			(type default)
		)
		(layer "F.Cu")
	)
	(gr_line
		(start 26.980388 -15.536926)
		(end 26.684478 -15.832836)
		(stroke
			(width 0.06477)
			(type default)
		)
		(layer "F.Cu")
	)
	(gr_line
		(start 27.220926 -428.755302)
		(end 26.59253 -428.755302)
		(stroke
			(width 0.06477)
			(type default)
		)
		(layer "F.Cu")
	)
	(gr_line
		(start 27.220926 -427.612302)
		(end 26.59253 -427.612302)
		(stroke
			(width 0.06477)
			(type default)
		)
		(layer "F.Cu")
	)
	(gr_line
		(start 27.302968 -17.34185)
		(end 27.573478 -17.61236)
		(stroke
			(width 0.06477)
			(type default)
		)
		(layer "F.Cu")
	)
	(gr_line
		(start 27.302968 -15.536926)
		(end 27.598878 -15.832836)
		(stroke
			(width 0.06477)
			(type default)
		)
		(layer "F.Cu")
	)
	(gr_line
		(start 27.322526 -428.183802)
		(end 27.754326 -427.752002)
		(stroke
			(width 0.06477)
			(type default)
		)
		(layer "F.Cu")
	)
	(gr_line
		(start 27.598878 -16.366236)
		(end 27.302968 -16.662146)
		(stroke
			(width 0.06477)
			(type default)
		)
		(layer "F.Cu")
	)
	(gr_line
		(start 27.754326 -428.615602)
		(end 27.754326 -428.755302)
		(stroke
			(width 0.06477)
			(type default)
		)
		(layer "F.Cu")
	)
	(gr_line
		(start 27.754326 -427.752002)
		(end 27.754326 -427.612302)
		(stroke
			(width 0.06477)
			(type default)
		)
		(layer "F.Cu")
	)
	(gr_line
		(start 28.13558 -422.330626)
		(end 28.13558 -422.132252)
		(stroke
			(width 0.06477)
			(type default)
		)
		(layer "F.Cu")
	)
	(gr_line
		(start 28.13558 -422.132252)
		(end 28.221432 -422.0464)
		(stroke
			(width 0.06477)
			(type default)
		)
		(layer "F.Cu")
	)
	(gr_line
		(start 28.13685 -421.267382)
		(end 28.119832 -421.2844)
		(stroke
			(width 0.06477)
			(type default)
		)
		(layer "F.Cu")
	)
	(gr_line
		(start 28.13685 -421.069008)
		(end 28.13685 -421.267382)
		(stroke
			(width 0.06477)
			(type default)
		)
		(layer "F.Cu")
	)
	(gr_line
		(start 28.14701 -11.881104)
		(end 28.285694 -12.019788)
		(stroke
			(width 0.06477)
			(type default)
		)
		(layer "F.Cu")
	)
	(gr_line
		(start 28.14701 -11.26998)
		(end 28.14701 -11.881104)
		(stroke
			(width 0.06477)
			(type default)
		)
		(layer "F.Cu")
	)
	(gr_line
		(start 28.186126 -428.183802)
		(end 27.754326 -428.615602)
		(stroke
			(width 0.06477)
			(type default)
		)
		(layer "F.Cu")
	)
	(gr_line
		(start 28.287726 -428.755302)
		(end 28.929838 -428.755302)
		(stroke
			(width 0.06477)
			(type default)
		)
		(layer "F.Cu")
	)
	(gr_line
		(start 28.287726 -427.612302)
		(end 28.916122 -427.612302)
		(stroke
			(width 0.06477)
			(type default)
		)
		(layer "F.Cu")
	)
	(gr_line
		(start 28.746958 -11.881104)
		(end 28.608274 -12.019788)
		(stroke
			(width 0.06477)
			(type default)
		)
		(layer "F.Cu")
	)
	(gr_line
		(start 28.746958 -11.26998)
		(end 28.746958 -11.881104)
		(stroke
			(width 0.06477)
			(type default)
		)
		(layer "F.Cu")
	)
	(gr_line
		(start 28.916122 -427.612302)
		(end 29.320236 -428.016416)
		(stroke
			(width 0.06477)
			(type default)
		)
		(layer "F.Cu")
	)
	(gr_line
		(start 28.929838 -428.755302)
		(end 29.344874 -428.340266)
		(stroke
			(width 0.06477)
			(type default)
		)
		(layer "F.Cu")
	)
	(gr_line
		(start 29.295344 -421.069008)
		(end 28.93695 -421.069008)
		(stroke
			(width 0.06477)
			(type default)
		)
		(layer "F.Cu")
	)
	(gr_line
		(start 29.320236 -428.016416)
		(end 29.346144 -428.016416)
		(stroke
			(width 0.06477)
			(type default)
		)
		(layer "F.Cu")
	)
	(gr_line
		(start 29.349954 -422.330626)
		(end 28.93568 -422.330626)
		(stroke
			(width 0.06477)
			(type default)
		)
		(layer "F.Cu")
	)
	(gr_line
		(start 29.478478 -17.890236)
		(end 29.774388 -18.186146)
		(stroke
			(width 0.06477)
			(type default)
		)
		(layer "F.Cu")
	)
	(gr_line
		(start 29.757878 -421.531542)
		(end 29.295344 -421.069008)
		(stroke
			(width 0.06477)
			(type default)
		)
		(layer "F.Cu")
	)
	(gr_line
		(start 29.774388 -18.86585)
		(end 29.503878 -19.13636)
		(stroke
			(width 0.06477)
			(type default)
		)
		(layer "F.Cu")
	)
	(gr_line
		(start 29.774388 -17.060926)
		(end 29.478478 -17.356836)
		(stroke
			(width 0.06477)
			(type default)
		)
		(layer "F.Cu")
	)
	(gr_line
		(start 29.825188 -421.855392)
		(end 29.349954 -422.330626)
		(stroke
			(width 0.06477)
			(type default)
		)
		(layer "F.Cu")
	)
	(gr_line
		(start 29.826458 -421.531542)
		(end 29.757878 -421.531542)
		(stroke
			(width 0.06477)
			(type default)
		)
		(layer "F.Cu")
	)
	(gr_line
		(start 29.947108 -11.881104)
		(end 30.085792 -12.019788)
		(stroke
			(width 0.06477)
			(type default)
		)
		(layer "F.Cu")
	)
	(gr_line
		(start 29.947108 -11.26998)
		(end 29.947108 -11.881104)
		(stroke
			(width 0.06477)
			(type default)
		)
		(layer "F.Cu")
	)
	(gr_line
		(start 30.096968 -18.86585)
		(end 30.367478 -19.13636)
		(stroke
			(width 0.06477)
			(type default)
		)
		(layer "F.Cu")
	)
	(gr_line
		(start 30.096968 -17.060926)
		(end 30.392878 -17.356836)
		(stroke
			(width 0.06477)
			(type default)
		)
		(layer "F.Cu")
	)
	(gr_line
		(start 30.392878 -17.890236)
		(end 30.096968 -18.186146)
		(stroke
			(width 0.06477)
			(type default)
		)
		(layer "F.Cu")
	)
	(gr_line
		(start 30.547056 -11.881104)
		(end 30.408372 -12.019788)
		(stroke
			(width 0.06477)
			(type default)
		)
		(layer "F.Cu")
	)
	(gr_line
		(start 30.547056 -11.26998)
		(end 30.547056 -11.881104)
		(stroke
			(width 0.06477)
			(type default)
		)
		(layer "F.Cu")
	)
	(gr_line
		(start 31.746952 -11.881104)
		(end 31.885636 -12.019788)
		(stroke
			(width 0.06477)
			(type default)
		)
		(layer "F.Cu")
	)
	(gr_line
		(start 31.746952 -11.26998)
		(end 31.746952 -11.881104)
		(stroke
			(width 0.06477)
			(type default)
		)
		(layer "F.Cu")
	)
	(gr_line
		(start 32.272478 -16.366236)
		(end 32.568388 -16.662146)
		(stroke
			(width 0.06477)
			(type default)
		)
		(layer "F.Cu")
	)
	(gr_line
		(start 32.3469 -11.881104)
		(end 32.208216 -12.019788)
		(stroke
			(width 0.06477)
			(type default)
		)
		(layer "F.Cu")
	)
	(gr_line
		(start 32.3469 -11.26998)
		(end 32.3469 -11.881104)
		(stroke
			(width 0.06477)
			(type default)
		)
		(layer "F.Cu")
	)
	(gr_line
		(start 32.567118 -17.342866)
		(end 32.296862 -17.613122)
		(stroke
			(width 0.06477)
			(type default)
		)
		(layer "F.Cu")
	)
	(gr_line
		(start 32.568388 -15.536926)
		(end 32.272478 -15.832836)
		(stroke
			(width 0.06477)
			(type default)
		)
		(layer "F.Cu")
	)
	(gr_line
		(start 32.695642 -426.071538)
		(end 32.748474 -426.071538)
		(stroke
			(width 0.06477)
			(type default)
		)
		(layer "F.Cu")
	)
	(gr_line
		(start 32.696912 -425.747688)
		(end 32.734504 -425.710096)
		(stroke
			(width 0.06477)
			(type default)
		)
		(layer "F.Cu")
	)
	(gr_line
		(start 32.734504 -425.710096)
		(end 33.002728 -425.710096)
		(stroke
			(width 0.06477)
			(type default)
		)
		(layer "F.Cu")
	)
	(gr_line
		(start 32.748474 -426.071538)
		(end 32.787082 -426.110146)
		(stroke
			(width 0.06477)
			(type default)
		)
		(layer "F.Cu")
	)
	(gr_line
		(start 32.751014 -423.7101)
		(end 32.712406 -423.671492)
		(stroke
			(width 0.06477)
			(type default)
		)
		(layer "F.Cu")
	)
	(gr_line
		(start 32.751268 -423.31005)
		(end 32.712406 -423.348912)
		(stroke
			(width 0.06477)
			(type default)
		)
		(layer "F.Cu")
	)
	(gr_line
		(start 32.787082 -426.110146)
		(end 33.002728 -426.110146)
		(stroke
			(width 0.06477)
			(type default)
		)
		(layer "F.Cu")
	)
	(gr_line
		(start 32.890968 -17.343628)
		(end 33.160462 -17.613122)
		(stroke
			(width 0.06477)
			(type default)
		)
		(layer "F.Cu")
	)
	(gr_line
		(start 32.890968 -17.341596)
		(end 32.890968 -17.343628)
		(stroke
			(width 0.06477)
			(type default)
		)
		(layer "F.Cu")
	)
	(gr_line
		(start 32.890968 -15.536926)
		(end 33.186878 -15.832836)
		(stroke
			(width 0.06477)
			(type default)
		)
		(layer "F.Cu")
	)
	(gr_line
		(start 33.002728 -423.7101)
		(end 32.751014 -423.7101)
		(stroke
			(width 0.06477)
			(type default)
		)
		(layer "F.Cu")
	)
	(gr_line
		(start 33.002728 -423.31005)
		(end 32.751268 -423.31005)
		(stroke
			(width 0.06477)
			(type default)
		)
		(layer "F.Cu")
	)
	(gr_line
		(start 33.186878 -16.366236)
		(end 32.890968 -16.662146)
		(stroke
			(width 0.06477)
			(type default)
		)
		(layer "F.Cu")
	)
	(gr_line
		(start 35.066478 -17.890236)
		(end 35.362388 -18.186146)
		(stroke
			(width 0.06477)
			(type default)
		)
		(layer "F.Cu")
	)
	(gr_line
		(start 35.362388 -18.86585)
		(end 35.091878 -19.13636)
		(stroke
			(width 0.06477)
			(type default)
		)
		(layer "F.Cu")
	)
	(gr_line
		(start 35.362388 -17.060926)
		(end 35.066478 -17.356836)
		(stroke
			(width 0.06477)
			(type default)
		)
		(layer "F.Cu")
	)
	(gr_line
		(start 35.502596 -426.110146)
		(end 35.754056 -426.110146)
		(stroke
			(width 0.06477)
			(type default)
		)
		(layer "F.Cu")
	)
	(gr_line
		(start 35.502596 -425.710096)
		(end 35.75431 -425.710096)
		(stroke
			(width 0.06477)
			(type default)
		)
		(layer "F.Cu")
	)
	(gr_line
		(start 35.684968 -18.86585)
		(end 35.955478 -19.13636)
		(stroke
			(width 0.06477)
			(type default)
		)
		(layer "F.Cu")
	)
	(gr_line
		(start 35.684968 -17.060926)
		(end 35.980878 -17.356836)
		(stroke
			(width 0.06477)
			(type default)
		)
		(layer "F.Cu")
	)
	(gr_line
		(start 35.754056 -426.110146)
		(end 35.792918 -426.071284)
		(stroke
			(width 0.06477)
			(type default)
		)
		(layer "F.Cu")
	)
	(gr_line
		(start 35.75431 -425.710096)
		(end 35.792918 -425.748704)
		(stroke
			(width 0.06477)
			(type default)
		)
		(layer "F.Cu")
	)
	(gr_line
		(start 35.768788 -423.31005)
		(end 35.502596 -423.31005)
		(stroke
			(width 0.06477)
			(type default)
		)
		(layer "F.Cu")
	)
	(gr_line
		(start 35.80765 -423.348912)
		(end 35.768788 -423.31005)
		(stroke
			(width 0.06477)
			(type default)
		)
		(layer "F.Cu")
	)
	(gr_line
		(start 35.818826 -423.7101)
		(end 35.502596 -423.7101)
		(stroke
			(width 0.06477)
			(type default)
		)
		(layer "F.Cu")
	)
	(gr_line
		(start 35.856164 -423.672762)
		(end 35.818826 -423.7101)
		(stroke
			(width 0.06477)
			(type default)
		)
		(layer "F.Cu")
	)
	(gr_line
		(start 35.857434 -423.348912)
		(end 35.80765 -423.348912)
		(stroke
			(width 0.06477)
			(type default)
		)
		(layer "F.Cu")
	)
	(gr_line
		(start 35.980878 -17.890236)
		(end 35.684968 -18.186146)
		(stroke
			(width 0.06477)
			(type default)
		)
		(layer "F.Cu")
	)
	(gr_line
		(start 37.860478 -16.366236)
		(end 38.156388 -16.662146)
		(stroke
			(width 0.06477)
			(type default)
		)
		(layer "F.Cu")
	)
	(gr_line
		(start 37.923978 -426.071284)
		(end 37.92982 -426.071284)
		(stroke
			(width 0.06477)
			(type default)
		)
		(layer "F.Cu")
	)
	(gr_line
		(start 37.925248 -425.747434)
		(end 38.415976 -425.256706)
		(stroke
			(width 0.06477)
			(type default)
		)
		(layer "F.Cu")
	)
	(gr_line
		(start 37.92982 -426.071284)
		(end 38.422072 -426.563536)
		(stroke
			(width 0.06477)
			(type default)
		)
		(layer "F.Cu")
	)
	(gr_line
		(start 38.155118 -17.342866)
		(end 37.884862 -17.613122)
		(stroke
			(width 0.06477)
			(type default)
		)
		(layer "F.Cu")
	)
	(gr_line
		(start 38.156388 -15.536926)
		(end 37.860478 -15.832836)
		(stroke
			(width 0.06477)
			(type default)
		)
		(layer "F.Cu")
	)
	(gr_line
		(start 38.355016 -423.21734)
		(end 37.941758 -422.804082)
		(stroke
			(width 0.06477)
			(type default)
		)
		(layer "F.Cu")
	)
	(gr_line
		(start 38.36289 -422.06037)
		(end 37.941758 -422.481502)
		(stroke
			(width 0.06477)
			(type default)
		)
		(layer "F.Cu")
	)
	(gr_line
		(start 38.415976 -425.256706)
		(end 38.75024 -425.256706)
		(stroke
			(width 0.06477)
			(type default)
		)
		(layer "F.Cu")
	)
	(gr_line
		(start 38.422072 -426.563536)
		(end 38.75024 -426.563536)
		(stroke
			(width 0.06477)
			(type default)
		)
		(layer "F.Cu")
	)
	(gr_line
		(start 38.478968 -17.343628)
		(end 38.748462 -17.613122)
		(stroke
			(width 0.06477)
			(type default)
		)
		(layer "F.Cu")
	)
	(gr_line
		(start 38.478968 -17.341596)
		(end 38.478968 -17.343628)
		(stroke
			(width 0.06477)
			(type default)
		)
		(layer "F.Cu")
	)
	(gr_line
		(start 38.478968 -15.536926)
		(end 38.774878 -15.832836)
		(stroke
			(width 0.06477)
			(type default)
		)
		(layer "F.Cu")
	)
	(gr_line
		(start 38.774878 -16.366236)
		(end 38.478968 -16.662146)
		(stroke
			(width 0.06477)
			(type default)
		)
		(layer "F.Cu")
	)
	(gr_line
		(start 39.042594 -423.21734)
		(end 38.355016 -423.21734)
		(stroke
			(width 0.06477)
			(type default)
		)
		(layer "F.Cu")
	)
	(gr_line
		(start 39.042594 -422.06037)
		(end 38.36289 -422.06037)
		(stroke
			(width 0.06477)
			(type default)
		)
		(layer "F.Cu")
	)
	(gr_line
		(start 39.057072 -11.881104)
		(end 39.195756 -12.019788)
		(stroke
			(width 0.06477)
			(type default)
		)
		(layer "F.Cu")
	)
	(gr_line
		(start 39.057072 -11.26998)
		(end 39.057072 -11.881104)
		(stroke
			(width 0.06477)
			(type default)
		)
		(layer "F.Cu")
	)
	(gr_line
		(start 39.144194 -422.638982)
		(end 39.575994 -423.070782)
		(stroke
			(width 0.06477)
			(type default)
		)
		(layer "F.Cu")
	)
	(gr_line
		(start 39.55034 -426.563536)
		(end 39.55034 -426.341794)
		(stroke
			(width 0.06477)
			(type default)
		)
		(layer "F.Cu")
	)
	(gr_line
		(start 39.55034 -426.341794)
		(end 39.603934 -426.2882)
		(stroke
			(width 0.06477)
			(type default)
		)
		(layer "F.Cu")
	)
	(gr_line
		(start 39.55034 -425.478194)
		(end 39.476934 -425.5516)
		(stroke
			(width 0.06477)
			(type default)
		)
		(layer "F.Cu")
	)
	(gr_line
		(start 39.55034 -425.256706)
		(end 39.55034 -425.478194)
		(stroke
			(width 0.06477)
			(type default)
		)
		(layer "F.Cu")
	)
	(gr_line
		(start 39.575994 -423.070782)
		(end 39.575994 -423.21734)
		(stroke
			(width 0.06477)
			(type default)
		)
		(layer "F.Cu")
	)
	(gr_line
		(start 39.575994 -422.207182)
		(end 39.575994 -422.06037)
		(stroke
			(width 0.06477)
			(type default)
		)
		(layer "F.Cu")
	)
	(gr_line
		(start 39.65702 -11.881104)
		(end 39.518336 -12.019788)
		(stroke
			(width 0.06477)
			(type default)
		)
		(layer "F.Cu")
	)
	(gr_line
		(start 39.65702 -11.26998)
		(end 39.65702 -11.881104)
		(stroke
			(width 0.06477)
			(type default)
		)
		(layer "F.Cu")
	)
	(gr_line
		(start 40.007794 -422.638982)
		(end 39.575994 -422.207182)
		(stroke
			(width 0.06477)
			(type default)
		)
		(layer "F.Cu")
	)
	(gr_line
		(start 40.109394 -423.21734)
		(end 40.789098 -423.21734)
		(stroke
			(width 0.06477)
			(type default)
		)
		(layer "F.Cu")
	)
	(gr_line
		(start 40.109394 -422.06037)
		(end 40.796972 -422.06037)
		(stroke
			(width 0.06477)
			(type default)
		)
		(layer "F.Cu")
	)
	(gr_line
		(start 40.678608 -425.256706)
		(end 40.35044 -425.256706)
		(stroke
			(width 0.06477)
			(type default)
		)
		(layer "F.Cu")
	)
	(gr_line
		(start 40.684704 -426.563536)
		(end 40.35044 -426.563536)
		(stroke
			(width 0.06477)
			(type default)
		)
		(layer "F.Cu")
	)
	(gr_line
		(start 40.789098 -423.21734)
		(end 41.21023 -422.796208)
		(stroke
			(width 0.06477)
			(type default)
		)
		(layer "F.Cu")
	)
	(gr_line
		(start 40.796972 -422.06037)
		(end 41.21023 -422.473628)
		(stroke
			(width 0.06477)
			(type default)
		)
		(layer "F.Cu")
	)
	(gr_line
		(start 40.856916 -11.881104)
		(end 40.9956 -12.019788)
		(stroke
			(width 0.06477)
			(type default)
		)
		(layer "F.Cu")
	)
	(gr_line
		(start 40.856916 -11.26998)
		(end 40.856916 -11.881104)
		(stroke
			(width 0.06477)
			(type default)
		)
		(layer "F.Cu")
	)
	(gr_line
		(start 40.960294 -17.890236)
		(end 41.256204 -18.186146)
		(stroke
			(width 0.06477)
			(type default)
		)
		(layer "F.Cu")
	)
	(gr_line
		(start 41.17086 -425.748958)
		(end 40.678608 -425.256706)
		(stroke
			(width 0.06477)
			(type default)
		)
		(layer "F.Cu")
	)
	(gr_line
		(start 41.173146 -426.075094)
		(end 40.684704 -426.563536)
		(stroke
			(width 0.06477)
			(type default)
		)
		(layer "F.Cu")
	)
	(gr_line
		(start 41.173146 -426.072808)
		(end 41.173146 -426.075094)
		(stroke
			(width 0.06477)
			(type default)
		)
		(layer "F.Cu")
	)
	(gr_line
		(start 41.173146 -425.748958)
		(end 41.17086 -425.748958)
		(stroke
			(width 0.06477)
			(type default)
		)
		(layer "F.Cu")
	)
	(gr_line
		(start 41.256204 -18.86585)
		(end 40.985694 -19.13636)
		(stroke
			(width 0.06477)
			(type default)
		)
		(layer "F.Cu")
	)
	(gr_line
		(start 41.256204 -17.060926)
		(end 40.960294 -17.356836)
		(stroke
			(width 0.06477)
			(type default)
		)
		(layer "F.Cu")
	)
	(gr_line
		(start 41.282874 -387.789674)
		(end 41.553384 -387.519164)
		(stroke
			(width 0.06477)
			(type default)
		)
		(layer "F.Cu")
	)
	(gr_line
		(start 41.282874 -386.926074)
		(end 41.553384 -387.196584)
		(stroke
			(width 0.06477)
			(type default)
		)
		(layer "F.Cu")
	)
	(gr_line
		(start 41.430702 -382.36906)
		(end 41.701212 -382.09855)
		(stroke
			(width 0.06477)
			(type default)
		)
		(layer "F.Cu")
	)
	(gr_line
		(start 41.430702 -381.50546)
		(end 41.701212 -381.77597)
		(stroke
			(width 0.06477)
			(type default)
		)
		(layer "F.Cu")
	)
	(gr_line
		(start 41.430702 -376.83186)
		(end 41.701212 -376.56135)
		(stroke
			(width 0.06477)
			(type default)
		)
		(layer "F.Cu")
	)
	(gr_line
		(start 41.430702 -375.96826)
		(end 41.701212 -376.23877)
		(stroke
			(width 0.06477)
			(type default)
		)
		(layer "F.Cu")
	)
	(gr_line
		(start 41.456864 -11.881104)
		(end 41.31818 -12.019788)
		(stroke
			(width 0.06477)
			(type default)
		)
		(layer "F.Cu")
	)
	(gr_line
		(start 41.456864 -11.26998)
		(end 41.456864 -11.881104)
		(stroke
			(width 0.06477)
			(type default)
		)
		(layer "F.Cu")
	)
	(gr_line
		(start 41.578784 -18.86585)
		(end 41.849294 -19.13636)
		(stroke
			(width 0.06477)
			(type default)
		)
		(layer "F.Cu")
	)
	(gr_line
		(start 41.578784 -17.060926)
		(end 41.874694 -17.356836)
		(stroke
			(width 0.06477)
			(type default)
		)
		(layer "F.Cu")
	)
	(gr_line
		(start 41.733724 -426.071538)
		(end 41.715944 -426.071538)
		(stroke
			(width 0.06477)
			(type default)
		)
		(layer "F.Cu")
	)
	(gr_line
		(start 41.755314 -422.796208)
		(end 41.773094 -422.796208)
		(stroke
			(width 0.06477)
			(type default)
		)
		(layer "F.Cu")
	)
	(gr_line
		(start 41.756584 -422.472358)
		(end 42.034714 -422.194228)
		(stroke
			(width 0.06477)
			(type default)
		)
		(layer "F.Cu")
	)
	(gr_line
		(start 41.773094 -422.796208)
		(end 42.034714 -423.057828)
		(stroke
			(width 0.06477)
			(type default)
		)
		(layer "F.Cu")
	)
	(gr_line
		(start 41.874694 -17.890236)
		(end 41.578784 -18.186146)
		(stroke
			(width 0.06477)
			(type default)
		)
		(layer "F.Cu")
	)
	(gr_line
		(start 41.995344 -426.333158)
		(end 41.733724 -426.071538)
		(stroke
			(width 0.06477)
			(type default)
		)
		(layer "F.Cu")
	)
	(gr_line
		(start 41.995344 -425.469558)
		(end 41.717214 -425.747688)
		(stroke
			(width 0.06477)
			(type default)
		)
		(layer "F.Cu")
	)
	(gr_line
		(start 42.016172 -387.519164)
		(end 42.261282 -387.764274)
		(stroke
			(width 0.06477)
			(type default)
		)
		(layer "F.Cu")
	)
	(gr_line
		(start 42.016172 -387.196584)
		(end 42.261282 -386.951474)
		(stroke
			(width 0.06477)
			(type default)
		)
		(layer "F.Cu")
	)
	(gr_line
		(start 42.404792 -382.09855)
		(end 42.700702 -382.39446)
		(stroke
			(width 0.06477)
			(type default)
		)
		(layer "F.Cu")
	)
	(gr_line
		(start 42.404792 -381.77597)
		(end 42.700702 -381.48006)
		(stroke
			(width 0.06477)
			(type default)
		)
		(layer "F.Cu")
	)
	(gr_line
		(start 42.404792 -376.56135)
		(end 42.700702 -376.85726)
		(stroke
			(width 0.06477)
			(type default)
		)
		(layer "F.Cu")
	)
	(gr_line
		(start 42.404792 -376.23877)
		(end 42.700702 -375.94286)
		(stroke
			(width 0.06477)
			(type default)
		)
		(layer "F.Cu")
	)
	(gr_line
		(start 42.657014 -11.881104)
		(end 42.795698 -12.019788)
		(stroke
			(width 0.06477)
			(type default)
		)
		(layer "F.Cu")
	)
	(gr_line
		(start 42.657014 -11.26998)
		(end 42.657014 -11.881104)
		(stroke
			(width 0.06477)
			(type default)
		)
		(layer "F.Cu")
	)
	(gr_line
		(start 42.794682 -387.764274)
		(end 43.039284 -387.519672)
		(stroke
			(width 0.06477)
			(type default)
		)
		(layer "F.Cu")
	)
	(gr_line
		(start 42.794682 -386.951474)
		(end 43.03903 -387.195822)
		(stroke
			(width 0.06477)
			(type default)
		)
		(layer "F.Cu")
	)
	(gr_line
		(start 42.989754 -373.30253)
		(end 43.339004 -373.65178)
		(stroke
			(width 0.0508)
			(type default)
		)
		(layer "F.Cu")
	)
	(gr_line
		(start 43.015154 -371.49913)
		(end 43.285664 -371.76964)
		(stroke
			(width 0.06477)
			(type default)
		)
		(layer "F.Cu")
	)
	(gr_line
		(start 43.03903 -387.195822)
		(end 43.040554 -387.195822)
		(stroke
			(width 0.06477)
			(type default)
		)
		(layer "F.Cu")
	)
	(gr_line
		(start 43.234102 -382.39446)
		(end 43.58386 -382.044702)
		(stroke
			(width 0.0508)
			(type default)
		)
		(layer "F.Cu")
	)
	(gr_line
		(start 43.234102 -381.48006)
		(end 43.581574 -381.827532)
		(stroke
			(width 0.0508)
			(type default)
		)
		(layer "F.Cu")
	)
	(gr_line
		(start 43.234102 -376.85726)
		(end 43.603926 -376.487436)
		(stroke
			(width 0.0508)
			(type default)
		)
		(layer "F.Cu")
	)
	(gr_line
		(start 43.234102 -375.94286)
		(end 43.561508 -376.270266)
		(stroke
			(width 0.0508)
			(type default)
		)
		(layer "F.Cu")
	)
	(gr_line
		(start 43.256962 -11.881104)
		(end 43.118278 -12.019788)
		(stroke
			(width 0.06477)
			(type default)
		)
		(layer "F.Cu")
	)
	(gr_line
		(start 43.256962 -11.26998)
		(end 43.256962 -11.881104)
		(stroke
			(width 0.06477)
			(type default)
		)
		(layer "F.Cu")
	)
	(gr_line
		(start 43.285664 -372.47322)
		(end 42.989754 -372.76913)
		(stroke
			(width 0.06477)
			(type default)
		)
		(layer "F.Cu")
	)
	(gr_line
		(start 43.29811 -387.195822)
		(end 43.299634 -387.195822)
		(stroke
			(width 0.06477)
			(type default)
		)
		(layer "F.Cu")
	)
	(gr_line
		(start 43.29938 -387.519672)
		(end 43.543982 -387.764274)
		(stroke
			(width 0.06477)
			(type default)
		)
		(layer "F.Cu")
	)
	(gr_line
		(start 43.299634 -387.195822)
		(end 43.543982 -386.951474)
		(stroke
			(width 0.06477)
			(type default)
		)
		(layer "F.Cu")
	)
	(gr_line
		(start 43.543982 -387.764274)
		(end 43.800014 -387.508242)
		(stroke
			(width 0.06477)
			(type default)
		)
		(layer "F.Cu")
	)
	(gr_line
		(start 43.543982 -386.951474)
		(end 43.7769 -387.184392)
		(stroke
			(width 0.06477)
			(type default)
		)
		(layer "F.Cu")
	)
	(gr_line
		(start 43.561508 -376.270266)
		(end 43.605196 -376.270266)
		(stroke
			(width 0.0508)
			(type default)
		)
		(layer "F.Cu")
	)
	(gr_line
		(start 43.581574 -381.827532)
		(end 43.58513 -381.827532)
		(stroke
			(width 0.0508)
			(type default)
		)
		(layer "F.Cu")
	)
	(gr_line
		(start 43.608244 -372.47322)
		(end 43.904154 -372.76913)
		(stroke
			(width 0.06477)
			(type default)
		)
		(layer "F.Cu")
	)
	(gr_line
		(start 43.754294 -16.366236)
		(end 44.050204 -16.662146)
		(stroke
			(width 0.06477)
			(type default)
		)
		(layer "F.Cu")
	)
	(gr_line
		(start 43.7769 -387.184392)
		(end 43.801284 -387.184392)
		(stroke
			(width 0.06477)
			(type default)
		)
		(layer "F.Cu")
	)
	(gr_line
		(start 43.878754 -371.49913)
		(end 43.608244 -371.76964)
		(stroke
			(width 0.06477)
			(type default)
		)
		(layer "F.Cu")
	)
	(gr_line
		(start 43.88993 -381.827532)
		(end 44.41825 -381.827532)
		(stroke
			(width 0.0508)
			(type default)
		)
		(layer "F.Cu")
	)
	(gr_line
		(start 43.8912 -382.044702)
		(end 44.00169 -382.155192)
		(stroke
			(width 0.0508)
			(type default)
		)
		(layer "F.Cu")
	)
	(gr_line
		(start 43.904154 -373.30253)
		(end 43.554904 -373.65178)
		(stroke
			(width 0.0508)
			(type default)
		)
		(layer "F.Cu")
	)
	(gr_line
		(start 44.00169 -382.155192)
		(end 44.30649 -382.155192)
		(stroke
			(width 0.0508)
			(type default)
		)
		(layer "F.Cu")
	)
	(gr_line
		(start 44.050204 -17.34185)
		(end 43.779694 -17.61236)
		(stroke
			(width 0.06477)
			(type default)
		)
		(layer "F.Cu")
	)
	(gr_line
		(start 44.050204 -15.536926)
		(end 43.754294 -15.832836)
		(stroke
			(width 0.06477)
			(type default)
		)
		(layer "F.Cu")
	)
	(gr_line
		(start 44.30649 -382.155192)
		(end 44.41698 -382.044702)
		(stroke
			(width 0.0508)
			(type default)
		)
		(layer "F.Cu")
	)
	(gr_line
		(start 44.372784 -17.34185)
		(end 44.643294 -17.61236)
		(stroke
			(width 0.06477)
			(type default)
		)
		(layer "F.Cu")
	)
	(gr_line
		(start 44.372784 -15.536926)
		(end 44.668694 -15.832836)
		(stroke
			(width 0.06477)
			(type default)
		)
		(layer "F.Cu")
	)
	(gr_line
		(start 44.457112 -11.881104)
		(end 44.595796 -12.019788)
		(stroke
			(width 0.06477)
			(type default)
		)
		(layer "F.Cu")
	)
	(gr_line
		(start 44.457112 -11.26998)
		(end 44.457112 -11.881104)
		(stroke
			(width 0.06477)
			(type default)
		)
		(layer "F.Cu")
	)
	(gr_line
		(start 44.668694 -16.366236)
		(end 44.372784 -16.662146)
		(stroke
			(width 0.06477)
			(type default)
		)
		(layer "F.Cu")
	)
	(gr_line
		(start 44.691554 -370.83873)
		(end 45.040804 -371.18798)
		(stroke
			(width 0.0508)
			(type default)
		)
		(layer "F.Cu")
	)
	(gr_line
		(start 44.716954 -369.03533)
		(end 44.987464 -369.30584)
		(stroke
			(width 0.06477)
			(type default)
		)
		(layer "F.Cu")
	)
	(gr_line
		(start 44.72305 -381.827532)
		(end 45.25137 -381.827532)
		(stroke
			(width 0.0508)
			(type default)
		)
		(layer "F.Cu")
	)
	(gr_line
		(start 44.72432 -382.044702)
		(end 44.83481 -382.155192)
		(stroke
			(width 0.0508)
			(type default)
		)
		(layer "F.Cu")
	)
	(gr_line
		(start 44.83481 -382.155192)
		(end 45.13961 -382.155192)
		(stroke
			(width 0.0508)
			(type default)
		)
		(layer "F.Cu")
	)
	(gr_line
		(start 44.987464 -370.00942)
		(end 44.691554 -370.30533)
		(stroke
			(width 0.06477)
			(type default)
		)
		(layer "F.Cu")
	)
	(gr_line
		(start 45.05706 -11.881104)
		(end 44.918376 -12.019788)
		(stroke
			(width 0.06477)
			(type default)
		)
		(layer "F.Cu")
	)
	(gr_line
		(start 45.05706 -11.26998)
		(end 45.05706 -11.881104)
		(stroke
			(width 0.06477)
			(type default)
		)
		(layer "F.Cu")
	)
	(gr_line
		(start 45.13961 -382.155192)
		(end 45.2501 -382.044702)
		(stroke
			(width 0.0508)
			(type default)
		)
		(layer "F.Cu")
	)
	(gr_line
		(start 45.310044 -370.00942)
		(end 45.605954 -370.30533)
		(stroke
			(width 0.06477)
			(type default)
		)
		(layer "F.Cu")
	)
	(gr_line
		(start 45.326554 -375.942098)
		(end 45.700442 -376.315986)
		(stroke
			(width 0.0508)
			(type default)
		)
		(layer "F.Cu")
	)
	(gr_line
		(start 45.335444 -378.53239)
		(end 45.45203 -378.81433)
		(stroke
			(width 0.0508)
			(type default)
		)
		(layer "F.Cu")
	)
	(gr_line
		(start 45.395388 -378.387864)
		(end 45.335444 -378.53239)
		(stroke
			(width 0.0508)
			(type default)
		)
		(layer "F.Cu")
	)
	(gr_line
		(start 45.45203 -378.81433)
		(end 45.59681 -378.87402)
		(stroke
			(width 0.0508)
			(type default)
		)
		(layer "F.Cu")
	)
	(gr_line
		(start 45.480732 -375.78919)
		(end 45.63745 -375.78919)
		(stroke
			(width 0.0508)
			(type default)
		)
		(layer "F.Cu")
	)
	(gr_line
		(start 45.498004 -387.531102)
		(end 46.101762 -387.531102)
		(stroke
			(width 0.0508)
			(type default)
		)
		(layer "F.Cu")
	)
	(gr_line
		(start 45.499274 -387.748272)
		(end 45.582078 -387.831076)
		(stroke
			(width 0.0508)
			(type default)
		)
		(layer "F.Cu")
	)
	(gr_line
		(start 45.580554 -369.03533)
		(end 45.310044 -369.30584)
		(stroke
			(width 0.06477)
			(type default)
		)
		(layer "F.Cu")
	)
	(gr_line
		(start 45.595794 -378.30379)
		(end 45.797978 -378.792232)
		(stroke
			(width 0.0508)
			(type default)
		)
		(layer "F.Cu")
	)
	(gr_line
		(start 45.605954 -370.83873)
		(end 45.256704 -371.18798)
		(stroke
			(width 0.0508)
			(type default)
		)
		(layer "F.Cu")
	)
	(gr_line
		(start 45.63745 -375.78919)
		(end 45.85335 -376.00509)
		(stroke
			(width 0.0508)
			(type default)
		)
		(layer "F.Cu")
	)
	(gr_line
		(start 45.85335 -376.00509)
		(end 45.85335 -376.161808)
		(stroke
			(width 0.0508)
			(type default)
		)
		(layer "F.Cu")
	)
	(gr_line
		(start 45.88002 -379.62967)
		(end 46.049438 -379.883162)
		(stroke
			(width 0.0508)
			(type default)
		)
		(layer "F.Cu")
	)
	(gr_line
		(start 45.9105 -379.476)
		(end 45.88002 -379.62967)
		(stroke
			(width 0.0508)
			(type default)
		)
		(layer "F.Cu")
	)
	(gr_line
		(start 46.039278 -372.921022)
		(end 46.413166 -373.294656)
		(stroke
			(width 0.0508)
			(type default)
		)
		(layer "F.Cu")
	)
	(gr_line
		(start 46.049438 -379.883162)
		(end 46.203108 -379.913896)
		(stroke
			(width 0.0508)
			(type default)
		)
		(layer "F.Cu")
	)
	(gr_line
		(start 46.090332 -379.354588)
		(end 46.090586 -379.354588)
		(stroke
			(width 0.0508)
			(type default)
		)
		(layer "F.Cu")
	)
	(gr_line
		(start 46.090586 -379.354588)
		(end 46.38421 -379.794008)
		(stroke
			(width 0.0508)
			(type default)
		)
		(layer "F.Cu")
	)
	(gr_line
		(start 46.19371 -372.768114)
		(end 46.350174 -372.768114)
		(stroke
			(width 0.0508)
			(type default)
		)
		(layer "F.Cu")
	)
	(gr_line
		(start 46.350174 -372.768114)
		(end 46.566074 -372.984014)
		(stroke
			(width 0.0508)
			(type default)
		)
		(layer "F.Cu")
	)
	(gr_line
		(start 46.38421 -379.794008)
		(end 46.38421 -379.794262)
		(stroke
			(width 0.0508)
			(type default)
		)
		(layer "F.Cu")
	)
	(gr_line
		(start 46.413166 -373.294656)
		(end 46.413166 -373.29491)
		(stroke
			(width 0.0508)
			(type default)
		)
		(layer "F.Cu")
	)
	(gr_line
		(start 46.548294 -17.890236)
		(end 46.844204 -18.186146)
		(stroke
			(width 0.06477)
			(type default)
		)
		(layer "F.Cu")
	)
	(gr_line
		(start 46.566074 -372.984014)
		(end 46.566074 -373.140478)
		(stroke
			(width 0.0508)
			(type default)
		)
		(layer "F.Cu")
	)
	(gr_line
		(start 46.81601 -383.50571)
		(end 46.907196 -383.596896)
		(stroke
			(width 0.0508)
			(type default)
		)
		(layer "F.Cu")
	)
	(gr_line
		(start 46.81601 -383.2352)
		(end 46.81601 -383.50571)
		(stroke
			(width 0.0508)
			(type default)
		)
		(layer "F.Cu")
	)
	(gr_line
		(start 46.842934 -18.866866)
		(end 46.572678 -19.137122)
		(stroke
			(width 0.06477)
			(type default)
		)
		(layer "F.Cu")
	)
	(gr_line
		(start 46.844204 -17.060926)
		(end 46.548294 -17.356836)
		(stroke
			(width 0.06477)
			(type default)
		)
		(layer "F.Cu")
	)
	(gr_line
		(start 46.907196 -383.596896)
		(end 47.041562 -383.596896)
		(stroke
			(width 0.0508)
			(type default)
		)
		(layer "F.Cu")
	)
	(gr_line
		(start 47.041562 -383.596896)
		(end 47.118016 -383.520442)
		(stroke
			(width 0.0508)
			(type default)
		)
		(layer "F.Cu")
	)
	(gr_line
		(start 47.107348 -382.943862)
		(end 46.81601 -383.2352)
		(stroke
			(width 0.0508)
			(type default)
		)
		(layer "F.Cu")
	)
	(gr_line
		(start 47.118016 -383.520442)
		(end 47.118016 -383.402586)
		(stroke
			(width 0.0508)
			(type default)
		)
		(layer "F.Cu")
	)
	(gr_line
		(start 47.166784 -18.867628)
		(end 47.436278 -19.137122)
		(stroke
			(width 0.06477)
			(type default)
		)
		(layer "F.Cu")
	)
	(gr_line
		(start 47.166784 -18.865596)
		(end 47.166784 -18.867628)
		(stroke
			(width 0.06477)
			(type default)
		)
		(layer "F.Cu")
	)
	(gr_line
		(start 47.166784 -17.060926)
		(end 47.462694 -17.356836)
		(stroke
			(width 0.06477)
			(type default)
		)
		(layer "F.Cu")
	)
	(gr_line
		(start 47.201328 -391.36447)
		(end 47.118016 -391.281158)
		(stroke
			(width 0.0508)
			(type default)
		)
		(layer "F.Cu")
	)
	(gr_line
		(start 47.27067 -388.774432)
		(end 47.79137 -388.774432)
		(stroke
			(width 0.0635)
			(type default)
		)
		(layer "F.Cu")
	)
	(gr_line
		(start 47.27067 -385.31038)
		(end 47.79137 -385.31038)
		(stroke
			(width 0.0635)
			(type default)
		)
		(layer "F.Cu")
	)
	(gr_line
		(start 47.324518 -383.13741)
		(end 47.41799 -383.230882)
		(stroke
			(width 0.0508)
			(type default)
		)
		(layer "F.Cu")
	)
	(gr_line
		(start 47.324518 -382.942592)
		(end 47.324518 -383.13741)
		(stroke
			(width 0.0508)
			(type default)
		)
		(layer "F.Cu")
	)
	(gr_line
		(start 47.41799 -383.230882)
		(end 47.41799 -383.92227)
		(stroke
			(width 0.0508)
			(type default)
		)
		(layer "F.Cu")
	)
	(gr_line
		(start 47.418498 -391.36574)
		(end 47.418498 -390.761982)
		(stroke
			(width 0.0508)
			(type default)
		)
		(layer "F.Cu")
	)
	(gr_line
		(start 47.418498 -390.761982)
		(end 47.41799 -390.761474)
		(stroke
			(width 0.0508)
			(type default)
		)
		(layer "F.Cu")
	)
	(gr_line
		(start 47.462694 -17.890236)
		(end 47.166784 -18.186146)
		(stroke
			(width 0.06477)
			(type default)
		)
		(layer "F.Cu")
	)
	(gr_line
		(start 47.67072 -389.467344)
		(end 48.19142 -389.467344)
		(stroke
			(width 0.0635)
			(type default)
		)
		(layer "F.Cu")
	)
	(gr_line
		(start 47.67072 -386.003292)
		(end 48.19142 -386.003292)
		(stroke
			(width 0.0635)
			(type default)
		)
		(layer "F.Cu")
	)
	(gr_line
		(start 47.677832 -392.977116)
		(end 47.6758 -392.977116)
		(stroke
			(width 0.0508)
			(type default)
		)
		(layer "F.Cu")
	)
	(gr_line
		(start 47.768764 -408.784044)
		(end 48.064674 -409.079954)
		(stroke
			(width 0.06477)
			(type default)
		)
		(layer "F.Cu")
	)
	(gr_line
		(start 47.794164 -404.46452)
		(end 48.064674 -404.73503)
		(stroke
			(width 0.06477)
			(type default)
		)
		(layer "F.Cu")
	)
	(gr_line
		(start 47.816516 -393.292838)
		(end 47.816516 -393.1158)
		(stroke
			(width 0.0508)
			(type default)
		)
		(layer "F.Cu")
	)
	(gr_line
		(start 47.816516 -393.1158)
		(end 47.677832 -392.977116)
		(stroke
			(width 0.0508)
			(type default)
		)
		(layer "F.Cu")
	)
	(gr_line
		(start 47.816516 -392.6205)
		(end 47.67707 -392.759946)
		(stroke
			(width 0.0508)
			(type default)
		)
		(layer "F.Cu")
	)
	(gr_line
		(start 47.816516 -392.429238)
		(end 47.816516 -392.6205)
		(stroke
			(width 0.0508)
			(type default)
		)
		(layer "F.Cu")
	)
	(gr_line
		(start 48.015906 -383.50571)
		(end 48.107092 -383.596896)
		(stroke
			(width 0.0508)
			(type default)
		)
		(layer "F.Cu")
	)
	(gr_line
		(start 48.015906 -383.2352)
		(end 48.015906 -383.50571)
		(stroke
			(width 0.0508)
			(type default)
		)
		(layer "F.Cu")
	)
	(gr_line
		(start 48.064674 -412.299658)
		(end 47.794164 -412.570168)
		(stroke
			(width 0.06477)
			(type default)
		)
		(layer "F.Cu")
	)
	(gr_line
		(start 48.064674 -407.954734)
		(end 47.768764 -408.250644)
		(stroke
			(width 0.06477)
			(type default)
		)
		(layer "F.Cu")
	)
	(gr_line
		(start 48.095154 -375.76633)
		(end 48.444404 -376.11558)
		(stroke
			(width 0.0508)
			(type default)
		)
		(layer "F.Cu")
	)
	(gr_line
		(start 48.107092 -383.596896)
		(end 48.241458 -383.596896)
		(stroke
			(width 0.0508)
			(type default)
		)
		(layer "F.Cu")
	)
	(gr_line
		(start 48.120554 -373.96293)
		(end 48.391064 -374.23344)
		(stroke
			(width 0.06477)
			(type default)
		)
		(layer "F.Cu")
	)
	(gr_line
		(start 48.241458 -383.596896)
		(end 48.317912 -383.520442)
		(stroke
			(width 0.0508)
			(type default)
		)
		(layer "F.Cu")
	)
	(gr_line
		(start 48.307244 -382.943862)
		(end 48.015906 -383.2352)
		(stroke
			(width 0.0508)
			(type default)
		)
		(layer "F.Cu")
	)
	(gr_line
		(start 48.317912 -383.520442)
		(end 48.317912 -383.402586)
		(stroke
			(width 0.0508)
			(type default)
		)
		(layer "F.Cu")
	)
	(gr_line
		(start 48.387254 -412.299658)
		(end 48.657764 -412.570168)
		(stroke
			(width 0.06477)
			(type default)
		)
		(layer "F.Cu")
	)
	(gr_line
		(start 48.387254 -407.954734)
		(end 48.683164 -408.250644)
		(stroke
			(width 0.06477)
			(type default)
		)
		(layer "F.Cu")
	)
	(gr_line
		(start 48.391064 -374.93702)
		(end 48.095154 -375.23293)
		(stroke
			(width 0.06477)
			(type default)
		)
		(layer "F.Cu")
	)
	(gr_line
		(start 48.401224 -391.36447)
		(end 48.317912 -391.281158)
		(stroke
			(width 0.0508)
			(type default)
		)
		(layer "F.Cu")
	)
	(gr_line
		(start 48.470566 -388.774432)
		(end 48.991266 -388.774432)
		(stroke
			(width 0.0635)
			(type default)
		)
		(layer "F.Cu")
	)
	(gr_line
		(start 48.470566 -385.31038)
		(end 48.991266 -385.31038)
		(stroke
			(width 0.0635)
			(type default)
		)
		(layer "F.Cu")
	)
	(gr_line
		(start 48.524414 -383.13741)
		(end 48.617886 -383.230882)
		(stroke
			(width 0.0508)
			(type default)
		)
		(layer "F.Cu")
	)
	(gr_line
		(start 48.524414 -382.942592)
		(end 48.524414 -383.13741)
		(stroke
			(width 0.0508)
			(type default)
		)
		(layer "F.Cu")
	)
	(gr_line
		(start 48.617886 -383.230882)
		(end 48.617886 -383.92227)
		(stroke
			(width 0.0508)
			(type default)
		)
		(layer "F.Cu")
	)
	(gr_line
		(start 48.618394 -391.36574)
		(end 48.618394 -390.761982)
		(stroke
			(width 0.0508)
			(type default)
		)
		(layer "F.Cu")
	)
	(gr_line
		(start 48.618394 -390.761982)
		(end 48.617886 -390.761474)
		(stroke
			(width 0.0508)
			(type default)
		)
		(layer "F.Cu")
	)
	(gr_line
		(start 48.657764 -404.46452)
		(end 48.387254 -404.73503)
		(stroke
			(width 0.06477)
			(type default)
		)
		(layer "F.Cu")
	)
	(gr_line
		(start 48.683164 -408.784044)
		(end 48.387254 -409.079954)
		(stroke
			(width 0.06477)
			(type default)
		)
		(layer "F.Cu")
	)
	(gr_line
		(start 48.713644 -374.93702)
		(end 49.009554 -375.23293)
		(stroke
			(width 0.06477)
			(type default)
		)
		(layer "F.Cu")
	)
	(gr_line
		(start 48.870616 -389.467344)
		(end 49.391316 -389.467344)
		(stroke
			(width 0.0635)
			(type default)
		)
		(layer "F.Cu")
	)
	(gr_line
		(start 48.870616 -386.003292)
		(end 49.391316 -386.003292)
		(stroke
			(width 0.0635)
			(type default)
		)
		(layer "F.Cu")
	)
	(gr_line
		(start 48.877728 -392.977116)
		(end 48.875696 -392.977116)
		(stroke
			(width 0.0508)
			(type default)
		)
		(layer "F.Cu")
	)
	(gr_line
		(start 48.984154 -373.96293)
		(end 48.713644 -374.23344)
		(stroke
			(width 0.06477)
			(type default)
		)
		(layer "F.Cu")
	)
	(gr_line
		(start 49.009554 -375.76633)
		(end 48.660304 -376.11558)
		(stroke
			(width 0.0508)
			(type default)
		)
		(layer "F.Cu")
	)
	(gr_line
		(start 49.016412 -393.292838)
		(end 49.016412 -393.1158)
		(stroke
			(width 0.0508)
			(type default)
		)
		(layer "F.Cu")
	)
	(gr_line
		(start 49.016412 -393.1158)
		(end 48.877728 -392.977116)
		(stroke
			(width 0.0508)
			(type default)
		)
		(layer "F.Cu")
	)
	(gr_line
		(start 49.016412 -392.6205)
		(end 48.876966 -392.759946)
		(stroke
			(width 0.0508)
			(type default)
		)
		(layer "F.Cu")
	)
	(gr_line
		(start 49.016412 -392.429238)
		(end 49.016412 -392.6205)
		(stroke
			(width 0.0508)
			(type default)
		)
		(layer "F.Cu")
	)
	(gr_line
		(start 49.216056 -383.50571)
		(end 49.307242 -383.596896)
		(stroke
			(width 0.0508)
			(type default)
		)
		(layer "F.Cu")
	)
	(gr_line
		(start 49.216056 -383.2352)
		(end 49.216056 -383.50571)
		(stroke
			(width 0.0508)
			(type default)
		)
		(layer "F.Cu")
	)
	(gr_line
		(start 49.251108 -377.606814)
		(end 49.586642 -378.015754)
		(stroke
			(width 0.0508)
			(type default)
		)
		(layer "F.Cu")
	)
	(gr_line
		(start 49.307242 -383.596896)
		(end 49.441608 -383.596896)
		(stroke
			(width 0.0508)
			(type default)
		)
		(layer "F.Cu")
	)
	(gr_line
		(start 49.342294 -16.366236)
		(end 49.638204 -16.662146)
		(stroke
			(width 0.06477)
			(type default)
		)
		(layer "F.Cu")
	)
	(gr_line
		(start 49.419764 -377.470162)
		(end 49.575212 -377.485402)
		(stroke
			(width 0.0508)
			(type default)
		)
		(layer "F.Cu")
	)
	(gr_line
		(start 49.441608 -383.596896)
		(end 49.518062 -383.520442)
		(stroke
			(width 0.0508)
			(type default)
		)
		(layer "F.Cu")
	)
	(gr_line
		(start 49.507394 -382.943862)
		(end 49.216056 -383.2352)
		(stroke
			(width 0.0508)
			(type default)
		)
		(layer "F.Cu")
	)
	(gr_line
		(start 49.518062 -383.520442)
		(end 49.518062 -383.402586)
		(stroke
			(width 0.0508)
			(type default)
		)
		(layer "F.Cu")
	)
	(gr_line
		(start 49.575212 -377.485402)
		(end 49.76876 -377.721114)
		(stroke
			(width 0.0508)
			(type default)
		)
		(layer "F.Cu")
	)
	(gr_line
		(start 49.601374 -391.36447)
		(end 49.518062 -391.281158)
		(stroke
			(width 0.0508)
			(type default)
		)
		(layer "F.Cu")
	)
	(gr_line
		(start 49.638204 -17.34185)
		(end 49.367694 -17.61236)
		(stroke
			(width 0.06477)
			(type default)
		)
		(layer "F.Cu")
	)
	(gr_line
		(start 49.638204 -15.536926)
		(end 49.342294 -15.832836)
		(stroke
			(width 0.06477)
			(type default)
		)
		(layer "F.Cu")
	)
	(gr_line
		(start 49.670716 -388.774432)
		(end 50.191416 -388.774432)
		(stroke
			(width 0.0635)
			(type default)
		)
		(layer "F.Cu")
	)
	(gr_line
		(start 49.670716 -385.31038)
		(end 50.191416 -385.31038)
		(stroke
			(width 0.0635)
			(type default)
		)
		(layer "F.Cu")
	)
	(gr_line
		(start 49.724564 -383.13741)
		(end 49.818036 -383.230882)
		(stroke
			(width 0.0508)
			(type default)
		)
		(layer "F.Cu")
	)
	(gr_line
		(start 49.724564 -382.942592)
		(end 49.724564 -383.13741)
		(stroke
			(width 0.0508)
			(type default)
		)
		(layer "F.Cu")
	)
	(gr_line
		(start 49.76876 -377.721114)
		(end 49.753774 -377.87707)
		(stroke
			(width 0.0508)
			(type default)
		)
		(layer "F.Cu")
	)
	(gr_line
		(start 49.796954 -373.30253)
		(end 50.146204 -373.65178)
		(stroke
			(width 0.0508)
			(type default)
		)
		(layer "F.Cu")
	)
	(gr_line
		(start 49.818036 -383.230882)
		(end 49.818036 -383.92227)
		(stroke
			(width 0.0508)
			(type default)
		)
		(layer "F.Cu")
	)
	(gr_line
		(start 49.818544 -391.36574)
		(end 49.818544 -390.761982)
		(stroke
			(width 0.0508)
			(type default)
		)
		(layer "F.Cu")
	)
	(gr_line
		(start 49.818544 -390.761982)
		(end 49.818036 -390.761474)
		(stroke
			(width 0.0508)
			(type default)
		)
		(layer "F.Cu")
	)
	(gr_line
		(start 49.822354 -371.49913)
		(end 50.092864 -371.76964)
		(stroke
			(width 0.06477)
			(type default)
		)
		(layer "F.Cu")
	)
	(gr_line
		(start 49.960784 -17.34185)
		(end 50.231294 -17.61236)
		(stroke
			(width 0.06477)
			(type default)
		)
		(layer "F.Cu")
	)
	(gr_line
		(start 49.960784 -15.536926)
		(end 50.256694 -15.832836)
		(stroke
			(width 0.06477)
			(type default)
		)
		(layer "F.Cu")
	)
	(gr_line
		(start 50.070512 -389.467344)
		(end 50.591212 -389.467344)
		(stroke
			(width 0.0635)
			(type default)
		)
		(layer "F.Cu")
	)
	(gr_line
		(start 50.070512 -386.003292)
		(end 50.591212 -386.003292)
		(stroke
			(width 0.0635)
			(type default)
		)
		(layer "F.Cu")
	)
	(gr_line
		(start 50.077878 -392.977116)
		(end 50.075846 -392.977116)
		(stroke
			(width 0.0508)
			(type default)
		)
		(layer "F.Cu")
	)
	(gr_line
		(start 50.092864 -372.47322)
		(end 49.796954 -372.76913)
		(stroke
			(width 0.06477)
			(type default)
		)
		(layer "F.Cu")
	)
	(gr_line
		(start 50.146204 -374.529096)
		(end 50.146204 -375.057416)
		(stroke
			(width 0.0508)
			(type default)
		)
		(layer "F.Cu")
	)
	(gr_line
		(start 50.216562 -393.292838)
		(end 50.216562 -393.1158)
		(stroke
			(width 0.0508)
			(type default)
		)
		(layer "F.Cu")
	)
	(gr_line
		(start 50.216562 -393.1158)
		(end 50.077878 -392.977116)
		(stroke
			(width 0.0508)
			(type default)
		)
		(layer "F.Cu")
	)
	(gr_line
		(start 50.216562 -392.6205)
		(end 50.077116 -392.759946)
		(stroke
			(width 0.0508)
			(type default)
		)
		(layer "F.Cu")
	)
	(gr_line
		(start 50.216562 -392.429238)
		(end 50.216562 -392.6205)
		(stroke
			(width 0.0508)
			(type default)
		)
		(layer "F.Cu")
	)
	(gr_line
		(start 50.256694 -16.366236)
		(end 49.960784 -16.662146)
		(stroke
			(width 0.06477)
			(type default)
		)
		(layer "F.Cu")
	)
	(gr_line
		(start 50.267108 -11.881104)
		(end 50.405792 -12.019788)
		(stroke
			(width 0.06477)
			(type default)
		)
		(layer "F.Cu")
	)
	(gr_line
		(start 50.267108 -11.26998)
		(end 50.267108 -11.881104)
		(stroke
			(width 0.06477)
			(type default)
		)
		(layer "F.Cu")
	)
	(gr_line
		(start 50.363374 -374.530366)
		(end 50.473864 -374.640856)
		(stroke
			(width 0.0508)
			(type default)
		)
		(layer "F.Cu")
	)
	(gr_line
		(start 50.415444 -372.47322)
		(end 50.711354 -372.76913)
		(stroke
			(width 0.06477)
			(type default)
		)
		(layer "F.Cu")
	)
	(gr_line
		(start 50.415952 -383.50571)
		(end 50.507138 -383.596896)
		(stroke
			(width 0.0508)
			(type default)
		)
		(layer "F.Cu")
	)
	(gr_line
		(start 50.415952 -383.2352)
		(end 50.415952 -383.50571)
		(stroke
			(width 0.0508)
			(type default)
		)
		(layer "F.Cu")
	)
	(gr_line
		(start 50.473864 -374.945656)
		(end 50.363374 -375.056146)
		(stroke
			(width 0.0508)
			(type default)
		)
		(layer "F.Cu")
	)
	(gr_line
		(start 50.473864 -374.640856)
		(end 50.473864 -374.945656)
		(stroke
			(width 0.0508)
			(type default)
		)
		(layer "F.Cu")
	)
	(gr_line
		(start 50.507138 -383.596896)
		(end 50.641504 -383.596896)
		(stroke
			(width 0.0508)
			(type default)
		)
		(layer "F.Cu")
	)
	(gr_line
		(start 50.641504 -383.596896)
		(end 50.717958 -383.520442)
		(stroke
			(width 0.0508)
			(type default)
		)
		(layer "F.Cu")
	)
	(gr_line
		(start 50.685954 -371.49913)
		(end 50.415444 -371.76964)
		(stroke
			(width 0.06477)
			(type default)
		)
		(layer "F.Cu")
	)
	(gr_line
		(start 50.70729 -382.943862)
		(end 50.415952 -383.2352)
		(stroke
			(width 0.0508)
			(type default)
		)
		(layer "F.Cu")
	)
	(gr_line
		(start 50.711354 -373.30253)
		(end 50.362104 -373.65178)
		(stroke
			(width 0.0508)
			(type default)
		)
		(layer "F.Cu")
	)
	(gr_line
		(start 50.717958 -383.520442)
		(end 50.717958 -383.402586)
		(stroke
			(width 0.0508)
			(type default)
		)
		(layer "F.Cu")
	)
	(gr_line
		(start 50.80127 -391.36447)
		(end 50.717958 -391.281158)
		(stroke
			(width 0.0508)
			(type default)
		)
		(layer "F.Cu")
	)
	(gr_line
		(start 50.832004 -408.784044)
		(end 51.127914 -409.079954)
		(stroke
			(width 0.06477)
			(type default)
		)
		(layer "F.Cu")
	)
	(gr_line
		(start 50.857404 -404.46452)
		(end 51.127914 -404.73503)
		(stroke
			(width 0.06477)
			(type default)
		)
		(layer "F.Cu")
	)
	(gr_line
		(start 50.867056 -11.881104)
		(end 50.728372 -12.019788)
		(stroke
			(width 0.06477)
			(type default)
		)
		(layer "F.Cu")
	)
	(gr_line
		(start 50.867056 -11.26998)
		(end 50.867056 -11.881104)
		(stroke
			(width 0.06477)
			(type default)
		)
		(layer "F.Cu")
	)
	(gr_line
		(start 50.870612 -388.774432)
		(end 51.391312 -388.774432)
		(stroke
			(width 0.0635)
			(type default)
		)
		(layer "F.Cu")
	)
	(gr_line
		(start 50.870612 -385.31038)
		(end 51.391312 -385.31038)
		(stroke
			(width 0.0635)
			(type default)
		)
		(layer "F.Cu")
	)
	(gr_line
		(start 50.92446 -383.13741)
		(end 51.017932 -383.230882)
		(stroke
			(width 0.0508)
			(type default)
		)
		(layer "F.Cu")
	)
	(gr_line
		(start 50.92446 -382.942592)
		(end 50.92446 -383.13741)
		(stroke
			(width 0.0508)
			(type default)
		)
		(layer "F.Cu")
	)
	(gr_line
		(start 51.017932 -383.230882)
		(end 51.017932 -383.92227)
		(stroke
			(width 0.0508)
			(type default)
		)
		(layer "F.Cu")
	)
	(gr_line
		(start 51.01844 -391.36574)
		(end 51.01844 -390.761982)
		(stroke
			(width 0.0508)
			(type default)
		)
		(layer "F.Cu")
	)
	(gr_line
		(start 51.01844 -390.761982)
		(end 51.017932 -390.761474)
		(stroke
			(width 0.0508)
			(type default)
		)
		(layer "F.Cu")
	)
	(gr_line
		(start 51.127914 -412.299658)
		(end 50.857404 -412.570168)
		(stroke
			(width 0.06477)
			(type default)
		)
		(layer "F.Cu")
	)
	(gr_line
		(start 51.127914 -407.954734)
		(end 50.832004 -408.250644)
		(stroke
			(width 0.06477)
			(type default)
		)
		(layer "F.Cu")
	)
	(gr_line
		(start 51.270662 -389.467344)
		(end 51.791362 -389.467344)
		(stroke
			(width 0.0635)
			(type default)
		)
		(layer "F.Cu")
	)
	(gr_line
		(start 51.270662 -386.003292)
		(end 51.791362 -386.003292)
		(stroke
			(width 0.0635)
			(type default)
		)
		(layer "F.Cu")
	)
	(gr_line
		(start 51.277774 -392.977116)
		(end 51.275742 -392.977116)
		(stroke
			(width 0.0508)
			(type default)
		)
		(layer "F.Cu")
	)
	(gr_line
		(start 51.416458 -393.292838)
		(end 51.416458 -393.1158)
		(stroke
			(width 0.0508)
			(type default)
		)
		(layer "F.Cu")
	)
	(gr_line
		(start 51.416458 -393.1158)
		(end 51.277774 -392.977116)
		(stroke
			(width 0.0508)
			(type default)
		)
		(layer "F.Cu")
	)
	(gr_line
		(start 51.416458 -392.6205)
		(end 51.277012 -392.759946)
		(stroke
			(width 0.0508)
			(type default)
		)
		(layer "F.Cu")
	)
	(gr_line
		(start 51.416458 -392.429238)
		(end 51.416458 -392.6205)
		(stroke
			(width 0.0508)
			(type default)
		)
		(layer "F.Cu")
	)
	(gr_line
		(start 51.450494 -412.299658)
		(end 51.721004 -412.570168)
		(stroke
			(width 0.06477)
			(type default)
		)
		(layer "F.Cu")
	)
	(gr_line
		(start 51.450494 -407.954734)
		(end 51.746404 -408.250644)
		(stroke
			(width 0.06477)
			(type default)
		)
		(layer "F.Cu")
	)
	(gr_line
		(start 51.498754 -370.83873)
		(end 51.848004 -371.18798)
		(stroke
			(width 0.0508)
			(type default)
		)
		(layer "F.Cu")
	)
	(gr_line
		(start 51.524154 -369.03533)
		(end 51.794664 -369.30584)
		(stroke
			(width 0.06477)
			(type default)
		)
		(layer "F.Cu")
	)
	(gr_line
		(start 51.616102 -383.50571)
		(end 51.707288 -383.596896)
		(stroke
			(width 0.0508)
			(type default)
		)
		(layer "F.Cu")
	)
	(gr_line
		(start 51.616102 -383.2352)
		(end 51.616102 -383.50571)
		(stroke
			(width 0.0508)
			(type default)
		)
		(layer "F.Cu")
	)
	(gr_line
		(start 51.707288 -383.596896)
		(end 51.841654 -383.596896)
		(stroke
			(width 0.0508)
			(type default)
		)
		(layer "F.Cu")
	)
	(gr_line
		(start 51.721004 -404.46452)
		(end 51.450494 -404.73503)
		(stroke
			(width 0.06477)
			(type default)
		)
		(layer "F.Cu")
	)
	(gr_line
		(start 51.746404 -408.784044)
		(end 51.450494 -409.079954)
		(stroke
			(width 0.06477)
			(type default)
		)
		(layer "F.Cu")
	)
	(gr_line
		(start 51.794664 -370.00942)
		(end 51.498754 -370.30533)
		(stroke
			(width 0.06477)
			(type default)
		)
		(layer "F.Cu")
	)
	(gr_line
		(start 51.841654 -383.596896)
		(end 51.918108 -383.520442)
		(stroke
			(width 0.0508)
			(type default)
		)
		(layer "F.Cu")
	)
	(gr_line
		(start 51.90744 -382.943862)
		(end 51.616102 -383.2352)
		(stroke
			(width 0.0508)
			(type default)
		)
		(layer "F.Cu")
	)
	(gr_line
		(start 51.918108 -383.520442)
		(end 51.918108 -383.402586)
		(stroke
			(width 0.0508)
			(type default)
		)
		(layer "F.Cu")
	)
	(gr_line
		(start 52.00142 -391.36447)
		(end 51.918108 -391.281158)
		(stroke
			(width 0.0508)
			(type default)
		)
		(layer "F.Cu")
	)
	(gr_line
		(start 52.066952 -11.881104)
		(end 52.205636 -12.019788)
		(stroke
			(width 0.06477)
			(type default)
		)
		(layer "F.Cu")
	)
	(gr_line
		(start 52.066952 -11.26998)
		(end 52.066952 -11.881104)
		(stroke
			(width 0.06477)
			(type default)
		)
		(layer "F.Cu")
	)
	(gr_line
		(start 52.070508 -388.774432)
		(end 52.591208 -388.774432)
		(stroke
			(width 0.0635)
			(type default)
		)
		(layer "F.Cu")
	)
	(gr_line
		(start 52.070508 -385.31038)
		(end 52.591208 -385.31038)
		(stroke
			(width 0.0635)
			(type default)
		)
		(layer "F.Cu")
	)
	(gr_line
		(start 52.117244 -370.00942)
		(end 52.413154 -370.30533)
		(stroke
			(width 0.06477)
			(type default)
		)
		(layer "F.Cu")
	)
	(gr_line
		(start 52.12461 -383.13741)
		(end 52.218082 -383.230882)
		(stroke
			(width 0.0508)
			(type default)
		)
		(layer "F.Cu")
	)
	(gr_line
		(start 52.12461 -382.942592)
		(end 52.12461 -383.13741)
		(stroke
			(width 0.0508)
			(type default)
		)
		(layer "F.Cu")
	)
	(gr_arc
		(start 52.12461 -381.5715)
		(mid 52.12461 -381.571881)
		(end 52.12461 -381.572262)
		(stroke
			(width 0.0508)
			(type default)
		)
		(layer "F.Cu")
	)
	(gr_line
		(start 52.17033 -17.890236)
		(end 52.46624 -18.186146)
		(stroke
			(width 0.06477)
			(type default)
		)
		(layer "F.Cu")
	)
	(gr_line
		(start 52.218082 -383.230882)
		(end 52.218082 -383.92227)
		(stroke
			(width 0.0508)
			(type default)
		)
		(layer "F.Cu")
	)
	(gr_line
		(start 52.21859 -391.36574)
		(end 52.21859 -390.761982)
		(stroke
			(width 0.0508)
			(type default)
		)
		(layer "F.Cu")
	)
	(gr_line
		(start 52.21859 -390.761982)
		(end 52.218082 -390.761474)
		(stroke
			(width 0.0508)
			(type default)
		)
		(layer "F.Cu")
	)
	(gr_line
		(start 52.387754 -369.03533)
		(end 52.117244 -369.30584)
		(stroke
			(width 0.06477)
			(type default)
		)
		(layer "F.Cu")
	)
	(gr_line
		(start 52.413154 -370.83873)
		(end 52.063904 -371.18798)
		(stroke
			(width 0.0508)
			(type default)
		)
		(layer "F.Cu")
	)
	(gr_line
		(start 52.46624 -18.86585)
		(end 52.19573 -19.13636)
		(stroke
			(width 0.06477)
			(type default)
		)
		(layer "F.Cu")
	)
	(gr_line
		(start 52.46624 -17.060926)
		(end 52.17033 -17.356836)
		(stroke
			(width 0.06477)
			(type default)
		)
		(layer "F.Cu")
	)
	(gr_line
		(start 52.470558 -389.467344)
		(end 52.991258 -389.467344)
		(stroke
			(width 0.0635)
			(type default)
		)
		(layer "F.Cu")
	)
	(gr_line
		(start 52.470558 -386.003292)
		(end 52.991258 -386.003292)
		(stroke
			(width 0.0635)
			(type default)
		)
		(layer "F.Cu")
	)
	(gr_line
		(start 52.477924 -392.977116)
		(end 52.475892 -392.977116)
		(stroke
			(width 0.0508)
			(type default)
		)
		(layer "F.Cu")
	)
	(gr_line
		(start 52.616608 -393.292838)
		(end 52.616608 -393.1158)
		(stroke
			(width 0.0508)
			(type default)
		)
		(layer "F.Cu")
	)
	(gr_line
		(start 52.616608 -393.1158)
		(end 52.477924 -392.977116)
		(stroke
			(width 0.0508)
			(type default)
		)
		(layer "F.Cu")
	)
	(gr_line
		(start 52.616608 -392.6205)
		(end 52.477162 -392.759946)
		(stroke
			(width 0.0508)
			(type default)
		)
		(layer "F.Cu")
	)
	(gr_line
		(start 52.616608 -392.429238)
		(end 52.616608 -392.6205)
		(stroke
			(width 0.0508)
			(type default)
		)
		(layer "F.Cu")
	)
	(gr_line
		(start 52.6669 -11.881104)
		(end 52.528216 -12.019788)
		(stroke
			(width 0.06477)
			(type default)
		)
		(layer "F.Cu")
	)
	(gr_line
		(start 52.6669 -11.26998)
		(end 52.6669 -11.881104)
		(stroke
			(width 0.06477)
			(type default)
		)
		(layer "F.Cu")
	)
	(gr_line
		(start 52.692046 -181.692296)
		(end 52.374546 -181.374796)
		(stroke
			(width 0.127)
			(type default)
		)
		(layer "F.Cu")
	)
	(gr_line
		(start 52.78882 -18.86585)
		(end 53.05933 -19.13636)
		(stroke
			(width 0.06477)
			(type default)
		)
		(layer "F.Cu")
	)
	(gr_line
		(start 52.78882 -17.060926)
		(end 53.08473 -17.356836)
		(stroke
			(width 0.06477)
			(type default)
		)
		(layer "F.Cu")
	)
	(gr_line
		(start 52.815998 -383.50571)
		(end 52.907184 -383.596896)
		(stroke
			(width 0.0508)
			(type default)
		)
		(layer "F.Cu")
	)
	(gr_line
		(start 52.815998 -383.2352)
		(end 52.815998 -383.50571)
		(stroke
			(width 0.0508)
			(type default)
		)
		(layer "F.Cu")
	)
	(gr_line
		(start 52.907184 -383.596896)
		(end 53.04155 -383.596896)
		(stroke
			(width 0.0508)
			(type default)
		)
		(layer "F.Cu")
	)
	(gr_line
		(start 53.04155 -383.596896)
		(end 53.118004 -383.520442)
		(stroke
			(width 0.0508)
			(type default)
		)
		(layer "F.Cu")
	)
	(gr_line
		(start 53.073046 -181.692296)
		(end 53.390546 -181.374796)
		(stroke
			(width 0.127)
			(type default)
		)
		(layer "F.Cu")
	)
	(gr_line
		(start 53.08473 -17.890236)
		(end 52.78882 -18.186146)
		(stroke
			(width 0.06477)
			(type default)
		)
		(layer "F.Cu")
	)
	(gr_line
		(start 53.107336 -382.943862)
		(end 52.815998 -383.2352)
		(stroke
			(width 0.0508)
			(type default)
		)
		(layer "F.Cu")
	)
	(gr_line
		(start 53.118004 -383.520442)
		(end 53.118004 -383.402586)
		(stroke
			(width 0.0508)
			(type default)
		)
		(layer "F.Cu")
	)
	(gr_line
		(start 53.201316 -391.36447)
		(end 53.118004 -391.281158)
		(stroke
			(width 0.0508)
			(type default)
		)
		(layer "F.Cu")
	)
	(gr_line
		(start 53.270658 -388.774432)
		(end 53.791358 -388.774432)
		(stroke
			(width 0.0635)
			(type default)
		)
		(layer "F.Cu")
	)
	(gr_line
		(start 53.270658 -385.31038)
		(end 53.791358 -385.31038)
		(stroke
			(width 0.0635)
			(type default)
		)
		(layer "F.Cu")
	)
	(gr_line
		(start 53.324506 -383.13741)
		(end 53.417978 -383.230882)
		(stroke
			(width 0.0508)
			(type default)
		)
		(layer "F.Cu")
	)
	(gr_line
		(start 53.324506 -382.942592)
		(end 53.324506 -383.13741)
		(stroke
			(width 0.0508)
			(type default)
		)
		(layer "F.Cu")
	)
	(gr_line
		(start 53.417978 -383.230882)
		(end 53.417978 -383.92227)
		(stroke
			(width 0.0508)
			(type default)
		)
		(layer "F.Cu")
	)
	(gr_line
		(start 53.418486 -391.36574)
		(end 53.418486 -390.761982)
		(stroke
			(width 0.0508)
			(type default)
		)
		(layer "F.Cu")
	)
	(gr_line
		(start 53.418486 -390.761982)
		(end 53.417978 -390.761474)
		(stroke
			(width 0.0508)
			(type default)
		)
		(layer "F.Cu")
	)
	(gr_line
		(start 53.56733 -374.849136)
		(end 53.56733 -375.377456)
		(stroke
			(width 0.0508)
			(type default)
		)
		(layer "F.Cu")
	)
	(gr_line
		(start 53.670708 -389.467344)
		(end 54.191408 -389.467344)
		(stroke
			(width 0.0635)
			(type default)
		)
		(layer "F.Cu")
	)
	(gr_line
		(start 53.670708 -386.003292)
		(end 54.191408 -386.003292)
		(stroke
			(width 0.0635)
			(type default)
		)
		(layer "F.Cu")
	)
	(gr_line
		(start 53.67782 -392.977116)
		(end 53.675788 -392.977116)
		(stroke
			(width 0.0508)
			(type default)
		)
		(layer "F.Cu")
	)
	(gr_line
		(start 53.7845 -374.850406)
		(end 53.89499 -374.960896)
		(stroke
			(width 0.0508)
			(type default)
		)
		(layer "F.Cu")
	)
	(gr_line
		(start 53.816504 -393.292838)
		(end 53.816504 -393.1158)
		(stroke
			(width 0.0508)
			(type default)
		)
		(layer "F.Cu")
	)
	(gr_line
		(start 53.816504 -393.1158)
		(end 53.67782 -392.977116)
		(stroke
			(width 0.0508)
			(type default)
		)
		(layer "F.Cu")
	)
	(gr_line
		(start 53.816504 -392.6205)
		(end 53.677058 -392.759946)
		(stroke
			(width 0.0508)
			(type default)
		)
		(layer "F.Cu")
	)
	(gr_line
		(start 53.816504 -392.429238)
		(end 53.816504 -392.6205)
		(stroke
			(width 0.0508)
			(type default)
		)
		(layer "F.Cu")
	)
	(gr_line
		(start 53.86705 -11.881104)
		(end 54.005734 -12.019788)
		(stroke
			(width 0.06477)
			(type default)
		)
		(layer "F.Cu")
	)
	(gr_line
		(start 53.86705 -11.26998)
		(end 53.86705 -11.881104)
		(stroke
			(width 0.06477)
			(type default)
		)
		(layer "F.Cu")
	)
	(gr_line
		(start 53.89499 -375.265696)
		(end 53.7845 -375.376186)
		(stroke
			(width 0.0508)
			(type default)
		)
		(layer "F.Cu")
	)
	(gr_line
		(start 53.89499 -374.960896)
		(end 53.89499 -375.265696)
		(stroke
			(width 0.0508)
			(type default)
		)
		(layer "F.Cu")
	)
	(gr_line
		(start 53.895244 -408.784044)
		(end 54.191154 -409.079954)
		(stroke
			(width 0.06477)
			(type default)
		)
		(layer "F.Cu")
	)
	(gr_line
		(start 53.920644 -404.46452)
		(end 54.191154 -404.73503)
		(stroke
			(width 0.06477)
			(type default)
		)
		(layer "F.Cu")
	)
	(gr_line
		(start 54.015894 -383.50571)
		(end 54.10708 -383.596896)
		(stroke
			(width 0.0508)
			(type default)
		)
		(layer "F.Cu")
	)
	(gr_line
		(start 54.015894 -383.2352)
		(end 54.015894 -383.50571)
		(stroke
			(width 0.0508)
			(type default)
		)
		(layer "F.Cu")
	)
	(gr_line
		(start 54.10708 -383.596896)
		(end 54.241446 -383.596896)
		(stroke
			(width 0.0508)
			(type default)
		)
		(layer "F.Cu")
	)
	(gr_line
		(start 54.191154 -412.299658)
		(end 53.920644 -412.570168)
		(stroke
			(width 0.06477)
			(type default)
		)
		(layer "F.Cu")
	)
	(gr_line
		(start 54.191154 -407.954734)
		(end 53.895244 -408.250644)
		(stroke
			(width 0.06477)
			(type default)
		)
		(layer "F.Cu")
	)
	(gr_line
		(start 54.241446 -383.596896)
		(end 54.3179 -383.520442)
		(stroke
			(width 0.0508)
			(type default)
		)
		(layer "F.Cu")
	)
	(gr_line
		(start 54.307232 -382.943862)
		(end 54.015894 -383.2352)
		(stroke
			(width 0.0508)
			(type default)
		)
		(layer "F.Cu")
	)
	(gr_line
		(start 54.3179 -383.520442)
		(end 54.3179 -383.402586)
		(stroke
			(width 0.0508)
			(type default)
		)
		(layer "F.Cu")
	)
	(gr_line
		(start 54.401466 -391.364724)
		(end 54.3179 -391.281158)
		(stroke
			(width 0.0508)
			(type default)
		)
		(layer "F.Cu")
	)
	(gr_line
		(start 54.466998 -11.881104)
		(end 54.328314 -12.019788)
		(stroke
			(width 0.06477)
			(type default)
		)
		(layer "F.Cu")
	)
	(gr_line
		(start 54.466998 -11.26998)
		(end 54.466998 -11.881104)
		(stroke
			(width 0.06477)
			(type default)
		)
		(layer "F.Cu")
	)
	(gr_line
		(start 54.470554 -388.774432)
		(end 54.991254 -388.774432)
		(stroke
			(width 0.0635)
			(type default)
		)
		(layer "F.Cu")
	)
	(gr_line
		(start 54.470554 -385.31038)
		(end 54.991254 -385.31038)
		(stroke
			(width 0.0635)
			(type default)
		)
		(layer "F.Cu")
	)
	(gr_line
		(start 54.513734 -412.299658)
		(end 54.784244 -412.570168)
		(stroke
			(width 0.06477)
			(type default)
		)
		(layer "F.Cu")
	)
	(gr_line
		(start 54.513734 -407.954734)
		(end 54.809644 -408.250644)
		(stroke
			(width 0.06477)
			(type default)
		)
		(layer "F.Cu")
	)
	(gr_line
		(start 54.524402 -383.13741)
		(end 54.618128 -383.231136)
		(stroke
			(width 0.0508)
			(type default)
		)
		(layer "F.Cu")
	)
	(gr_line
		(start 54.524402 -382.942592)
		(end 54.524402 -383.13741)
		(stroke
			(width 0.0508)
			(type default)
		)
		(layer "F.Cu")
	)
	(gr_line
		(start 54.618128 -383.231136)
		(end 54.618128 -383.92227)
		(stroke
			(width 0.0508)
			(type default)
		)
		(layer "F.Cu")
	)
	(gr_line
		(start 54.618636 -391.365486)
		(end 54.618382 -391.36574)
		(stroke
			(width 0.0508)
			(type default)
		)
		(layer "F.Cu")
	)
	(gr_line
		(start 54.618636 -391.365486)
		(end 54.618636 -390.761982)
		(stroke
			(width 0.0508)
			(type default)
		)
		(layer "F.Cu")
	)
	(gr_line
		(start 54.618636 -390.761982)
		(end 54.618128 -390.761474)
		(stroke
			(width 0.0508)
			(type default)
		)
		(layer "F.Cu")
	)
	(gr_line
		(start 54.784244 -404.46452)
		(end 54.513734 -404.73503)
		(stroke
			(width 0.06477)
			(type default)
		)
		(layer "F.Cu")
	)
	(gr_line
		(start 54.809644 -408.784044)
		(end 54.513734 -409.079954)
		(stroke
			(width 0.06477)
			(type default)
		)
		(layer "F.Cu")
	)
	(gr_line
		(start 54.870604 -389.467344)
		(end 55.391304 -389.467344)
		(stroke
			(width 0.0635)
			(type default)
		)
		(layer "F.Cu")
	)
	(gr_line
		(start 54.870604 -386.003292)
		(end 55.391304 -386.003292)
		(stroke
			(width 0.0635)
			(type default)
		)
		(layer "F.Cu")
	)
	(gr_line
		(start 54.877716 -392.977116)
		(end 54.875938 -392.977116)
		(stroke
			(width 0.0508)
			(type default)
		)
		(layer "F.Cu")
	)
	(gr_line
		(start 54.902354 -375.76633)
		(end 55.204106 -376.068082)
		(stroke
			(width 0.0508)
			(type default)
		)
		(layer "F.Cu")
	)
	(gr_line
		(start 54.927754 -373.96293)
		(end 55.198264 -374.23344)
		(stroke
			(width 0.06477)
			(type default)
		)
		(layer "F.Cu")
	)
	(gr_line
		(start 54.96433 -16.366236)
		(end 55.26024 -16.662146)
		(stroke
			(width 0.06477)
			(type default)
		)
		(layer "F.Cu")
	)
	(gr_line
		(start 55.016654 -393.292838)
		(end 55.016654 -393.116054)
		(stroke
			(width 0.0508)
			(type default)
		)
		(layer "F.Cu")
	)
	(gr_line
		(start 55.016654 -393.116054)
		(end 54.877716 -392.977116)
		(stroke
			(width 0.0508)
			(type default)
		)
		(layer "F.Cu")
	)
	(gr_line
		(start 55.016654 -392.6205)
		(end 54.877208 -392.759946)
		(stroke
			(width 0.0508)
			(type default)
		)
		(layer "F.Cu")
	)
	(gr_line
		(start 55.016654 -392.429238)
		(end 55.016654 -392.6205)
		(stroke
			(width 0.0508)
			(type default)
		)
		(layer "F.Cu")
	)
	(gr_line
		(start 55.198264 -374.93702)
		(end 54.902354 -375.23293)
		(stroke
			(width 0.06477)
			(type default)
		)
		(layer "F.Cu")
	)
	(gr_line
		(start 55.216044 -383.50571)
		(end 55.30723 -383.596896)
		(stroke
			(width 0.0508)
			(type default)
		)
		(layer "F.Cu")
	)
	(gr_line
		(start 55.216044 -383.2352)
		(end 55.216044 -383.50571)
		(stroke
			(width 0.0508)
			(type default)
		)
		(layer "F.Cu")
	)
	(gr_arc
		(start 55.250588 -376.165872)
		(mid 55.23571 -376.113003)
		(end 55.204106 -376.068082)
		(stroke
			(width 0.0508)
			(type default)
		)
		(layer "F.Cu")
	)
	(gr_line
		(start 55.251604 -377.07443)
		(end 55.251604 -377.60275)
		(stroke
			(width 0.0508)
			(type default)
		)
		(layer "F.Cu")
	)
	(gr_line
		(start 55.25897 -17.342866)
		(end 54.988714 -17.613122)
		(stroke
			(width 0.06477)
			(type default)
		)
		(layer "F.Cu")
	)
	(gr_line
		(start 55.26024 -15.536926)
		(end 54.96433 -15.832836)
		(stroke
			(width 0.06477)
			(type default)
		)
		(layer "F.Cu")
	)
	(gr_line
		(start 55.30723 -383.596896)
		(end 55.441596 -383.596896)
		(stroke
			(width 0.0508)
			(type default)
		)
		(layer "F.Cu")
	)
	(gr_line
		(start 55.441596 -383.596896)
		(end 55.51805 -383.520442)
		(stroke
			(width 0.0508)
			(type default)
		)
		(layer "F.Cu")
	)
	(gr_line
		(start 55.468774 -377.0757)
		(end 55.579264 -377.18619)
		(stroke
			(width 0.0508)
			(type default)
		)
		(layer "F.Cu")
	)
	(gr_line
		(start 55.507382 -382.943862)
		(end 55.216044 -383.2352)
		(stroke
			(width 0.0508)
			(type default)
		)
		(layer "F.Cu")
	)
	(gr_arc
		(start 55.514748 -376.068336)
		(mid 55.483147 -376.112981)
		(end 55.468266 -376.165618)
		(stroke
			(width 0.0508)
			(type default)
		)
		(layer "F.Cu")
	)
	(gr_line
		(start 55.51805 -383.520442)
		(end 55.51805 -383.402586)
		(stroke
			(width 0.0508)
			(type default)
		)
		(layer "F.Cu")
	)
	(gr_line
		(start 55.520844 -374.93702)
		(end 55.816754 -375.23293)
		(stroke
			(width 0.06477)
			(type default)
		)
		(layer "F.Cu")
	)
	(gr_line
		(start 55.579264 -377.49099)
		(end 55.468774 -377.60148)
		(stroke
			(width 0.0508)
			(type default)
		)
		(layer "F.Cu")
	)
	(gr_line
		(start 55.579264 -377.18619)
		(end 55.579264 -377.49099)
		(stroke
			(width 0.0508)
			(type default)
		)
		(layer "F.Cu")
	)
	(gr_line
		(start 55.58282 -17.343628)
		(end 55.852314 -17.613122)
		(stroke
			(width 0.06477)
			(type default)
		)
		(layer "F.Cu")
	)
	(gr_line
		(start 55.58282 -17.341596)
		(end 55.58282 -17.343628)
		(stroke
			(width 0.06477)
			(type default)
		)
		(layer "F.Cu")
	)
	(gr_line
		(start 55.58282 -15.536926)
		(end 55.87873 -15.832836)
		(stroke
			(width 0.06477)
			(type default)
		)
		(layer "F.Cu")
	)
	(gr_line
		(start 55.601362 -391.36447)
		(end 55.51805 -391.281158)
		(stroke
			(width 0.0508)
			(type default)
		)
		(layer "F.Cu")
	)
	(gr_line
		(start 55.666894 -11.881104)
		(end 55.805578 -12.019788)
		(stroke
			(width 0.06477)
			(type default)
		)
		(layer "F.Cu")
	)
	(gr_line
		(start 55.666894 -11.26998)
		(end 55.666894 -11.881104)
		(stroke
			(width 0.06477)
			(type default)
		)
		(layer "F.Cu")
	)
	(gr_line
		(start 55.670704 -388.774432)
		(end 56.191404 -388.774432)
		(stroke
			(width 0.0635)
			(type default)
		)
		(layer "F.Cu")
	)
	(gr_line
		(start 55.670704 -385.31038)
		(end 56.191404 -385.31038)
		(stroke
			(width 0.0635)
			(type default)
		)
		(layer "F.Cu")
	)
	(gr_line
		(start 55.724552 -383.13741)
		(end 55.818024 -383.230882)
		(stroke
			(width 0.0508)
			(type default)
		)
		(layer "F.Cu")
	)
	(gr_line
		(start 55.724552 -382.94183)
		(end 55.724552 -383.13741)
		(stroke
			(width 0.0508)
			(type default)
		)
		(layer "F.Cu")
	)
	(gr_line
		(start 55.791354 -373.96293)
		(end 55.520844 -374.23344)
		(stroke
			(width 0.06477)
			(type default)
		)
		(layer "F.Cu")
	)
	(gr_line
		(start 55.816754 -375.76633)
		(end 55.514748 -376.068336)
		(stroke
			(width 0.0508)
			(type default)
		)
		(layer "F.Cu")
	)
	(gr_line
		(start 55.818024 -383.230882)
		(end 55.818024 -383.92227)
		(stroke
			(width 0.0508)
			(type default)
		)
		(layer "F.Cu")
	)
	(gr_line
		(start 55.818532 -391.36574)
		(end 55.818532 -390.761982)
		(stroke
			(width 0.0508)
			(type default)
		)
		(layer "F.Cu")
	)
	(gr_line
		(start 55.818532 -390.761982)
		(end 55.818024 -390.761474)
		(stroke
			(width 0.0508)
			(type default)
		)
		(layer "F.Cu")
	)
	(gr_line
		(start 55.87873 -16.366236)
		(end 55.58282 -16.662146)
		(stroke
			(width 0.06477)
			(type default)
		)
		(layer "F.Cu")
	)
	(gr_line
		(start 56.0705 -389.467344)
		(end 56.5912 -389.467344)
		(stroke
			(width 0.0635)
			(type default)
		)
		(layer "F.Cu")
	)
	(gr_line
		(start 56.0705 -386.003292)
		(end 56.5912 -386.003292)
		(stroke
			(width 0.0635)
			(type default)
		)
		(layer "F.Cu")
	)
	(gr_line
		(start 56.077866 -392.977116)
		(end 56.075834 -392.977116)
		(stroke
			(width 0.0508)
			(type default)
		)
		(layer "F.Cu")
	)
	(gr_line
		(start 56.21655 -393.292838)
		(end 56.21655 -393.1158)
		(stroke
			(width 0.0508)
			(type default)
		)
		(layer "F.Cu")
	)
	(gr_line
		(start 56.21655 -393.1158)
		(end 56.077866 -392.977116)
		(stroke
			(width 0.0508)
			(type default)
		)
		(layer "F.Cu")
	)
	(gr_line
		(start 56.21655 -392.6205)
		(end 56.077104 -392.759946)
		(stroke
			(width 0.0508)
			(type default)
		)
		(layer "F.Cu")
	)
	(gr_line
		(start 56.21655 -392.429238)
		(end 56.21655 -392.6205)
		(stroke
			(width 0.0508)
			(type default)
		)
		(layer "F.Cu")
	)
	(gr_line
		(start 56.267096 -11.88085)
		(end 56.128158 -12.019788)
		(stroke
			(width 0.06477)
			(type default)
		)
		(layer "F.Cu")
	)
	(gr_line
		(start 56.267096 -11.26998)
		(end 56.267096 -11.88085)
		(stroke
			(width 0.06477)
			(type default)
		)
		(layer "F.Cu")
	)
	(gr_line
		(start 56.41594 -383.50571)
		(end 56.507126 -383.596896)
		(stroke
			(width 0.0508)
			(type default)
		)
		(layer "F.Cu")
	)
	(gr_line
		(start 56.41594 -383.2352)
		(end 56.41594 -383.50571)
		(stroke
			(width 0.0508)
			(type default)
		)
		(layer "F.Cu")
	)
	(gr_line
		(start 56.507126 -383.596896)
		(end 56.641492 -383.596896)
		(stroke
			(width 0.0508)
			(type default)
		)
		(layer "F.Cu")
	)
	(gr_line
		(start 56.604154 -373.30253)
		(end 56.905906 -373.604282)
		(stroke
			(width 0.0508)
			(type default)
		)
		(layer "F.Cu")
	)
	(gr_line
		(start 56.629554 -371.49913)
		(end 56.900064 -371.76964)
		(stroke
			(width 0.06477)
			(type default)
		)
		(layer "F.Cu")
	)
	(gr_line
		(start 56.641492 -383.596896)
		(end 56.717946 -383.520442)
		(stroke
			(width 0.0508)
			(type default)
		)
		(layer "F.Cu")
	)
	(gr_line
		(start 56.707278 -382.943862)
		(end 56.41594 -383.2352)
		(stroke
			(width 0.0508)
			(type default)
		)
		(layer "F.Cu")
	)
	(gr_line
		(start 56.717946 -383.520442)
		(end 56.717946 -383.402586)
		(stroke
			(width 0.0508)
			(type default)
		)
		(layer "F.Cu")
	)
	(gr_line
		(start 56.801258 -391.36447)
		(end 56.717946 -391.281158)
		(stroke
			(width 0.0508)
			(type default)
		)
		(layer "F.Cu")
	)
	(gr_line
		(start 56.8706 -388.774432)
		(end 57.3913 -388.774432)
		(stroke
			(width 0.0635)
			(type default)
		)
		(layer "F.Cu")
	)
	(gr_line
		(start 56.8706 -385.31038)
		(end 57.3913 -385.31038)
		(stroke
			(width 0.0635)
			(type default)
		)
		(layer "F.Cu")
	)
	(gr_line
		(start 56.900064 -372.47322)
		(end 56.604154 -372.76913)
		(stroke
			(width 0.06477)
			(type default)
		)
		(layer "F.Cu")
	)
	(gr_line
		(start 56.924448 -383.13741)
		(end 57.01792 -383.230882)
		(stroke
			(width 0.0508)
			(type default)
		)
		(layer "F.Cu")
	)
	(gr_line
		(start 56.924448 -382.942592)
		(end 56.924448 -383.13741)
		(stroke
			(width 0.0508)
			(type default)
		)
		(layer "F.Cu")
	)
	(gr_arc
		(start 56.952388 -373.702072)
		(mid 56.93751 -373.649203)
		(end 56.905906 -373.604282)
		(stroke
			(width 0.0508)
			(type default)
		)
		(layer "F.Cu")
	)
	(gr_line
		(start 56.953404 -374.84304)
		(end 56.953404 -375.37136)
		(stroke
			(width 0.0508)
			(type default)
		)
		(layer "F.Cu")
	)
	(gr_line
		(start 56.958484 -408.784044)
		(end 57.254394 -409.079954)
		(stroke
			(width 0.06477)
			(type default)
		)
		(layer "F.Cu")
	)
	(gr_line
		(start 56.983884 -404.46452)
		(end 57.254394 -404.73503)
		(stroke
			(width 0.06477)
			(type default)
		)
		(layer "F.Cu")
	)
	(gr_line
		(start 57.01792 -383.230882)
		(end 57.01792 -383.92227)
		(stroke
			(width 0.0508)
			(type default)
		)
		(layer "F.Cu")
	)
	(gr_line
		(start 57.018428 -391.36574)
		(end 57.018428 -390.761982)
		(stroke
			(width 0.0508)
			(type default)
		)
		(layer "F.Cu")
	)
	(gr_line
		(start 57.018428 -390.761982)
		(end 57.01792 -390.761474)
		(stroke
			(width 0.0508)
			(type default)
		)
		(layer "F.Cu")
	)
	(gr_line
		(start 57.170574 -374.84431)
		(end 57.281064 -374.9548)
		(stroke
			(width 0.0508)
			(type default)
		)
		(layer "F.Cu")
	)
	(gr_arc
		(start 57.216802 -373.604282)
		(mid 57.185163 -373.649183)
		(end 57.17032 -373.702072)
		(stroke
			(width 0.0508)
			(type default)
		)
		(layer "F.Cu")
	)
	(gr_line
		(start 57.222644 -372.47322)
		(end 57.518554 -372.76913)
		(stroke
			(width 0.06477)
			(type default)
		)
		(layer "F.Cu")
	)
	(gr_line
		(start 57.254394 -412.299658)
		(end 56.983884 -412.570168)
		(stroke
			(width 0.06477)
			(type default)
		)
		(layer "F.Cu")
	)
	(gr_line
		(start 57.254394 -407.954734)
		(end 56.958484 -408.250644)
		(stroke
			(width 0.06477)
			(type default)
		)
		(layer "F.Cu")
	)
	(gr_line
		(start 57.27065 -389.467344)
		(end 57.79135 -389.467344)
		(stroke
			(width 0.0635)
			(type default)
		)
		(layer "F.Cu")
	)
	(gr_line
		(start 57.27065 -386.003292)
		(end 57.79135 -386.003292)
		(stroke
			(width 0.0635)
			(type default)
		)
		(layer "F.Cu")
	)
	(gr_line
		(start 57.277762 -392.977116)
		(end 57.27573 -392.977116)
		(stroke
			(width 0.0508)
			(type default)
		)
		(layer "F.Cu")
	)
	(gr_line
		(start 57.281064 -375.2596)
		(end 57.170574 -375.37009)
		(stroke
			(width 0.0508)
			(type default)
		)
		(layer "F.Cu")
	)
	(gr_line
		(start 57.281064 -374.9548)
		(end 57.281064 -375.2596)
		(stroke
			(width 0.0508)
			(type default)
		)
		(layer "F.Cu")
	)
	(gr_line
		(start 57.334658 -12.864846)
		(end 57.60466 -12.594844)
		(stroke
			(width 0.06477)
			(type default)
		)
		(layer "F.Cu")
	)
	(gr_line
		(start 57.335674 -6.725158)
		(end 57.605676 -6.99516)
		(stroke
			(width 0.06477)
			(type default)
		)
		(layer "F.Cu")
	)
	(gr_line
		(start 57.4167 -393.292838)
		(end 57.4167 -393.116054)
		(stroke
			(width 0.0508)
			(type default)
		)
		(layer "F.Cu")
	)
	(gr_line
		(start 57.4167 -393.116054)
		(end 57.277762 -392.977116)
		(stroke
			(width 0.0508)
			(type default)
		)
		(layer "F.Cu")
	)
	(gr_line
		(start 57.4167 -392.620246)
		(end 57.277 -392.759946)
		(stroke
			(width 0.0508)
			(type default)
		)
		(layer "F.Cu")
	)
	(gr_line
		(start 57.4167 -392.429238)
		(end 57.4167 -392.620246)
		(stroke
			(width 0.0508)
			(type default)
		)
		(layer "F.Cu")
	)
	(gr_line
		(start 57.466992 -11.881104)
		(end 57.466992 -11.26998)
		(stroke
			(width 0.06477)
			(type default)
		)
		(layer "F.Cu")
	)
	(gr_line
		(start 57.466992 -7.709154)
		(end 57.466992 -8.320024)
		(stroke
			(width 0.06477)
			(type default)
		)
		(layer "F.Cu")
	)
	(gr_line
		(start 57.493154 -371.49913)
		(end 57.222644 -371.76964)
		(stroke
			(width 0.06477)
			(type default)
		)
		(layer "F.Cu")
	)
	(gr_line
		(start 57.518554 -373.30253)
		(end 57.216802 -373.604282)
		(stroke
			(width 0.0508)
			(type default)
		)
		(layer "F.Cu")
	)
	(gr_line
		(start 57.576974 -412.299658)
		(end 57.847484 -412.570168)
		(stroke
			(width 0.06477)
			(type default)
		)
		(layer "F.Cu")
	)
	(gr_line
		(start 57.576974 -407.954734)
		(end 57.872884 -408.250644)
		(stroke
			(width 0.06477)
			(type default)
		)
		(layer "F.Cu")
	)
	(gr_line
		(start 57.605676 -12.019788)
		(end 57.466992 -11.881104)
		(stroke
			(width 0.06477)
			(type default)
		)
		(layer "F.Cu")
	)
	(gr_line
		(start 57.605676 -7.57047)
		(end 57.466992 -7.709154)
		(stroke
			(width 0.06477)
			(type default)
		)
		(layer "F.Cu")
	)
	(gr_line
		(start 57.605676 -6.99516)
		(end 57.605676 -6.996176)
		(stroke
			(width 0.06477)
			(type default)
		)
		(layer "F.Cu")
	)
	(gr_line
		(start 57.61609 -383.50571)
		(end 57.707276 -383.596896)
		(stroke
			(width 0.0508)
			(type default)
		)
		(layer "F.Cu")
	)
	(gr_line
		(start 57.61609 -383.2352)
		(end 57.61609 -383.50571)
		(stroke
			(width 0.0508)
			(type default)
		)
		(layer "F.Cu")
	)
	(gr_line
		(start 57.707276 -383.596896)
		(end 57.841642 -383.596896)
		(stroke
			(width 0.0508)
			(type default)
		)
		(layer "F.Cu")
	)
	(gr_line
		(start 57.75833 -17.890236)
		(end 58.05424 -18.186146)
		(stroke
			(width 0.06477)
			(type default)
		)
		(layer "F.Cu")
	)
	(gr_line
		(start 57.841642 -383.596896)
		(end 57.918096 -383.520442)
		(stroke
			(width 0.0508)
			(type default)
		)
		(layer "F.Cu")
	)
	(gr_line
		(start 57.847484 -404.46452)
		(end 57.576974 -404.73503)
		(stroke
			(width 0.06477)
			(type default)
		)
		(layer "F.Cu")
	)
	(gr_line
		(start 57.872884 -408.784044)
		(end 57.576974 -409.079954)
		(stroke
			(width 0.06477)
			(type default)
		)
		(layer "F.Cu")
	)
	(gr_line
		(start 57.907428 -382.943862)
		(end 57.61609 -383.2352)
		(stroke
			(width 0.0508)
			(type default)
		)
		(layer "F.Cu")
	)
	(gr_line
		(start 57.918096 -383.520442)
		(end 57.918096 -383.402586)
		(stroke
			(width 0.0508)
			(type default)
		)
		(layer "F.Cu")
	)
	(gr_line
		(start 57.928256 -12.594844)
		(end 57.928256 -12.593828)
		(stroke
			(width 0.06477)
			(type default)
		)
		(layer "F.Cu")
	)
	(gr_line
		(start 57.928256 -12.019788)
		(end 58.067194 -11.88085)
		(stroke
			(width 0.06477)
			(type default)
		)
		(layer "F.Cu")
	)
	(gr_line
		(start 57.929272 -6.99516)
		(end 58.199274 -6.725158)
		(stroke
			(width 0.06477)
			(type default)
		)
		(layer "F.Cu")
	)
	(gr_line
		(start 58.001408 -391.36447)
		(end 57.918096 -391.281158)
		(stroke
			(width 0.0508)
			(type default)
		)
		(layer "F.Cu")
	)
	(gr_line
		(start 58.05424 -18.86585)
		(end 57.78373 -19.13636)
		(stroke
			(width 0.06477)
			(type default)
		)
		(layer "F.Cu")
	)
	(gr_line
		(start 58.05424 -17.060926)
		(end 57.75833 -17.356836)
		(stroke
			(width 0.06477)
			(type default)
		)
		(layer "F.Cu")
	)
	(gr_line
		(start 58.06694 -11.880596)
		(end 58.06694 -11.26998)
		(stroke
			(width 0.06477)
			(type default)
		)
		(layer "F.Cu")
	)
	(gr_line
		(start 58.06694 -11.880596)
		(end 58.067194 -11.88085)
		(stroke
			(width 0.06477)
			(type default)
		)
		(layer "F.Cu")
	)
	(gr_line
		(start 58.06694 -8.320024)
		(end 58.06694 -7.709154)
		(stroke
			(width 0.06477)
			(type default)
		)
		(layer "F.Cu")
	)
	(gr_line
		(start 58.06694 -7.709154)
		(end 57.928256 -7.57047)
		(stroke
			(width 0.06477)
			(type default)
		)
		(layer "F.Cu")
	)
	(gr_line
		(start 58.070496 -388.774432)
		(end 58.591196 -388.774432)
		(stroke
			(width 0.0635)
			(type default)
		)
		(layer "F.Cu")
	)
	(gr_line
		(start 58.070496 -385.31038)
		(end 58.591196 -385.31038)
		(stroke
			(width 0.0635)
			(type default)
		)
		(layer "F.Cu")
	)
	(gr_line
		(start 58.124598 -383.13741)
		(end 58.21807 -383.230882)
		(stroke
			(width 0.0508)
			(type default)
		)
		(layer "F.Cu")
	)
	(gr_line
		(start 58.124598 -382.942592)
		(end 58.124598 -383.13741)
		(stroke
			(width 0.0508)
			(type default)
		)
		(layer "F.Cu")
	)
	(gr_line
		(start 58.198258 -12.864846)
		(end 57.928256 -12.594844)
		(stroke
			(width 0.06477)
			(type default)
		)
		(layer "F.Cu")
	)
	(gr_line
		(start 58.21807 -383.230882)
		(end 58.21807 -383.92227)
		(stroke
			(width 0.0508)
			(type default)
		)
		(layer "F.Cu")
	)
	(gr_line
		(start 58.218578 -391.36574)
		(end 58.218578 -390.761982)
		(stroke
			(width 0.0508)
			(type default)
		)
		(layer "F.Cu")
	)
	(gr_line
		(start 58.218578 -390.761982)
		(end 58.21807 -390.761474)
		(stroke
			(width 0.0508)
			(type default)
		)
		(layer "F.Cu")
	)
	(gr_line
		(start 58.305954 -370.83873)
		(end 58.655204 -371.18798)
		(stroke
			(width 0.0508)
			(type default)
		)
		(layer "F.Cu")
	)
	(gr_line
		(start 58.31205 -143.036036)
		(end 58.08345 -143.264636)
		(stroke
			(width 0.127)
			(type default)
		)
		(layer "F.Cu")
	)
	(gr_line
		(start 58.31205 -142.636748)
		(end 58.31205 -143.036036)
		(stroke
			(width 0.127)
			(type default)
		)
		(layer "F.Cu")
	)
	(gr_line
		(start 58.331354 -369.03533)
		(end 58.601864 -369.30584)
		(stroke
			(width 0.06477)
			(type default)
		)
		(layer "F.Cu")
	)
	(gr_line
		(start 58.37682 -18.86585)
		(end 58.64733 -19.13636)
		(stroke
			(width 0.06477)
			(type default)
		)
		(layer "F.Cu")
	)
	(gr_line
		(start 58.37682 -17.060926)
		(end 58.67273 -17.356836)
		(stroke
			(width 0.06477)
			(type default)
		)
		(layer "F.Cu")
	)
	(gr_line
		(start 58.470546 -389.467344)
		(end 58.991246 -389.467344)
		(stroke
			(width 0.0635)
			(type default)
		)
		(layer "F.Cu")
	)
	(gr_line
		(start 58.470546 -386.003292)
		(end 58.991246 -386.003292)
		(stroke
			(width 0.0635)
			(type default)
		)
		(layer "F.Cu")
	)
	(gr_line
		(start 58.477912 -392.977116)
		(end 58.47588 -392.977116)
		(stroke
			(width 0.0508)
			(type default)
		)
		(layer "F.Cu")
	)
	(gr_line
		(start 58.601864 -370.00942)
		(end 58.305954 -370.30533)
		(stroke
			(width 0.06477)
			(type default)
		)
		(layer "F.Cu")
	)
	(gr_line
		(start 58.616596 -393.292838)
		(end 58.616596 -393.1158)
		(stroke
			(width 0.0508)
			(type default)
		)
		(layer "F.Cu")
	)
	(gr_line
		(start 58.616596 -393.1158)
		(end 58.477912 -392.977116)
		(stroke
			(width 0.0508)
			(type default)
		)
		(layer "F.Cu")
	)
	(gr_line
		(start 58.616596 -392.6205)
		(end 58.47715 -392.759946)
		(stroke
			(width 0.0508)
			(type default)
		)
		(layer "F.Cu")
	)
	(gr_line
		(start 58.616596 -392.429238)
		(end 58.616596 -392.6205)
		(stroke
			(width 0.0508)
			(type default)
		)
		(layer "F.Cu")
	)
	(gr_line
		(start 58.67273 -17.890236)
		(end 58.37682 -18.186146)
		(stroke
			(width 0.06477)
			(type default)
		)
		(layer "F.Cu")
	)
	(gr_line
		(start 58.815986 -383.50571)
		(end 58.907172 -383.596896)
		(stroke
			(width 0.0508)
			(type default)
		)
		(layer "F.Cu")
	)
	(gr_line
		(start 58.815986 -383.2352)
		(end 58.815986 -383.50571)
		(stroke
			(width 0.0508)
			(type default)
		)
		(layer "F.Cu")
	)
	(gr_line
		(start 58.83275 -142.116048)
		(end 58.31205 -142.636748)
		(stroke
			(width 0.127)
			(type default)
		)
		(layer "F.Cu")
	)
	(gr_line
		(start 58.862468 -142.983458)
		(end 59.135518 -143.256508)
		(stroke
			(width 0.127)
			(type default)
		)
		(layer "F.Cu")
	)
	(gr_line
		(start 58.862468 -142.751048)
		(end 58.862468 -142.983458)
		(stroke
			(width 0.127)
			(type default)
		)
		(layer "F.Cu")
	)
	(gr_line
		(start 58.907172 -383.596896)
		(end 59.041538 -383.596896)
		(stroke
			(width 0.0508)
			(type default)
		)
		(layer "F.Cu")
	)
	(gr_line
		(start 58.924444 -370.00942)
		(end 59.220354 -370.30533)
		(stroke
			(width 0.06477)
			(type default)
		)
		(layer "F.Cu")
	)
	(gr_line
		(start 58.989468 -142.624048)
		(end 58.862468 -142.751048)
		(stroke
			(width 0.127)
			(type default)
		)
		(layer "F.Cu")
	)
	(gr_line
		(start 59.041538 -383.596896)
		(end 59.117992 -383.520442)
		(stroke
			(width 0.0508)
			(type default)
		)
		(layer "F.Cu")
	)
	(gr_line
		(start 59.107324 -382.943862)
		(end 58.815986 -383.2352)
		(stroke
			(width 0.0508)
			(type default)
		)
		(layer "F.Cu")
	)
	(gr_line
		(start 59.117992 -383.520442)
		(end 59.117992 -383.402586)
		(stroke
			(width 0.0508)
			(type default)
		)
		(layer "F.Cu")
	)
	(gr_line
		(start 59.194954 -369.03533)
		(end 58.924444 -369.30584)
		(stroke
			(width 0.06477)
			(type default)
		)
		(layer "F.Cu")
	)
	(gr_line
		(start 59.200796 -391.363962)
		(end 59.117992 -391.281158)
		(stroke
			(width 0.0508)
			(type default)
		)
		(layer "F.Cu")
	)
	(gr_line
		(start 59.220354 -370.83873)
		(end 58.871104 -371.18798)
		(stroke
			(width 0.0508)
			(type default)
		)
		(layer "F.Cu")
	)
	(gr_line
		(start 59.270646 -388.774432)
		(end 59.791346 -388.774432)
		(stroke
			(width 0.0635)
			(type default)
		)
		(layer "F.Cu")
	)
	(gr_line
		(start 59.270646 -385.31038)
		(end 59.791346 -385.31038)
		(stroke
			(width 0.0635)
			(type default)
		)
		(layer "F.Cu")
	)
	(gr_line
		(start 59.324494 -383.13741)
		(end 59.417966 -383.230882)
		(stroke
			(width 0.0508)
			(type default)
		)
		(layer "F.Cu")
	)
	(gr_line
		(start 59.324494 -382.942592)
		(end 59.324494 -383.13741)
		(stroke
			(width 0.0508)
			(type default)
		)
		(layer "F.Cu")
	)
	(gr_line
		(start 59.338464 -376.553984)
		(end 59.181746 -376.553984)
		(stroke
			(width 0.0508)
			(type default)
		)
		(layer "F.Cu")
	)
	(gr_line
		(start 59.387994 -378.48286)
		(end 59.38774 -378.48286)
		(stroke
			(width 0.0508)
			(type default)
		)
		(layer "F.Cu")
	)
	(gr_line
		(start 59.401456 -376.027188)
		(end 59.027568 -376.401076)
		(stroke
			(width 0.0508)
			(type default)
		)
		(layer "F.Cu")
	)
	(gr_line
		(start 59.417966 -391.365232)
		(end 59.417966 -390.761474)
		(stroke
			(width 0.0508)
			(type default)
		)
		(layer "F.Cu")
	)
	(gr_line
		(start 59.417966 -383.230882)
		(end 59.417966 -383.92227)
		(stroke
			(width 0.0508)
			(type default)
		)
		(layer "F.Cu")
	)
	(gr_line
		(start 59.554364 -376.338084)
		(end 59.338464 -376.553984)
		(stroke
			(width 0.0508)
			(type default)
		)
		(layer "F.Cu")
	)
	(gr_line
		(start 59.554364 -376.181366)
		(end 59.554364 -376.338084)
		(stroke
			(width 0.0508)
			(type default)
		)
		(layer "F.Cu")
	)
	(gr_line
		(start 59.670696 -389.467344)
		(end 60.191396 -389.467344)
		(stroke
			(width 0.0635)
			(type default)
		)
		(layer "F.Cu")
	)
	(gr_line
		(start 59.670696 -386.003292)
		(end 60.191396 -386.003292)
		(stroke
			(width 0.0635)
			(type default)
		)
		(layer "F.Cu")
	)
	(gr_line
		(start 59.677808 -392.977116)
		(end 59.675776 -392.977116)
		(stroke
			(width 0.0508)
			(type default)
		)
		(layer "F.Cu")
	)
	(gr_line
		(start 59.698636 -378.635768)
		(end 59.542172 -378.635768)
		(stroke
			(width 0.0508)
			(type default)
		)
		(layer "F.Cu")
	)
	(gr_line
		(start 59.761374 -378.10948)
		(end 59.387994 -378.48286)
		(stroke
			(width 0.0508)
			(type default)
		)
		(layer "F.Cu")
	)
	(gr_line
		(start 59.816746 -393.292838)
		(end 59.816746 -393.116054)
		(stroke
			(width 0.0508)
			(type default)
		)
		(layer "F.Cu")
	)
	(gr_line
		(start 59.816746 -393.116054)
		(end 59.677808 -392.977116)
		(stroke
			(width 0.0508)
			(type default)
		)
		(layer "F.Cu")
	)
	(gr_line
		(start 59.816746 -392.620246)
		(end 59.677046 -392.759946)
		(stroke
			(width 0.0508)
			(type default)
		)
		(layer "F.Cu")
	)
	(gr_line
		(start 59.816746 -392.429238)
		(end 59.816746 -392.620246)
		(stroke
			(width 0.0508)
			(type default)
		)
		(layer "F.Cu")
	)
	(gr_line
		(start 59.914282 -378.420122)
		(end 59.698636 -378.635768)
		(stroke
			(width 0.0508)
			(type default)
		)
		(layer "F.Cu")
	)
	(gr_line
		(start 59.914282 -378.263658)
		(end 59.914282 -378.420122)
		(stroke
			(width 0.0508)
			(type default)
		)
		(layer "F.Cu")
	)
	(gr_line
		(start 60.015882 -383.50571)
		(end 60.107068 -383.596896)
		(stroke
			(width 0.0508)
			(type default)
		)
		(layer "F.Cu")
	)
	(gr_line
		(start 60.015882 -383.2352)
		(end 60.015882 -383.50571)
		(stroke
			(width 0.0508)
			(type default)
		)
		(layer "F.Cu")
	)
	(gr_line
		(start 60.021724 -408.784044)
		(end 60.317634 -409.079954)
		(stroke
			(width 0.06477)
			(type default)
		)
		(layer "F.Cu")
	)
	(gr_line
		(start 60.047124 -404.46452)
		(end 60.317634 -404.73503)
		(stroke
			(width 0.06477)
			(type default)
		)
		(layer "F.Cu")
	)
	(gr_line
		(start 60.107068 -383.596896)
		(end 60.241434 -383.596896)
		(stroke
			(width 0.0508)
			(type default)
		)
		(layer "F.Cu")
	)
	(gr_line
		(start 60.241434 -383.596896)
		(end 60.317888 -383.520442)
		(stroke
			(width 0.0508)
			(type default)
		)
		(layer "F.Cu")
	)
	(gr_line
		(start 60.30722 -382.943862)
		(end 60.015882 -383.2352)
		(stroke
			(width 0.0508)
			(type default)
		)
		(layer "F.Cu")
	)
	(gr_line
		(start 60.317634 -412.299658)
		(end 60.047124 -412.570168)
		(stroke
			(width 0.06477)
			(type default)
		)
		(layer "F.Cu")
	)
	(gr_line
		(start 60.317634 -407.954734)
		(end 60.021724 -408.250644)
		(stroke
			(width 0.06477)
			(type default)
		)
		(layer "F.Cu")
	)
	(gr_line
		(start 60.317888 -383.520442)
		(end 60.317888 -383.402586)
		(stroke
			(width 0.0508)
			(type default)
		)
		(layer "F.Cu")
	)
	(gr_line
		(start 60.4012 -391.36447)
		(end 60.317888 -391.281158)
		(stroke
			(width 0.0508)
			(type default)
		)
		(layer "F.Cu")
	)
	(gr_line
		(start 60.470542 -388.774432)
		(end 60.991242 -388.774432)
		(stroke
			(width 0.0635)
			(type default)
		)
		(layer "F.Cu")
	)
	(gr_line
		(start 60.470542 -385.31038)
		(end 60.991242 -385.31038)
		(stroke
			(width 0.0635)
			(type default)
		)
		(layer "F.Cu")
	)
	(gr_line
		(start 60.52439 -383.13741)
		(end 60.618116 -383.231136)
		(stroke
			(width 0.0508)
			(type default)
		)
		(layer "F.Cu")
	)
	(gr_line
		(start 60.52439 -382.942592)
		(end 60.52439 -383.13741)
		(stroke
			(width 0.0508)
			(type default)
		)
		(layer "F.Cu")
	)
	(gr_line
		(start 60.618116 -383.231136)
		(end 60.618116 -383.92227)
		(stroke
			(width 0.0508)
			(type default)
		)
		(layer "F.Cu")
	)
	(gr_line
		(start 60.61837 -391.36574)
		(end 60.61837 -390.761728)
		(stroke
			(width 0.0508)
			(type default)
		)
		(layer "F.Cu")
	)
	(gr_line
		(start 60.61837 -390.761728)
		(end 60.618116 -390.761474)
		(stroke
			(width 0.0508)
			(type default)
		)
		(layer "F.Cu")
	)
	(gr_line
		(start 60.640214 -412.299658)
		(end 60.910724 -412.570168)
		(stroke
			(width 0.06477)
			(type default)
		)
		(layer "F.Cu")
	)
	(gr_line
		(start 60.640214 -407.954734)
		(end 60.936124 -408.250644)
		(stroke
			(width 0.06477)
			(type default)
		)
		(layer "F.Cu")
	)
	(gr_line
		(start 60.870592 -389.467344)
		(end 61.391292 -389.467344)
		(stroke
			(width 0.0635)
			(type default)
		)
		(layer "F.Cu")
	)
	(gr_line
		(start 60.870592 -386.003292)
		(end 61.391292 -386.003292)
		(stroke
			(width 0.0635)
			(type default)
		)
		(layer "F.Cu")
	)
	(gr_line
		(start 60.877704 -392.977116)
		(end 60.875672 -392.977116)
		(stroke
			(width 0.0508)
			(type default)
		)
		(layer "F.Cu")
	)
	(gr_line
		(start 60.910724 -404.46452)
		(end 60.640214 -404.73503)
		(stroke
			(width 0.06477)
			(type default)
		)
		(layer "F.Cu")
	)
	(gr_line
		(start 60.936124 -408.784044)
		(end 60.640214 -409.079954)
		(stroke
			(width 0.06477)
			(type default)
		)
		(layer "F.Cu")
	)
	(gr_line
		(start 61.016642 -393.292838)
		(end 61.016642 -393.116054)
		(stroke
			(width 0.0508)
			(type default)
		)
		(layer "F.Cu")
	)
	(gr_line
		(start 61.016642 -393.116054)
		(end 60.877704 -392.977116)
		(stroke
			(width 0.0508)
			(type default)
		)
		(layer "F.Cu")
	)
	(gr_line
		(start 61.016642 -392.620246)
		(end 60.876942 -392.759946)
		(stroke
			(width 0.0508)
			(type default)
		)
		(layer "F.Cu")
	)
	(gr_line
		(start 61.016642 -392.429238)
		(end 61.016642 -392.620246)
		(stroke
			(width 0.0508)
			(type default)
		)
		(layer "F.Cu")
	)
	(gr_line
		(start 61.216032 -383.50571)
		(end 61.307218 -383.596896)
		(stroke
			(width 0.0508)
			(type default)
		)
		(layer "F.Cu")
	)
	(gr_line
		(start 61.216032 -383.2352)
		(end 61.216032 -383.50571)
		(stroke
			(width 0.0508)
			(type default)
		)
		(layer "F.Cu")
	)
	(gr_line
		(start 61.307218 -383.596896)
		(end 61.441584 -383.596896)
		(stroke
			(width 0.0508)
			(type default)
		)
		(layer "F.Cu")
	)
	(gr_line
		(start 61.441584 -383.596896)
		(end 61.518038 -383.520442)
		(stroke
			(width 0.0508)
			(type default)
		)
		(layer "F.Cu")
	)
	(gr_line
		(start 61.50737 -382.943862)
		(end 61.216032 -383.2352)
		(stroke
			(width 0.0508)
			(type default)
		)
		(layer "F.Cu")
	)
	(gr_line
		(start 61.518038 -383.520442)
		(end 61.518038 -383.402586)
		(stroke
			(width 0.0508)
			(type default)
		)
		(layer "F.Cu")
	)
	(gr_line
		(start 61.60135 -391.36447)
		(end 61.518038 -391.281158)
		(stroke
			(width 0.0508)
			(type default)
		)
		(layer "F.Cu")
	)
	(gr_line
		(start 61.670692 -388.774432)
		(end 62.191392 -388.774432)
		(stroke
			(width 0.0635)
			(type default)
		)
		(layer "F.Cu")
	)
	(gr_line
		(start 61.670692 -385.31038)
		(end 62.191392 -385.31038)
		(stroke
			(width 0.0635)
			(type default)
		)
		(layer "F.Cu")
	)
	(gr_line
		(start 61.709554 -375.76633)
		(end 62.057788 -376.114564)
		(stroke
			(width 0.0508)
			(type default)
		)
		(layer "F.Cu")
	)
	(gr_line
		(start 61.72454 -383.13741)
		(end 61.818012 -383.230882)
		(stroke
			(width 0.0508)
			(type default)
		)
		(layer "F.Cu")
	)
	(gr_line
		(start 61.72454 -382.942592)
		(end 61.72454 -383.13741)
		(stroke
			(width 0.0508)
			(type default)
		)
		(layer "F.Cu")
	)
	(gr_line
		(start 61.734954 -373.96293)
		(end 62.005464 -374.23344)
		(stroke
			(width 0.06477)
			(type default)
		)
		(layer "F.Cu")
	)
	(gr_line
		(start 61.818012 -383.230882)
		(end 61.818012 -383.92227)
		(stroke
			(width 0.0508)
			(type default)
		)
		(layer "F.Cu")
	)
	(gr_line
		(start 61.81852 -391.36574)
		(end 61.81852 -390.761982)
		(stroke
			(width 0.0508)
			(type default)
		)
		(layer "F.Cu")
	)
	(gr_line
		(start 61.81852 -390.761982)
		(end 61.818012 -390.761474)
		(stroke
			(width 0.0508)
			(type default)
		)
		(layer "F.Cu")
	)
	(gr_line
		(start 61.88075 -193.594228)
		(end 62.333632 -193.141346)
		(stroke
			(width 0.127)
			(type default)
		)
		(layer "F.Cu")
	)
	(gr_line
		(start 62.005464 -374.93702)
		(end 61.709554 -375.23293)
		(stroke
			(width 0.06477)
			(type default)
		)
		(layer "F.Cu")
	)
	(gr_line
		(start 62.057788 -376.114564)
		(end 62.057788 -376.116596)
		(stroke
			(width 0.0508)
			(type default)
		)
		(layer "F.Cu")
	)
	(gr_line
		(start 62.070488 -389.467344)
		(end 62.591188 -389.467344)
		(stroke
			(width 0.0635)
			(type default)
		)
		(layer "F.Cu")
	)
	(gr_line
		(start 62.070488 -386.003292)
		(end 62.591188 -386.003292)
		(stroke
			(width 0.0635)
			(type default)
		)
		(layer "F.Cu")
	)
	(gr_line
		(start 62.074552 -392.977116)
		(end 62.051184 -392.977116)
		(stroke
			(width 0.0508)
			(type default)
		)
		(layer "F.Cu")
	)
	(gr_line
		(start 62.216538 -393.292838)
		(end 62.216538 -393.119102)
		(stroke
			(width 0.0508)
			(type default)
		)
		(layer "F.Cu")
	)
	(gr_line
		(start 62.216538 -393.119102)
		(end 62.074552 -392.977116)
		(stroke
			(width 0.0508)
			(type default)
		)
		(layer "F.Cu")
	)
	(gr_line
		(start 62.216538 -392.595862)
		(end 62.052454 -392.759946)
		(stroke
			(width 0.0508)
			(type default)
		)
		(layer "F.Cu")
	)
	(gr_line
		(start 62.216538 -392.429238)
		(end 62.216538 -392.595862)
		(stroke
			(width 0.0508)
			(type default)
		)
		(layer "F.Cu")
	)
	(gr_line
		(start 62.328044 -374.93702)
		(end 62.623954 -375.23293)
		(stroke
			(width 0.06477)
			(type default)
		)
		(layer "F.Cu")
	)
	(gr_line
		(start 62.333632 -194.04711)
		(end 61.88075 -193.594228)
		(stroke
			(width 0.127)
			(type default)
		)
		(layer "F.Cu")
	)
	(gr_line
		(start 62.415928 -383.50571)
		(end 62.507114 -383.596896)
		(stroke
			(width 0.0508)
			(type default)
		)
		(layer "F.Cu")
	)
	(gr_line
		(start 62.415928 -383.2352)
		(end 62.415928 -383.50571)
		(stroke
			(width 0.0508)
			(type default)
		)
		(layer "F.Cu")
	)
	(gr_line
		(start 62.507114 -383.596896)
		(end 62.64148 -383.596896)
		(stroke
			(width 0.0508)
			(type default)
		)
		(layer "F.Cu")
	)
	(gr_line
		(start 62.563756 -142.624048)
		(end 58.989468 -142.624048)
		(stroke
			(width 0.127)
			(type default)
		)
		(layer "F.Cu")
	)
	(gr_line
		(start 62.598554 -373.96293)
		(end 62.328044 -374.23344)
		(stroke
			(width 0.06477)
			(type default)
		)
		(layer "F.Cu")
	)
	(gr_line
		(start 62.623954 -375.76633)
		(end 62.274958 -376.115326)
		(stroke
			(width 0.0508)
			(type default)
		)
		(layer "F.Cu")
	)
	(gr_line
		(start 62.64148 -383.596896)
		(end 62.717934 -383.520442)
		(stroke
			(width 0.0508)
			(type default)
		)
		(layer "F.Cu")
	)
	(gr_line
		(start 62.707266 -382.943862)
		(end 62.415928 -383.2352)
		(stroke
			(width 0.0508)
			(type default)
		)
		(layer "F.Cu")
	)
	(gr_line
		(start 62.715902 -194.04838)
		(end 62.715902 -194.029076)
		(stroke
			(width 0.127)
			(type default)
		)
		(layer "F.Cu")
	)
	(gr_line
		(start 62.715902 -194.029076)
		(end 63.15075 -193.594228)
		(stroke
			(width 0.127)
			(type default)
		)
		(layer "F.Cu")
	)
	(gr_line
		(start 62.715902 -193.15938)
		(end 62.715902 -193.140076)
		(stroke
			(width 0.127)
			(type default)
		)
		(layer "F.Cu")
	)
	(gr_line
		(start 62.717934 -383.520442)
		(end 62.717934 -383.402586)
		(stroke
			(width 0.0508)
			(type default)
		)
		(layer "F.Cu")
	)
	(gr_line
		(start 62.801246 -391.36447)
		(end 62.717934 -391.281158)
		(stroke
			(width 0.0508)
			(type default)
		)
		(layer "F.Cu")
	)
	(gr_line
		(start 62.870588 -388.774432)
		(end 63.391288 -388.774432)
		(stroke
			(width 0.0635)
			(type default)
		)
		(layer "F.Cu")
	)
	(gr_line
		(start 62.870588 -385.31038)
		(end 63.391288 -385.31038)
		(stroke
			(width 0.0635)
			(type default)
		)
		(layer "F.Cu")
	)
	(gr_line
		(start 62.924436 -383.13741)
		(end 63.017908 -383.230882)
		(stroke
			(width 0.0508)
			(type default)
		)
		(layer "F.Cu")
	)
	(gr_line
		(start 62.924436 -382.942592)
		(end 62.924436 -383.13741)
		(stroke
			(width 0.0508)
			(type default)
		)
		(layer "F.Cu")
	)
	(gr_line
		(start 63.017908 -383.230882)
		(end 63.017908 -383.92227)
		(stroke
			(width 0.0508)
			(type default)
		)
		(layer "F.Cu")
	)
	(gr_line
		(start 63.018416 -391.36574)
		(end 63.018416 -390.761982)
		(stroke
			(width 0.0508)
			(type default)
		)
		(layer "F.Cu")
	)
	(gr_line
		(start 63.018416 -390.761982)
		(end 63.017908 -390.761474)
		(stroke
			(width 0.0508)
			(type default)
		)
		(layer "F.Cu")
	)
	(gr_line
		(start 63.084964 -408.784044)
		(end 63.380874 -409.079954)
		(stroke
			(width 0.06477)
			(type default)
		)
		(layer "F.Cu")
	)
	(gr_line
		(start 63.110364 -404.46452)
		(end 63.380874 -404.73503)
		(stroke
			(width 0.06477)
			(type default)
		)
		(layer "F.Cu")
	)
	(gr_line
		(start 63.15075 -193.594228)
		(end 62.715902 -193.15938)
		(stroke
			(width 0.127)
			(type default)
		)
		(layer "F.Cu")
	)
	(gr_line
		(start 63.270638 -389.467344)
		(end 63.791338 -389.467344)
		(stroke
			(width 0.0635)
			(type default)
		)
		(layer "F.Cu")
	)
	(gr_line
		(start 63.270638 -386.003292)
		(end 63.791338 -386.003292)
		(stroke
			(width 0.0635)
			(type default)
		)
		(layer "F.Cu")
	)
	(gr_line
		(start 63.27775 -392.977116)
		(end 63.275718 -392.977116)
		(stroke
			(width 0.0508)
			(type default)
		)
		(layer "F.Cu")
	)
	(gr_line
		(start 63.380874 -412.299658)
		(end 63.110364 -412.570168)
		(stroke
			(width 0.06477)
			(type default)
		)
		(layer "F.Cu")
	)
	(gr_line
		(start 63.380874 -407.954734)
		(end 63.084964 -408.250644)
		(stroke
			(width 0.06477)
			(type default)
		)
		(layer "F.Cu")
	)
	(gr_line
		(start 63.411354 -373.30253)
		(end 63.760604 -373.65178)
		(stroke
			(width 0.0508)
			(type default)
		)
		(layer "F.Cu")
	)
	(gr_line
		(start 63.416434 -393.292838)
		(end 63.416434 -393.1158)
		(stroke
			(width 0.0508)
			(type default)
		)
		(layer "F.Cu")
	)
	(gr_line
		(start 63.416434 -393.1158)
		(end 63.27775 -392.977116)
		(stroke
			(width 0.0508)
			(type default)
		)
		(layer "F.Cu")
	)
	(gr_line
		(start 63.416434 -392.6205)
		(end 63.276988 -392.759946)
		(stroke
			(width 0.0508)
			(type default)
		)
		(layer "F.Cu")
	)
	(gr_line
		(start 63.416434 -392.429238)
		(end 63.416434 -392.6205)
		(stroke
			(width 0.0508)
			(type default)
		)
		(layer "F.Cu")
	)
	(gr_line
		(start 63.436754 -371.49913)
		(end 63.707264 -371.76964)
		(stroke
			(width 0.06477)
			(type default)
		)
		(layer "F.Cu")
	)
	(gr_line
		(start 63.703454 -412.299658)
		(end 63.973964 -412.570168)
		(stroke
			(width 0.06477)
			(type default)
		)
		(layer "F.Cu")
	)
	(gr_line
		(start 63.703454 -407.954734)
		(end 63.999364 -408.250644)
		(stroke
			(width 0.06477)
			(type default)
		)
		(layer "F.Cu")
	)
	(gr_line
		(start 63.707264 -372.47322)
		(end 63.411354 -372.76913)
		(stroke
			(width 0.06477)
			(type default)
		)
		(layer "F.Cu")
	)
	(gr_line
		(start 63.760604 -375.021856)
		(end 63.760604 -375.550176)
		(stroke
			(width 0.0508)
			(type default)
		)
		(layer "F.Cu")
	)
	(gr_line
		(start 63.973964 -404.46452)
		(end 63.703454 -404.73503)
		(stroke
			(width 0.06477)
			(type default)
		)
		(layer "F.Cu")
	)
	(gr_line
		(start 63.977774 -375.023126)
		(end 64.088264 -375.133616)
		(stroke
			(width 0.0508)
			(type default)
		)
		(layer "F.Cu")
	)
	(gr_line
		(start 63.999364 -408.784044)
		(end 63.703454 -409.079954)
		(stroke
			(width 0.06477)
			(type default)
		)
		(layer "F.Cu")
	)
	(gr_line
		(start 64.001396 -391.36447)
		(end 63.918084 -391.281158)
		(stroke
			(width 0.0508)
			(type default)
		)
		(layer "F.Cu")
	)
	(gr_line
		(start 64.001396 -383.319274)
		(end 63.918084 -383.402586)
		(stroke
			(width 0.0508)
			(type default)
		)
		(layer "F.Cu")
	)
	(gr_line
		(start 64.029844 -372.47322)
		(end 64.325754 -372.76913)
		(stroke
			(width 0.06477)
			(type default)
		)
		(layer "F.Cu")
	)
	(gr_line
		(start 64.070738 -388.774432)
		(end 64.591438 -388.774432)
		(stroke
			(width 0.0635)
			(type default)
		)
		(layer "F.Cu")
	)
	(gr_line
		(start 64.070738 -385.31038)
		(end 64.591438 -385.31038)
		(stroke
			(width 0.0635)
			(type default)
		)
		(layer "F.Cu")
	)
	(gr_line
		(start 64.088264 -375.438416)
		(end 63.977774 -375.548906)
		(stroke
			(width 0.0508)
			(type default)
		)
		(layer "F.Cu")
	)
	(gr_line
		(start 64.088264 -375.133616)
		(end 64.088264 -375.438416)
		(stroke
			(width 0.0508)
			(type default)
		)
		(layer "F.Cu")
	)
	(gr_line
		(start 64.12484 -381.689102)
		(end 64.124586 -381.688848)
		(stroke
			(width 0.0508)
			(type default)
		)
		(layer "F.Cu")
	)
	(gr_line
		(start 64.218566 -391.36574)
		(end 64.218566 -390.761982)
		(stroke
			(width 0.0508)
			(type default)
		)
		(layer "F.Cu")
	)
	(gr_line
		(start 64.218566 -390.761982)
		(end 64.218058 -390.761474)
		(stroke
			(width 0.0508)
			(type default)
		)
		(layer "F.Cu")
	)
	(gr_line
		(start 64.218566 -383.921762)
		(end 64.218058 -383.92227)
		(stroke
			(width 0.0508)
			(type default)
		)
		(layer "F.Cu")
	)
	(gr_line
		(start 64.218566 -383.318004)
		(end 64.218566 -383.921762)
		(stroke
			(width 0.0508)
			(type default)
		)
		(layer "F.Cu")
	)
	(gr_line
		(start 64.300354 -371.49913)
		(end 64.029844 -371.76964)
		(stroke
			(width 0.06477)
			(type default)
		)
		(layer "F.Cu")
	)
	(gr_line
		(start 64.325754 -373.30253)
		(end 63.976504 -373.65178)
		(stroke
			(width 0.0508)
			(type default)
		)
		(layer "F.Cu")
	)
	(gr_line
		(start 64.459866 -392.977116)
		(end 64.449198 -392.977116)
		(stroke
			(width 0.0508)
			(type default)
		)
		(layer "F.Cu")
	)
	(gr_line
		(start 64.470534 -389.467344)
		(end 64.991234 -389.467344)
		(stroke
			(width 0.0635)
			(type default)
		)
		(layer "F.Cu")
	)
	(gr_line
		(start 64.470534 -386.003292)
		(end 64.991234 -386.003292)
		(stroke
			(width 0.0635)
			(type default)
		)
		(layer "F.Cu")
	)
	(gr_line
		(start 64.616584 -393.292838)
		(end 64.616584 -393.133834)
		(stroke
			(width 0.0508)
			(type default)
		)
		(layer "F.Cu")
	)
	(gr_line
		(start 64.616584 -393.133834)
		(end 64.459866 -392.977116)
		(stroke
			(width 0.0508)
			(type default)
		)
		(layer "F.Cu")
	)
	(gr_line
		(start 64.616584 -392.59383)
		(end 64.450468 -392.759946)
		(stroke
			(width 0.0508)
			(type default)
		)
		(layer "F.Cu")
	)
	(gr_line
		(start 64.616584 -392.429238)
		(end 64.616584 -392.59383)
		(stroke
			(width 0.0508)
			(type default)
		)
		(layer "F.Cu")
	)
	(gr_line
		(start 65.113154 -370.83873)
		(end 65.462404 -371.18798)
		(stroke
			(width 0.0508)
			(type default)
		)
		(layer "F.Cu")
	)
	(gr_line
		(start 65.138554 -369.03533)
		(end 65.409064 -369.30584)
		(stroke
			(width 0.06477)
			(type default)
		)
		(layer "F.Cu")
	)
	(gr_line
		(start 65.201292 -391.36447)
		(end 65.11798 -391.281158)
		(stroke
			(width 0.0508)
			(type default)
		)
		(layer "F.Cu")
	)
	(gr_line
		(start 65.201292 -383.319274)
		(end 65.11798 -383.402586)
		(stroke
			(width 0.0508)
			(type default)
		)
		(layer "F.Cu")
	)
	(gr_line
		(start 65.270634 -388.774432)
		(end 65.791334 -388.774432)
		(stroke
			(width 0.0635)
			(type default)
		)
		(layer "F.Cu")
	)
	(gr_line
		(start 65.270634 -385.31038)
		(end 65.791334 -385.31038)
		(stroke
			(width 0.0635)
			(type default)
		)
		(layer "F.Cu")
	)
	(gr_line
		(start 65.409064 -370.00942)
		(end 65.113154 -370.30533)
		(stroke
			(width 0.06477)
			(type default)
		)
		(layer "F.Cu")
	)
	(gr_line
		(start 65.418462 -391.36574)
		(end 65.418462 -390.761982)
		(stroke
			(width 0.0508)
			(type default)
		)
		(layer "F.Cu")
	)
	(gr_line
		(start 65.418462 -390.761982)
		(end 65.417954 -390.761474)
		(stroke
			(width 0.0508)
			(type default)
		)
		(layer "F.Cu")
	)
	(gr_line
		(start 65.418462 -383.921762)
		(end 65.417954 -383.92227)
		(stroke
			(width 0.0508)
			(type default)
		)
		(layer "F.Cu")
	)
	(gr_line
		(start 65.418462 -383.318004)
		(end 65.418462 -383.921762)
		(stroke
			(width 0.0508)
			(type default)
		)
		(layer "F.Cu")
	)
	(gr_line
		(start 65.661286 -392.977116)
		(end 65.65519 -392.977116)
		(stroke
			(width 0.0508)
			(type default)
		)
		(layer "F.Cu")
	)
	(gr_line
		(start 65.670684 -389.467344)
		(end 66.191384 -389.467344)
		(stroke
			(width 0.0635)
			(type default)
		)
		(layer "F.Cu")
	)
	(gr_line
		(start 65.670684 -386.003292)
		(end 66.191384 -386.003292)
		(stroke
			(width 0.0635)
			(type default)
		)
		(layer "F.Cu")
	)
	(gr_line
		(start 65.731644 -370.00942)
		(end 66.027554 -370.30533)
		(stroke
			(width 0.06477)
			(type default)
		)
		(layer "F.Cu")
	)
	(gr_line
		(start 65.81648 -393.292838)
		(end 65.81648 -393.13231)
		(stroke
			(width 0.0508)
			(type default)
		)
		(layer "F.Cu")
	)
	(gr_line
		(start 65.81648 -393.13231)
		(end 65.661286 -392.977116)
		(stroke
			(width 0.0508)
			(type default)
		)
		(layer "F.Cu")
	)
	(gr_line
		(start 65.81648 -392.599926)
		(end 65.65646 -392.759946)
		(stroke
			(width 0.0508)
			(type default)
		)
		(layer "F.Cu")
	)
	(gr_line
		(start 65.81648 -392.429238)
		(end 65.81648 -392.599926)
		(stroke
			(width 0.0508)
			(type default)
		)
		(layer "F.Cu")
	)
	(gr_line
		(start 66.002154 -369.03533)
		(end 65.731644 -369.30584)
		(stroke
			(width 0.06477)
			(type default)
		)
		(layer "F.Cu")
	)
	(gr_line
		(start 66.027554 -370.83873)
		(end 65.678304 -371.18798)
		(stroke
			(width 0.0508)
			(type default)
		)
		(layer "F.Cu")
	)
	(gr_line
		(start 66.148204 -408.784044)
		(end 66.444114 -409.079954)
		(stroke
			(width 0.06477)
			(type default)
		)
		(layer "F.Cu")
	)
	(gr_line
		(start 66.173604 -404.46452)
		(end 66.444114 -404.73503)
		(stroke
			(width 0.06477)
			(type default)
		)
		(layer "F.Cu")
	)
	(gr_line
		(start 66.444114 -412.299658)
		(end 66.173604 -412.570168)
		(stroke
			(width 0.06477)
			(type default)
		)
		(layer "F.Cu")
	)
	(gr_line
		(start 66.444114 -407.954734)
		(end 66.148204 -408.250644)
		(stroke
			(width 0.06477)
			(type default)
		)
		(layer "F.Cu")
	)
	(gr_line
		(start 66.64579 -373.078502)
		(end 67.019678 -373.45239)
		(stroke
			(width 0.0508)
			(type default)
		)
		(layer "F.Cu")
	)
	(gr_line
		(start 66.766694 -412.299658)
		(end 67.037204 -412.570168)
		(stroke
			(width 0.06477)
			(type default)
		)
		(layer "F.Cu")
	)
	(gr_line
		(start 66.766694 -407.954734)
		(end 67.062604 -408.250644)
		(stroke
			(width 0.06477)
			(type default)
		)
		(layer "F.Cu")
	)
	(gr_line
		(start 66.800222 -372.925594)
		(end 66.956686 -372.925594)
		(stroke
			(width 0.0508)
			(type default)
		)
		(layer "F.Cu")
	)
	(gr_line
		(start 66.956686 -372.925594)
		(end 67.172586 -373.141494)
		(stroke
			(width 0.0508)
			(type default)
		)
		(layer "F.Cu")
	)
	(gr_line
		(start 67.037204 -404.46452)
		(end 66.766694 -404.73503)
		(stroke
			(width 0.06477)
			(type default)
		)
		(layer "F.Cu")
	)
	(gr_line
		(start 67.062604 -408.784044)
		(end 66.766694 -409.079954)
		(stroke
			(width 0.06477)
			(type default)
		)
		(layer "F.Cu")
	)
	(gr_line
		(start 67.172586 -373.141494)
		(end 67.172586 -373.297958)
		(stroke
			(width 0.0508)
			(type default)
		)
		(layer "F.Cu")
	)
	(gr_line
		(start 67.36334 -142.116048)
		(end 58.83275 -142.116048)
		(stroke
			(width 0.127)
			(type default)
		)
		(layer "F.Cu")
	)
	(gr_line
		(start 68.246752 -379.708918)
		(end 68.136262 -379.819408)
		(stroke
			(width 0.0508)
			(type default)
		)
		(layer "F.Cu")
	)
	(gr_line
		(start 68.516754 -370.83873)
		(end 68.866004 -371.18798)
		(stroke
			(width 0.0508)
			(type default)
		)
		(layer "F.Cu")
	)
	(gr_line
		(start 68.542154 -369.03533)
		(end 68.812664 -369.30584)
		(stroke
			(width 0.06477)
			(type default)
		)
		(layer "F.Cu")
	)
	(gr_line
		(start 68.551552 -379.708918)
		(end 68.246752 -379.708918)
		(stroke
			(width 0.0508)
			(type default)
		)
		(layer "F.Cu")
	)
	(gr_line
		(start 68.662042 -379.819408)
		(end 68.551552 -379.708918)
		(stroke
			(width 0.0508)
			(type default)
		)
		(layer "F.Cu")
	)
	(gr_line
		(start 68.663312 -380.036578)
		(end 68.134992 -380.036578)
		(stroke
			(width 0.0508)
			(type default)
		)
		(layer "F.Cu")
	)
	(gr_line
		(start 68.812664 -370.00942)
		(end 68.516754 -370.30533)
		(stroke
			(width 0.06477)
			(type default)
		)
		(layer "F.Cu")
	)
	(gr_line
		(start 69.081904 -371.527832)
		(end 69.082158 -371.527578)
		(stroke
			(width 0.0508)
			(type default)
		)
		(layer "F.Cu")
	)
	(gr_line
		(start 69.129148 -376.71883)
		(end 69.039232 -376.71883)
		(stroke
			(width 0.0508)
			(type default)
		)
		(layer "F.Cu")
	)
	(gr_line
		(start 69.135244 -370.00942)
		(end 69.431154 -370.30533)
		(stroke
			(width 0.06477)
			(type default)
		)
		(layer "F.Cu")
	)
	(gr_line
		(start 69.211444 -408.784044)
		(end 69.507354 -409.079954)
		(stroke
			(width 0.06477)
			(type default)
		)
		(layer "F.Cu")
	)
	(gr_line
		(start 69.236844 -404.46452)
		(end 69.507354 -404.73503)
		(stroke
			(width 0.06477)
			(type default)
		)
		(layer "F.Cu")
	)
	(gr_line
		(start 69.268848 -376.776742)
		(end 69.129148 -376.71883)
		(stroke
			(width 0.0508)
			(type default)
		)
		(layer "F.Cu")
	)
	(gr_line
		(start 69.405754 -369.03533)
		(end 69.135244 -369.30584)
		(stroke
			(width 0.06477)
			(type default)
		)
		(layer "F.Cu")
	)
	(gr_line
		(start 69.431154 -370.83873)
		(end 69.081904 -371.18798)
		(stroke
			(width 0.0508)
			(type default)
		)
		(layer "F.Cu")
	)
	(gr_line
		(start 69.474334 -380.385828)
		(end 69.125084 -380.036578)
		(stroke
			(width 0.0508)
			(type default)
		)
		(layer "F.Cu")
	)
	(gr_line
		(start 69.474334 -379.471428)
		(end 69.125084 -379.820678)
		(stroke
			(width 0.0508)
			(type default)
		)
		(layer "F.Cu")
	)
	(gr_line
		(start 69.474334 -376.982228)
		(end 69.268848 -376.776742)
		(stroke
			(width 0.0508)
			(type default)
		)
		(layer "F.Cu")
	)
	(gr_line
		(start 69.474334 -376.067828)
		(end 69.040502 -376.50166)
		(stroke
			(width 0.0508)
			(type default)
		)
		(layer "F.Cu")
	)
	(gr_line
		(start 69.487796 -142.624048)
		(end 62.563756 -142.624048)
		(stroke
			(width 0.127)
			(type default)
		)
		(layer "F.Cu")
	)
	(gr_line
		(start 69.507354 -412.299658)
		(end 69.236844 -412.570168)
		(stroke
			(width 0.06477)
			(type default)
		)
		(layer "F.Cu")
	)
	(gr_line
		(start 69.507354 -407.954734)
		(end 69.211444 -408.250644)
		(stroke
			(width 0.06477)
			(type default)
		)
		(layer "F.Cu")
	)
	(gr_line
		(start 69.620384 -145.973292)
		(end 69.620384 -145.580862)
		(stroke
			(width 0.127)
			(type default)
		)
		(layer "F.Cu")
	)
	(gr_line
		(start 69.620384 -145.580862)
		(end 70.320154 -144.881092)
		(stroke
			(width 0.127)
			(type default)
		)
		(layer "F.Cu")
	)
	(gr_line
		(start 69.726048 -142.116048)
		(end 67.36334 -142.116048)
		(stroke
			(width 0.127)
			(type default)
		)
		(layer "F.Cu")
	)
	(gr_line
		(start 69.796406 -372.904258)
		(end 70.170294 -373.278146)
		(stroke
			(width 0.0508)
			(type default)
		)
		(layer "F.Cu")
	)
	(gr_line
		(start 69.829934 -412.299658)
		(end 70.100444 -412.570168)
		(stroke
			(width 0.06477)
			(type default)
		)
		(layer "F.Cu")
	)
	(gr_line
		(start 69.829934 -407.954734)
		(end 70.125844 -408.250644)
		(stroke
			(width 0.06477)
			(type default)
		)
		(layer "F.Cu")
	)
	(gr_line
		(start 69.950584 -372.75135)
		(end 70.107302 -372.75135)
		(stroke
			(width 0.0508)
			(type default)
		)
		(layer "F.Cu")
	)
	(gr_line
		(start 70.100444 -404.46452)
		(end 69.829934 -404.73503)
		(stroke
			(width 0.06477)
			(type default)
		)
		(layer "F.Cu")
	)
	(gr_line
		(start 70.107302 -372.75135)
		(end 70.323202 -372.96725)
		(stroke
			(width 0.0508)
			(type default)
		)
		(layer "F.Cu")
	)
	(gr_line
		(start 70.125844 -408.784044)
		(end 69.829934 -409.079954)
		(stroke
			(width 0.06477)
			(type default)
		)
		(layer "F.Cu")
	)
	(gr_line
		(start 70.303644 -380.089918)
		(end 70.007734 -380.385828)
		(stroke
			(width 0.06477)
			(type default)
		)
		(layer "F.Cu")
	)
	(gr_line
		(start 70.303644 -379.767338)
		(end 70.007734 -379.471428)
		(stroke
			(width 0.06477)
			(type default)
		)
		(layer "F.Cu")
	)
	(gr_line
		(start 70.303644 -376.686318)
		(end 70.007734 -376.982228)
		(stroke
			(width 0.06477)
			(type default)
		)
		(layer "F.Cu")
	)
	(gr_line
		(start 70.303644 -376.363738)
		(end 70.007734 -376.067828)
		(stroke
			(width 0.06477)
			(type default)
		)
		(layer "F.Cu")
	)
	(gr_line
		(start 70.323202 -372.96725)
		(end 70.323202 -373.123968)
		(stroke
			(width 0.0508)
			(type default)
		)
		(layer "F.Cu")
	)
	(gr_line
		(start 71.120254 -144.881092)
		(end 71.252842 -144.748504)
		(stroke
			(width 0.127)
			(type default)
		)
		(layer "F.Cu")
	)
	(gr_line
		(start 71.252842 -144.748504)
		(end 71.252842 -144.389094)
		(stroke
			(width 0.127)
			(type default)
		)
		(layer "F.Cu")
	)
	(gr_line
		(start 71.252842 -144.389094)
		(end 69.487796 -142.624048)
		(stroke
			(width 0.127)
			(type default)
		)
		(layer "F.Cu")
	)
	(gr_line
		(start 71.277734 -380.360428)
		(end 71.007224 -380.089918)
		(stroke
			(width 0.06477)
			(type default)
		)
		(layer "F.Cu")
	)
	(gr_line
		(start 71.277734 -379.496828)
		(end 71.007224 -379.767338)
		(stroke
			(width 0.06477)
			(type default)
		)
		(layer "F.Cu")
	)
	(gr_line
		(start 71.277734 -376.956828)
		(end 71.007224 -376.686318)
		(stroke
			(width 0.06477)
			(type default)
		)
		(layer "F.Cu")
	)
	(gr_line
		(start 71.277734 -376.093228)
		(end 71.007224 -376.363738)
		(stroke
			(width 0.06477)
			(type default)
		)
		(layer "F.Cu")
	)
	(gr_line
		(start 71.329804 -12.864846)
		(end 71.599806 -12.594844)
		(stroke
			(width 0.06477)
			(type default)
		)
		(layer "F.Cu")
	)
	(gr_line
		(start 71.330312 -6.58749)
		(end 71.600822 -6.858)
		(stroke
			(width 0.06477)
			(type default)
		)
		(layer "F.Cu")
	)
	(gr_line
		(start 71.461884 -11.87196)
		(end 71.461884 -11.26998)
		(stroke
			(width 0.06477)
			(type default)
		)
		(layer "F.Cu")
	)
	(gr_line
		(start 71.461884 -7.748778)
		(end 71.461884 -8.320024)
		(stroke
			(width 0.06477)
			(type default)
		)
		(layer "F.Cu")
	)
	(gr_line
		(start 71.599552 -12.009628)
		(end 71.461884 -11.87196)
		(stroke
			(width 0.06477)
			(type default)
		)
		(layer "F.Cu")
	)
	(gr_line
		(start 71.599552 -7.61111)
		(end 71.461884 -7.748778)
		(stroke
			(width 0.06477)
			(type default)
		)
		(layer "F.Cu")
	)
	(gr_line
		(start 71.8058 -144.623028)
		(end 71.8058 -144.1958)
		(stroke
			(width 0.127)
			(type default)
		)
		(layer "F.Cu")
	)
	(gr_line
		(start 71.8058 -144.1958)
		(end 69.726048 -142.116048)
		(stroke
			(width 0.127)
			(type default)
		)
		(layer "F.Cu")
	)
	(gr_line
		(start 71.923402 -12.594844)
		(end 72.193404 -12.864846)
		(stroke
			(width 0.06477)
			(type default)
		)
		(layer "F.Cu")
	)
	(gr_line
		(start 71.923402 -12.593828)
		(end 71.923402 -12.594844)
		(stroke
			(width 0.06477)
			(type default)
		)
		(layer "F.Cu")
	)
	(gr_line
		(start 71.923402 -11.95959)
		(end 71.923402 -12.010898)
		(stroke
			(width 0.06477)
			(type default)
		)
		(layer "F.Cu")
	)
	(gr_line
		(start 71.923402 -7.613396)
		(end 71.923402 -7.60984)
		(stroke
			(width 0.06477)
			(type default)
		)
		(layer "F.Cu")
	)
	(gr_line
		(start 71.923402 -6.858)
		(end 72.193912 -6.58749)
		(stroke
			(width 0.06477)
			(type default)
		)
		(layer "F.Cu")
	)
	(gr_line
		(start 72.062086 -11.820906)
		(end 71.923402 -11.95959)
		(stroke
			(width 0.06477)
			(type default)
		)
		(layer "F.Cu")
	)
	(gr_line
		(start 72.062086 -11.26998)
		(end 72.062086 -11.820906)
		(stroke
			(width 0.06477)
			(type default)
		)
		(layer "F.Cu")
	)
	(gr_line
		(start 72.062086 -8.320024)
		(end 72.062086 -7.75208)
		(stroke
			(width 0.06477)
			(type default)
		)
		(layer "F.Cu")
	)
	(gr_line
		(start 72.062086 -7.75208)
		(end 71.923402 -7.613396)
		(stroke
			(width 0.06477)
			(type default)
		)
		(layer "F.Cu")
	)
	(gr_line
		(start 72.063864 -144.881092)
		(end 71.8058 -144.623028)
		(stroke
			(width 0.127)
			(type default)
		)
		(layer "F.Cu")
	)
	(gr_line
		(start 72.274684 -408.784044)
		(end 72.570594 -409.079954)
		(stroke
			(width 0.06477)
			(type default)
		)
		(layer "F.Cu")
	)
	(gr_line
		(start 72.300084 -404.46452)
		(end 72.570594 -404.73503)
		(stroke
			(width 0.06477)
			(type default)
		)
		(layer "F.Cu")
	)
	(gr_line
		(start 72.570594 -412.299658)
		(end 72.300084 -412.570168)
		(stroke
			(width 0.06477)
			(type default)
		)
		(layer "F.Cu")
	)
	(gr_line
		(start 72.570594 -407.954734)
		(end 72.274684 -408.250644)
		(stroke
			(width 0.06477)
			(type default)
		)
		(layer "F.Cu")
	)
	(gr_line
		(start 72.893174 -412.299658)
		(end 73.163684 -412.570168)
		(stroke
			(width 0.06477)
			(type default)
		)
		(layer "F.Cu")
	)
	(gr_line
		(start 72.893174 -407.954734)
		(end 73.189084 -408.250644)
		(stroke
			(width 0.06477)
			(type default)
		)
		(layer "F.Cu")
	)
	(gr_line
		(start 73.163684 -404.46452)
		(end 72.893174 -404.73503)
		(stroke
			(width 0.06477)
			(type default)
		)
		(layer "F.Cu")
	)
	(gr_line
		(start 73.189084 -408.784044)
		(end 72.893174 -409.079954)
		(stroke
			(width 0.06477)
			(type default)
		)
		(layer "F.Cu")
	)
	(gr_line
		(start 73.512934 -146.074892)
		(end 73.512934 -145.530062)
		(stroke
			(width 0.127)
			(type default)
		)
		(layer "F.Cu")
	)
	(gr_line
		(start 73.512934 -145.530062)
		(end 72.863964 -144.881092)
		(stroke
			(width 0.127)
			(type default)
		)
		(layer "F.Cu")
	)
	(gr_line
		(start 73.810622 -387.789674)
		(end 74.081132 -387.519164)
		(stroke
			(width 0.06477)
			(type default)
		)
		(layer "F.Cu")
	)
	(gr_line
		(start 73.810622 -386.926074)
		(end 74.081132 -387.196584)
		(stroke
			(width 0.06477)
			(type default)
		)
		(layer "F.Cu")
	)
	(gr_line
		(start 73.95845 -382.36906)
		(end 74.22896 -382.09855)
		(stroke
			(width 0.06477)
			(type default)
		)
		(layer "F.Cu")
	)
	(gr_line
		(start 73.95845 -381.50546)
		(end 74.22896 -381.77597)
		(stroke
			(width 0.06477)
			(type default)
		)
		(layer "F.Cu")
	)
	(gr_line
		(start 73.95845 -376.83186)
		(end 74.22896 -376.56135)
		(stroke
			(width 0.06477)
			(type default)
		)
		(layer "F.Cu")
	)
	(gr_line
		(start 73.95845 -375.96826)
		(end 74.22896 -376.23877)
		(stroke
			(width 0.06477)
			(type default)
		)
		(layer "F.Cu")
	)
	(gr_line
		(start 74.54392 -387.519164)
		(end 74.78903 -387.764274)
		(stroke
			(width 0.06477)
			(type default)
		)
		(layer "F.Cu")
	)
	(gr_line
		(start 74.54392 -387.196584)
		(end 74.78903 -386.951474)
		(stroke
			(width 0.06477)
			(type default)
		)
		(layer "F.Cu")
	)
	(gr_line
		(start 74.93254 -382.09855)
		(end 75.22845 -382.39446)
		(stroke
			(width 0.06477)
			(type default)
		)
		(layer "F.Cu")
	)
	(gr_line
		(start 74.93254 -381.77597)
		(end 75.22845 -381.48006)
		(stroke
			(width 0.06477)
			(type default)
		)
		(layer "F.Cu")
	)
	(gr_line
		(start 74.93254 -376.56135)
		(end 75.22845 -376.85726)
		(stroke
			(width 0.06477)
			(type default)
		)
		(layer "F.Cu")
	)
	(gr_line
		(start 74.93254 -376.23877)
		(end 75.22845 -375.94286)
		(stroke
			(width 0.06477)
			(type default)
		)
		(layer "F.Cu")
	)
	(gr_line
		(start 75.32243 -387.764274)
		(end 75.567032 -387.519672)
		(stroke
			(width 0.06477)
			(type default)
		)
		(layer "F.Cu")
	)
	(gr_line
		(start 75.32243 -386.951474)
		(end 75.566778 -387.195822)
		(stroke
			(width 0.06477)
			(type default)
		)
		(layer "F.Cu")
	)
	(gr_line
		(start 75.337924 -408.784044)
		(end 75.633834 -409.079954)
		(stroke
			(width 0.06477)
			(type default)
		)
		(layer "F.Cu")
	)
	(gr_line
		(start 75.363324 -404.46452)
		(end 75.633834 -404.73503)
		(stroke
			(width 0.06477)
			(type default)
		)
		(layer "F.Cu")
	)
	(gr_line
		(start 75.517502 -373.30253)
		(end 75.866752 -373.65178)
		(stroke
			(width 0.0508)
			(type default)
		)
		(layer "F.Cu")
	)
	(gr_line
		(start 75.542902 -371.49913)
		(end 75.813412 -371.76964)
		(stroke
			(width 0.06477)
			(type default)
		)
		(layer "F.Cu")
	)
	(gr_line
		(start 75.566778 -387.195822)
		(end 75.568302 -387.195822)
		(stroke
			(width 0.06477)
			(type default)
		)
		(layer "F.Cu")
	)
	(gr_line
		(start 75.633834 -412.299658)
		(end 75.363324 -412.570168)
		(stroke
			(width 0.06477)
			(type default)
		)
		(layer "F.Cu")
	)
	(gr_line
		(start 75.633834 -407.954734)
		(end 75.337924 -408.250644)
		(stroke
			(width 0.06477)
			(type default)
		)
		(layer "F.Cu")
	)
	(gr_line
		(start 75.76185 -382.39446)
		(end 76.111608 -382.044702)
		(stroke
			(width 0.0508)
			(type default)
		)
		(layer "F.Cu")
	)
	(gr_line
		(start 75.76185 -381.48006)
		(end 76.109322 -381.827532)
		(stroke
			(width 0.0508)
			(type default)
		)
		(layer "F.Cu")
	)
	(gr_line
		(start 75.76185 -376.85726)
		(end 76.131674 -376.487436)
		(stroke
			(width 0.0508)
			(type default)
		)
		(layer "F.Cu")
	)
	(gr_line
		(start 75.76185 -375.94286)
		(end 76.089256 -376.270266)
		(stroke
			(width 0.0508)
			(type default)
		)
		(layer "F.Cu")
	)
	(gr_line
		(start 75.813412 -372.47322)
		(end 75.517502 -372.76913)
		(stroke
			(width 0.06477)
			(type default)
		)
		(layer "F.Cu")
	)
	(gr_line
		(start 75.825858 -387.195822)
		(end 75.827382 -387.195822)
		(stroke
			(width 0.06477)
			(type default)
		)
		(layer "F.Cu")
	)
	(gr_line
		(start 75.827128 -387.519672)
		(end 76.07173 -387.764274)
		(stroke
			(width 0.06477)
			(type default)
		)
		(layer "F.Cu")
	)
	(gr_line
		(start 75.827382 -387.195822)
		(end 76.07173 -386.951474)
		(stroke
			(width 0.06477)
			(type default)
		)
		(layer "F.Cu")
	)
	(gr_line
		(start 75.956414 -412.299658)
		(end 76.226924 -412.570168)
		(stroke
			(width 0.06477)
			(type default)
		)
		(layer "F.Cu")
	)
	(gr_line
		(start 75.956414 -407.954734)
		(end 76.252324 -408.250644)
		(stroke
			(width 0.06477)
			(type default)
		)
		(layer "F.Cu")
	)
	(gr_line
		(start 76.07173 -387.764274)
		(end 76.327762 -387.508242)
		(stroke
			(width 0.06477)
			(type default)
		)
		(layer "F.Cu")
	)
	(gr_line
		(start 76.07173 -386.951474)
		(end 76.304648 -387.184392)
		(stroke
			(width 0.06477)
			(type default)
		)
		(layer "F.Cu")
	)
	(gr_line
		(start 76.089256 -376.270266)
		(end 76.132944 -376.270266)
		(stroke
			(width 0.0508)
			(type default)
		)
		(layer "F.Cu")
	)
	(gr_line
		(start 76.109322 -381.827532)
		(end 76.112878 -381.827532)
		(stroke
			(width 0.0508)
			(type default)
		)
		(layer "F.Cu")
	)
	(gr_line
		(start 76.135992 -372.47322)
		(end 76.431902 -372.76913)
		(stroke
			(width 0.06477)
			(type default)
		)
		(layer "F.Cu")
	)
	(gr_line
		(start 76.226924 -404.46452)
		(end 75.956414 -404.73503)
		(stroke
			(width 0.06477)
			(type default)
		)
		(layer "F.Cu")
	)
	(gr_line
		(start 76.252324 -408.784044)
		(end 75.956414 -409.079954)
		(stroke
			(width 0.06477)
			(type default)
		)
		(layer "F.Cu")
	)
	(gr_line
		(start 76.304648 -387.184392)
		(end 76.329032 -387.184392)
		(stroke
			(width 0.06477)
			(type default)
		)
		(layer "F.Cu")
	)
	(gr_line
		(start 76.406502 -371.49913)
		(end 76.135992 -371.76964)
		(stroke
			(width 0.06477)
			(type default)
		)
		(layer "F.Cu")
	)
	(gr_line
		(start 76.417678 -381.827532)
		(end 76.945998 -381.827532)
		(stroke
			(width 0.0508)
			(type default)
		)
		(layer "F.Cu")
	)
	(gr_line
		(start 76.418948 -382.044702)
		(end 76.529438 -382.155192)
		(stroke
			(width 0.0508)
			(type default)
		)
		(layer "F.Cu")
	)
	(gr_line
		(start 76.431902 -373.30253)
		(end 76.082652 -373.65178)
		(stroke
			(width 0.0508)
			(type default)
		)
		(layer "F.Cu")
	)
	(gr_line
		(start 76.529438 -382.155192)
		(end 76.834238 -382.155192)
		(stroke
			(width 0.0508)
			(type default)
		)
		(layer "F.Cu")
	)
	(gr_line
		(start 76.834238 -382.155192)
		(end 76.944728 -382.044702)
		(stroke
			(width 0.0508)
			(type default)
		)
		(layer "F.Cu")
	)
	(gr_line
		(start 77.219302 -370.83873)
		(end 77.568552 -371.18798)
		(stroke
			(width 0.0508)
			(type default)
		)
		(layer "F.Cu")
	)
	(gr_line
		(start 77.244702 -369.03533)
		(end 77.515212 -369.30584)
		(stroke
			(width 0.06477)
			(type default)
		)
		(layer "F.Cu")
	)
	(gr_line
		(start 77.250798 -381.827532)
		(end 77.779118 -381.827532)
		(stroke
			(width 0.0508)
			(type default)
		)
		(layer "F.Cu")
	)
	(gr_line
		(start 77.252068 -382.044702)
		(end 77.362558 -382.155192)
		(stroke
			(width 0.0508)
			(type default)
		)
		(layer "F.Cu")
	)
	(gr_line
		(start 77.362558 -382.155192)
		(end 77.667358 -382.155192)
		(stroke
			(width 0.0508)
			(type default)
		)
		(layer "F.Cu")
	)
	(gr_line
		(start 77.515212 -370.00942)
		(end 77.219302 -370.30533)
		(stroke
			(width 0.06477)
			(type default)
		)
		(layer "F.Cu")
	)
	(gr_line
		(start 77.667358 -382.155192)
		(end 77.777848 -382.044702)
		(stroke
			(width 0.0508)
			(type default)
		)
		(layer "F.Cu")
	)
	(gr_line
		(start 77.837792 -370.00942)
		(end 78.133702 -370.30533)
		(stroke
			(width 0.06477)
			(type default)
		)
		(layer "F.Cu")
	)
	(gr_line
		(start 77.854302 -375.942098)
		(end 78.22819 -376.315986)
		(stroke
			(width 0.0508)
			(type default)
		)
		(layer "F.Cu")
	)
	(gr_line
		(start 77.863192 -378.53239)
		(end 77.979778 -378.81433)
		(stroke
			(width 0.0508)
			(type default)
		)
		(layer "F.Cu")
	)
	(gr_line
		(start 77.923136 -378.387864)
		(end 77.863192 -378.53239)
		(stroke
			(width 0.0508)
			(type default)
		)
		(layer "F.Cu")
	)
	(gr_line
		(start 77.979778 -378.81433)
		(end 78.124558 -378.87402)
		(stroke
			(width 0.0508)
			(type default)
		)
		(layer "F.Cu")
	)
	(gr_line
		(start 78.00848 -375.78919)
		(end 78.165198 -375.78919)
		(stroke
			(width 0.0508)
			(type default)
		)
		(layer "F.Cu")
	)
	(gr_line
		(start 78.025752 -387.531102)
		(end 78.62951 -387.531102)
		(stroke
			(width 0.0508)
			(type default)
		)
		(layer "F.Cu")
	)
	(gr_line
		(start 78.027022 -387.748272)
		(end 78.109826 -387.831076)
		(stroke
			(width 0.0508)
			(type default)
		)
		(layer "F.Cu")
	)
	(gr_line
		(start 78.108302 -369.03533)
		(end 77.837792 -369.30584)
		(stroke
			(width 0.06477)
			(type default)
		)
		(layer "F.Cu")
	)
	(gr_line
		(start 78.123542 -378.30379)
		(end 78.325726 -378.792232)
		(stroke
			(width 0.0508)
			(type default)
		)
		(layer "F.Cu")
	)
	(gr_line
		(start 78.133702 -370.83873)
		(end 77.784452 -371.18798)
		(stroke
			(width 0.0508)
			(type default)
		)
		(layer "F.Cu")
	)
	(gr_line
		(start 78.165198 -375.78919)
		(end 78.381098 -376.00509)
		(stroke
			(width 0.0508)
			(type default)
		)
		(layer "F.Cu")
	)
	(gr_line
		(start 78.381098 -376.00509)
		(end 78.381098 -376.161808)
		(stroke
			(width 0.0508)
			(type default)
		)
		(layer "F.Cu")
	)
	(gr_line
		(start 78.401164 -408.784044)
		(end 78.697074 -409.079954)
		(stroke
			(width 0.06477)
			(type default)
		)
		(layer "F.Cu")
	)
	(gr_line
		(start 78.407768 -379.62967)
		(end 78.577186 -379.883162)
		(stroke
			(width 0.0508)
			(type default)
		)
		(layer "F.Cu")
	)
	(gr_line
		(start 78.408022 -223.690434)
		(end 78.30693 -223.310958)
		(stroke
			(width 0.127)
			(type default)
		)
		(layer "F.Cu")
	)
	(gr_line
		(start 78.426564 -404.46452)
		(end 78.697074 -404.73503)
		(stroke
			(width 0.06477)
			(type default)
		)
		(layer "F.Cu")
	)
	(gr_line
		(start 78.438248 -379.476)
		(end 78.407768 -379.62967)
		(stroke
			(width 0.0508)
			(type default)
		)
		(layer "F.Cu")
	)
	(gr_line
		(start 78.497938 -222.981266)
		(end 78.498192 -222.981266)
		(stroke
			(width 0.127)
			(type default)
		)
		(layer "F.Cu")
	)
	(gr_line
		(start 78.567026 -372.921022)
		(end 78.940914 -373.294656)
		(stroke
			(width 0.0508)
			(type default)
		)
		(layer "F.Cu")
	)
	(gr_line
		(start 78.577186 -379.883162)
		(end 78.730856 -379.913896)
		(stroke
			(width 0.0508)
			(type default)
		)
		(layer "F.Cu")
	)
	(gr_line
		(start 78.61808 -379.354588)
		(end 78.618334 -379.354588)
		(stroke
			(width 0.0508)
			(type default)
		)
		(layer "F.Cu")
	)
	(gr_line
		(start 78.618334 -379.354588)
		(end 78.911958 -379.794008)
		(stroke
			(width 0.0508)
			(type default)
		)
		(layer "F.Cu")
	)
	(gr_line
		(start 78.697074 -412.299658)
		(end 78.426564 -412.570168)
		(stroke
			(width 0.06477)
			(type default)
		)
		(layer "F.Cu")
	)
	(gr_line
		(start 78.697074 -407.954734)
		(end 78.401164 -408.250644)
		(stroke
			(width 0.06477)
			(type default)
		)
		(layer "F.Cu")
	)
	(gr_line
		(start 78.721458 -372.768114)
		(end 78.877922 -372.768114)
		(stroke
			(width 0.0508)
			(type default)
		)
		(layer "F.Cu")
	)
	(gr_line
		(start 78.877922 -372.768114)
		(end 79.093822 -372.984014)
		(stroke
			(width 0.0508)
			(type default)
		)
		(layer "F.Cu")
	)
	(gr_line
		(start 78.877922 -222.880428)
		(end 78.498192 -222.981266)
		(stroke
			(width 0.127)
			(type default)
		)
		(layer "F.Cu")
	)
	(gr_line
		(start 78.911958 -379.794008)
		(end 78.911958 -379.794262)
		(stroke
			(width 0.0508)
			(type default)
		)
		(layer "F.Cu")
	)
	(gr_line
		(start 78.940914 -373.294656)
		(end 78.940914 -373.29491)
		(stroke
			(width 0.0508)
			(type default)
		)
		(layer "F.Cu")
	)
	(gr_line
		(start 79.019654 -412.299658)
		(end 79.290164 -412.570168)
		(stroke
			(width 0.06477)
			(type default)
		)
		(layer "F.Cu")
	)
	(gr_line
		(start 79.019654 -407.954734)
		(end 79.315564 -408.250644)
		(stroke
			(width 0.06477)
			(type default)
		)
		(layer "F.Cu")
	)
	(gr_line
		(start 79.093822 -372.984014)
		(end 79.093822 -373.140478)
		(stroke
			(width 0.0508)
			(type default)
		)
		(layer "F.Cu")
	)
	(gr_line
		(start 79.290164 -404.46452)
		(end 79.019654 -404.73503)
		(stroke
			(width 0.06477)
			(type default)
		)
		(layer "F.Cu")
	)
	(gr_line
		(start 79.315564 -408.784044)
		(end 79.019654 -409.079954)
		(stroke
			(width 0.06477)
			(type default)
		)
		(layer "F.Cu")
	)
	(gr_line
		(start 79.343758 -383.50571)
		(end 79.434944 -383.596896)
		(stroke
			(width 0.0508)
			(type default)
		)
		(layer "F.Cu")
	)
	(gr_line
		(start 79.343758 -383.2352)
		(end 79.343758 -383.50571)
		(stroke
			(width 0.0508)
			(type default)
		)
		(layer "F.Cu")
	)
	(gr_line
		(start 79.434944 -383.596896)
		(end 79.56931 -383.596896)
		(stroke
			(width 0.0508)
			(type default)
		)
		(layer "F.Cu")
	)
	(gr_line
		(start 79.56931 -383.596896)
		(end 79.645764 -383.520442)
		(stroke
			(width 0.0508)
			(type default)
		)
		(layer "F.Cu")
	)
	(gr_line
		(start 79.635096 -382.943862)
		(end 79.343758 -383.2352)
		(stroke
			(width 0.0508)
			(type default)
		)
		(layer "F.Cu")
	)
	(gr_line
		(start 79.645764 -383.520442)
		(end 79.645764 -383.402586)
		(stroke
			(width 0.0508)
			(type default)
		)
		(layer "F.Cu")
	)
	(gr_line
		(start 79.729076 -391.36447)
		(end 79.645764 -391.281158)
		(stroke
			(width 0.0508)
			(type default)
		)
		(layer "F.Cu")
	)
	(gr_line
		(start 79.798418 -388.774432)
		(end 80.319118 -388.774432)
		(stroke
			(width 0.0635)
			(type default)
		)
		(layer "F.Cu")
	)
	(gr_line
		(start 79.798418 -385.31038)
		(end 80.319118 -385.31038)
		(stroke
			(width 0.0635)
			(type default)
		)
		(layer "F.Cu")
	)
	(gr_line
		(start 79.852266 -383.13741)
		(end 79.945738 -383.230882)
		(stroke
			(width 0.0508)
			(type default)
		)
		(layer "F.Cu")
	)
	(gr_line
		(start 79.852266 -382.942592)
		(end 79.852266 -383.13741)
		(stroke
			(width 0.0508)
			(type default)
		)
		(layer "F.Cu")
	)
	(gr_line
		(start 79.945738 -383.230882)
		(end 79.945738 -383.92227)
		(stroke
			(width 0.0508)
			(type default)
		)
		(layer "F.Cu")
	)
	(gr_line
		(start 79.946246 -391.36574)
		(end 79.946246 -390.761982)
		(stroke
			(width 0.0508)
			(type default)
		)
		(layer "F.Cu")
	)
	(gr_line
		(start 79.946246 -390.761982)
		(end 79.945738 -390.761474)
		(stroke
			(width 0.0508)
			(type default)
		)
		(layer "F.Cu")
	)
	(gr_line
		(start 80.198468 -389.467344)
		(end 80.719168 -389.467344)
		(stroke
			(width 0.0635)
			(type default)
		)
		(layer "F.Cu")
	)
	(gr_line
		(start 80.198468 -386.003292)
		(end 80.719168 -386.003292)
		(stroke
			(width 0.0635)
			(type default)
		)
		(layer "F.Cu")
	)
	(gr_line
		(start 80.20558 -392.977116)
		(end 80.203548 -392.977116)
		(stroke
			(width 0.0508)
			(type default)
		)
		(layer "F.Cu")
	)
	(gr_line
		(start 80.344264 -393.292838)
		(end 80.344264 -393.1158)
		(stroke
			(width 0.0508)
			(type default)
		)
		(layer "F.Cu")
	)
	(gr_line
		(start 80.344264 -393.1158)
		(end 80.20558 -392.977116)
		(stroke
			(width 0.0508)
			(type default)
		)
		(layer "F.Cu")
	)
	(gr_line
		(start 80.344264 -392.6205)
		(end 80.204818 -392.759946)
		(stroke
			(width 0.0508)
			(type default)
		)
		(layer "F.Cu")
	)
	(gr_line
		(start 80.344264 -392.429238)
		(end 80.344264 -392.6205)
		(stroke
			(width 0.0508)
			(type default)
		)
		(layer "F.Cu")
	)
	(gr_line
		(start 80.543654 -383.50571)
		(end 80.63484 -383.596896)
		(stroke
			(width 0.0508)
			(type default)
		)
		(layer "F.Cu")
	)
	(gr_line
		(start 80.543654 -383.2352)
		(end 80.543654 -383.50571)
		(stroke
			(width 0.0508)
			(type default)
		)
		(layer "F.Cu")
	)
	(gr_line
		(start 80.622902 -375.76633)
		(end 80.972152 -376.11558)
		(stroke
			(width 0.0508)
			(type default)
		)
		(layer "F.Cu")
	)
	(gr_line
		(start 80.63484 -383.596896)
		(end 80.769206 -383.596896)
		(stroke
			(width 0.0508)
			(type default)
		)
		(layer "F.Cu")
	)
	(gr_line
		(start 80.648302 -373.96293)
		(end 80.918812 -374.23344)
		(stroke
			(width 0.06477)
			(type default)
		)
		(layer "F.Cu")
	)
	(gr_line
		(start 80.769206 -383.596896)
		(end 80.84566 -383.520442)
		(stroke
			(width 0.0508)
			(type default)
		)
		(layer "F.Cu")
	)
	(gr_line
		(start 80.834992 -382.943862)
		(end 80.543654 -383.2352)
		(stroke
			(width 0.0508)
			(type default)
		)
		(layer "F.Cu")
	)
	(gr_line
		(start 80.84566 -383.520442)
		(end 80.84566 -383.402586)
		(stroke
			(width 0.0508)
			(type default)
		)
		(layer "F.Cu")
	)
	(gr_line
		(start 80.918812 -374.93702)
		(end 80.622902 -375.23293)
		(stroke
			(width 0.06477)
			(type default)
		)
		(layer "F.Cu")
	)
	(gr_line
		(start 80.928972 -391.36447)
		(end 80.84566 -391.281158)
		(stroke
			(width 0.0508)
			(type default)
		)
		(layer "F.Cu")
	)
	(gr_line
		(start 80.998314 -388.774432)
		(end 81.519014 -388.774432)
		(stroke
			(width 0.0635)
			(type default)
		)
		(layer "F.Cu")
	)
	(gr_line
		(start 80.998314 -385.31038)
		(end 81.519014 -385.31038)
		(stroke
			(width 0.0635)
			(type default)
		)
		(layer "F.Cu")
	)
	(gr_line
		(start 81.052162 -383.13741)
		(end 81.145634 -383.230882)
		(stroke
			(width 0.0508)
			(type default)
		)
		(layer "F.Cu")
	)
	(gr_line
		(start 81.052162 -382.942592)
		(end 81.052162 -383.13741)
		(stroke
			(width 0.0508)
			(type default)
		)
		(layer "F.Cu")
	)
	(gr_line
		(start 81.145634 -383.230882)
		(end 81.145634 -383.92227)
		(stroke
			(width 0.0508)
			(type default)
		)
		(layer "F.Cu")
	)
	(gr_line
		(start 81.146142 -391.36574)
		(end 81.146142 -390.761982)
		(stroke
			(width 0.0508)
			(type default)
		)
		(layer "F.Cu")
	)
	(gr_line
		(start 81.146142 -390.761982)
		(end 81.145634 -390.761474)
		(stroke
			(width 0.0508)
			(type default)
		)
		(layer "F.Cu")
	)
	(gr_line
		(start 81.241392 -374.93702)
		(end 81.537302 -375.23293)
		(stroke
			(width 0.06477)
			(type default)
		)
		(layer "F.Cu")
	)
	(gr_line
		(start 81.398364 -389.467344)
		(end 81.919064 -389.467344)
		(stroke
			(width 0.0635)
			(type default)
		)
		(layer "F.Cu")
	)
	(gr_line
		(start 81.398364 -386.003292)
		(end 81.919064 -386.003292)
		(stroke
			(width 0.0635)
			(type default)
		)
		(layer "F.Cu")
	)
	(gr_line
		(start 81.405476 -392.977116)
		(end 81.403444 -392.977116)
		(stroke
			(width 0.0508)
			(type default)
		)
		(layer "F.Cu")
	)
	(gr_line
		(start 81.464404 -408.784044)
		(end 81.760314 -409.079954)
		(stroke
			(width 0.06477)
			(type default)
		)
		(layer "F.Cu")
	)
	(gr_line
		(start 81.489804 -404.46452)
		(end 81.760314 -404.73503)
		(stroke
			(width 0.06477)
			(type default)
		)
		(layer "F.Cu")
	)
	(gr_line
		(start 81.511902 -373.96293)
		(end 81.241392 -374.23344)
		(stroke
			(width 0.06477)
			(type default)
		)
		(layer "F.Cu")
	)
	(gr_line
		(start 81.537302 -375.76633)
		(end 81.188052 -376.11558)
		(stroke
			(width 0.0508)
			(type default)
		)
		(layer "F.Cu")
	)
	(gr_line
		(start 81.54416 -393.292838)
		(end 81.54416 -393.1158)
		(stroke
			(width 0.0508)
			(type default)
		)
		(layer "F.Cu")
	)
	(gr_line
		(start 81.54416 -393.1158)
		(end 81.405476 -392.977116)
		(stroke
			(width 0.0508)
			(type default)
		)
		(layer "F.Cu")
	)
	(gr_line
		(start 81.54416 -392.6205)
		(end 81.404714 -392.759946)
		(stroke
			(width 0.0508)
			(type default)
		)
		(layer "F.Cu")
	)
	(gr_line
		(start 81.54416 -392.429238)
		(end 81.54416 -392.6205)
		(stroke
			(width 0.0508)
			(type default)
		)
		(layer "F.Cu")
	)
	(gr_line
		(start 81.743804 -383.50571)
		(end 81.83499 -383.596896)
		(stroke
			(width 0.0508)
			(type default)
		)
		(layer "F.Cu")
	)
	(gr_line
		(start 81.743804 -383.2352)
		(end 81.743804 -383.50571)
		(stroke
			(width 0.0508)
			(type default)
		)
		(layer "F.Cu")
	)
	(gr_line
		(start 81.760314 -412.299658)
		(end 81.489804 -412.570168)
		(stroke
			(width 0.06477)
			(type default)
		)
		(layer "F.Cu")
	)
	(gr_line
		(start 81.760314 -407.954734)
		(end 81.464404 -408.250644)
		(stroke
			(width 0.06477)
			(type default)
		)
		(layer "F.Cu")
	)
	(gr_line
		(start 81.778856 -377.606814)
		(end 82.11439 -378.015754)
		(stroke
			(width 0.0508)
			(type default)
		)
		(layer "F.Cu")
	)
	(gr_line
		(start 81.83499 -383.596896)
		(end 81.969356 -383.596896)
		(stroke
			(width 0.0508)
			(type default)
		)
		(layer "F.Cu")
	)
	(gr_line
		(start 81.947512 -377.470162)
		(end 82.10296 -377.485402)
		(stroke
			(width 0.0508)
			(type default)
		)
		(layer "F.Cu")
	)
	(gr_line
		(start 81.969356 -383.596896)
		(end 82.04581 -383.520442)
		(stroke
			(width 0.0508)
			(type default)
		)
		(layer "F.Cu")
	)
	(gr_line
		(start 82.035142 -382.943862)
		(end 81.743804 -383.2352)
		(stroke
			(width 0.0508)
			(type default)
		)
		(layer "F.Cu")
	)
	(gr_line
		(start 82.04581 -383.520442)
		(end 82.04581 -383.402586)
		(stroke
			(width 0.0508)
			(type default)
		)
		(layer "F.Cu")
	)
	(gr_line
		(start 82.082894 -412.299658)
		(end 82.353404 -412.570168)
		(stroke
			(width 0.06477)
			(type default)
		)
		(layer "F.Cu")
	)
	(gr_line
		(start 82.082894 -407.954734)
		(end 82.378804 -408.250644)
		(stroke
			(width 0.06477)
			(type default)
		)
		(layer "F.Cu")
	)
	(gr_line
		(start 82.10296 -377.485402)
		(end 82.296508 -377.721114)
		(stroke
			(width 0.0508)
			(type default)
		)
		(layer "F.Cu")
	)
	(gr_line
		(start 82.129122 -391.36447)
		(end 82.04581 -391.281158)
		(stroke
			(width 0.0508)
			(type default)
		)
		(layer "F.Cu")
	)
	(gr_line
		(start 82.198464 -388.774432)
		(end 82.719164 -388.774432)
		(stroke
			(width 0.0635)
			(type default)
		)
		(layer "F.Cu")
	)
	(gr_line
		(start 82.198464 -385.31038)
		(end 82.719164 -385.31038)
		(stroke
			(width 0.0635)
			(type default)
		)
		(layer "F.Cu")
	)
	(gr_line
		(start 82.252312 -383.13741)
		(end 82.345784 -383.230882)
		(stroke
			(width 0.0508)
			(type default)
		)
		(layer "F.Cu")
	)
	(gr_line
		(start 82.252312 -382.942592)
		(end 82.252312 -383.13741)
		(stroke
			(width 0.0508)
			(type default)
		)
		(layer "F.Cu")
	)
	(gr_line
		(start 82.296508 -377.721114)
		(end 82.281522 -377.87707)
		(stroke
			(width 0.0508)
			(type default)
		)
		(layer "F.Cu")
	)
	(gr_line
		(start 82.324702 -373.30253)
		(end 82.673952 -373.65178)
		(stroke
			(width 0.0508)
			(type default)
		)
		(layer "F.Cu")
	)
	(gr_line
		(start 82.345784 -383.230882)
		(end 82.345784 -383.92227)
		(stroke
			(width 0.0508)
			(type default)
		)
		(layer "F.Cu")
	)
	(gr_line
		(start 82.346292 -391.36574)
		(end 82.346292 -390.761982)
		(stroke
			(width 0.0508)
			(type default)
		)
		(layer "F.Cu")
	)
	(gr_line
		(start 82.346292 -390.761982)
		(end 82.345784 -390.761474)
		(stroke
			(width 0.0508)
			(type default)
		)
		(layer "F.Cu")
	)
	(gr_line
		(start 82.350102 -371.49913)
		(end 82.620612 -371.76964)
		(stroke
			(width 0.06477)
			(type default)
		)
		(layer "F.Cu")
	)
	(gr_line
		(start 82.353404 -404.46452)
		(end 82.082894 -404.73503)
		(stroke
			(width 0.06477)
			(type default)
		)
		(layer "F.Cu")
	)
	(gr_line
		(start 82.378804 -408.784044)
		(end 82.082894 -409.079954)
		(stroke
			(width 0.06477)
			(type default)
		)
		(layer "F.Cu")
	)
	(gr_line
		(start 82.59826 -389.467344)
		(end 83.11896 -389.467344)
		(stroke
			(width 0.0635)
			(type default)
		)
		(layer "F.Cu")
	)
	(gr_line
		(start 82.59826 -386.003292)
		(end 83.11896 -386.003292)
		(stroke
			(width 0.0635)
			(type default)
		)
		(layer "F.Cu")
	)
	(gr_line
		(start 82.605626 -392.977116)
		(end 82.603594 -392.977116)
		(stroke
			(width 0.0508)
			(type default)
		)
		(layer "F.Cu")
	)
	(gr_line
		(start 82.620612 -372.47322)
		(end 82.324702 -372.76913)
		(stroke
			(width 0.06477)
			(type default)
		)
		(layer "F.Cu")
	)
	(gr_line
		(start 82.673952 -374.529096)
		(end 82.673952 -375.057416)
		(stroke
			(width 0.0508)
			(type default)
		)
		(layer "F.Cu")
	)
	(gr_line
		(start 82.74431 -393.292838)
		(end 82.74431 -393.1158)
		(stroke
			(width 0.0508)
			(type default)
		)
		(layer "F.Cu")
	)
	(gr_line
		(start 82.74431 -393.1158)
		(end 82.605626 -392.977116)
		(stroke
			(width 0.0508)
			(type default)
		)
		(layer "F.Cu")
	)
	(gr_line
		(start 82.74431 -392.6205)
		(end 82.604864 -392.759946)
		(stroke
			(width 0.0508)
			(type default)
		)
		(layer "F.Cu")
	)
	(gr_line
		(start 82.74431 -392.429238)
		(end 82.74431 -392.6205)
		(stroke
			(width 0.0508)
			(type default)
		)
		(layer "F.Cu")
	)
	(gr_line
		(start 82.891122 -374.530366)
		(end 83.001612 -374.640856)
		(stroke
			(width 0.0508)
			(type default)
		)
		(layer "F.Cu")
	)
	(gr_line
		(start 82.943192 -372.47322)
		(end 83.239102 -372.76913)
		(stroke
			(width 0.06477)
			(type default)
		)
		(layer "F.Cu")
	)
	(gr_line
		(start 82.9437 -383.50571)
		(end 83.034886 -383.596896)
		(stroke
			(width 0.0508)
			(type default)
		)
		(layer "F.Cu")
	)
	(gr_line
		(start 82.9437 -383.2352)
		(end 82.9437 -383.50571)
		(stroke
			(width 0.0508)
			(type default)
		)
		(layer "F.Cu")
	)
	(gr_line
		(start 83.001612 -374.945656)
		(end 82.891122 -375.056146)
		(stroke
			(width 0.0508)
			(type default)
		)
		(layer "F.Cu")
	)
	(gr_line
		(start 83.001612 -374.640856)
		(end 83.001612 -374.945656)
		(stroke
			(width 0.0508)
			(type default)
		)
		(layer "F.Cu")
	)
	(gr_line
		(start 83.034886 -383.596896)
		(end 83.169252 -383.596896)
		(stroke
			(width 0.0508)
			(type default)
		)
		(layer "F.Cu")
	)
	(gr_line
		(start 83.169252 -383.596896)
		(end 83.245706 -383.520442)
		(stroke
			(width 0.0508)
			(type default)
		)
		(layer "F.Cu")
	)
	(gr_line
		(start 83.213702 -371.49913)
		(end 82.943192 -371.76964)
		(stroke
			(width 0.06477)
			(type default)
		)
		(layer "F.Cu")
	)
	(gr_line
		(start 83.235038 -382.943862)
		(end 82.9437 -383.2352)
		(stroke
			(width 0.0508)
			(type default)
		)
		(layer "F.Cu")
	)
	(gr_line
		(start 83.239102 -373.30253)
		(end 82.889852 -373.65178)
		(stroke
			(width 0.0508)
			(type default)
		)
		(layer "F.Cu")
	)
	(gr_line
		(start 83.245706 -383.520442)
		(end 83.245706 -383.402586)
		(stroke
			(width 0.0508)
			(type default)
		)
		(layer "F.Cu")
	)
	(gr_line
		(start 83.329018 -391.36447)
		(end 83.245706 -391.281158)
		(stroke
			(width 0.0508)
			(type default)
		)
		(layer "F.Cu")
	)
	(gr_line
		(start 83.39836 -388.774432)
		(end 83.91906 -388.774432)
		(stroke
			(width 0.0635)
			(type default)
		)
		(layer "F.Cu")
	)
	(gr_line
		(start 83.39836 -385.31038)
		(end 83.91906 -385.31038)
		(stroke
			(width 0.0635)
			(type default)
		)
		(layer "F.Cu")
	)
	(gr_line
		(start 83.452208 -383.13741)
		(end 83.54568 -383.230882)
		(stroke
			(width 0.0508)
			(type default)
		)
		(layer "F.Cu")
	)
	(gr_line
		(start 83.452208 -382.942592)
		(end 83.452208 -383.13741)
		(stroke
			(width 0.0508)
			(type default)
		)
		(layer "F.Cu")
	)
	(gr_line
		(start 83.54568 -383.230882)
		(end 83.54568 -383.92227)
		(stroke
			(width 0.0508)
			(type default)
		)
		(layer "F.Cu")
	)
	(gr_line
		(start 83.546188 -391.36574)
		(end 83.546188 -390.761982)
		(stroke
			(width 0.0508)
			(type default)
		)
		(layer "F.Cu")
	)
	(gr_line
		(start 83.546188 -390.761982)
		(end 83.54568 -390.761474)
		(stroke
			(width 0.0508)
			(type default)
		)
		(layer "F.Cu")
	)
	(gr_line
		(start 83.79841 -389.467344)
		(end 84.31911 -389.467344)
		(stroke
			(width 0.0635)
			(type default)
		)
		(layer "F.Cu")
	)
	(gr_line
		(start 83.79841 -386.003292)
		(end 84.31911 -386.003292)
		(stroke
			(width 0.0635)
			(type default)
		)
		(layer "F.Cu")
	)
	(gr_line
		(start 83.805522 -392.977116)
		(end 83.80349 -392.977116)
		(stroke
			(width 0.0508)
			(type default)
		)
		(layer "F.Cu")
	)
	(gr_line
		(start 83.944206 -393.292838)
		(end 83.944206 -393.1158)
		(stroke
			(width 0.0508)
			(type default)
		)
		(layer "F.Cu")
	)
	(gr_line
		(start 83.944206 -393.1158)
		(end 83.805522 -392.977116)
		(stroke
			(width 0.0508)
			(type default)
		)
		(layer "F.Cu")
	)
	(gr_line
		(start 83.944206 -392.6205)
		(end 83.80476 -392.759946)
		(stroke
			(width 0.0508)
			(type default)
		)
		(layer "F.Cu")
	)
	(gr_line
		(start 83.944206 -392.429238)
		(end 83.944206 -392.6205)
		(stroke
			(width 0.0508)
			(type default)
		)
		(layer "F.Cu")
	)
	(gr_line
		(start 84.026502 -370.83873)
		(end 84.375752 -371.18798)
		(stroke
			(width 0.0508)
			(type default)
		)
		(layer "F.Cu")
	)
	(gr_line
		(start 84.051902 -369.03533)
		(end 84.322412 -369.30584)
		(stroke
			(width 0.06477)
			(type default)
		)
		(layer "F.Cu")
	)
	(gr_line
		(start 84.14385 -383.50571)
		(end 84.235036 -383.596896)
		(stroke
			(width 0.0508)
			(type default)
		)
		(layer "F.Cu")
	)
	(gr_line
		(start 84.14385 -383.2352)
		(end 84.14385 -383.50571)
		(stroke
			(width 0.0508)
			(type default)
		)
		(layer "F.Cu")
	)
	(gr_line
		(start 84.235036 -383.596896)
		(end 84.369402 -383.596896)
		(stroke
			(width 0.0508)
			(type default)
		)
		(layer "F.Cu")
	)
	(gr_line
		(start 84.322412 -370.00942)
		(end 84.026502 -370.30533)
		(stroke
			(width 0.06477)
			(type default)
		)
		(layer "F.Cu")
	)
	(gr_line
		(start 84.369402 -383.596896)
		(end 84.445856 -383.520442)
		(stroke
			(width 0.0508)
			(type default)
		)
		(layer "F.Cu")
	)
	(gr_line
		(start 84.435188 -382.943862)
		(end 84.14385 -383.2352)
		(stroke
			(width 0.0508)
			(type default)
		)
		(layer "F.Cu")
	)
	(gr_line
		(start 84.445856 -383.520442)
		(end 84.445856 -383.402586)
		(stroke
			(width 0.0508)
			(type default)
		)
		(layer "F.Cu")
	)
	(gr_line
		(start 84.527644 -408.784044)
		(end 84.823554 -409.079954)
		(stroke
			(width 0.06477)
			(type default)
		)
		(layer "F.Cu")
	)
	(gr_line
		(start 84.529168 -391.36447)
		(end 84.445856 -391.281158)
		(stroke
			(width 0.0508)
			(type default)
		)
		(layer "F.Cu")
	)
	(gr_line
		(start 84.553044 -404.46452)
		(end 84.823554 -404.73503)
		(stroke
			(width 0.06477)
			(type default)
		)
		(layer "F.Cu")
	)
	(gr_line
		(start 84.598256 -388.774432)
		(end 85.118956 -388.774432)
		(stroke
			(width 0.0635)
			(type default)
		)
		(layer "F.Cu")
	)
	(gr_line
		(start 84.598256 -385.31038)
		(end 85.118956 -385.31038)
		(stroke
			(width 0.0635)
			(type default)
		)
		(layer "F.Cu")
	)
	(gr_line
		(start 84.644992 -370.00942)
		(end 84.940902 -370.30533)
		(stroke
			(width 0.06477)
			(type default)
		)
		(layer "F.Cu")
	)
	(gr_line
		(start 84.652358 -383.13741)
		(end 84.74583 -383.230882)
		(stroke
			(width 0.0508)
			(type default)
		)
		(layer "F.Cu")
	)
	(gr_line
		(start 84.652358 -382.942592)
		(end 84.652358 -383.13741)
		(stroke
			(width 0.0508)
			(type default)
		)
		(layer "F.Cu")
	)
	(gr_arc
		(start 84.652358 -381.5715)
		(mid 84.652358 -381.571881)
		(end 84.652358 -381.572262)
		(stroke
			(width 0.0508)
			(type default)
		)
		(layer "F.Cu")
	)
	(gr_line
		(start 84.74583 -383.230882)
		(end 84.74583 -383.92227)
		(stroke
			(width 0.0508)
			(type default)
		)
		(layer "F.Cu")
	)
	(gr_line
		(start 84.746338 -391.36574)
		(end 84.746338 -390.761982)
		(stroke
			(width 0.0508)
			(type default)
		)
		(layer "F.Cu")
	)
	(gr_line
		(start 84.746338 -390.761982)
		(end 84.74583 -390.761474)
		(stroke
			(width 0.0508)
			(type default)
		)
		(layer "F.Cu")
	)
	(gr_line
		(start 84.823554 -412.299658)
		(end 84.553044 -412.570168)
		(stroke
			(width 0.06477)
			(type default)
		)
		(layer "F.Cu")
	)
	(gr_line
		(start 84.823554 -407.954734)
		(end 84.527644 -408.250644)
		(stroke
			(width 0.06477)
			(type default)
		)
		(layer "F.Cu")
	)
	(gr_line
		(start 84.915502 -369.03533)
		(end 84.644992 -369.30584)
		(stroke
			(width 0.06477)
			(type default)
		)
		(layer "F.Cu")
	)
	(gr_line
		(start 84.940902 -370.83873)
		(end 84.591652 -371.18798)
		(stroke
			(width 0.0508)
			(type default)
		)
		(layer "F.Cu")
	)
	(gr_line
		(start 84.998306 -389.467344)
		(end 85.519006 -389.467344)
		(stroke
			(width 0.0635)
			(type default)
		)
		(layer "F.Cu")
	)
	(gr_line
		(start 84.998306 -386.003292)
		(end 85.519006 -386.003292)
		(stroke
			(width 0.0635)
			(type default)
		)
		(layer "F.Cu")
	)
	(gr_line
		(start 85.005672 -392.977116)
		(end 85.00364 -392.977116)
		(stroke
			(width 0.0508)
			(type default)
		)
		(layer "F.Cu")
	)
	(gr_line
		(start 85.144356 -393.292838)
		(end 85.144356 -393.1158)
		(stroke
			(width 0.0508)
			(type default)
		)
		(layer "F.Cu")
	)
	(gr_line
		(start 85.144356 -393.1158)
		(end 85.005672 -392.977116)
		(stroke
			(width 0.0508)
			(type default)
		)
		(layer "F.Cu")
	)
	(gr_line
		(start 85.144356 -392.6205)
		(end 85.00491 -392.759946)
		(stroke
			(width 0.0508)
			(type default)
		)
		(layer "F.Cu")
	)
	(gr_line
		(start 85.144356 -392.429238)
		(end 85.144356 -392.6205)
		(stroke
			(width 0.0508)
			(type default)
		)
		(layer "F.Cu")
	)
	(gr_line
		(start 85.146134 -412.299658)
		(end 85.416644 -412.570168)
		(stroke
			(width 0.06477)
			(type default)
		)
		(layer "F.Cu")
	)
	(gr_line
		(start 85.146134 -407.954734)
		(end 85.442044 -408.250644)
		(stroke
			(width 0.06477)
			(type default)
		)
		(layer "F.Cu")
	)
	(gr_line
		(start 85.343746 -383.50571)
		(end 85.434932 -383.596896)
		(stroke
			(width 0.0508)
			(type default)
		)
		(layer "F.Cu")
	)
	(gr_line
		(start 85.343746 -383.2352)
		(end 85.343746 -383.50571)
		(stroke
			(width 0.0508)
			(type default)
		)
		(layer "F.Cu")
	)
	(gr_line
		(start 85.416644 -404.46452)
		(end 85.146134 -404.73503)
		(stroke
			(width 0.06477)
			(type default)
		)
		(layer "F.Cu")
	)
	(gr_line
		(start 85.434932 -383.596896)
		(end 85.569298 -383.596896)
		(stroke
			(width 0.0508)
			(type default)
		)
		(layer "F.Cu")
	)
	(gr_line
		(start 85.442044 -408.784044)
		(end 85.146134 -409.079954)
		(stroke
			(width 0.06477)
			(type default)
		)
		(layer "F.Cu")
	)
	(gr_line
		(start 85.569298 -383.596896)
		(end 85.645752 -383.520442)
		(stroke
			(width 0.0508)
			(type default)
		)
		(layer "F.Cu")
	)
	(gr_line
		(start 85.635084 -382.943862)
		(end 85.343746 -383.2352)
		(stroke
			(width 0.0508)
			(type default)
		)
		(layer "F.Cu")
	)
	(gr_line
		(start 85.645752 -383.520442)
		(end 85.645752 -383.402586)
		(stroke
			(width 0.0508)
			(type default)
		)
		(layer "F.Cu")
	)
	(gr_line
		(start 85.729064 -391.36447)
		(end 85.645752 -391.281158)
		(stroke
			(width 0.0508)
			(type default)
		)
		(layer "F.Cu")
	)
	(gr_line
		(start 85.798406 -388.774432)
		(end 86.319106 -388.774432)
		(stroke
			(width 0.0635)
			(type default)
		)
		(layer "F.Cu")
	)
	(gr_line
		(start 85.798406 -385.31038)
		(end 86.319106 -385.31038)
		(stroke
			(width 0.0635)
			(type default)
		)
		(layer "F.Cu")
	)
	(gr_line
		(start 85.852254 -383.13741)
		(end 85.945726 -383.230882)
		(stroke
			(width 0.0508)
			(type default)
		)
		(layer "F.Cu")
	)
	(gr_line
		(start 85.852254 -382.942592)
		(end 85.852254 -383.13741)
		(stroke
			(width 0.0508)
			(type default)
		)
		(layer "F.Cu")
	)
	(gr_line
		(start 85.945726 -383.230882)
		(end 85.945726 -383.92227)
		(stroke
			(width 0.0508)
			(type default)
		)
		(layer "F.Cu")
	)
	(gr_line
		(start 85.946234 -391.36574)
		(end 85.946234 -390.761982)
		(stroke
			(width 0.0508)
			(type default)
		)
		(layer "F.Cu")
	)
	(gr_line
		(start 85.946234 -390.761982)
		(end 85.945726 -390.761474)
		(stroke
			(width 0.0508)
			(type default)
		)
		(layer "F.Cu")
	)
	(gr_line
		(start 86.095078 -374.849136)
		(end 86.095078 -375.377456)
		(stroke
			(width 0.0508)
			(type default)
		)
		(layer "F.Cu")
	)
	(gr_line
		(start 86.198456 -389.467344)
		(end 86.719156 -389.467344)
		(stroke
			(width 0.0635)
			(type default)
		)
		(layer "F.Cu")
	)
	(gr_line
		(start 86.198456 -386.003292)
		(end 86.719156 -386.003292)
		(stroke
			(width 0.0635)
			(type default)
		)
		(layer "F.Cu")
	)
	(gr_line
		(start 86.205568 -392.977116)
		(end 86.203536 -392.977116)
		(stroke
			(width 0.0508)
			(type default)
		)
		(layer "F.Cu")
	)
	(gr_line
		(start 86.312248 -374.850406)
		(end 86.422738 -374.960896)
		(stroke
			(width 0.0508)
			(type default)
		)
		(layer "F.Cu")
	)
	(gr_line
		(start 86.344252 -393.292838)
		(end 86.344252 -393.1158)
		(stroke
			(width 0.0508)
			(type default)
		)
		(layer "F.Cu")
	)
	(gr_line
		(start 86.344252 -393.1158)
		(end 86.205568 -392.977116)
		(stroke
			(width 0.0508)
			(type default)
		)
		(layer "F.Cu")
	)
	(gr_line
		(start 86.344252 -392.6205)
		(end 86.204806 -392.759946)
		(stroke
			(width 0.0508)
			(type default)
		)
		(layer "F.Cu")
	)
	(gr_line
		(start 86.344252 -392.429238)
		(end 86.344252 -392.6205)
		(stroke
			(width 0.0508)
			(type default)
		)
		(layer "F.Cu")
	)
	(gr_line
		(start 86.422738 -375.265696)
		(end 86.312248 -375.376186)
		(stroke
			(width 0.0508)
			(type default)
		)
		(layer "F.Cu")
	)
	(gr_line
		(start 86.422738 -374.960896)
		(end 86.422738 -375.265696)
		(stroke
			(width 0.0508)
			(type default)
		)
		(layer "F.Cu")
	)
	(gr_line
		(start 86.543642 -383.50571)
		(end 86.634828 -383.596896)
		(stroke
			(width 0.0508)
			(type default)
		)
		(layer "F.Cu")
	)
	(gr_line
		(start 86.543642 -383.2352)
		(end 86.543642 -383.50571)
		(stroke
			(width 0.0508)
			(type default)
		)
		(layer "F.Cu")
	)
	(gr_line
		(start 86.634828 -383.596896)
		(end 86.769194 -383.596896)
		(stroke
			(width 0.0508)
			(type default)
		)
		(layer "F.Cu")
	)
	(gr_line
		(start 86.769194 -383.596896)
		(end 86.845648 -383.520442)
		(stroke
			(width 0.0508)
			(type default)
		)
		(layer "F.Cu")
	)
	(gr_line
		(start 86.83498 -382.943862)
		(end 86.543642 -383.2352)
		(stroke
			(width 0.0508)
			(type default)
		)
		(layer "F.Cu")
	)
	(gr_line
		(start 86.845648 -383.520442)
		(end 86.845648 -383.402586)
		(stroke
			(width 0.0508)
			(type default)
		)
		(layer "F.Cu")
	)
	(gr_line
		(start 86.929214 -391.364724)
		(end 86.845648 -391.281158)
		(stroke
			(width 0.0508)
			(type default)
		)
		(layer "F.Cu")
	)
	(gr_line
		(start 86.998302 -388.774432)
		(end 87.519002 -388.774432)
		(stroke
			(width 0.0635)
			(type default)
		)
		(layer "F.Cu")
	)
	(gr_line
		(start 86.998302 -385.31038)
		(end 87.519002 -385.31038)
		(stroke
			(width 0.0635)
			(type default)
		)
		(layer "F.Cu")
	)
	(gr_line
		(start 87.05215 -383.13741)
		(end 87.145876 -383.231136)
		(stroke
			(width 0.0508)
			(type default)
		)
		(layer "F.Cu")
	)
	(gr_line
		(start 87.05215 -382.942592)
		(end 87.05215 -383.13741)
		(stroke
			(width 0.0508)
			(type default)
		)
		(layer "F.Cu")
	)
	(gr_line
		(start 87.145876 -383.231136)
		(end 87.145876 -383.92227)
		(stroke
			(width 0.0508)
			(type default)
		)
		(layer "F.Cu")
	)
	(gr_line
		(start 87.146384 -391.365486)
		(end 87.14613 -391.36574)
		(stroke
			(width 0.0508)
			(type default)
		)
		(layer "F.Cu")
	)
	(gr_line
		(start 87.146384 -391.365486)
		(end 87.146384 -390.761982)
		(stroke
			(width 0.0508)
			(type default)
		)
		(layer "F.Cu")
	)
	(gr_line
		(start 87.146384 -390.761982)
		(end 87.145876 -390.761474)
		(stroke
			(width 0.0508)
			(type default)
		)
		(layer "F.Cu")
	)
	(gr_line
		(start 87.398352 -389.467344)
		(end 87.919052 -389.467344)
		(stroke
			(width 0.0635)
			(type default)
		)
		(layer "F.Cu")
	)
	(gr_line
		(start 87.398352 -386.003292)
		(end 87.919052 -386.003292)
		(stroke
			(width 0.0635)
			(type default)
		)
		(layer "F.Cu")
	)
	(gr_line
		(start 87.405464 -392.977116)
		(end 87.403686 -392.977116)
		(stroke
			(width 0.0508)
			(type default)
		)
		(layer "F.Cu")
	)
	(gr_line
		(start 87.430102 -375.76633)
		(end 87.731854 -376.068082)
		(stroke
			(width 0.0508)
			(type default)
		)
		(layer "F.Cu")
	)
	(gr_line
		(start 87.455502 -373.96293)
		(end 87.726012 -374.23344)
		(stroke
			(width 0.06477)
			(type default)
		)
		(layer "F.Cu")
	)
	(gr_line
		(start 87.544402 -393.292838)
		(end 87.544402 -393.116054)
		(stroke
			(width 0.0508)
			(type default)
		)
		(layer "F.Cu")
	)
	(gr_line
		(start 87.544402 -393.116054)
		(end 87.405464 -392.977116)
		(stroke
			(width 0.0508)
			(type default)
		)
		(layer "F.Cu")
	)
	(gr_line
		(start 87.544402 -392.6205)
		(end 87.404956 -392.759946)
		(stroke
			(width 0.0508)
			(type default)
		)
		(layer "F.Cu")
	)
	(gr_line
		(start 87.544402 -392.429238)
		(end 87.544402 -392.6205)
		(stroke
			(width 0.0508)
			(type default)
		)
		(layer "F.Cu")
	)
	(gr_line
		(start 87.590884 -408.784044)
		(end 87.886794 -409.079954)
		(stroke
			(width 0.06477)
			(type default)
		)
		(layer "F.Cu")
	)
	(gr_line
		(start 87.616284 -404.46452)
		(end 87.886794 -404.73503)
		(stroke
			(width 0.06477)
			(type default)
		)
		(layer "F.Cu")
	)
	(gr_line
		(start 87.726012 -374.93702)
		(end 87.430102 -375.23293)
		(stroke
			(width 0.06477)
			(type default)
		)
		(layer "F.Cu")
	)
	(gr_line
		(start 87.743792 -383.50571)
		(end 87.834978 -383.596896)
		(stroke
			(width 0.0508)
			(type default)
		)
		(layer "F.Cu")
	)
	(gr_line
		(start 87.743792 -383.2352)
		(end 87.743792 -383.50571)
		(stroke
			(width 0.0508)
			(type default)
		)
		(layer "F.Cu")
	)
	(gr_arc
		(start 87.778336 -376.165872)
		(mid 87.763462 -376.113)
		(end 87.731854 -376.068082)
		(stroke
			(width 0.0508)
			(type default)
		)
		(layer "F.Cu")
	)
	(gr_line
		(start 87.779352 -377.07443)
		(end 87.779352 -377.60275)
		(stroke
			(width 0.0508)
			(type default)
		)
		(layer "F.Cu")
	)
	(gr_line
		(start 87.834978 -383.596896)
		(end 87.969344 -383.596896)
		(stroke
			(width 0.0508)
			(type default)
		)
		(layer "F.Cu")
	)
	(gr_line
		(start 87.886794 -412.299658)
		(end 87.616284 -412.570168)
		(stroke
			(width 0.06477)
			(type default)
		)
		(layer "F.Cu")
	)
	(gr_line
		(start 87.886794 -407.954734)
		(end 87.590884 -408.250644)
		(stroke
			(width 0.06477)
			(type default)
		)
		(layer "F.Cu")
	)
	(gr_line
		(start 87.969344 -383.596896)
		(end 88.045798 -383.520442)
		(stroke
			(width 0.0508)
			(type default)
		)
		(layer "F.Cu")
	)
	(gr_line
		(start 87.996522 -377.0757)
		(end 88.107012 -377.18619)
		(stroke
			(width 0.0508)
			(type default)
		)
		(layer "F.Cu")
	)
	(gr_line
		(start 88.03513 -382.943862)
		(end 87.743792 -383.2352)
		(stroke
			(width 0.0508)
			(type default)
		)
		(layer "F.Cu")
	)
	(gr_arc
		(start 88.042496 -376.068336)
		(mid 88.010905 -376.112984)
		(end 87.996014 -376.165618)
		(stroke
			(width 0.0508)
			(type default)
		)
		(layer "F.Cu")
	)
	(gr_line
		(start 88.045798 -383.520442)
		(end 88.045798 -383.402586)
		(stroke
			(width 0.0508)
			(type default)
		)
		(layer "F.Cu")
	)
	(gr_line
		(start 88.048592 -374.93702)
		(end 88.344502 -375.23293)
		(stroke
			(width 0.06477)
			(type default)
		)
		(layer "F.Cu")
	)
	(gr_line
		(start 88.107012 -377.49099)
		(end 87.996522 -377.60148)
		(stroke
			(width 0.0508)
			(type default)
		)
		(layer "F.Cu")
	)
	(gr_line
		(start 88.107012 -377.18619)
		(end 88.107012 -377.49099)
		(stroke
			(width 0.0508)
			(type default)
		)
		(layer "F.Cu")
	)
	(gr_line
		(start 88.12911 -391.36447)
		(end 88.045798 -391.281158)
		(stroke
			(width 0.0508)
			(type default)
		)
		(layer "F.Cu")
	)
	(gr_line
		(start 88.198452 -388.774432)
		(end 88.719152 -388.774432)
		(stroke
			(width 0.0635)
			(type default)
		)
		(layer "F.Cu")
	)
	(gr_line
		(start 88.198452 -385.31038)
		(end 88.719152 -385.31038)
		(stroke
			(width 0.0635)
			(type default)
		)
		(layer "F.Cu")
	)
	(gr_line
		(start 88.209374 -412.299658)
		(end 88.479884 -412.570168)
		(stroke
			(width 0.06477)
			(type default)
		)
		(layer "F.Cu")
	)
	(gr_line
		(start 88.209374 -407.954734)
		(end 88.505284 -408.250644)
		(stroke
			(width 0.06477)
			(type default)
		)
		(layer "F.Cu")
	)
	(gr_line
		(start 88.2523 -383.13741)
		(end 88.345772 -383.230882)
		(stroke
			(width 0.0508)
			(type default)
		)
		(layer "F.Cu")
	)
	(gr_line
		(start 88.2523 -382.94183)
		(end 88.2523 -383.13741)
		(stroke
			(width 0.0508)
			(type default)
		)
		(layer "F.Cu")
	)
	(gr_line
		(start 88.319102 -373.96293)
		(end 88.048592 -374.23344)
		(stroke
			(width 0.06477)
			(type default)
		)
		(layer "F.Cu")
	)
	(gr_line
		(start 88.344502 -375.76633)
		(end 88.042496 -376.068336)
		(stroke
			(width 0.0508)
			(type default)
		)
		(layer "F.Cu")
	)
	(gr_line
		(start 88.345772 -383.230882)
		(end 88.345772 -383.92227)
		(stroke
			(width 0.0508)
			(type default)
		)
		(layer "F.Cu")
	)
	(gr_line
		(start 88.34628 -391.36574)
		(end 88.34628 -390.761982)
		(stroke
			(width 0.0508)
			(type default)
		)
		(layer "F.Cu")
	)
	(gr_line
		(start 88.34628 -390.761982)
		(end 88.345772 -390.761474)
		(stroke
			(width 0.0508)
			(type default)
		)
		(layer "F.Cu")
	)
	(gr_line
		(start 88.479884 -404.46452)
		(end 88.209374 -404.73503)
		(stroke
			(width 0.06477)
			(type default)
		)
		(layer "F.Cu")
	)
	(gr_line
		(start 88.505284 -408.784044)
		(end 88.209374 -409.079954)
		(stroke
			(width 0.06477)
			(type default)
		)
		(layer "F.Cu")
	)
	(gr_line
		(start 88.598248 -389.467344)
		(end 89.118948 -389.467344)
		(stroke
			(width 0.0635)
			(type default)
		)
		(layer "F.Cu")
	)
	(gr_line
		(start 88.598248 -386.003292)
		(end 89.118948 -386.003292)
		(stroke
			(width 0.0635)
			(type default)
		)
		(layer "F.Cu")
	)
	(gr_line
		(start 88.605614 -392.977116)
		(end 88.603582 -392.977116)
		(stroke
			(width 0.0508)
			(type default)
		)
		(layer "F.Cu")
	)
	(gr_line
		(start 88.744298 -393.292838)
		(end 88.744298 -393.1158)
		(stroke
			(width 0.0508)
			(type default)
		)
		(layer "F.Cu")
	)
	(gr_line
		(start 88.744298 -393.1158)
		(end 88.605614 -392.977116)
		(stroke
			(width 0.0508)
			(type default)
		)
		(layer "F.Cu")
	)
	(gr_line
		(start 88.744298 -392.6205)
		(end 88.604852 -392.759946)
		(stroke
			(width 0.0508)
			(type default)
		)
		(layer "F.Cu")
	)
	(gr_line
		(start 88.744298 -392.429238)
		(end 88.744298 -392.6205)
		(stroke
			(width 0.0508)
			(type default)
		)
		(layer "F.Cu")
	)
	(gr_line
		(start 88.943688 -383.50571)
		(end 89.034874 -383.596896)
		(stroke
			(width 0.0508)
			(type default)
		)
		(layer "F.Cu")
	)
	(gr_line
		(start 88.943688 -383.2352)
		(end 88.943688 -383.50571)
		(stroke
			(width 0.0508)
			(type default)
		)
		(layer "F.Cu")
	)
	(gr_line
		(start 89.034874 -383.596896)
		(end 89.16924 -383.596896)
		(stroke
			(width 0.0508)
			(type default)
		)
		(layer "F.Cu")
	)
	(gr_line
		(start 89.131902 -373.30253)
		(end 89.433654 -373.604282)
		(stroke
			(width 0.0508)
			(type default)
		)
		(layer "F.Cu")
	)
	(gr_line
		(start 89.157302 -371.49913)
		(end 89.427812 -371.76964)
		(stroke
			(width 0.06477)
			(type default)
		)
		(layer "F.Cu")
	)
	(gr_line
		(start 89.16924 -383.596896)
		(end 89.245694 -383.520442)
		(stroke
			(width 0.0508)
			(type default)
		)
		(layer "F.Cu")
	)
	(gr_line
		(start 89.235026 -382.943862)
		(end 88.943688 -383.2352)
		(stroke
			(width 0.0508)
			(type default)
		)
		(layer "F.Cu")
	)
	(gr_line
		(start 89.245694 -383.520442)
		(end 89.245694 -383.402586)
		(stroke
			(width 0.0508)
			(type default)
		)
		(layer "F.Cu")
	)
	(gr_line
		(start 89.329006 -391.36447)
		(end 89.245694 -391.281158)
		(stroke
			(width 0.0508)
			(type default)
		)
		(layer "F.Cu")
	)
	(gr_line
		(start 89.398348 -388.774432)
		(end 89.919048 -388.774432)
		(stroke
			(width 0.0635)
			(type default)
		)
		(layer "F.Cu")
	)
	(gr_line
		(start 89.398348 -385.31038)
		(end 89.919048 -385.31038)
		(stroke
			(width 0.0635)
			(type default)
		)
		(layer "F.Cu")
	)
	(gr_line
		(start 89.427812 -372.47322)
		(end 89.131902 -372.76913)
		(stroke
			(width 0.06477)
			(type default)
		)
		(layer "F.Cu")
	)
	(gr_line
		(start 89.452196 -383.13741)
		(end 89.545668 -383.230882)
		(stroke
			(width 0.0508)
			(type default)
		)
		(layer "F.Cu")
	)
	(gr_line
		(start 89.452196 -382.942592)
		(end 89.452196 -383.13741)
		(stroke
			(width 0.0508)
			(type default)
		)
		(layer "F.Cu")
	)
	(gr_arc
		(start 89.480136 -373.702072)
		(mid 89.465262 -373.6492)
		(end 89.433654 -373.604282)
		(stroke
			(width 0.0508)
			(type default)
		)
		(layer "F.Cu")
	)
	(gr_line
		(start 89.481152 -374.84304)
		(end 89.481152 -375.37136)
		(stroke
			(width 0.0508)
			(type default)
		)
		(layer "F.Cu")
	)
	(gr_line
		(start 89.545668 -383.230882)
		(end 89.545668 -383.92227)
		(stroke
			(width 0.0508)
			(type default)
		)
		(layer "F.Cu")
	)
	(gr_line
		(start 89.546176 -391.36574)
		(end 89.546176 -390.761982)
		(stroke
			(width 0.0508)
			(type default)
		)
		(layer "F.Cu")
	)
	(gr_line
		(start 89.546176 -390.761982)
		(end 89.545668 -390.761474)
		(stroke
			(width 0.0508)
			(type default)
		)
		(layer "F.Cu")
	)
	(gr_line
		(start 89.698322 -374.84431)
		(end 89.808812 -374.9548)
		(stroke
			(width 0.0508)
			(type default)
		)
		(layer "F.Cu")
	)
	(gr_arc
		(start 89.74455 -373.604282)
		(mid 89.712902 -373.64918)
		(end 89.698068 -373.702072)
		(stroke
			(width 0.0508)
			(type default)
		)
		(layer "F.Cu")
	)
	(gr_line
		(start 89.750392 -372.47322)
		(end 90.046302 -372.76913)
		(stroke
			(width 0.06477)
			(type default)
		)
		(layer "F.Cu")
	)
	(gr_line
		(start 89.798398 -389.467344)
		(end 90.319098 -389.467344)
		(stroke
			(width 0.0635)
			(type default)
		)
		(layer "F.Cu")
	)
	(gr_line
		(start 89.798398 -386.003292)
		(end 90.319098 -386.003292)
		(stroke
			(width 0.0635)
			(type default)
		)
		(layer "F.Cu")
	)
	(gr_line
		(start 89.80551 -392.977116)
		(end 89.803478 -392.977116)
		(stroke
			(width 0.0508)
			(type default)
		)
		(layer "F.Cu")
	)
	(gr_line
		(start 89.808812 -375.2596)
		(end 89.698322 -375.37009)
		(stroke
			(width 0.0508)
			(type default)
		)
		(layer "F.Cu")
	)
	(gr_line
		(start 89.808812 -374.9548)
		(end 89.808812 -375.2596)
		(stroke
			(width 0.0508)
			(type default)
		)
		(layer "F.Cu")
	)
	(gr_line
		(start 89.944448 -393.292838)
		(end 89.944448 -393.116054)
		(stroke
			(width 0.0508)
			(type default)
		)
		(layer "F.Cu")
	)
	(gr_line
		(start 89.944448 -393.116054)
		(end 89.80551 -392.977116)
		(stroke
			(width 0.0508)
			(type default)
		)
		(layer "F.Cu")
	)
	(gr_line
		(start 89.944448 -392.620246)
		(end 89.804748 -392.759946)
		(stroke
			(width 0.0508)
			(type default)
		)
		(layer "F.Cu")
	)
	(gr_line
		(start 89.944448 -392.429238)
		(end 89.944448 -392.620246)
		(stroke
			(width 0.0508)
			(type default)
		)
		(layer "F.Cu")
	)
	(gr_line
		(start 90.020902 -371.49913)
		(end 89.750392 -371.76964)
		(stroke
			(width 0.06477)
			(type default)
		)
		(layer "F.Cu")
	)
	(gr_line
		(start 90.046302 -373.30253)
		(end 89.74455 -373.604282)
		(stroke
			(width 0.0508)
			(type default)
		)
		(layer "F.Cu")
	)
	(gr_line
		(start 90.143838 -383.50571)
		(end 90.235024 -383.596896)
		(stroke
			(width 0.0508)
			(type default)
		)
		(layer "F.Cu")
	)
	(gr_line
		(start 90.143838 -383.2352)
		(end 90.143838 -383.50571)
		(stroke
			(width 0.0508)
			(type default)
		)
		(layer "F.Cu")
	)
	(gr_line
		(start 90.235024 -383.596896)
		(end 90.36939 -383.596896)
		(stroke
			(width 0.0508)
			(type default)
		)
		(layer "F.Cu")
	)
	(gr_line
		(start 90.36939 -383.596896)
		(end 90.445844 -383.520442)
		(stroke
			(width 0.0508)
			(type default)
		)
		(layer "F.Cu")
	)
	(gr_line
		(start 90.435176 -382.943862)
		(end 90.143838 -383.2352)
		(stroke
			(width 0.0508)
			(type default)
		)
		(layer "F.Cu")
	)
	(gr_line
		(start 90.445844 -383.520442)
		(end 90.445844 -383.402586)
		(stroke
			(width 0.0508)
			(type default)
		)
		(layer "F.Cu")
	)
	(gr_line
		(start 90.529156 -391.36447)
		(end 90.445844 -391.281158)
		(stroke
			(width 0.0508)
			(type default)
		)
		(layer "F.Cu")
	)
	(gr_line
		(start 90.598244 -388.774432)
		(end 91.118944 -388.774432)
		(stroke
			(width 0.0635)
			(type default)
		)
		(layer "F.Cu")
	)
	(gr_line
		(start 90.598244 -385.31038)
		(end 91.118944 -385.31038)
		(stroke
			(width 0.0635)
			(type default)
		)
		(layer "F.Cu")
	)
	(gr_line
		(start 90.652346 -383.13741)
		(end 90.745818 -383.230882)
		(stroke
			(width 0.0508)
			(type default)
		)
		(layer "F.Cu")
	)
	(gr_line
		(start 90.652346 -382.942592)
		(end 90.652346 -383.13741)
		(stroke
			(width 0.0508)
			(type default)
		)
		(layer "F.Cu")
	)
	(gr_line
		(start 90.654124 -408.784044)
		(end 90.950034 -409.079954)
		(stroke
			(width 0.06477)
			(type default)
		)
		(layer "F.Cu")
	)
	(gr_line
		(start 90.679524 -404.46452)
		(end 90.950034 -404.73503)
		(stroke
			(width 0.06477)
			(type default)
		)
		(layer "F.Cu")
	)
	(gr_line
		(start 90.745818 -383.230882)
		(end 90.745818 -383.92227)
		(stroke
			(width 0.0508)
			(type default)
		)
		(layer "F.Cu")
	)
	(gr_line
		(start 90.746326 -391.36574)
		(end 90.746326 -390.761982)
		(stroke
			(width 0.0508)
			(type default)
		)
		(layer "F.Cu")
	)
	(gr_line
		(start 90.746326 -390.761982)
		(end 90.745818 -390.761474)
		(stroke
			(width 0.0508)
			(type default)
		)
		(layer "F.Cu")
	)
	(gr_line
		(start 90.833702 -370.83873)
		(end 91.182952 -371.18798)
		(stroke
			(width 0.0508)
			(type default)
		)
		(layer "F.Cu")
	)
	(gr_line
		(start 90.859102 -369.03533)
		(end 91.129612 -369.30584)
		(stroke
			(width 0.06477)
			(type default)
		)
		(layer "F.Cu")
	)
	(gr_line
		(start 90.950034 -412.299658)
		(end 90.679524 -412.570168)
		(stroke
			(width 0.06477)
			(type default)
		)
		(layer "F.Cu")
	)
	(gr_line
		(start 90.950034 -407.954734)
		(end 90.654124 -408.250644)
		(stroke
			(width 0.06477)
			(type default)
		)
		(layer "F.Cu")
	)
	(gr_line
		(start 90.998294 -389.467344)
		(end 91.518994 -389.467344)
		(stroke
			(width 0.0635)
			(type default)
		)
		(layer "F.Cu")
	)
	(gr_line
		(start 90.998294 -386.003292)
		(end 91.518994 -386.003292)
		(stroke
			(width 0.0635)
			(type default)
		)
		(layer "F.Cu")
	)
	(gr_line
		(start 91.00566 -392.977116)
		(end 91.003628 -392.977116)
		(stroke
			(width 0.0508)
			(type default)
		)
		(layer "F.Cu")
	)
	(gr_line
		(start 91.129612 -370.00942)
		(end 90.833702 -370.30533)
		(stroke
			(width 0.06477)
			(type default)
		)
		(layer "F.Cu")
	)
	(gr_line
		(start 91.144344 -393.292838)
		(end 91.144344 -393.1158)
		(stroke
			(width 0.0508)
			(type default)
		)
		(layer "F.Cu")
	)
	(gr_line
		(start 91.144344 -393.1158)
		(end 91.00566 -392.977116)
		(stroke
			(width 0.0508)
			(type default)
		)
		(layer "F.Cu")
	)
	(gr_line
		(start 91.144344 -392.6205)
		(end 91.004898 -392.759946)
		(stroke
			(width 0.0508)
			(type default)
		)
		(layer "F.Cu")
	)
	(gr_line
		(start 91.144344 -392.429238)
		(end 91.144344 -392.6205)
		(stroke
			(width 0.0508)
			(type default)
		)
		(layer "F.Cu")
	)
	(gr_line
		(start 91.272614 -412.299658)
		(end 91.543124 -412.570168)
		(stroke
			(width 0.06477)
			(type default)
		)
		(layer "F.Cu")
	)
	(gr_line
		(start 91.272614 -407.954734)
		(end 91.568524 -408.250644)
		(stroke
			(width 0.06477)
			(type default)
		)
		(layer "F.Cu")
	)
	(gr_line
		(start 91.343734 -383.50571)
		(end 91.43492 -383.596896)
		(stroke
			(width 0.0508)
			(type default)
		)
		(layer "F.Cu")
	)
	(gr_line
		(start 91.343734 -383.2352)
		(end 91.343734 -383.50571)
		(stroke
			(width 0.0508)
			(type default)
		)
		(layer "F.Cu")
	)
	(gr_line
		(start 91.43492 -383.596896)
		(end 91.569286 -383.596896)
		(stroke
			(width 0.0508)
			(type default)
		)
		(layer "F.Cu")
	)
	(gr_line
		(start 91.452192 -370.00942)
		(end 91.748102 -370.30533)
		(stroke
			(width 0.06477)
			(type default)
		)
		(layer "F.Cu")
	)
	(gr_line
		(start 91.543124 -404.46452)
		(end 91.272614 -404.73503)
		(stroke
			(width 0.06477)
			(type default)
		)
		(layer "F.Cu")
	)
	(gr_line
		(start 91.568524 -408.784044)
		(end 91.272614 -409.079954)
		(stroke
			(width 0.06477)
			(type default)
		)
		(layer "F.Cu")
	)
	(gr_line
		(start 91.569286 -383.596896)
		(end 91.64574 -383.520442)
		(stroke
			(width 0.0508)
			(type default)
		)
		(layer "F.Cu")
	)
	(gr_line
		(start 91.635072 -382.943862)
		(end 91.343734 -383.2352)
		(stroke
			(width 0.0508)
			(type default)
		)
		(layer "F.Cu")
	)
	(gr_line
		(start 91.64574 -383.520442)
		(end 91.64574 -383.402586)
		(stroke
			(width 0.0508)
			(type default)
		)
		(layer "F.Cu")
	)
	(gr_line
		(start 91.722702 -369.03533)
		(end 91.452192 -369.30584)
		(stroke
			(width 0.06477)
			(type default)
		)
		(layer "F.Cu")
	)
	(gr_line
		(start 91.728544 -391.363962)
		(end 91.64574 -391.281158)
		(stroke
			(width 0.0508)
			(type default)
		)
		(layer "F.Cu")
	)
	(gr_line
		(start 91.748102 -370.83873)
		(end 91.398852 -371.18798)
		(stroke
			(width 0.0508)
			(type default)
		)
		(layer "F.Cu")
	)
	(gr_line
		(start 91.798394 -388.774432)
		(end 92.319094 -388.774432)
		(stroke
			(width 0.0635)
			(type default)
		)
		(layer "F.Cu")
	)
	(gr_line
		(start 91.798394 -385.31038)
		(end 92.319094 -385.31038)
		(stroke
			(width 0.0635)
			(type default)
		)
		(layer "F.Cu")
	)
	(gr_line
		(start 91.852242 -383.13741)
		(end 91.945714 -383.230882)
		(stroke
			(width 0.0508)
			(type default)
		)
		(layer "F.Cu")
	)
	(gr_line
		(start 91.852242 -382.942592)
		(end 91.852242 -383.13741)
		(stroke
			(width 0.0508)
			(type default)
		)
		(layer "F.Cu")
	)
	(gr_line
		(start 91.866212 -376.553984)
		(end 91.709494 -376.553984)
		(stroke
			(width 0.0508)
			(type default)
		)
		(layer "F.Cu")
	)
	(gr_line
		(start 91.915742 -378.48286)
		(end 91.915488 -378.48286)
		(stroke
			(width 0.0508)
			(type default)
		)
		(layer "F.Cu")
	)
	(gr_line
		(start 91.929204 -376.027188)
		(end 91.555316 -376.401076)
		(stroke
			(width 0.0508)
			(type default)
		)
		(layer "F.Cu")
	)
	(gr_line
		(start 91.945714 -391.365232)
		(end 91.945714 -390.761474)
		(stroke
			(width 0.0508)
			(type default)
		)
		(layer "F.Cu")
	)
	(gr_line
		(start 91.945714 -383.230882)
		(end 91.945714 -383.92227)
		(stroke
			(width 0.0508)
			(type default)
		)
		(layer "F.Cu")
	)
	(gr_line
		(start 92.082112 -376.338084)
		(end 91.866212 -376.553984)
		(stroke
			(width 0.0508)
			(type default)
		)
		(layer "F.Cu")
	)
	(gr_line
		(start 92.082112 -376.181366)
		(end 92.082112 -376.338084)
		(stroke
			(width 0.0508)
			(type default)
		)
		(layer "F.Cu")
	)
	(gr_line
		(start 92.198444 -389.467344)
		(end 92.719144 -389.467344)
		(stroke
			(width 0.0635)
			(type default)
		)
		(layer "F.Cu")
	)
	(gr_line
		(start 92.198444 -386.003292)
		(end 92.719144 -386.003292)
		(stroke
			(width 0.0635)
			(type default)
		)
		(layer "F.Cu")
	)
	(gr_line
		(start 92.205556 -392.977116)
		(end 92.203524 -392.977116)
		(stroke
			(width 0.0508)
			(type default)
		)
		(layer "F.Cu")
	)
	(gr_line
		(start 92.226384 -378.635768)
		(end 92.06992 -378.635768)
		(stroke
			(width 0.0508)
			(type default)
		)
		(layer "F.Cu")
	)
	(gr_line
		(start 92.289122 -378.10948)
		(end 91.915742 -378.48286)
		(stroke
			(width 0.0508)
			(type default)
		)
		(layer "F.Cu")
	)
	(gr_line
		(start 92.344494 -393.292838)
		(end 92.344494 -393.116054)
		(stroke
			(width 0.0508)
			(type default)
		)
		(layer "F.Cu")
	)
	(gr_line
		(start 92.344494 -393.116054)
		(end 92.205556 -392.977116)
		(stroke
			(width 0.0508)
			(type default)
		)
		(layer "F.Cu")
	)
	(gr_line
		(start 92.344494 -392.620246)
		(end 92.204794 -392.759946)
		(stroke
			(width 0.0508)
			(type default)
		)
		(layer "F.Cu")
	)
	(gr_line
		(start 92.344494 -392.429238)
		(end 92.344494 -392.620246)
		(stroke
			(width 0.0508)
			(type default)
		)
		(layer "F.Cu")
	)
	(gr_line
		(start 92.44203 -378.420122)
		(end 92.226384 -378.635768)
		(stroke
			(width 0.0508)
			(type default)
		)
		(layer "F.Cu")
	)
	(gr_line
		(start 92.44203 -378.263658)
		(end 92.44203 -378.420122)
		(stroke
			(width 0.0508)
			(type default)
		)
		(layer "F.Cu")
	)
	(gr_line
		(start 92.54363 -383.50571)
		(end 92.634816 -383.596896)
		(stroke
			(width 0.0508)
			(type default)
		)
		(layer "F.Cu")
	)
	(gr_line
		(start 92.54363 -383.2352)
		(end 92.54363 -383.50571)
		(stroke
			(width 0.0508)
			(type default)
		)
		(layer "F.Cu")
	)
	(gr_line
		(start 92.634816 -383.596896)
		(end 92.769182 -383.596896)
		(stroke
			(width 0.0508)
			(type default)
		)
		(layer "F.Cu")
	)
	(gr_line
		(start 92.769182 -383.596896)
		(end 92.845636 -383.520442)
		(stroke
			(width 0.0508)
			(type default)
		)
		(layer "F.Cu")
	)
	(gr_line
		(start 92.834968 -382.943862)
		(end 92.54363 -383.2352)
		(stroke
			(width 0.0508)
			(type default)
		)
		(layer "F.Cu")
	)
	(gr_line
		(start 92.845636 -383.520442)
		(end 92.845636 -383.402586)
		(stroke
			(width 0.0508)
			(type default)
		)
		(layer "F.Cu")
	)
	(gr_line
		(start 92.928948 -391.36447)
		(end 92.845636 -391.281158)
		(stroke
			(width 0.0508)
			(type default)
		)
		(layer "F.Cu")
	)
	(gr_line
		(start 92.99829 -388.774432)
		(end 93.51899 -388.774432)
		(stroke
			(width 0.0635)
			(type default)
		)
		(layer "F.Cu")
	)
	(gr_line
		(start 92.99829 -385.31038)
		(end 93.51899 -385.31038)
		(stroke
			(width 0.0635)
			(type default)
		)
		(layer "F.Cu")
	)
	(gr_line
		(start 93.052138 -383.13741)
		(end 93.145864 -383.231136)
		(stroke
			(width 0.0508)
			(type default)
		)
		(layer "F.Cu")
	)
	(gr_line
		(start 93.052138 -382.942592)
		(end 93.052138 -383.13741)
		(stroke
			(width 0.0508)
			(type default)
		)
		(layer "F.Cu")
	)
	(gr_line
		(start 93.145864 -383.231136)
		(end 93.145864 -383.92227)
		(stroke
			(width 0.0508)
			(type default)
		)
		(layer "F.Cu")
	)
	(gr_line
		(start 93.146118 -391.36574)
		(end 93.146118 -390.761728)
		(stroke
			(width 0.0508)
			(type default)
		)
		(layer "F.Cu")
	)
	(gr_line
		(start 93.146118 -390.761728)
		(end 93.145864 -390.761474)
		(stroke
			(width 0.0508)
			(type default)
		)
		(layer "F.Cu")
	)
	(gr_line
		(start 93.39834 -389.467344)
		(end 93.91904 -389.467344)
		(stroke
			(width 0.0635)
			(type default)
		)
		(layer "F.Cu")
	)
	(gr_line
		(start 93.39834 -386.003292)
		(end 93.91904 -386.003292)
		(stroke
			(width 0.0635)
			(type default)
		)
		(layer "F.Cu")
	)
	(gr_line
		(start 93.405452 -392.977116)
		(end 93.40342 -392.977116)
		(stroke
			(width 0.0508)
			(type default)
		)
		(layer "F.Cu")
	)
	(gr_line
		(start 93.54439 -393.292838)
		(end 93.54439 -393.116054)
		(stroke
			(width 0.0508)
			(type default)
		)
		(layer "F.Cu")
	)
	(gr_line
		(start 93.54439 -393.116054)
		(end 93.405452 -392.977116)
		(stroke
			(width 0.0508)
			(type default)
		)
		(layer "F.Cu")
	)
	(gr_line
		(start 93.54439 -392.620246)
		(end 93.40469 -392.759946)
		(stroke
			(width 0.0508)
			(type default)
		)
		(layer "F.Cu")
	)
	(gr_line
		(start 93.54439 -392.429238)
		(end 93.54439 -392.620246)
		(stroke
			(width 0.0508)
			(type default)
		)
		(layer "F.Cu")
	)
	(gr_line
		(start 93.717364 -408.784044)
		(end 94.013274 -409.079954)
		(stroke
			(width 0.06477)
			(type default)
		)
		(layer "F.Cu")
	)
	(gr_line
		(start 93.742764 -404.46452)
		(end 94.013274 -404.73503)
		(stroke
			(width 0.06477)
			(type default)
		)
		(layer "F.Cu")
	)
	(gr_line
		(start 93.74378 -383.50571)
		(end 93.834966 -383.596896)
		(stroke
			(width 0.0508)
			(type default)
		)
		(layer "F.Cu")
	)
	(gr_line
		(start 93.74378 -383.2352)
		(end 93.74378 -383.50571)
		(stroke
			(width 0.0508)
			(type default)
		)
		(layer "F.Cu")
	)
	(gr_line
		(start 93.834966 -383.596896)
		(end 93.969332 -383.596896)
		(stroke
			(width 0.0508)
			(type default)
		)
		(layer "F.Cu")
	)
	(gr_line
		(start 93.969332 -383.596896)
		(end 94.045786 -383.520442)
		(stroke
			(width 0.0508)
			(type default)
		)
		(layer "F.Cu")
	)
	(gr_line
		(start 94.013274 -412.299658)
		(end 93.742764 -412.570168)
		(stroke
			(width 0.06477)
			(type default)
		)
		(layer "F.Cu")
	)
	(gr_line
		(start 94.013274 -407.954734)
		(end 93.717364 -408.250644)
		(stroke
			(width 0.06477)
			(type default)
		)
		(layer "F.Cu")
	)
	(gr_line
		(start 94.035118 -382.943862)
		(end 93.74378 -383.2352)
		(stroke
			(width 0.0508)
			(type default)
		)
		(layer "F.Cu")
	)
	(gr_line
		(start 94.045786 -383.520442)
		(end 94.045786 -383.402586)
		(stroke
			(width 0.0508)
			(type default)
		)
		(layer "F.Cu")
	)
	(gr_line
		(start 94.129098 -391.36447)
		(end 94.045786 -391.281158)
		(stroke
			(width 0.0508)
			(type default)
		)
		(layer "F.Cu")
	)
	(gr_line
		(start 94.19844 -388.774432)
		(end 94.71914 -388.774432)
		(stroke
			(width 0.0635)
			(type default)
		)
		(layer "F.Cu")
	)
	(gr_line
		(start 94.19844 -385.31038)
		(end 94.71914 -385.31038)
		(stroke
			(width 0.0635)
			(type default)
		)
		(layer "F.Cu")
	)
	(gr_line
		(start 94.237302 -375.76633)
		(end 94.585536 -376.114564)
		(stroke
			(width 0.0508)
			(type default)
		)
		(layer "F.Cu")
	)
	(gr_line
		(start 94.252288 -383.13741)
		(end 94.34576 -383.230882)
		(stroke
			(width 0.0508)
			(type default)
		)
		(layer "F.Cu")
	)
	(gr_line
		(start 94.252288 -382.942592)
		(end 94.252288 -383.13741)
		(stroke
			(width 0.0508)
			(type default)
		)
		(layer "F.Cu")
	)
	(gr_line
		(start 94.262702 -373.96293)
		(end 94.533212 -374.23344)
		(stroke
			(width 0.06477)
			(type default)
		)
		(layer "F.Cu")
	)
	(gr_line
		(start 94.335854 -412.299658)
		(end 94.606364 -412.570168)
		(stroke
			(width 0.06477)
			(type default)
		)
		(layer "F.Cu")
	)
	(gr_line
		(start 94.335854 -407.954734)
		(end 94.631764 -408.250644)
		(stroke
			(width 0.06477)
			(type default)
		)
		(layer "F.Cu")
	)
	(gr_line
		(start 94.34576 -383.230882)
		(end 94.34576 -383.92227)
		(stroke
			(width 0.0508)
			(type default)
		)
		(layer "F.Cu")
	)
	(gr_line
		(start 94.346268 -391.36574)
		(end 94.346268 -390.761982)
		(stroke
			(width 0.0508)
			(type default)
		)
		(layer "F.Cu")
	)
	(gr_line
		(start 94.346268 -390.761982)
		(end 94.34576 -390.761474)
		(stroke
			(width 0.0508)
			(type default)
		)
		(layer "F.Cu")
	)
	(gr_line
		(start 94.487746 -209.023458)
		(end 94.758256 -208.752948)
		(stroke
			(width 0.06477)
			(type default)
		)
		(layer "F.Cu")
	)
	(gr_line
		(start 94.487746 -208.159858)
		(end 94.758256 -208.430368)
		(stroke
			(width 0.06477)
			(type default)
		)
		(layer "F.Cu")
	)
	(gr_line
		(start 94.488 -212.140038)
		(end 94.75851 -211.869528)
		(stroke
			(width 0.06477)
			(type default)
		)
		(layer "F.Cu")
	)
	(gr_line
		(start 94.488 -211.276438)
		(end 94.75851 -211.546948)
		(stroke
			(width 0.06477)
			(type default)
		)
		(layer "F.Cu")
	)
	(gr_line
		(start 94.533212 -374.93702)
		(end 94.237302 -375.23293)
		(stroke
			(width 0.06477)
			(type default)
		)
		(layer "F.Cu")
	)
	(gr_line
		(start 94.585536 -376.114564)
		(end 94.585536 -376.116596)
		(stroke
			(width 0.0508)
			(type default)
		)
		(layer "F.Cu")
	)
	(gr_line
		(start 94.598236 -389.467344)
		(end 95.118936 -389.467344)
		(stroke
			(width 0.0635)
			(type default)
		)
		(layer "F.Cu")
	)
	(gr_line
		(start 94.598236 -386.003292)
		(end 95.118936 -386.003292)
		(stroke
			(width 0.0635)
			(type default)
		)
		(layer "F.Cu")
	)
	(gr_line
		(start 94.6023 -392.977116)
		(end 94.578932 -392.977116)
		(stroke
			(width 0.0508)
			(type default)
		)
		(layer "F.Cu")
	)
	(gr_line
		(start 94.606364 -404.46452)
		(end 94.335854 -404.73503)
		(stroke
			(width 0.06477)
			(type default)
		)
		(layer "F.Cu")
	)
	(gr_line
		(start 94.631764 -408.784044)
		(end 94.335854 -409.079954)
		(stroke
			(width 0.06477)
			(type default)
		)
		(layer "F.Cu")
	)
	(gr_line
		(start 94.744286 -393.292838)
		(end 94.744286 -393.119102)
		(stroke
			(width 0.0508)
			(type default)
		)
		(layer "F.Cu")
	)
	(gr_line
		(start 94.744286 -393.119102)
		(end 94.6023 -392.977116)
		(stroke
			(width 0.0508)
			(type default)
		)
		(layer "F.Cu")
	)
	(gr_line
		(start 94.744286 -392.595862)
		(end 94.580202 -392.759946)
		(stroke
			(width 0.0508)
			(type default)
		)
		(layer "F.Cu")
	)
	(gr_line
		(start 94.744286 -392.429238)
		(end 94.744286 -392.595862)
		(stroke
			(width 0.0508)
			(type default)
		)
		(layer "F.Cu")
	)
	(gr_line
		(start 94.75851 -214.721948)
		(end 94.488 -214.992458)
		(stroke
			(width 0.06477)
			(type default)
		)
		(layer "F.Cu")
	)
	(gr_line
		(start 94.75851 -214.399368)
		(end 94.488 -214.128858)
		(stroke
			(width 0.06477)
			(type default)
		)
		(layer "F.Cu")
	)
	(gr_line
		(start 94.855792 -374.93702)
		(end 95.151702 -375.23293)
		(stroke
			(width 0.06477)
			(type default)
		)
		(layer "F.Cu")
	)
	(gr_line
		(start 94.943676 -383.50571)
		(end 95.034862 -383.596896)
		(stroke
			(width 0.0508)
			(type default)
		)
		(layer "F.Cu")
	)
	(gr_line
		(start 94.943676 -383.2352)
		(end 94.943676 -383.50571)
		(stroke
			(width 0.0508)
			(type default)
		)
		(layer "F.Cu")
	)
	(gr_line
		(start 95.034862 -383.596896)
		(end 95.169228 -383.596896)
		(stroke
			(width 0.0508)
			(type default)
		)
		(layer "F.Cu")
	)
	(gr_line
		(start 95.126302 -373.96293)
		(end 94.855792 -374.23344)
		(stroke
			(width 0.06477)
			(type default)
		)
		(layer "F.Cu")
	)
	(gr_line
		(start 95.151702 -375.76633)
		(end 94.802706 -376.115326)
		(stroke
			(width 0.0508)
			(type default)
		)
		(layer "F.Cu")
	)
	(gr_line
		(start 95.169228 -383.596896)
		(end 95.245682 -383.520442)
		(stroke
			(width 0.0508)
			(type default)
		)
		(layer "F.Cu")
	)
	(gr_line
		(start 95.235014 -382.943862)
		(end 94.943676 -383.2352)
		(stroke
			(width 0.0508)
			(type default)
		)
		(layer "F.Cu")
	)
	(gr_line
		(start 95.245682 -383.520442)
		(end 95.245682 -383.402586)
		(stroke
			(width 0.0508)
			(type default)
		)
		(layer "F.Cu")
	)
	(gr_line
		(start 95.328994 -391.36447)
		(end 95.245682 -391.281158)
		(stroke
			(width 0.0508)
			(type default)
		)
		(layer "F.Cu")
	)
	(gr_line
		(start 95.398336 -388.774432)
		(end 95.919036 -388.774432)
		(stroke
			(width 0.0635)
			(type default)
		)
		(layer "F.Cu")
	)
	(gr_line
		(start 95.398336 -385.31038)
		(end 95.919036 -385.31038)
		(stroke
			(width 0.0635)
			(type default)
		)
		(layer "F.Cu")
	)
	(gr_line
		(start 95.452184 -383.13741)
		(end 95.545656 -383.230882)
		(stroke
			(width 0.0508)
			(type default)
		)
		(layer "F.Cu")
	)
	(gr_line
		(start 95.452184 -382.942592)
		(end 95.452184 -383.13741)
		(stroke
			(width 0.0508)
			(type default)
		)
		(layer "F.Cu")
	)
	(gr_line
		(start 95.488506 -214.82304)
		(end 95.488252 -214.822786)
		(stroke
			(width 0.06477)
			(type default)
		)
		(layer "F.Cu")
	)
	(gr_line
		(start 95.545656 -383.230882)
		(end 95.545656 -383.92227)
		(stroke
			(width 0.0508)
			(type default)
		)
		(layer "F.Cu")
	)
	(gr_line
		(start 95.546164 -391.36574)
		(end 95.546164 -390.761982)
		(stroke
			(width 0.0508)
			(type default)
		)
		(layer "F.Cu")
	)
	(gr_line
		(start 95.546164 -390.761982)
		(end 95.545656 -390.761474)
		(stroke
			(width 0.0508)
			(type default)
		)
		(layer "F.Cu")
	)
	(gr_line
		(start 95.634556 -207.777588)
		(end 95.996506 -207.100678)
		(stroke
			(width 0.06477)
			(type default)
		)
		(layer "F.Cu")
	)
	(gr_line
		(start 95.656146 -214.543132)
		(end 95.656146 -214.542878)
		(stroke
			(width 0.06477)
			(type default)
		)
		(layer "F.Cu")
	)
	(gr_line
		(start 95.656146 -214.542878)
		(end 95.61195 -214.52459)
		(stroke
			(width 0.06477)
			(type default)
		)
		(layer "F.Cu")
	)
	(gr_line
		(start 95.69323 -214.573612)
		(end 95.656146 -214.543132)
		(stroke
			(width 0.06477)
			(type default)
		)
		(layer "F.Cu")
	)
	(gr_line
		(start 95.798386 -389.467344)
		(end 96.319086 -389.467344)
		(stroke
			(width 0.0635)
			(type default)
		)
		(layer "F.Cu")
	)
	(gr_line
		(start 95.798386 -386.003292)
		(end 96.319086 -386.003292)
		(stroke
			(width 0.0635)
			(type default)
		)
		(layer "F.Cu")
	)
	(gr_line
		(start 95.805498 -392.977116)
		(end 95.803466 -392.977116)
		(stroke
			(width 0.0508)
			(type default)
		)
		(layer "F.Cu")
	)
	(gr_line
		(start 95.920814 -207.929226)
		(end 96.177354 -207.851502)
		(stroke
			(width 0.06477)
			(type default)
		)
		(layer "F.Cu")
	)
	(gr_line
		(start 95.939102 -373.30253)
		(end 96.288352 -373.65178)
		(stroke
			(width 0.0508)
			(type default)
		)
		(layer "F.Cu")
	)
	(gr_line
		(start 95.944182 -393.292838)
		(end 95.944182 -393.1158)
		(stroke
			(width 0.0508)
			(type default)
		)
		(layer "F.Cu")
	)
	(gr_line
		(start 95.944182 -393.1158)
		(end 95.805498 -392.977116)
		(stroke
			(width 0.0508)
			(type default)
		)
		(layer "F.Cu")
	)
	(gr_line
		(start 95.944182 -392.6205)
		(end 95.804736 -392.759946)
		(stroke
			(width 0.0508)
			(type default)
		)
		(layer "F.Cu")
	)
	(gr_line
		(start 95.944182 -392.429238)
		(end 95.944182 -392.6205)
		(stroke
			(width 0.0508)
			(type default)
		)
		(layer "F.Cu")
	)
	(gr_line
		(start 95.964502 -371.49913)
		(end 96.235012 -371.76964)
		(stroke
			(width 0.06477)
			(type default)
		)
		(layer "F.Cu")
	)
	(gr_line
		(start 95.969582 -215.461342)
		(end 95.943674 -215.197944)
		(stroke
			(width 0.06477)
			(type default)
		)
		(layer "F.Cu")
	)
	(gr_line
		(start 96.177354 -207.851502)
		(end 96.359472 -207.510634)
		(stroke
			(width 0.06477)
			(type default)
		)
		(layer "F.Cu")
	)
	(gr_line
		(start 96.235012 -372.47322)
		(end 95.939102 -372.76913)
		(stroke
			(width 0.06477)
			(type default)
		)
		(layer "F.Cu")
	)
	(gr_line
		(start 96.264222 -215.702896)
		(end 95.969582 -215.461342)
		(stroke
			(width 0.06477)
			(type default)
		)
		(layer "F.Cu")
	)
	(gr_line
		(start 96.288352 -375.021856)
		(end 96.288352 -375.550176)
		(stroke
			(width 0.0508)
			(type default)
		)
		(layer "F.Cu")
	)
	(gr_line
		(start 96.359472 -207.510634)
		(end 96.281748 -207.254094)
		(stroke
			(width 0.06477)
			(type default)
		)
		(layer "F.Cu")
	)
	(gr_line
		(start 96.505522 -375.023126)
		(end 96.616012 -375.133616)
		(stroke
			(width 0.0508)
			(type default)
		)
		(layer "F.Cu")
	)
	(gr_line
		(start 96.527366 -215.677242)
		(end 96.264222 -215.702896)
		(stroke
			(width 0.06477)
			(type default)
		)
		(layer "F.Cu")
	)
	(gr_line
		(start 96.529144 -391.36447)
		(end 96.445832 -391.281158)
		(stroke
			(width 0.0508)
			(type default)
		)
		(layer "F.Cu")
	)
	(gr_line
		(start 96.529144 -383.319274)
		(end 96.445832 -383.402586)
		(stroke
			(width 0.0508)
			(type default)
		)
		(layer "F.Cu")
	)
	(gr_line
		(start 96.557592 -372.47322)
		(end 96.853502 -372.76913)
		(stroke
			(width 0.06477)
			(type default)
		)
		(layer "F.Cu")
	)
	(gr_line
		(start 96.598486 -388.774432)
		(end 97.119186 -388.774432)
		(stroke
			(width 0.0635)
			(type default)
		)
		(layer "F.Cu")
	)
	(gr_line
		(start 96.598486 -385.31038)
		(end 97.119186 -385.31038)
		(stroke
			(width 0.0635)
			(type default)
		)
		(layer "F.Cu")
	)
	(gr_line
		(start 96.616012 -375.438416)
		(end 96.505522 -375.548906)
		(stroke
			(width 0.0508)
			(type default)
		)
		(layer "F.Cu")
	)
	(gr_line
		(start 96.616012 -375.133616)
		(end 96.616012 -375.438416)
		(stroke
			(width 0.0508)
			(type default)
		)
		(layer "F.Cu")
	)
	(gr_line
		(start 96.652588 -381.689102)
		(end 96.652334 -381.688848)
		(stroke
			(width 0.0508)
			(type default)
		)
		(layer "F.Cu")
	)
	(gr_line
		(start 96.733614 -215.42756)
		(end 96.148144 -214.946992)
		(stroke
			(width 0.06477)
			(type default)
		)
		(layer "F.Cu")
	)
	(gr_line
		(start 96.746314 -391.36574)
		(end 96.746314 -390.761982)
		(stroke
			(width 0.0508)
			(type default)
		)
		(layer "F.Cu")
	)
	(gr_line
		(start 96.746314 -390.761982)
		(end 96.745806 -390.761474)
		(stroke
			(width 0.0508)
			(type default)
		)
		(layer "F.Cu")
	)
	(gr_line
		(start 96.746314 -383.921762)
		(end 96.745806 -383.92227)
		(stroke
			(width 0.0508)
			(type default)
		)
		(layer "F.Cu")
	)
	(gr_line
		(start 96.746314 -383.318004)
		(end 96.746314 -383.921762)
		(stroke
			(width 0.0508)
			(type default)
		)
		(layer "F.Cu")
	)
	(gr_line
		(start 96.788478 -213.251034)
		(end 96.807528 -213.51494)
		(stroke
			(width 0.06477)
			(type default)
		)
		(layer "F.Cu")
	)
	(gr_line
		(start 96.807528 -213.51494)
		(end 97.096072 -213.764114)
		(stroke
			(width 0.06477)
			(type default)
		)
		(layer "F.Cu")
	)
	(gr_line
		(start 96.828102 -371.49913)
		(end 96.557592 -371.76964)
		(stroke
			(width 0.06477)
			(type default)
		)
		(layer "F.Cu")
	)
	(gr_line
		(start 96.849438 -216.183464)
		(end 96.82353 -215.920066)
		(stroke
			(width 0.06477)
			(type default)
		)
		(layer "F.Cu")
	)
	(gr_line
		(start 96.853502 -373.30253)
		(end 96.504252 -373.65178)
		(stroke
			(width 0.0508)
			(type default)
		)
		(layer "F.Cu")
	)
	(gr_line
		(start 96.987614 -392.977116)
		(end 96.976946 -392.977116)
		(stroke
			(width 0.0508)
			(type default)
		)
		(layer "F.Cu")
	)
	(gr_line
		(start 96.998282 -389.467344)
		(end 97.518982 -389.467344)
		(stroke
			(width 0.0635)
			(type default)
		)
		(layer "F.Cu")
	)
	(gr_line
		(start 96.998282 -386.003292)
		(end 97.518982 -386.003292)
		(stroke
			(width 0.0635)
			(type default)
		)
		(layer "F.Cu")
	)
	(gr_line
		(start 96.999552 -213.005416)
		(end 97.572068 -213.50097)
		(stroke
			(width 0.06477)
			(type default)
		)
		(layer "F.Cu")
	)
	(gr_line
		(start 97.040954 -294.336216)
		(end 97.507806 -294.070278)
		(stroke
			(width 0.06477)
			(type default)
		)
		(layer "F.Cu")
	)
	(gr_line
		(start 97.096072 -213.764114)
		(end 97.35947 -213.745064)
		(stroke
			(width 0.06477)
			(type default)
		)
		(layer "F.Cu")
	)
	(gr_line
		(start 97.144078 -216.425018)
		(end 96.849438 -216.183464)
		(stroke
			(width 0.06477)
			(type default)
		)
		(layer "F.Cu")
	)
	(gr_line
		(start 97.144332 -393.292838)
		(end 97.144332 -393.133834)
		(stroke
			(width 0.0508)
			(type default)
		)
		(layer "F.Cu")
	)
	(gr_line
		(start 97.144332 -393.133834)
		(end 96.987614 -392.977116)
		(stroke
			(width 0.0508)
			(type default)
		)
		(layer "F.Cu")
	)
	(gr_line
		(start 97.144332 -392.59383)
		(end 96.978216 -392.759946)
		(stroke
			(width 0.0508)
			(type default)
		)
		(layer "F.Cu")
	)
	(gr_line
		(start 97.144332 -392.429238)
		(end 97.144332 -392.59383)
		(stroke
			(width 0.0508)
			(type default)
		)
		(layer "F.Cu")
	)
	(gr_line
		(start 97.407222 -216.399364)
		(end 97.144078 -216.425018)
		(stroke
			(width 0.06477)
			(type default)
		)
		(layer "F.Cu")
	)
	(gr_line
		(start 97.507806 -295.69029)
		(end 97.816416 -295.9989)
		(stroke
			(width 0.06477)
			(type default)
		)
		(layer "F.Cu")
	)
	(gr_line
		(start 97.613216 -216.149428)
		(end 97.028 -215.669114)
		(stroke
			(width 0.06477)
			(type default)
		)
		(layer "F.Cu")
	)
	(gr_line
		(start 97.640902 -370.83873)
		(end 97.990152 -371.18798)
		(stroke
			(width 0.0508)
			(type default)
		)
		(layer "F.Cu")
	)
	(gr_line
		(start 97.64903 -213.995762)
		(end 97.66808 -214.259668)
		(stroke
			(width 0.06477)
			(type default)
		)
		(layer "F.Cu")
	)
	(gr_line
		(start 97.666302 -369.03533)
		(end 97.936812 -369.30584)
		(stroke
			(width 0.06477)
			(type default)
		)
		(layer "F.Cu")
	)
	(gr_line
		(start 97.66808 -214.259668)
		(end 97.95637 -214.508842)
		(stroke
			(width 0.06477)
			(type default)
		)
		(layer "F.Cu")
	)
	(gr_line
		(start 97.681034 -247.724422)
		(end 98.147886 -247.99036)
		(stroke
			(width 0.06477)
			(type default)
		)
		(layer "F.Cu")
	)
	(gr_line
		(start 97.681034 -246.10441)
		(end 98.147886 -246.370348)
		(stroke
			(width 0.06477)
			(type default)
		)
		(layer "F.Cu")
	)
	(gr_line
		(start 97.681034 -244.484398)
		(end 98.147886 -244.750336)
		(stroke
			(width 0.06477)
			(type default)
		)
		(layer "F.Cu")
	)
	(gr_line
		(start 97.72904 -391.36447)
		(end 97.645728 -391.281158)
		(stroke
			(width 0.0508)
			(type default)
		)
		(layer "F.Cu")
	)
	(gr_line
		(start 97.72904 -383.319274)
		(end 97.645728 -383.402586)
		(stroke
			(width 0.0508)
			(type default)
		)
		(layer "F.Cu")
	)
	(gr_line
		(start 97.72904 -216.905586)
		(end 97.703132 -216.642188)
		(stroke
			(width 0.06477)
			(type default)
		)
		(layer "F.Cu")
	)
	(gr_line
		(start 97.798382 -388.774432)
		(end 98.319082 -388.774432)
		(stroke
			(width 0.0635)
			(type default)
		)
		(layer "F.Cu")
	)
	(gr_line
		(start 97.798382 -385.31038)
		(end 98.319082 -385.31038)
		(stroke
			(width 0.0635)
			(type default)
		)
		(layer "F.Cu")
	)
	(gr_line
		(start 97.860104 -213.750144)
		(end 98.43262 -214.245698)
		(stroke
			(width 0.06477)
			(type default)
		)
		(layer "F.Cu")
	)
	(gr_line
		(start 97.936812 -370.00942)
		(end 97.640902 -370.30533)
		(stroke
			(width 0.06477)
			(type default)
		)
		(layer "F.Cu")
	)
	(gr_line
		(start 97.94621 -391.36574)
		(end 97.94621 -390.761982)
		(stroke
			(width 0.0508)
			(type default)
		)
		(layer "F.Cu")
	)
	(gr_line
		(start 97.94621 -390.761982)
		(end 97.945702 -390.761474)
		(stroke
			(width 0.0508)
			(type default)
		)
		(layer "F.Cu")
	)
	(gr_line
		(start 97.94621 -383.921762)
		(end 97.945702 -383.92227)
		(stroke
			(width 0.0508)
			(type default)
		)
		(layer "F.Cu")
	)
	(gr_line
		(start 97.94621 -383.318004)
		(end 97.94621 -383.921762)
		(stroke
			(width 0.0508)
			(type default)
		)
		(layer "F.Cu")
	)
	(gr_line
		(start 97.95637 -214.508842)
		(end 98.220022 -214.489792)
		(stroke
			(width 0.06477)
			(type default)
		)
		(layer "F.Cu")
	)
	(gr_line
		(start 97.981008 -294.336216)
		(end 98.44786 -294.070278)
		(stroke
			(width 0.06477)
			(type default)
		)
		(layer "F.Cu")
	)
	(gr_line
		(start 97.981008 -278.13635)
		(end 98.44786 -277.870412)
		(stroke
			(width 0.06477)
			(type default)
		)
		(layer "F.Cu")
	)
	(gr_line
		(start 97.981008 -276.516338)
		(end 98.44786 -276.2504)
		(stroke
			(width 0.06477)
			(type default)
		)
		(layer "F.Cu")
	)
	(gr_line
		(start 97.981008 -274.896326)
		(end 98.44786 -274.630388)
		(stroke
			(width 0.06477)
			(type default)
		)
		(layer "F.Cu")
	)
	(gr_line
		(start 97.981008 -273.276314)
		(end 98.44786 -273.010376)
		(stroke
			(width 0.06477)
			(type default)
		)
		(layer "F.Cu")
	)
	(gr_line
		(start 97.981008 -271.656302)
		(end 98.44786 -271.390364)
		(stroke
			(width 0.06477)
			(type default)
		)
		(layer "F.Cu")
	)
	(gr_line
		(start 97.981008 -270.03629)
		(end 98.44786 -269.770352)
		(stroke
			(width 0.06477)
			(type default)
		)
		(layer "F.Cu")
	)
	(gr_line
		(start 98.02368 -217.14714)
		(end 97.72904 -216.905586)
		(stroke
			(width 0.06477)
			(type default)
		)
		(layer "F.Cu")
	)
	(gr_line
		(start 98.060764 -207.228948)
		(end 97.790254 -207.499458)
		(stroke
			(width 0.06477)
			(type default)
		)
		(layer "F.Cu")
	)
	(gr_line
		(start 98.060764 -206.906368)
		(end 97.790254 -206.635858)
		(stroke
			(width 0.06477)
			(type default)
		)
		(layer "F.Cu")
	)
	(gr_line
		(start 98.189034 -392.977116)
		(end 98.182938 -392.977116)
		(stroke
			(width 0.0508)
			(type default)
		)
		(layer "F.Cu")
	)
	(gr_line
		(start 98.198432 -389.467344)
		(end 98.719132 -389.467344)
		(stroke
			(width 0.0635)
			(type default)
		)
		(layer "F.Cu")
	)
	(gr_line
		(start 98.198432 -386.003292)
		(end 98.719132 -386.003292)
		(stroke
			(width 0.0635)
			(type default)
		)
		(layer "F.Cu")
	)
	(gr_line
		(start 98.259392 -370.00942)
		(end 98.555302 -370.30533)
		(stroke
			(width 0.06477)
			(type default)
		)
		(layer "F.Cu")
	)
	(gr_line
		(start 98.287078 -217.121486)
		(end 98.02368 -217.14714)
		(stroke
			(width 0.06477)
			(type default)
		)
		(layer "F.Cu")
	)
	(gr_line
		(start 98.344228 -393.292838)
		(end 98.344228 -393.13231)
		(stroke
			(width 0.0508)
			(type default)
		)
		(layer "F.Cu")
	)
	(gr_line
		(start 98.344228 -393.13231)
		(end 98.189034 -392.977116)
		(stroke
			(width 0.0508)
			(type default)
		)
		(layer "F.Cu")
	)
	(gr_line
		(start 98.344228 -392.599926)
		(end 98.184208 -392.759946)
		(stroke
			(width 0.0508)
			(type default)
		)
		(layer "F.Cu")
	)
	(gr_line
		(start 98.344228 -392.429238)
		(end 98.344228 -392.599926)
		(stroke
			(width 0.0508)
			(type default)
		)
		(layer "F.Cu")
	)
	(gr_line
		(start 98.44786 -295.69029)
		(end 98.138996 -295.999154)
		(stroke
			(width 0.06477)
			(type default)
		)
		(layer "F.Cu")
	)
	(gr_line
		(start 98.44786 -292.450266)
		(end 97.981008 -292.716204)
		(stroke
			(width 0.06477)
			(type default)
		)
		(layer "F.Cu")
	)
	(gr_line
		(start 98.44786 -290.830254)
		(end 97.981008 -291.096192)
		(stroke
			(width 0.06477)
			(type default)
		)
		(layer "F.Cu")
	)
	(gr_line
		(start 98.44786 -289.210242)
		(end 97.981008 -289.47618)
		(stroke
			(width 0.06477)
			(type default)
		)
		(layer "F.Cu")
	)
	(gr_line
		(start 98.44786 -287.590484)
		(end 97.981008 -287.856422)
		(stroke
			(width 0.06477)
			(type default)
		)
		(layer "F.Cu")
	)
	(gr_line
		(start 98.44786 -285.970472)
		(end 97.981008 -286.23641)
		(stroke
			(width 0.06477)
			(type default)
		)
		(layer "F.Cu")
	)
	(gr_line
		(start 98.44786 -284.35046)
		(end 97.981008 -284.616398)
		(stroke
			(width 0.06477)
			(type default)
		)
		(layer "F.Cu")
	)
	(gr_line
		(start 98.44786 -282.730448)
		(end 97.981008 -282.996386)
		(stroke
			(width 0.06477)
			(type default)
		)
		(layer "F.Cu")
	)
	(gr_line
		(start 98.44786 -281.110436)
		(end 97.981008 -281.376374)
		(stroke
			(width 0.06477)
			(type default)
		)
		(layer "F.Cu")
	)
	(gr_line
		(start 98.493072 -216.87155)
		(end 97.907602 -216.390982)
		(stroke
			(width 0.06477)
			(type default)
		)
		(layer "F.Cu")
	)
	(gr_line
		(start 98.509582 -214.74049)
		(end 98.528632 -215.004396)
		(stroke
			(width 0.06477)
			(type default)
		)
		(layer "F.Cu")
	)
	(gr_line
		(start 98.528632 -215.004396)
		(end 98.816922 -215.25357)
		(stroke
			(width 0.06477)
			(type default)
		)
		(layer "F.Cu")
	)
	(gr_line
		(start 98.529902 -369.03533)
		(end 98.259392 -369.30584)
		(stroke
			(width 0.06477)
			(type default)
		)
		(layer "F.Cu")
	)
	(gr_line
		(start 98.555302 -370.83873)
		(end 98.206052 -371.18798)
		(stroke
			(width 0.0508)
			(type default)
		)
		(layer "F.Cu")
	)
	(gr_line
		(start 98.621088 -247.724422)
		(end 99.08794 -247.99036)
		(stroke
			(width 0.06477)
			(type default)
		)
		(layer "F.Cu")
	)
	(gr_line
		(start 98.621088 -246.10441)
		(end 99.08794 -246.370348)
		(stroke
			(width 0.06477)
			(type default)
		)
		(layer "F.Cu")
	)
	(gr_line
		(start 98.621088 -244.484398)
		(end 99.08794 -244.750336)
		(stroke
			(width 0.06477)
			(type default)
		)
		(layer "F.Cu")
	)
	(gr_line
		(start 98.720656 -214.494872)
		(end 99.293426 -214.990426)
		(stroke
			(width 0.06477)
			(type default)
		)
		(layer "F.Cu")
	)
	(gr_line
		(start 98.816922 -215.25357)
		(end 99.080574 -215.23452)
		(stroke
			(width 0.06477)
			(type default)
		)
		(layer "F.Cu")
	)
	(gr_line
		(start 98.921062 -278.13635)
		(end 99.387914 -277.870412)
		(stroke
			(width 0.06477)
			(type default)
		)
		(layer "F.Cu")
	)
	(gr_line
		(start 98.921062 -276.516338)
		(end 99.387914 -276.2504)
		(stroke
			(width 0.06477)
			(type default)
		)
		(layer "F.Cu")
	)
	(gr_line
		(start 98.921062 -274.896326)
		(end 99.387914 -274.630388)
		(stroke
			(width 0.06477)
			(type default)
		)
		(layer "F.Cu")
	)
	(gr_line
		(start 98.921062 -273.276314)
		(end 99.387914 -273.010376)
		(stroke
			(width 0.06477)
			(type default)
		)
		(layer "F.Cu")
	)
	(gr_line
		(start 98.921062 -271.656302)
		(end 99.387914 -271.390364)
		(stroke
			(width 0.06477)
			(type default)
		)
		(layer "F.Cu")
	)
	(gr_line
		(start 98.921062 -270.03629)
		(end 99.387914 -269.770352)
		(stroke
			(width 0.06477)
			(type default)
		)
		(layer "F.Cu")
	)
	(gr_line
		(start 99.173538 -373.078502)
		(end 99.547426 -373.45239)
		(stroke
			(width 0.0508)
			(type default)
		)
		(layer "F.Cu")
	)
	(gr_line
		(start 99.273614 5.631434)
		(end 98.621342 5.813298)
		(stroke
			(width 0.06477)
			(type default)
		)
		(layer "F.Cu")
	)
	(gr_line
		(start 99.273614 6.495034)
		(end 98.621342 6.31317)
		(stroke
			(width 0.06477)
			(type default)
		)
		(layer "F.Cu")
	)
	(gr_line
		(start 99.32797 -372.925594)
		(end 99.484434 -372.925594)
		(stroke
			(width 0.0508)
			(type default)
		)
		(layer "F.Cu")
	)
	(gr_line
		(start 99.387914 -292.450266)
		(end 98.921062 -292.716204)
		(stroke
			(width 0.06477)
			(type default)
		)
		(layer "F.Cu")
	)
	(gr_line
		(start 99.387914 -290.830254)
		(end 98.921062 -291.096192)
		(stroke
			(width 0.06477)
			(type default)
		)
		(layer "F.Cu")
	)
	(gr_line
		(start 99.387914 -289.210242)
		(end 98.921062 -289.47618)
		(stroke
			(width 0.06477)
			(type default)
		)
		(layer "F.Cu")
	)
	(gr_line
		(start 99.387914 -287.590484)
		(end 98.921062 -287.856422)
		(stroke
			(width 0.06477)
			(type default)
		)
		(layer "F.Cu")
	)
	(gr_line
		(start 99.387914 -285.970472)
		(end 98.921062 -286.23641)
		(stroke
			(width 0.06477)
			(type default)
		)
		(layer "F.Cu")
	)
	(gr_line
		(start 99.387914 -284.35046)
		(end 98.921062 -284.616398)
		(stroke
			(width 0.06477)
			(type default)
		)
		(layer "F.Cu")
	)
	(gr_line
		(start 99.387914 -282.730448)
		(end 98.921062 -282.996386)
		(stroke
			(width 0.06477)
			(type default)
		)
		(layer "F.Cu")
	)
	(gr_line
		(start 99.387914 -281.110436)
		(end 98.921062 -281.376374)
		(stroke
			(width 0.06477)
			(type default)
		)
		(layer "F.Cu")
	)
	(gr_line
		(start 99.484434 -372.925594)
		(end 99.700334 -373.141494)
		(stroke
			(width 0.0508)
			(type default)
		)
		(layer "F.Cu")
	)
	(gr_line
		(start 99.700334 -373.141494)
		(end 99.700334 -373.297958)
		(stroke
			(width 0.0508)
			(type default)
		)
		(layer "F.Cu")
	)
	(gr_line
		(start 99.749356 -207.067658)
		(end 100.000054 -207.354678)
		(stroke
			(width 0.06477)
			(type default)
		)
		(layer "F.Cu")
	)
	(gr_line
		(start 99.767136 -206.803752)
		(end 99.749356 -207.067658)
		(stroke
			(width 0.06477)
			(type default)
		)
		(layer "F.Cu")
	)
	(gr_line
		(start 99.861116 -294.336216)
		(end 100.327968 -294.070278)
		(stroke
			(width 0.06477)
			(type default)
		)
		(layer "F.Cu")
	)
	(gr_line
		(start 99.905058 -209.464402)
		(end 99.932236 -209.201258)
		(stroke
			(width 0.06477)
			(type default)
		)
		(layer "F.Cu")
	)
	(gr_line
		(start 100.000054 -207.354678)
		(end 100.264214 -207.372458)
		(stroke
			(width 0.06477)
			(type default)
		)
		(layer "F.Cu")
	)
	(gr_line
		(start 100.00996 -206.589884)
		(end 100.508562 -207.15986)
		(stroke
			(width 0.06477)
			(type default)
		)
		(layer "F.Cu")
	)
	(gr_line
		(start 100.145342 -209.760312)
		(end 99.905058 -209.464402)
		(stroke
			(width 0.06477)
			(type default)
		)
		(layer "F.Cu")
	)
	(gr_line
		(start 100.40874 -209.787236)
		(end 100.145342 -209.760312)
		(stroke
			(width 0.06477)
			(type default)
		)
		(layer "F.Cu")
	)
	(gr_line
		(start 100.498402 -207.9244)
		(end 100.7491 -208.21142)
		(stroke
			(width 0.06477)
			(type default)
		)
		(layer "F.Cu")
	)
	(gr_line
		(start 100.500942 -247.724422)
		(end 100.967794 -247.99036)
		(stroke
			(width 0.06477)
			(type default)
		)
		(layer "F.Cu")
	)
	(gr_line
		(start 100.500942 -246.10441)
		(end 100.967794 -246.370348)
		(stroke
			(width 0.06477)
			(type default)
		)
		(layer "F.Cu")
	)
	(gr_line
		(start 100.500942 -244.484398)
		(end 100.967794 -244.750336)
		(stroke
			(width 0.06477)
			(type default)
		)
		(layer "F.Cu")
	)
	(gr_line
		(start 100.516182 -207.660494)
		(end 100.498402 -207.9244)
		(stroke
			(width 0.06477)
			(type default)
		)
		(layer "F.Cu")
	)
	(gr_line
		(start 100.622862 -210.347306)
		(end 100.65004 -210.084416)
		(stroke
			(width 0.06477)
			(type default)
		)
		(layer "F.Cu")
	)
	(gr_line
		(start 100.660454 -209.583782)
		(end 100.182934 -208.99628)
		(stroke
			(width 0.06477)
			(type default)
		)
		(layer "F.Cu")
	)
	(gr_line
		(start 100.7491 -208.21142)
		(end 101.01326 -208.2292)
		(stroke
			(width 0.06477)
			(type default)
		)
		(layer "F.Cu")
	)
	(gr_line
		(start 100.75926 -207.446626)
		(end 101.257862 -208.016602)
		(stroke
			(width 0.06477)
			(type default)
		)
		(layer "F.Cu")
	)
	(gr_line
		(start 100.7745 -379.708918)
		(end 100.66401 -379.819408)
		(stroke
			(width 0.0508)
			(type default)
		)
		(layer "F.Cu")
	)
	(gr_line
		(start 100.80117 -294.336216)
		(end 101.268022 -294.070278)
		(stroke
			(width 0.06477)
			(type default)
		)
		(layer "F.Cu")
	)
	(gr_line
		(start 100.80117 -278.13635)
		(end 101.268022 -277.870412)
		(stroke
			(width 0.06477)
			(type default)
		)
		(layer "F.Cu")
	)
	(gr_line
		(start 100.80117 -276.516338)
		(end 101.268022 -276.2504)
		(stroke
			(width 0.06477)
			(type default)
		)
		(layer "F.Cu")
	)
	(gr_line
		(start 100.80117 -274.896326)
		(end 101.268022 -274.630388)
		(stroke
			(width 0.06477)
			(type default)
		)
		(layer "F.Cu")
	)
	(gr_line
		(start 100.80117 -273.276314)
		(end 101.268022 -273.010376)
		(stroke
			(width 0.06477)
			(type default)
		)
		(layer "F.Cu")
	)
	(gr_line
		(start 100.80117 -271.656302)
		(end 101.268022 -271.390364)
		(stroke
			(width 0.06477)
			(type default)
		)
		(layer "F.Cu")
	)
	(gr_line
		(start 100.80117 -270.03629)
		(end 101.268022 -269.770352)
		(stroke
			(width 0.06477)
			(type default)
		)
		(layer "F.Cu")
	)
	(gr_line
		(start 100.8634 -210.643216)
		(end 100.622862 -210.347306)
		(stroke
			(width 0.06477)
			(type default)
		)
		(layer "F.Cu")
	)
	(gr_line
		(start 101.044502 -370.83873)
		(end 101.393752 -371.18798)
		(stroke
			(width 0.0508)
			(type default)
		)
		(layer "F.Cu")
	)
	(gr_line
		(start 101.069902 -369.03533)
		(end 101.340412 -369.30584)
		(stroke
			(width 0.06477)
			(type default)
		)
		(layer "F.Cu")
	)
	(gr_line
		(start 101.0793 -379.708918)
		(end 100.7745 -379.708918)
		(stroke
			(width 0.0508)
			(type default)
		)
		(layer "F.Cu")
	)
	(gr_line
		(start 101.126544 -210.670394)
		(end 100.8634 -210.643216)
		(stroke
			(width 0.06477)
			(type default)
		)
		(layer "F.Cu")
	)
	(gr_line
		(start 101.18979 -379.819408)
		(end 101.0793 -379.708918)
		(stroke
			(width 0.0508)
			(type default)
		)
		(layer "F.Cu")
	)
	(gr_line
		(start 101.19106 -380.036578)
		(end 100.66274 -380.036578)
		(stroke
			(width 0.0508)
			(type default)
		)
		(layer "F.Cu")
	)
	(gr_line
		(start 101.247702 -208.781142)
		(end 101.4984 -209.068162)
		(stroke
			(width 0.06477)
			(type default)
		)
		(layer "F.Cu")
	)
	(gr_line
		(start 101.265482 -208.517236)
		(end 101.247702 -208.781142)
		(stroke
			(width 0.06477)
			(type default)
		)
		(layer "F.Cu")
	)
	(gr_line
		(start 101.268022 -292.450266)
		(end 100.80117 -292.716204)
		(stroke
			(width 0.06477)
			(type default)
		)
		(layer "F.Cu")
	)
	(gr_line
		(start 101.268022 -290.830254)
		(end 100.80117 -291.096192)
		(stroke
			(width 0.06477)
			(type default)
		)
		(layer "F.Cu")
	)
	(gr_line
		(start 101.268022 -289.210242)
		(end 100.80117 -289.47618)
		(stroke
			(width 0.06477)
			(type default)
		)
		(layer "F.Cu")
	)
	(gr_line
		(start 101.268022 -287.590484)
		(end 100.80117 -287.856422)
		(stroke
			(width 0.06477)
			(type default)
		)
		(layer "F.Cu")
	)
	(gr_line
		(start 101.268022 -285.970472)
		(end 100.80117 -286.23641)
		(stroke
			(width 0.06477)
			(type default)
		)
		(layer "F.Cu")
	)
	(gr_line
		(start 101.268022 -284.35046)
		(end 100.80117 -284.616398)
		(stroke
			(width 0.06477)
			(type default)
		)
		(layer "F.Cu")
	)
	(gr_line
		(start 101.268022 -282.730448)
		(end 100.80117 -282.996386)
		(stroke
			(width 0.06477)
			(type default)
		)
		(layer "F.Cu")
	)
	(gr_line
		(start 101.268022 -281.110436)
		(end 100.80117 -281.376374)
		(stroke
			(width 0.06477)
			(type default)
		)
		(layer "F.Cu")
	)
	(gr_line
		(start 101.340412 -370.00942)
		(end 101.044502 -370.30533)
		(stroke
			(width 0.06477)
			(type default)
		)
		(layer "F.Cu")
	)
	(gr_line
		(start 101.34092 -211.230464)
		(end 101.368098 -210.967574)
		(stroke
			(width 0.06477)
			(type default)
		)
		(layer "F.Cu")
	)
	(gr_line
		(start 101.378512 -210.46694)
		(end 100.900738 -209.879184)
		(stroke
			(width 0.06477)
			(type default)
		)
		(layer "F.Cu")
	)
	(gr_line
		(start 101.440996 -247.724422)
		(end 101.907848 -247.99036)
		(stroke
			(width 0.06477)
			(type default)
		)
		(layer "F.Cu")
	)
	(gr_line
		(start 101.440996 -246.10441)
		(end 101.907848 -246.370348)
		(stroke
			(width 0.06477)
			(type default)
		)
		(layer "F.Cu")
	)
	(gr_line
		(start 101.440996 -244.484398)
		(end 101.907848 -244.750336)
		(stroke
			(width 0.06477)
			(type default)
		)
		(layer "F.Cu")
	)
	(gr_line
		(start 101.4984 -209.068162)
		(end 101.76256 -209.085942)
		(stroke
			(width 0.06477)
			(type default)
		)
		(layer "F.Cu")
	)
	(gr_line
		(start 101.50856 -208.303368)
		(end 102.006908 -208.873598)
		(stroke
			(width 0.06477)
			(type default)
		)
		(layer "F.Cu")
	)
	(gr_line
		(start 101.581458 -211.526374)
		(end 101.34092 -211.230464)
		(stroke
			(width 0.06477)
			(type default)
		)
		(layer "F.Cu")
	)
	(gr_line
		(start 101.609652 -371.527832)
		(end 101.609906 -371.527578)
		(stroke
			(width 0.0508)
			(type default)
		)
		(layer "F.Cu")
	)
	(gr_line
		(start 101.656896 -376.71883)
		(end 101.56698 -376.71883)
		(stroke
			(width 0.0508)
			(type default)
		)
		(layer "F.Cu")
	)
	(gr_line
		(start 101.662992 -370.00942)
		(end 101.958902 -370.30533)
		(stroke
			(width 0.06477)
			(type default)
		)
		(layer "F.Cu")
	)
	(gr_line
		(start 101.74097 -278.13635)
		(end 102.207822 -277.870412)
		(stroke
			(width 0.06477)
			(type default)
		)
		(layer "F.Cu")
	)
	(gr_line
		(start 101.74097 -276.516338)
		(end 102.207822 -276.2504)
		(stroke
			(width 0.06477)
			(type default)
		)
		(layer "F.Cu")
	)
	(gr_line
		(start 101.74097 -274.896326)
		(end 102.207822 -274.630388)
		(stroke
			(width 0.06477)
			(type default)
		)
		(layer "F.Cu")
	)
	(gr_line
		(start 101.74097 -273.276314)
		(end 102.207822 -273.010376)
		(stroke
			(width 0.06477)
			(type default)
		)
		(layer "F.Cu")
	)
	(gr_line
		(start 101.74097 -271.656302)
		(end 102.207822 -271.390364)
		(stroke
			(width 0.06477)
			(type default)
		)
		(layer "F.Cu")
	)
	(gr_line
		(start 101.74097 -270.03629)
		(end 102.207822 -269.770352)
		(stroke
			(width 0.06477)
			(type default)
		)
		(layer "F.Cu")
	)
	(gr_line
		(start 101.796596 -376.776742)
		(end 101.656896 -376.71883)
		(stroke
			(width 0.0508)
			(type default)
		)
		(layer "F.Cu")
	)
	(gr_line
		(start 101.844602 -211.553552)
		(end 101.581458 -211.526374)
		(stroke
			(width 0.06477)
			(type default)
		)
		(layer "F.Cu")
	)
	(gr_line
		(start 101.933502 -369.03533)
		(end 101.662992 -369.30584)
		(stroke
			(width 0.06477)
			(type default)
		)
		(layer "F.Cu")
	)
	(gr_line
		(start 101.958902 -370.83873)
		(end 101.609652 -371.18798)
		(stroke
			(width 0.0508)
			(type default)
		)
		(layer "F.Cu")
	)
	(gr_line
		(start 102.002082 -380.385828)
		(end 101.652832 -380.036578)
		(stroke
			(width 0.0508)
			(type default)
		)
		(layer "F.Cu")
	)
	(gr_line
		(start 102.002082 -379.471428)
		(end 101.652832 -379.820678)
		(stroke
			(width 0.0508)
			(type default)
		)
		(layer "F.Cu")
	)
	(gr_line
		(start 102.002082 -376.982228)
		(end 101.796596 -376.776742)
		(stroke
			(width 0.0508)
			(type default)
		)
		(layer "F.Cu")
	)
	(gr_line
		(start 102.002082 -376.067828)
		(end 101.56825 -376.50166)
		(stroke
			(width 0.0508)
			(type default)
		)
		(layer "F.Cu")
	)
	(gr_line
		(start 102.09657 -211.350098)
		(end 101.618796 -210.762342)
		(stroke
			(width 0.06477)
			(type default)
		)
		(layer "F.Cu")
	)
	(gr_line
		(start 102.207822 -292.450266)
		(end 101.74097 -292.716204)
		(stroke
			(width 0.06477)
			(type default)
		)
		(layer "F.Cu")
	)
	(gr_line
		(start 102.207822 -290.830254)
		(end 101.74097 -291.096192)
		(stroke
			(width 0.06477)
			(type default)
		)
		(layer "F.Cu")
	)
	(gr_line
		(start 102.207822 -289.210242)
		(end 101.74097 -289.47618)
		(stroke
			(width 0.06477)
			(type default)
		)
		(layer "F.Cu")
	)
	(gr_line
		(start 102.207822 -287.590484)
		(end 101.74097 -287.856422)
		(stroke
			(width 0.06477)
			(type default)
		)
		(layer "F.Cu")
	)
	(gr_line
		(start 102.207822 -285.970472)
		(end 101.74097 -286.23641)
		(stroke
			(width 0.06477)
			(type default)
		)
		(layer "F.Cu")
	)
	(gr_line
		(start 102.207822 -284.35046)
		(end 101.74097 -284.616398)
		(stroke
			(width 0.06477)
			(type default)
		)
		(layer "F.Cu")
	)
	(gr_line
		(start 102.207822 -282.730448)
		(end 101.74097 -282.996386)
		(stroke
			(width 0.06477)
			(type default)
		)
		(layer "F.Cu")
	)
	(gr_line
		(start 102.207822 -281.110436)
		(end 101.74097 -281.376374)
		(stroke
			(width 0.06477)
			(type default)
		)
		(layer "F.Cu")
	)
	(gr_line
		(start 102.324154 -372.904258)
		(end 102.698042 -373.278146)
		(stroke
			(width 0.0508)
			(type default)
		)
		(layer "F.Cu")
	)
	(gr_line
		(start 102.478332 -372.75135)
		(end 102.63505 -372.75135)
		(stroke
			(width 0.0508)
			(type default)
		)
		(layer "F.Cu")
	)
	(gr_line
		(start 102.63505 -372.75135)
		(end 102.85095 -372.96725)
		(stroke
			(width 0.0508)
			(type default)
		)
		(layer "F.Cu")
	)
	(gr_line
		(start 102.681024 -294.336216)
		(end 103.147876 -294.070278)
		(stroke
			(width 0.06477)
			(type default)
		)
		(layer "F.Cu")
	)
	(gr_line
		(start 102.831392 -380.089918)
		(end 102.535482 -380.385828)
		(stroke
			(width 0.06477)
			(type default)
		)
		(layer "F.Cu")
	)
	(gr_line
		(start 102.831392 -379.767338)
		(end 102.535482 -379.471428)
		(stroke
			(width 0.06477)
			(type default)
		)
		(layer "F.Cu")
	)
	(gr_line
		(start 102.831392 -376.686318)
		(end 102.535482 -376.982228)
		(stroke
			(width 0.06477)
			(type default)
		)
		(layer "F.Cu")
	)
	(gr_line
		(start 102.831392 -376.363738)
		(end 102.535482 -376.067828)
		(stroke
			(width 0.06477)
			(type default)
		)
		(layer "F.Cu")
	)
	(gr_line
		(start 102.845108 -409.293314)
		(end 102.574598 -409.563824)
		(stroke
			(width 0.06477)
			(type default)
		)
		(layer "F.Cu")
	)
	(gr_line
		(start 102.845108 -408.970734)
		(end 102.574598 -408.700224)
		(stroke
			(width 0.06477)
			(type default)
		)
		(layer "F.Cu")
	)
	(gr_line
		(start 102.847902 -223.690434)
		(end 102.38105 -223.424496)
		(stroke
			(width 0.06477)
			(type default)
		)
		(layer "F.Cu")
	)
	(gr_line
		(start 102.85095 -372.96725)
		(end 102.85095 -373.123968)
		(stroke
			(width 0.0508)
			(type default)
		)
		(layer "F.Cu")
	)
	(gr_line
		(start 103.156766 -221.322138)
		(end 103.156766 -221.303088)
		(stroke
			(width 0.0381)
			(type default)
		)
		(layer "F.Cu")
	)
	(gr_line
		(start 103.185722 -29.553154)
		(end 103.456232 -29.282644)
		(stroke
			(width 0.06477)
			(type default)
		)
		(layer "F.Cu")
	)
	(gr_line
		(start 103.222806 -221.388178)
		(end 103.156766 -221.322138)
		(stroke
			(width 0.0381)
			(type default)
		)
		(layer "F.Cu")
	)
	(gr_line
		(start 103.321104 -247.724422)
		(end 103.787956 -247.99036)
		(stroke
			(width 0.06477)
			(type default)
		)
		(layer "F.Cu")
	)
	(gr_line
		(start 103.321104 -246.10441)
		(end 103.787956 -246.370348)
		(stroke
			(width 0.06477)
			(type default)
		)
		(layer "F.Cu")
	)
	(gr_line
		(start 103.321104 -244.484398)
		(end 103.787956 -244.750336)
		(stroke
			(width 0.06477)
			(type default)
		)
		(layer "F.Cu")
	)
	(gr_line
		(start 103.321104 -225.044508)
		(end 103.787956 -225.310446)
		(stroke
			(width 0.06477)
			(type default)
		)
		(layer "F.Cu")
	)
	(gr_line
		(start 103.413306 -221.388178)
		(end 103.479346 -221.322138)
		(stroke
			(width 0.0381)
			(type default)
		)
		(layer "F.Cu")
	)
	(gr_line
		(start 103.456232 -29.282644)
		(end 103.185722 -29.553154)
		(stroke
			(width 0.06477)
			(type default)
		)
		(layer "F.Cu")
	)
	(gr_line
		(start 103.456232 -28.960064)
		(end 103.185722 -28.689554)
		(stroke
			(width 0.06477)
			(type default)
		)
		(layer "F.Cu")
	)
	(gr_line
		(start 103.479346 -221.322138)
		(end 103.479346 -221.303088)
		(stroke
			(width 0.0381)
			(type default)
		)
		(layer "F.Cu")
	)
	(gr_line
		(start 103.592376 -408.970734)
		(end 103.579676 -408.970734)
		(stroke
			(width 0.06477)
			(type default)
		)
		(layer "F.Cu")
	)
	(gr_line
		(start 103.621078 -294.336216)
		(end 104.08793 -294.070278)
		(stroke
			(width 0.06477)
			(type default)
		)
		(layer "F.Cu")
	)
	(gr_line
		(start 103.621078 -278.13635)
		(end 104.08793 -277.870412)
		(stroke
			(width 0.06477)
			(type default)
		)
		(layer "F.Cu")
	)
	(gr_line
		(start 103.621078 -276.516338)
		(end 104.08793 -276.2504)
		(stroke
			(width 0.06477)
			(type default)
		)
		(layer "F.Cu")
	)
	(gr_line
		(start 103.621078 -274.896326)
		(end 104.08793 -274.630388)
		(stroke
			(width 0.06477)
			(type default)
		)
		(layer "F.Cu")
	)
	(gr_line
		(start 103.621078 -273.276314)
		(end 104.08793 -273.010376)
		(stroke
			(width 0.06477)
			(type default)
		)
		(layer "F.Cu")
	)
	(gr_line
		(start 103.621078 -271.656302)
		(end 104.08793 -271.390364)
		(stroke
			(width 0.06477)
			(type default)
		)
		(layer "F.Cu")
	)
	(gr_line
		(start 103.621078 -270.03629)
		(end 104.08793 -269.770352)
		(stroke
			(width 0.06477)
			(type default)
		)
		(layer "F.Cu")
	)
	(gr_line
		(start 103.668576 -409.382214)
		(end 103.580946 -409.294584)
		(stroke
			(width 0.06477)
			(type default)
		)
		(layer "F.Cu")
	)
	(gr_line
		(start 103.681022 -408.882088)
		(end 103.592376 -408.970734)
		(stroke
			(width 0.06477)
			(type default)
		)
		(layer "F.Cu")
	)
	(gr_line
		(start 103.787956 -223.690434)
		(end 103.321104 -223.424496)
		(stroke
			(width 0.06477)
			(type default)
		)
		(layer "F.Cu")
	)
	(gr_line
		(start 103.805482 -380.360428)
		(end 103.534972 -380.089918)
		(stroke
			(width 0.06477)
			(type default)
		)
		(layer "F.Cu")
	)
	(gr_line
		(start 103.805482 -379.496828)
		(end 103.534972 -379.767338)
		(stroke
			(width 0.06477)
			(type default)
		)
		(layer "F.Cu")
	)
	(gr_line
		(start 103.805482 -376.956828)
		(end 103.534972 -376.686318)
		(stroke
			(width 0.06477)
			(type default)
		)
		(layer "F.Cu")
	)
	(gr_line
		(start 103.805482 -376.093228)
		(end 103.534972 -376.363738)
		(stroke
			(width 0.06477)
			(type default)
		)
		(layer "F.Cu")
	)
	(gr_line
		(start 103.871522 -409.382214)
		(end 103.668576 -409.382214)
		(stroke
			(width 0.06477)
			(type default)
		)
		(layer "F.Cu")
	)
	(gr_line
		(start 103.871522 -408.882088)
		(end 103.681022 -408.882088)
		(stroke
			(width 0.06477)
			(type default)
		)
		(layer "F.Cu")
	)
	(gr_line
		(start 103.971344 -223.365822)
		(end 103.966264 -223.362774)
		(stroke
			(width 0.0381)
			(type default)
		)
		(layer "F.Cu")
	)
	(gr_line
		(start 103.97236 -223.36633)
		(end 103.971344 -223.365822)
		(stroke
			(width 0.0381)
			(type default)
		)
		(layer "F.Cu")
	)
	(gr_line
		(start 103.973884 -223.367346)
		(end 103.97236 -223.36633)
		(stroke
			(width 0.0381)
			(type default)
		)
		(layer "F.Cu")
	)
	(gr_line
		(start 103.9749 -223.367854)
		(end 103.973884 -223.367346)
		(stroke
			(width 0.0381)
			(type default)
		)
		(layer "F.Cu")
	)
	(gr_arc
		(start 103.984044 -223.373188)
		(mid 103.986074 -223.374208)
		(end 103.988108 -223.37522)
		(stroke
			(width 0.0381)
			(type default)
		)
		(layer "F.Cu")
	)
	(gr_line
		(start 104.07015 -223.2025)
		(end 104.067356 -223.200976)
		(stroke
			(width 0.0381)
			(type default)
		)
		(layer "F.Cu")
	)
	(gr_line
		(start 104.070658 -223.202754)
		(end 104.07015 -223.2025)
		(stroke
			(width 0.0381)
			(type default)
		)
		(layer "F.Cu")
	)
	(gr_line
		(start 104.08793 -292.450266)
		(end 103.621078 -292.716204)
		(stroke
			(width 0.06477)
			(type default)
		)
		(layer "F.Cu")
	)
	(gr_line
		(start 104.08793 -290.830254)
		(end 103.621078 -291.096192)
		(stroke
			(width 0.06477)
			(type default)
		)
		(layer "F.Cu")
	)
	(gr_line
		(start 104.08793 -289.210242)
		(end 103.621078 -289.47618)
		(stroke
			(width 0.06477)
			(type default)
		)
		(layer "F.Cu")
	)
	(gr_line
		(start 104.08793 -287.590484)
		(end 103.621078 -287.856422)
		(stroke
			(width 0.06477)
			(type default)
		)
		(layer "F.Cu")
	)
	(gr_line
		(start 104.08793 -285.970472)
		(end 103.621078 -286.23641)
		(stroke
			(width 0.06477)
			(type default)
		)
		(layer "F.Cu")
	)
	(gr_line
		(start 104.08793 -284.35046)
		(end 103.621078 -284.616398)
		(stroke
			(width 0.06477)
			(type default)
		)
		(layer "F.Cu")
	)
	(gr_line
		(start 104.08793 -282.730448)
		(end 103.621078 -282.996386)
		(stroke
			(width 0.06477)
			(type default)
		)
		(layer "F.Cu")
	)
	(gr_line
		(start 104.261158 -247.724422)
		(end 104.72801 -247.99036)
		(stroke
			(width 0.06477)
			(type default)
		)
		(layer "F.Cu")
	)
	(gr_line
		(start 104.261158 -246.10441)
		(end 104.72801 -246.370348)
		(stroke
			(width 0.06477)
			(type default)
		)
		(layer "F.Cu")
	)
	(gr_line
		(start 104.261158 -244.484398)
		(end 104.72801 -244.750336)
		(stroke
			(width 0.06477)
			(type default)
		)
		(layer "F.Cu")
	)
	(gr_line
		(start 104.261158 -225.044508)
		(end 104.72801 -225.310446)
		(stroke
			(width 0.06477)
			(type default)
		)
		(layer "F.Cu")
	)
	(gr_line
		(start 104.269032 -32.325564)
		(end 103.998522 -32.055054)
		(stroke
			(width 0.06477)
			(type default)
		)
		(layer "F.Cu")
	)
	(gr_line
		(start 104.561132 -278.13635)
		(end 105.027984 -277.870412)
		(stroke
			(width 0.06477)
			(type default)
		)
		(layer "F.Cu")
	)
	(gr_line
		(start 104.561132 -276.516338)
		(end 105.027984 -276.2504)
		(stroke
			(width 0.06477)
			(type default)
		)
		(layer "F.Cu")
	)
	(gr_line
		(start 104.561132 -274.896326)
		(end 105.027984 -274.630388)
		(stroke
			(width 0.06477)
			(type default)
		)
		(layer "F.Cu")
	)
	(gr_line
		(start 104.561132 -273.276314)
		(end 105.027984 -273.010376)
		(stroke
			(width 0.06477)
			(type default)
		)
		(layer "F.Cu")
	)
	(gr_line
		(start 104.561132 -271.656302)
		(end 105.027984 -271.390364)
		(stroke
			(width 0.06477)
			(type default)
		)
		(layer "F.Cu")
	)
	(gr_line
		(start 104.561132 -270.03629)
		(end 105.027984 -269.770352)
		(stroke
			(width 0.06477)
			(type default)
		)
		(layer "F.Cu")
	)
	(gr_line
		(start 104.77373 -405.638508)
		(end 104.391714 -405.638508)
		(stroke
			(width 0.06477)
			(type default)
		)
		(layer "F.Cu")
	)
	(gr_arc
		(start 105.001822 -223.197674)
		(mid 104.999792 -223.196654)
		(end 104.997758 -223.195642)
		(stroke
			(width 0.0381)
			(type default)
		)
		(layer "F.Cu")
	)
	(gr_line
		(start 105.002584 -405.409654)
		(end 105.002584 -405.027638)
		(stroke
			(width 0.06477)
			(type default)
		)
		(layer "F.Cu")
	)
	(gr_line
		(start 105.003346 -405.410416)
		(end 105.002584 -405.409654)
		(stroke
			(width 0.06477)
			(type default)
		)
		(layer "F.Cu")
	)
	(gr_arc
		(start 105.010204 -223.2025)
		(mid 105.010585 -223.202754)
		(end 105.010966 -223.203008)
		(stroke
			(width 0.0381)
			(type default)
		)
		(layer "F.Cu")
	)
	(gr_line
		(start 105.027984 -292.450266)
		(end 104.561132 -292.716204)
		(stroke
			(width 0.06477)
			(type default)
		)
		(layer "F.Cu")
	)
	(gr_line
		(start 105.027984 -290.830254)
		(end 104.561132 -291.096192)
		(stroke
			(width 0.06477)
			(type default)
		)
		(layer "F.Cu")
	)
	(gr_line
		(start 105.027984 -289.210242)
		(end 104.561132 -289.47618)
		(stroke
			(width 0.06477)
			(type default)
		)
		(layer "F.Cu")
	)
	(gr_line
		(start 105.027984 -287.590484)
		(end 104.561132 -287.856422)
		(stroke
			(width 0.06477)
			(type default)
		)
		(layer "F.Cu")
	)
	(gr_line
		(start 105.027984 -285.970472)
		(end 104.561132 -286.23641)
		(stroke
			(width 0.06477)
			(type default)
		)
		(layer "F.Cu")
	)
	(gr_line
		(start 105.027984 -284.35046)
		(end 104.561132 -284.616398)
		(stroke
			(width 0.06477)
			(type default)
		)
		(layer "F.Cu")
	)
	(gr_line
		(start 105.027984 -282.730448)
		(end 104.561132 -282.996386)
		(stroke
			(width 0.06477)
			(type default)
		)
		(layer "F.Cu")
	)
	(gr_line
		(start 105.385108 -223.202754)
		(end 105.385616 -223.2025)
		(stroke
			(width 0.0381)
			(type default)
		)
		(layer "F.Cu")
	)
	(gr_arc
		(start 105.398062 -223.195642)
		(mid 105.396028 -223.196653)
		(end 105.393998 -223.197674)
		(stroke
			(width 0.0381)
			(type default)
		)
		(layer "F.Cu")
	)
	(gr_line
		(start 105.49636 -407.25725)
		(end 105.49636 -407.100786)
		(stroke
			(width 0.06477)
			(type default)
		)
		(layer "F.Cu")
	)
	(gr_line
		(start 105.49636 -407.100786)
		(end 105.585006 -407.01214)
		(stroke
			(width 0.06477)
			(type default)
		)
		(layer "F.Cu")
	)
	(gr_line
		(start 105.500932 -294.336216)
		(end 105.967784 -294.070278)
		(stroke
			(width 0.06477)
			(type default)
		)
		(layer "F.Cu")
	)
	(gr_line
		(start 105.585006 -407.01214)
		(end 105.585006 -406.998932)
		(stroke
			(width 0.06477)
			(type default)
		)
		(layer "F.Cu")
	)
	(gr_line
		(start 105.66781 -223.690434)
		(end 105.98531 -223.690434)
		(stroke
			(width 0.0381)
			(type default)
		)
		(layer "F.Cu")
	)
	(gr_line
		(start 105.967784 -295.69029)
		(end 106.276648 -295.999154)
		(stroke
			(width 0.06477)
			(type default)
		)
		(layer "F.Cu")
	)
	(gr_line
		(start 105.97642 -221.550738)
		(end 106.04246 -221.616778)
		(stroke
			(width 0.0381)
			(type default)
		)
		(layer "F.Cu")
	)
	(gr_line
		(start 105.97642 -221.531688)
		(end 105.97642 -221.550738)
		(stroke
			(width 0.0381)
			(type default)
		)
		(layer "F.Cu")
	)
	(gr_line
		(start 105.98531 -223.690434)
		(end 106.037888 -223.637856)
		(stroke
			(width 0.0381)
			(type default)
		)
		(layer "F.Cu")
	)
	(gr_line
		(start 105.996486 -407.25725)
		(end 105.996486 -407.087832)
		(stroke
			(width 0.06477)
			(type default)
		)
		(layer "F.Cu")
	)
	(gr_line
		(start 105.996486 -407.087832)
		(end 105.908856 -407.000202)
		(stroke
			(width 0.06477)
			(type default)
		)
		(layer "F.Cu")
	)
	(gr_arc
		(start 105.996486 -223.23044)
		(mid 105.993951 -223.228655)
		(end 105.991406 -223.226884)
		(stroke
			(width 0.0381)
			(type default)
		)
		(layer "F.Cu")
	)
	(gr_line
		(start 106.01071 -413.43453)
		(end 106.28122 -413.16402)
		(stroke
			(width 0.06477)
			(type default)
		)
		(layer "F.Cu")
	)
	(gr_line
		(start 106.047032 -220.83522)
		(end 106.100118 -220.881194)
		(stroke
			(width 0.06477)
			(type default)
		)
		(layer "F.Cu")
	)
	(gr_line
		(start 106.100372 -220.881194)
		(end 106.100118 -220.881194)
		(stroke
			(width 0.06477)
			(type default)
		)
		(layer "F.Cu")
	)
	(gr_line
		(start 106.100372 -220.881194)
		(end 106.129582 -220.944948)
		(stroke
			(width 0.06477)
			(type default)
		)
		(layer "F.Cu")
	)
	(gr_line
		(start 106.141012 -247.724422)
		(end 106.607864 -247.99036)
		(stroke
			(width 0.06477)
			(type default)
		)
		(layer "F.Cu")
	)
	(gr_line
		(start 106.141012 -246.10441)
		(end 106.607864 -246.370348)
		(stroke
			(width 0.06477)
			(type default)
		)
		(layer "F.Cu")
	)
	(gr_line
		(start 106.141012 -244.484398)
		(end 106.607864 -244.750336)
		(stroke
			(width 0.06477)
			(type default)
		)
		(layer "F.Cu")
	)
	(gr_arc
		(start 106.230166 -223.630236)
		(mid 106.228984 -223.620319)
		(end 106.227626 -223.610424)
		(stroke
			(width 0.0381)
			(type default)
		)
		(layer "F.Cu")
	)
	(gr_line
		(start 106.290364 -223.690434)
		(end 106.230166 -223.630236)
		(stroke
			(width 0.0381)
			(type default)
		)
		(layer "F.Cu")
	)
	(gr_line
		(start 106.299 -221.550738)
		(end 106.23296 -221.616778)
		(stroke
			(width 0.0381)
			(type default)
		)
		(layer "F.Cu")
	)
	(gr_line
		(start 106.299 -221.531688)
		(end 106.299 -221.550738)
		(stroke
			(width 0.0381)
			(type default)
		)
		(layer "F.Cu")
	)
	(gr_line
		(start 106.440986 -294.336216)
		(end 106.907838 -294.070278)
		(stroke
			(width 0.06477)
			(type default)
		)
		(layer "F.Cu")
	)
	(gr_line
		(start 106.440986 -279.756362)
		(end 106.907838 -279.490424)
		(stroke
			(width 0.06477)
			(type default)
		)
		(layer "F.Cu")
	)
	(gr_line
		(start 106.440986 -278.13635)
		(end 106.907838 -277.870412)
		(stroke
			(width 0.06477)
			(type default)
		)
		(layer "F.Cu")
	)
	(gr_line
		(start 106.440986 -276.516338)
		(end 106.907838 -276.2504)
		(stroke
			(width 0.06477)
			(type default)
		)
		(layer "F.Cu")
	)
	(gr_line
		(start 106.440986 -274.896326)
		(end 106.907838 -274.630388)
		(stroke
			(width 0.06477)
			(type default)
		)
		(layer "F.Cu")
	)
	(gr_line
		(start 106.440986 -273.276314)
		(end 106.907838 -273.010376)
		(stroke
			(width 0.06477)
			(type default)
		)
		(layer "F.Cu")
	)
	(gr_line
		(start 106.440986 -271.656302)
		(end 106.907838 -271.390364)
		(stroke
			(width 0.06477)
			(type default)
		)
		(layer "F.Cu")
	)
	(gr_line
		(start 106.440986 -270.03629)
		(end 106.907838 -269.770352)
		(stroke
			(width 0.06477)
			(type default)
		)
		(layer "F.Cu")
	)
	(gr_line
		(start 106.496358 -412.210504)
		(end 106.496358 -412.00705)
		(stroke
			(width 0.06477)
			(type default)
		)
		(layer "F.Cu")
	)
	(gr_line
		(start 106.583734 -412.29788)
		(end 106.496358 -412.210504)
		(stroke
			(width 0.06477)
			(type default)
		)
		(layer "F.Cu")
	)
	(gr_line
		(start 106.607864 -223.690434)
		(end 106.290364 -223.690434)
		(stroke
			(width 0.0381)
			(type default)
		)
		(layer "F.Cu")
	)
	(gr_line
		(start 106.87431 -413.43453)
		(end 106.6038 -413.16402)
		(stroke
			(width 0.06477)
			(type default)
		)
		(layer "F.Cu")
	)
	(gr_line
		(start 106.907584 -412.29915)
		(end 106.907584 -412.29407)
		(stroke
			(width 0.06477)
			(type default)
		)
		(layer "F.Cu")
	)
	(gr_line
		(start 106.907584 -412.29407)
		(end 106.996484 -412.20517)
		(stroke
			(width 0.06477)
			(type default)
		)
		(layer "F.Cu")
	)
	(gr_line
		(start 106.907838 -295.69029)
		(end 106.599228 -295.9989)
		(stroke
			(width 0.06477)
			(type default)
		)
		(layer "F.Cu")
	)
	(gr_line
		(start 106.907838 -292.450266)
		(end 106.440986 -292.716204)
		(stroke
			(width 0.06477)
			(type default)
		)
		(layer "F.Cu")
	)
	(gr_line
		(start 106.907838 -290.830254)
		(end 106.440986 -291.096192)
		(stroke
			(width 0.06477)
			(type default)
		)
		(layer "F.Cu")
	)
	(gr_line
		(start 106.907838 -289.210242)
		(end 106.440986 -289.47618)
		(stroke
			(width 0.06477)
			(type default)
		)
		(layer "F.Cu")
	)
	(gr_line
		(start 106.907838 -287.590484)
		(end 106.440986 -287.856422)
		(stroke
			(width 0.06477)
			(type default)
		)
		(layer "F.Cu")
	)
	(gr_line
		(start 106.907838 -285.970472)
		(end 106.440986 -286.23641)
		(stroke
			(width 0.06477)
			(type default)
		)
		(layer "F.Cu")
	)
	(gr_line
		(start 106.907838 -284.35046)
		(end 106.440986 -284.616398)
		(stroke
			(width 0.06477)
			(type default)
		)
		(layer "F.Cu")
	)
	(gr_line
		(start 106.907838 -282.730448)
		(end 106.440986 -282.996386)
		(stroke
			(width 0.06477)
			(type default)
		)
		(layer "F.Cu")
	)
	(gr_line
		(start 106.925364 -225.310446)
		(end 106.607864 -225.310446)
		(stroke
			(width 0.0381)
			(type default)
		)
		(layer "F.Cu")
	)
	(gr_line
		(start 106.985562 -225.250248)
		(end 106.925364 -225.310446)
		(stroke
			(width 0.0381)
			(type default)
		)
		(layer "F.Cu")
	)
	(gr_arc
		(start 106.988102 -225.230436)
		(mid 106.986744 -225.240331)
		(end 106.985562 -225.250248)
		(stroke
			(width 0.0381)
			(type default)
		)
		(layer "F.Cu")
	)
	(gr_line
		(start 106.996484 -412.20517)
		(end 106.996484 -412.00705)
		(stroke
			(width 0.06477)
			(type default)
		)
		(layer "F.Cu")
	)
	(gr_line
		(start 106.996484 -407.25725)
		(end 106.996484 -407.07437)
		(stroke
			(width 0.06477)
			(type default)
		)
		(layer "F.Cu")
	)
	(gr_line
		(start 106.996484 -407.07437)
		(end 107.08513 -406.985724)
		(stroke
			(width 0.06477)
			(type default)
		)
		(layer "F.Cu")
	)
	(gr_line
		(start 107.081066 -247.724422)
		(end 107.547918 -247.99036)
		(stroke
			(width 0.06477)
			(type default)
		)
		(layer "F.Cu")
	)
	(gr_line
		(start 107.081066 -246.10441)
		(end 107.547918 -246.370348)
		(stroke
			(width 0.06477)
			(type default)
		)
		(layer "F.Cu")
	)
	(gr_line
		(start 107.081066 -244.484398)
		(end 107.547918 -244.750336)
		(stroke
			(width 0.06477)
			(type default)
		)
		(layer "F.Cu")
	)
	(gr_line
		(start 107.08513 -406.985724)
		(end 107.08513 -406.975564)
		(stroke
			(width 0.06477)
			(type default)
		)
		(layer "F.Cu")
	)
	(gr_line
		(start 107.17784 -225.257868)
		(end 107.230418 -225.310446)
		(stroke
			(width 0.0381)
			(type default)
		)
		(layer "F.Cu")
	)
	(gr_arc
		(start 107.217972 -224.149412)
		(mid 107.221897 -224.152223)
		(end 107.225846 -224.155)
		(stroke
			(width 0.0381)
			(type default)
		)
		(layer "F.Cu")
	)
	(gr_line
		(start 107.225846 -224.155)
		(end 107.232704 -224.159064)
		(stroke
			(width 0.0381)
			(type default)
		)
		(layer "F.Cu")
	)
	(gr_line
		(start 107.230418 -225.310446)
		(end 107.547918 -225.310446)
		(stroke
			(width 0.0381)
			(type default)
		)
		(layer "F.Cu")
	)
	(gr_line
		(start 107.232704 -224.159064)
		(end 107.233466 -224.159572)
		(stroke
			(width 0.0381)
			(type default)
		)
		(layer "F.Cu")
	)
	(gr_line
		(start 107.233466 -224.159572)
		(end 107.234228 -224.16008)
		(stroke
			(width 0.0381)
			(type default)
		)
		(layer "F.Cu")
	)
	(gr_line
		(start 107.265216 -224.178114)
		(end 107.265724 -224.178368)
		(stroke
			(width 0.0381)
			(type default)
		)
		(layer "F.Cu")
	)
	(gr_line
		(start 107.265724 -224.178368)
		(end 107.269026 -224.180146)
		(stroke
			(width 0.0381)
			(type default)
		)
		(layer "F.Cu")
	)
	(gr_line
		(start 107.360212 -224.012506)
		(end 107.360974 -224.013014)
		(stroke
			(width 0.0381)
			(type default)
		)
		(layer "F.Cu")
	)
	(gr_line
		(start 107.38104 -279.756362)
		(end 107.847892 -279.490424)
		(stroke
			(width 0.06477)
			(type default)
		)
		(layer "F.Cu")
	)
	(gr_line
		(start 107.38104 -278.13635)
		(end 107.847892 -277.870412)
		(stroke
			(width 0.06477)
			(type default)
		)
		(layer "F.Cu")
	)
	(gr_line
		(start 107.38104 -276.516338)
		(end 107.847892 -276.2504)
		(stroke
			(width 0.06477)
			(type default)
		)
		(layer "F.Cu")
	)
	(gr_line
		(start 107.38104 -274.896326)
		(end 107.847892 -274.630388)
		(stroke
			(width 0.06477)
			(type default)
		)
		(layer "F.Cu")
	)
	(gr_line
		(start 107.38104 -273.276314)
		(end 107.847892 -273.010376)
		(stroke
			(width 0.06477)
			(type default)
		)
		(layer "F.Cu")
	)
	(gr_line
		(start 107.38104 -271.656302)
		(end 107.847892 -271.390364)
		(stroke
			(width 0.06477)
			(type default)
		)
		(layer "F.Cu")
	)
	(gr_line
		(start 107.38104 -270.03629)
		(end 107.847892 -269.770352)
		(stroke
			(width 0.06477)
			(type default)
		)
		(layer "F.Cu")
	)
	(gr_line
		(start 107.476036 -405.510492)
		(end 107.205526 -405.239982)
		(stroke
			(width 0.06477)
			(type default)
		)
		(layer "F.Cu")
	)
	(gr_line
		(start 107.496356 -407.25725)
		(end 107.496356 -407.06421)
		(stroke
			(width 0.06477)
			(type default)
		)
		(layer "F.Cu")
	)
	(gr_line
		(start 107.496356 -407.06421)
		(end 107.40898 -406.976834)
		(stroke
			(width 0.06477)
			(type default)
		)
		(layer "F.Cu")
	)
	(gr_line
		(start 107.798616 -405.510492)
		(end 108.069126 -405.239982)
		(stroke
			(width 0.06477)
			(type default)
		)
		(layer "F.Cu")
	)
	(gr_line
		(start 107.847892 -292.450266)
		(end 107.38104 -292.716204)
		(stroke
			(width 0.06477)
			(type default)
		)
		(layer "F.Cu")
	)
	(gr_line
		(start 107.847892 -290.830254)
		(end 107.38104 -291.096192)
		(stroke
			(width 0.06477)
			(type default)
		)
		(layer "F.Cu")
	)
	(gr_line
		(start 107.847892 -289.210242)
		(end 107.38104 -289.47618)
		(stroke
			(width 0.06477)
			(type default)
		)
		(layer "F.Cu")
	)
	(gr_line
		(start 107.847892 -287.590484)
		(end 107.38104 -287.856422)
		(stroke
			(width 0.06477)
			(type default)
		)
		(layer "F.Cu")
	)
	(gr_line
		(start 107.847892 -285.970472)
		(end 107.38104 -286.23641)
		(stroke
			(width 0.06477)
			(type default)
		)
		(layer "F.Cu")
	)
	(gr_line
		(start 107.847892 -284.35046)
		(end 107.38104 -284.616398)
		(stroke
			(width 0.06477)
			(type default)
		)
		(layer "F.Cu")
	)
	(gr_line
		(start 107.847892 -282.730448)
		(end 107.38104 -282.996386)
		(stroke
			(width 0.06477)
			(type default)
		)
		(layer "F.Cu")
	)
	(gr_line
		(start 108.065316 -30.66034)
		(end 108.152692 -30.747716)
		(stroke
			(width 0.06477)
			(type default)
		)
		(layer "F.Cu")
	)
	(gr_line
		(start 108.066586 -30.33649)
		(end 108.064046 -30.33649)
		(stroke
			(width 0.06477)
			(type default)
		)
		(layer "F.Cu")
	)
	(gr_line
		(start 108.152692 -30.747716)
		(end 108.065316 -30.66034)
		(stroke
			(width 0.06477)
			(type default)
		)
		(layer "F.Cu")
	)
	(gr_line
		(start 108.152692 -30.747716)
		(end 108.398818 -30.747716)
		(stroke
			(width 0.06477)
			(type default)
		)
		(layer "F.Cu")
	)
	(gr_line
		(start 108.154216 -32.747712)
		(end 108.06684 -32.835088)
		(stroke
			(width 0.06477)
			(type default)
		)
		(layer "F.Cu")
	)
	(gr_line
		(start 108.155232 -30.247844)
		(end 108.066586 -30.33649)
		(stroke
			(width 0.06477)
			(type default)
		)
		(layer "F.Cu")
	)
	(gr_line
		(start 108.382816 -387.789674)
		(end 108.653326 -387.519164)
		(stroke
			(width 0.06477)
			(type default)
		)
		(layer "F.Cu")
	)
	(gr_line
		(start 108.382816 -386.926074)
		(end 108.653326 -387.196584)
		(stroke
			(width 0.06477)
			(type default)
		)
		(layer "F.Cu")
	)
	(gr_line
		(start 108.398818 -32.747712)
		(end 108.154216 -32.747712)
		(stroke
			(width 0.06477)
			(type default)
		)
		(layer "F.Cu")
	)
	(gr_line
		(start 108.398818 -30.747716)
		(end 108.152692 -30.747716)
		(stroke
			(width 0.06477)
			(type default)
		)
		(layer "F.Cu")
	)
	(gr_line
		(start 108.398818 -30.247844)
		(end 108.155232 -30.247844)
		(stroke
			(width 0.06477)
			(type default)
		)
		(layer "F.Cu")
	)
	(gr_line
		(start 108.487972 -223.690434)
		(end 108.847382 -223.690434)
		(stroke
			(width 0.0381)
			(type default)
		)
		(layer "F.Cu")
	)
	(gr_line
		(start 108.49102 -248.534428)
		(end 108.957872 -248.800366)
		(stroke
			(width 0.06477)
			(type default)
		)
		(layer "F.Cu")
	)
	(gr_line
		(start 108.49102 -246.914416)
		(end 108.957872 -247.180354)
		(stroke
			(width 0.06477)
			(type default)
		)
		(layer "F.Cu")
	)
	(gr_line
		(start 108.49102 -245.294404)
		(end 108.957872 -245.560342)
		(stroke
			(width 0.06477)
			(type default)
		)
		(layer "F.Cu")
	)
	(gr_line
		(start 108.49102 -243.674392)
		(end 108.957872 -243.94033)
		(stroke
			(width 0.06477)
			(type default)
		)
		(layer "F.Cu")
	)
	(gr_line
		(start 108.530644 -382.36906)
		(end 108.801154 -382.09855)
		(stroke
			(width 0.06477)
			(type default)
		)
		(layer "F.Cu")
	)
	(gr_line
		(start 108.530644 -381.50546)
		(end 108.801154 -381.77597)
		(stroke
			(width 0.06477)
			(type default)
		)
		(layer "F.Cu")
	)
	(gr_line
		(start 108.530644 -376.83186)
		(end 108.801154 -376.56135)
		(stroke
			(width 0.06477)
			(type default)
		)
		(layer "F.Cu")
	)
	(gr_line
		(start 108.530644 -375.96826)
		(end 108.801154 -376.23877)
		(stroke
			(width 0.06477)
			(type default)
		)
		(layer "F.Cu")
	)
	(gr_line
		(start 108.621322 -409.382214)
		(end 108.839762 -409.382214)
		(stroke
			(width 0.06477)
			(type default)
		)
		(layer "F.Cu")
	)
	(gr_line
		(start 108.621322 -408.882088)
		(end 108.82884 -408.882088)
		(stroke
			(width 0.06477)
			(type default)
		)
		(layer "F.Cu")
	)
	(gr_line
		(start 108.787946 -295.69029)
		(end 109.09681 -295.999154)
		(stroke
			(width 0.06477)
			(type default)
		)
		(layer "F.Cu")
	)
	(gr_line
		(start 108.790994 -278.946356)
		(end 109.257846 -278.680418)
		(stroke
			(width 0.06477)
			(type default)
		)
		(layer "F.Cu")
	)
	(gr_line
		(start 108.790994 -277.326344)
		(end 109.257846 -277.060406)
		(stroke
			(width 0.06477)
			(type default)
		)
		(layer "F.Cu")
	)
	(gr_line
		(start 108.790994 -275.706332)
		(end 109.257846 -275.440394)
		(stroke
			(width 0.06477)
			(type default)
		)
		(layer "F.Cu")
	)
	(gr_line
		(start 108.790994 -274.08632)
		(end 109.257846 -273.820382)
		(stroke
			(width 0.06477)
			(type default)
		)
		(layer "F.Cu")
	)
	(gr_line
		(start 108.790994 -272.466308)
		(end 109.257846 -272.20037)
		(stroke
			(width 0.06477)
			(type default)
		)
		(layer "F.Cu")
	)
	(gr_line
		(start 108.790994 -270.846296)
		(end 109.257846 -270.580358)
		(stroke
			(width 0.06477)
			(type default)
		)
		(layer "F.Cu")
	)
	(gr_line
		(start 108.790994 -269.226284)
		(end 109.257846 -268.960346)
		(stroke
			(width 0.06477)
			(type default)
		)
		(layer "F.Cu")
	)
	(gr_line
		(start 108.796582 -221.7166)
		(end 108.796582 -221.69755)
		(stroke
			(width 0.0381)
			(type default)
		)
		(layer "F.Cu")
	)
	(gr_line
		(start 108.82884 -408.882088)
		(end 108.917486 -408.970734)
		(stroke
			(width 0.06477)
			(type default)
		)
		(layer "F.Cu")
	)
	(gr_line
		(start 108.839762 -409.382214)
		(end 108.927392 -409.294584)
		(stroke
			(width 0.06477)
			(type default)
		)
		(layer "F.Cu")
	)
	(gr_line
		(start 108.847382 -223.690434)
		(end 108.862622 -223.675194)
		(stroke
			(width 0.0381)
			(type default)
		)
		(layer "F.Cu")
	)
	(gr_arc
		(start 108.862622 -222.070422)
		(mid 108.924822 -222.328307)
		(end 109.097826 -222.5294)
		(stroke
			(width 0.0381)
			(type default)
		)
		(layer "F.Cu")
	)
	(gr_line
		(start 108.862622 -221.78264)
		(end 108.796582 -221.7166)
		(stroke
			(width 0.0381)
			(type default)
		)
		(layer "F.Cu")
	)
	(gr_line
		(start 108.917486 -408.970734)
		(end 108.928662 -408.970734)
		(stroke
			(width 0.06477)
			(type default)
		)
		(layer "F.Cu")
	)
	(gr_arc
		(start 109.053122 -222.070422)
		(mid 109.094415 -222.241364)
		(end 109.209078 -222.374714)
		(stroke
			(width 0.0381)
			(type default)
		)
		(layer "F.Cu")
	)
	(gr_line
		(start 109.053122 -221.78264)
		(end 109.119162 -221.7166)
		(stroke
			(width 0.0381)
			(type default)
		)
		(layer "F.Cu")
	)
	(gr_line
		(start 109.068362 -223.690434)
		(end 109.053122 -223.675194)
		(stroke
			(width 0.0381)
			(type default)
		)
		(layer "F.Cu")
	)
	(gr_line
		(start 109.116114 -387.519164)
		(end 109.361224 -387.764274)
		(stroke
			(width 0.06477)
			(type default)
		)
		(layer "F.Cu")
	)
	(gr_line
		(start 109.116114 -387.196584)
		(end 109.361224 -386.951474)
		(stroke
			(width 0.06477)
			(type default)
		)
		(layer "F.Cu")
	)
	(gr_line
		(start 109.119162 -221.7166)
		(end 109.119162 -221.69755)
		(stroke
			(width 0.0381)
			(type default)
		)
		(layer "F.Cu")
	)
	(gr_line
		(start 109.257846 -290.020248)
		(end 108.790994 -290.286186)
		(stroke
			(width 0.06477)
			(type default)
		)
		(layer "F.Cu")
	)
	(gr_line
		(start 109.257846 -288.400236)
		(end 108.790994 -288.666174)
		(stroke
			(width 0.06477)
			(type default)
		)
		(layer "F.Cu")
	)
	(gr_line
		(start 109.257846 -286.780478)
		(end 108.790994 -287.046162)
		(stroke
			(width 0.06477)
			(type default)
		)
		(layer "F.Cu")
	)
	(gr_line
		(start 109.257846 -285.160466)
		(end 108.790994 -285.426404)
		(stroke
			(width 0.06477)
			(type default)
		)
		(layer "F.Cu")
	)
	(gr_line
		(start 109.257846 -283.540454)
		(end 108.790994 -283.806392)
		(stroke
			(width 0.06477)
			(type default)
		)
		(layer "F.Cu")
	)
	(gr_line
		(start 109.257846 -281.920442)
		(end 108.790994 -282.18638)
		(stroke
			(width 0.06477)
			(type default)
		)
		(layer "F.Cu")
	)
	(gr_line
		(start 109.271562 -223.34982)
		(end 109.279182 -223.345502)
		(stroke
			(width 0.0381)
			(type default)
		)
		(layer "F.Cu")
	)
	(gr_line
		(start 109.27715 -222.41383)
		(end 109.271562 -222.410528)
		(stroke
			(width 0.0381)
			(type default)
		)
		(layer "F.Cu")
	)
	(gr_arc
		(start 109.279944 -223.344994)
		(mid 109.279563 -223.345248)
		(end 109.279182 -223.345502)
		(stroke
			(width 0.0381)
			(type default)
		)
		(layer "F.Cu")
	)
	(gr_arc
		(start 109.279944 -223.344994)
		(mid 109.283893 -223.342217)
		(end 109.287818 -223.339406)
		(stroke
			(width 0.0381)
			(type default)
		)
		(layer "F.Cu")
	)
	(gr_line
		(start 109.279944 -222.415862)
		(end 109.27715 -222.41383)
		(stroke
			(width 0.0381)
			(type default)
		)
		(layer "F.Cu")
	)
	(gr_arc
		(start 109.287818 -222.42145)
		(mid 109.283893 -222.418639)
		(end 109.279944 -222.415862)
		(stroke
			(width 0.0381)
			(type default)
		)
		(layer "F.Cu")
	)
	(gr_line
		(start 109.427772 -223.690434)
		(end 109.068362 -223.690434)
		(stroke
			(width 0.0381)
			(type default)
		)
		(layer "F.Cu")
	)
	(gr_line
		(start 109.431074 -248.534428)
		(end 109.897926 -248.800366)
		(stroke
			(width 0.06477)
			(type default)
		)
		(layer "F.Cu")
	)
	(gr_line
		(start 109.431074 -246.914416)
		(end 109.897926 -247.180354)
		(stroke
			(width 0.06477)
			(type default)
		)
		(layer "F.Cu")
	)
	(gr_line
		(start 109.431074 -245.294404)
		(end 109.897926 -245.560342)
		(stroke
			(width 0.06477)
			(type default)
		)
		(layer "F.Cu")
	)
	(gr_line
		(start 109.431074 -243.674392)
		(end 109.897926 -243.94033)
		(stroke
			(width 0.06477)
			(type default)
		)
		(layer "F.Cu")
	)
	(gr_line
		(start 109.504734 -382.09855)
		(end 109.800644 -382.39446)
		(stroke
			(width 0.06477)
			(type default)
		)
		(layer "F.Cu")
	)
	(gr_line
		(start 109.504734 -381.77597)
		(end 109.800644 -381.48006)
		(stroke
			(width 0.06477)
			(type default)
		)
		(layer "F.Cu")
	)
	(gr_line
		(start 109.504734 -376.56135)
		(end 109.800644 -376.85726)
		(stroke
			(width 0.06477)
			(type default)
		)
		(layer "F.Cu")
	)
	(gr_line
		(start 109.504734 -376.23877)
		(end 109.800644 -375.94286)
		(stroke
			(width 0.06477)
			(type default)
		)
		(layer "F.Cu")
	)
	(gr_line
		(start 109.728 -295.69029)
		(end 109.41939 -295.9989)
		(stroke
			(width 0.06477)
			(type default)
		)
		(layer "F.Cu")
	)
	(gr_line
		(start 109.731048 -278.946356)
		(end 110.1979 -278.680418)
		(stroke
			(width 0.06477)
			(type default)
		)
		(layer "F.Cu")
	)
	(gr_line
		(start 109.731048 -277.326344)
		(end 110.1979 -277.060406)
		(stroke
			(width 0.06477)
			(type default)
		)
		(layer "F.Cu")
	)
	(gr_line
		(start 109.731048 -275.706332)
		(end 110.1979 -275.440394)
		(stroke
			(width 0.06477)
			(type default)
		)
		(layer "F.Cu")
	)
	(gr_line
		(start 109.731048 -274.08632)
		(end 110.1979 -273.820382)
		(stroke
			(width 0.06477)
			(type default)
		)
		(layer "F.Cu")
	)
	(gr_line
		(start 109.731048 -272.466308)
		(end 110.1979 -272.20037)
		(stroke
			(width 0.06477)
			(type default)
		)
		(layer "F.Cu")
	)
	(gr_line
		(start 109.731048 -270.846296)
		(end 110.1979 -270.580358)
		(stroke
			(width 0.06477)
			(type default)
		)
		(layer "F.Cu")
	)
	(gr_line
		(start 109.731048 -269.226284)
		(end 110.1979 -268.960346)
		(stroke
			(width 0.06477)
			(type default)
		)
		(layer "F.Cu")
	)
	(gr_line
		(start 109.745272 -225.310446)
		(end 109.427772 -225.310446)
		(stroke
			(width 0.0381)
			(type default)
		)
		(layer "F.Cu")
	)
	(gr_line
		(start 109.80547 -225.250248)
		(end 109.745272 -225.310446)
		(stroke
			(width 0.0381)
			(type default)
		)
		(layer "F.Cu")
	)
	(gr_arc
		(start 109.80801 -225.230436)
		(mid 109.806652 -225.240331)
		(end 109.80547 -225.250248)
		(stroke
			(width 0.0381)
			(type default)
		)
		(layer "F.Cu")
	)
	(gr_line
		(start 109.894624 -387.764274)
		(end 110.139226 -387.519672)
		(stroke
			(width 0.06477)
			(type default)
		)
		(layer "F.Cu")
	)
	(gr_line
		(start 109.894624 -386.951474)
		(end 110.138972 -387.195822)
		(stroke
			(width 0.06477)
			(type default)
		)
		(layer "F.Cu")
	)
	(gr_line
		(start 109.997748 -225.257868)
		(end 110.050326 -225.310446)
		(stroke
			(width 0.0381)
			(type default)
		)
		(layer "F.Cu")
	)
	(gr_line
		(start 110.050326 -225.310446)
		(end 110.367826 -225.310446)
		(stroke
			(width 0.0381)
			(type default)
		)
		(layer "F.Cu")
	)
	(gr_line
		(start 110.08487 -224.82302)
		(end 110.083854 -224.823528)
		(stroke
			(width 0.0381)
			(type default)
		)
		(layer "F.Cu")
	)
	(gr_arc
		(start 110.08487 -224.82302)
		(mid 110.085251 -224.822766)
		(end 110.085632 -224.822512)
		(stroke
			(width 0.0381)
			(type default)
		)
		(layer "F.Cu")
	)
	(gr_line
		(start 110.089696 -373.30253)
		(end 110.438946 -373.65178)
		(stroke
			(width 0.0508)
			(type default)
		)
		(layer "F.Cu")
	)
	(gr_arc
		(start 110.098078 -224.815654)
		(mid 110.096044 -224.816665)
		(end 110.094014 -224.817686)
		(stroke
			(width 0.0381)
			(type default)
		)
		(layer "F.Cu")
	)
	(gr_line
		(start 110.115096 -371.49913)
		(end 110.385606 -371.76964)
		(stroke
			(width 0.06477)
			(type default)
		)
		(layer "F.Cu")
	)
	(gr_line
		(start 110.138972 -387.195822)
		(end 110.140496 -387.195822)
		(stroke
			(width 0.06477)
			(type default)
		)
		(layer "F.Cu")
	)
	(gr_line
		(start 110.18012 -224.988374)
		(end 110.17885 -224.989136)
		(stroke
			(width 0.0381)
			(type default)
		)
		(layer "F.Cu")
	)
	(gr_line
		(start 110.180628 -224.98812)
		(end 110.18012 -224.988374)
		(stroke
			(width 0.0381)
			(type default)
		)
		(layer "F.Cu")
	)
	(gr_line
		(start 110.1979 -290.020248)
		(end 109.731048 -290.286186)
		(stroke
			(width 0.06477)
			(type default)
		)
		(layer "F.Cu")
	)
	(gr_line
		(start 110.1979 -288.400236)
		(end 109.731048 -288.666174)
		(stroke
			(width 0.06477)
			(type default)
		)
		(layer "F.Cu")
	)
	(gr_line
		(start 110.1979 -286.780478)
		(end 109.731048 -287.046162)
		(stroke
			(width 0.06477)
			(type default)
		)
		(layer "F.Cu")
	)
	(gr_line
		(start 110.1979 -285.160466)
		(end 109.731048 -285.426404)
		(stroke
			(width 0.06477)
			(type default)
		)
		(layer "F.Cu")
	)
	(gr_line
		(start 110.1979 -283.540454)
		(end 109.731048 -283.806392)
		(stroke
			(width 0.06477)
			(type default)
		)
		(layer "F.Cu")
	)
	(gr_line
		(start 110.1979 -281.920442)
		(end 109.731048 -282.18638)
		(stroke
			(width 0.06477)
			(type default)
		)
		(layer "F.Cu")
	)
	(gr_line
		(start 110.334044 -382.39446)
		(end 110.683802 -382.044702)
		(stroke
			(width 0.0508)
			(type default)
		)
		(layer "F.Cu")
	)
	(gr_line
		(start 110.334044 -381.48006)
		(end 110.681516 -381.827532)
		(stroke
			(width 0.0508)
			(type default)
		)
		(layer "F.Cu")
	)
	(gr_line
		(start 110.334044 -376.85726)
		(end 110.703868 -376.487436)
		(stroke
			(width 0.0508)
			(type default)
		)
		(layer "F.Cu")
	)
	(gr_line
		(start 110.334044 -375.94286)
		(end 110.66145 -376.270266)
		(stroke
			(width 0.0508)
			(type default)
		)
		(layer "F.Cu")
	)
	(gr_line
		(start 110.385606 -372.47322)
		(end 110.089696 -372.76913)
		(stroke
			(width 0.06477)
			(type default)
		)
		(layer "F.Cu")
	)
	(gr_line
		(start 110.398052 -387.195822)
		(end 110.399576 -387.195822)
		(stroke
			(width 0.06477)
			(type default)
		)
		(layer "F.Cu")
	)
	(gr_line
		(start 110.399322 -387.519672)
		(end 110.643924 -387.764274)
		(stroke
			(width 0.06477)
			(type default)
		)
		(layer "F.Cu")
	)
	(gr_line
		(start 110.399576 -387.195822)
		(end 110.643924 -386.951474)
		(stroke
			(width 0.06477)
			(type default)
		)
		(layer "F.Cu")
	)
	(gr_line
		(start 110.643924 -387.764274)
		(end 110.899956 -387.508242)
		(stroke
			(width 0.06477)
			(type default)
		)
		(layer "F.Cu")
	)
	(gr_line
		(start 110.643924 -386.951474)
		(end 110.876842 -387.184392)
		(stroke
			(width 0.06477)
			(type default)
		)
		(layer "F.Cu")
	)
	(gr_line
		(start 110.66145 -376.270266)
		(end 110.705138 -376.270266)
		(stroke
			(width 0.0508)
			(type default)
		)
		(layer "F.Cu")
	)
	(gr_line
		(start 110.670594 -409.633166)
		(end 110.941104 -409.903676)
		(stroke
			(width 0.06477)
			(type default)
		)
		(layer "F.Cu")
	)
	(gr_line
		(start 110.670594 -409.310586)
		(end 110.941104 -409.040076)
		(stroke
			(width 0.06477)
			(type default)
		)
		(layer "F.Cu")
	)
	(gr_line
		(start 110.681516 -381.827532)
		(end 110.685072 -381.827532)
		(stroke
			(width 0.0508)
			(type default)
		)
		(layer "F.Cu")
	)
	(gr_line
		(start 110.708186 -372.47322)
		(end 111.004096 -372.76913)
		(stroke
			(width 0.06477)
			(type default)
		)
		(layer "F.Cu")
	)
	(gr_line
		(start 110.876842 -387.184392)
		(end 110.901226 -387.184392)
		(stroke
			(width 0.06477)
			(type default)
		)
		(layer "F.Cu")
	)
	(gr_line
		(start 110.978696 -371.49913)
		(end 110.708186 -371.76964)
		(stroke
			(width 0.06477)
			(type default)
		)
		(layer "F.Cu")
	)
	(gr_line
		(start 110.989872 -381.827532)
		(end 111.518192 -381.827532)
		(stroke
			(width 0.0508)
			(type default)
		)
		(layer "F.Cu")
	)
	(gr_line
		(start 110.991142 -382.044702)
		(end 111.101632 -382.155192)
		(stroke
			(width 0.0508)
			(type default)
		)
		(layer "F.Cu")
	)
	(gr_line
		(start 111.004096 -373.30253)
		(end 110.654846 -373.65178)
		(stroke
			(width 0.0508)
			(type default)
		)
		(layer "F.Cu")
	)
	(gr_line
		(start 111.101632 -382.155192)
		(end 111.406432 -382.155192)
		(stroke
			(width 0.0508)
			(type default)
		)
		(layer "F.Cu")
	)
	(gr_line
		(start 111.384842 -224.38741)
		(end 111.384842 -224.480882)
		(stroke
			(width 0.0381)
			(type default)
		)
		(layer "F.Cu")
	)
	(gr_line
		(start 111.398304 -224.373948)
		(end 111.384842 -224.38741)
		(stroke
			(width 0.0381)
			(type default)
		)
		(layer "F.Cu")
	)
	(gr_line
		(start 111.406432 -382.155192)
		(end 111.516922 -382.044702)
		(stroke
			(width 0.0508)
			(type default)
		)
		(layer "F.Cu")
	)
	(gr_line
		(start 111.613188 -224.615756)
		(end 111.519716 -224.615756)
		(stroke
			(width 0.0381)
			(type default)
		)
		(layer "F.Cu")
	)
	(gr_line
		(start 111.62665 -224.602294)
		(end 111.613188 -224.615756)
		(stroke
			(width 0.0381)
			(type default)
		)
		(layer "F.Cu")
	)
	(gr_line
		(start 111.62665 -224.602294)
		(end 111.626396 -224.602294)
		(stroke
			(width 0.0381)
			(type default)
		)
		(layer "F.Cu")
	)
	(gr_line
		(start 111.791496 -370.83873)
		(end 112.140746 -371.18798)
		(stroke
			(width 0.0508)
			(type default)
		)
		(layer "F.Cu")
	)
	(gr_line
		(start 111.816896 -369.03533)
		(end 112.087406 -369.30584)
		(stroke
			(width 0.06477)
			(type default)
		)
		(layer "F.Cu")
	)
	(gr_line
		(start 111.822992 -381.827532)
		(end 112.351312 -381.827532)
		(stroke
			(width 0.0508)
			(type default)
		)
		(layer "F.Cu")
	)
	(gr_line
		(start 111.824262 -382.044702)
		(end 111.934752 -382.155192)
		(stroke
			(width 0.0508)
			(type default)
		)
		(layer "F.Cu")
	)
	(gr_line
		(start 111.934752 -382.155192)
		(end 112.239552 -382.155192)
		(stroke
			(width 0.0508)
			(type default)
		)
		(layer "F.Cu")
	)
	(gr_line
		(start 112.087406 -370.00942)
		(end 111.791496 -370.30533)
		(stroke
			(width 0.06477)
			(type default)
		)
		(layer "F.Cu")
	)
	(gr_line
		(start 112.239552 -382.155192)
		(end 112.350042 -382.044702)
		(stroke
			(width 0.0508)
			(type default)
		)
		(layer "F.Cu")
	)
	(gr_line
		(start 112.409986 -370.00942)
		(end 112.705896 -370.30533)
		(stroke
			(width 0.06477)
			(type default)
		)
		(layer "F.Cu")
	)
	(gr_line
		(start 112.426496 -375.942098)
		(end 112.800384 -376.315986)
		(stroke
			(width 0.0508)
			(type default)
		)
		(layer "F.Cu")
	)
	(gr_line
		(start 112.435386 -378.53239)
		(end 112.551972 -378.81433)
		(stroke
			(width 0.0508)
			(type default)
		)
		(layer "F.Cu")
	)
	(gr_line
		(start 112.49533 -378.387864)
		(end 112.435386 -378.53239)
		(stroke
			(width 0.0508)
			(type default)
		)
		(layer "F.Cu")
	)
	(gr_line
		(start 112.551972 -378.81433)
		(end 112.696752 -378.87402)
		(stroke
			(width 0.0508)
			(type default)
		)
		(layer "F.Cu")
	)
	(gr_line
		(start 112.580674 -375.78919)
		(end 112.737392 -375.78919)
		(stroke
			(width 0.0508)
			(type default)
		)
		(layer "F.Cu")
	)
	(gr_line
		(start 112.597946 -387.531102)
		(end 113.201704 -387.531102)
		(stroke
			(width 0.0508)
			(type default)
		)
		(layer "F.Cu")
	)
	(gr_line
		(start 112.599216 -387.748272)
		(end 112.68202 -387.831076)
		(stroke
			(width 0.0508)
			(type default)
		)
		(layer "F.Cu")
	)
	(gr_line
		(start 112.680496 -369.03533)
		(end 112.409986 -369.30584)
		(stroke
			(width 0.06477)
			(type default)
		)
		(layer "F.Cu")
	)
	(gr_line
		(start 112.695736 -378.30379)
		(end 112.89792 -378.792232)
		(stroke
			(width 0.0508)
			(type default)
		)
		(layer "F.Cu")
	)
	(gr_line
		(start 112.705896 -370.83873)
		(end 112.356646 -371.18798)
		(stroke
			(width 0.0508)
			(type default)
		)
		(layer "F.Cu")
	)
	(gr_line
		(start 112.737392 -375.78919)
		(end 112.953292 -376.00509)
		(stroke
			(width 0.0508)
			(type default)
		)
		(layer "F.Cu")
	)
	(gr_line
		(start 112.953292 -376.00509)
		(end 112.953292 -376.161808)
		(stroke
			(width 0.0508)
			(type default)
		)
		(layer "F.Cu")
	)
	(gr_line
		(start 112.979962 -379.62967)
		(end 113.14938 -379.883162)
		(stroke
			(width 0.0508)
			(type default)
		)
		(layer "F.Cu")
	)
	(gr_line
		(start 113.010442 -379.476)
		(end 112.979962 -379.62967)
		(stroke
			(width 0.0508)
			(type default)
		)
		(layer "F.Cu")
	)
	(gr_line
		(start 113.13922 -372.921022)
		(end 113.513108 -373.294656)
		(stroke
			(width 0.0508)
			(type default)
		)
		(layer "F.Cu")
	)
	(gr_line
		(start 113.14938 -379.883162)
		(end 113.30305 -379.913896)
		(stroke
			(width 0.0508)
			(type default)
		)
		(layer "F.Cu")
	)
	(gr_line
		(start 113.190274 -379.354588)
		(end 113.190528 -379.354588)
		(stroke
			(width 0.0508)
			(type default)
		)
		(layer "F.Cu")
	)
	(gr_line
		(start 113.190528 -379.354588)
		(end 113.484152 -379.794008)
		(stroke
			(width 0.0508)
			(type default)
		)
		(layer "F.Cu")
	)
	(gr_line
		(start 113.293652 -372.768114)
		(end 113.450116 -372.768114)
		(stroke
			(width 0.0508)
			(type default)
		)
		(layer "F.Cu")
	)
	(gr_line
		(start 113.450116 -372.768114)
		(end 113.666016 -372.984014)
		(stroke
			(width 0.0508)
			(type default)
		)
		(layer "F.Cu")
	)
	(gr_line
		(start 113.461292 -26.774648)
		(end 113.548922 -26.862278)
		(stroke
			(width 0.06477)
			(type default)
		)
		(layer "F.Cu")
	)
	(gr_line
		(start 113.484152 -379.794008)
		(end 113.484152 -379.794262)
		(stroke
			(width 0.0508)
			(type default)
		)
		(layer "F.Cu")
	)
	(gr_line
		(start 113.513108 -373.294656)
		(end 113.513108 -373.29491)
		(stroke
			(width 0.0508)
			(type default)
		)
		(layer "F.Cu")
	)
	(gr_line
		(start 113.548922 -26.862278)
		(end 113.548922 -27.097736)
		(stroke
			(width 0.06477)
			(type default)
		)
		(layer "F.Cu")
	)
	(gr_line
		(start 113.666016 -372.984014)
		(end 113.666016 -373.140478)
		(stroke
			(width 0.0508)
			(type default)
		)
		(layer "F.Cu")
	)
	(gr_line
		(start 113.897156 -24.049736)
		(end 113.618772 -24.32812)
		(stroke
			(width 0.06477)
			(type default)
		)
		(layer "F.Cu")
	)
	(gr_line
		(start 113.915952 -383.50571)
		(end 114.007138 -383.596896)
		(stroke
			(width 0.0508)
			(type default)
		)
		(layer "F.Cu")
	)
	(gr_line
		(start 113.915952 -383.2352)
		(end 113.915952 -383.50571)
		(stroke
			(width 0.0508)
			(type default)
		)
		(layer "F.Cu")
	)
	(gr_line
		(start 113.957862 -278.680418)
		(end 114.424714 -278.946356)
		(stroke
			(width 0.06477)
			(type default)
		)
		(layer "F.Cu")
	)
	(gr_line
		(start 113.957862 -277.060406)
		(end 114.424714 -277.326344)
		(stroke
			(width 0.06477)
			(type default)
		)
		(layer "F.Cu")
	)
	(gr_line
		(start 113.957862 -275.440394)
		(end 114.424714 -275.706332)
		(stroke
			(width 0.06477)
			(type default)
		)
		(layer "F.Cu")
	)
	(gr_line
		(start 113.957862 -273.820382)
		(end 114.424714 -274.08632)
		(stroke
			(width 0.06477)
			(type default)
		)
		(layer "F.Cu")
	)
	(gr_line
		(start 113.957862 -272.20037)
		(end 114.424714 -272.466308)
		(stroke
			(width 0.06477)
			(type default)
		)
		(layer "F.Cu")
	)
	(gr_line
		(start 113.957862 -270.580358)
		(end 114.424714 -270.846296)
		(stroke
			(width 0.06477)
			(type default)
		)
		(layer "F.Cu")
	)
	(gr_line
		(start 113.957862 -268.960346)
		(end 114.424714 -269.226284)
		(stroke
			(width 0.06477)
			(type default)
		)
		(layer "F.Cu")
	)
	(gr_line
		(start 114.007138 -383.596896)
		(end 114.141504 -383.596896)
		(stroke
			(width 0.0508)
			(type default)
		)
		(layer "F.Cu")
	)
	(gr_line
		(start 114.048794 -27.097736)
		(end 114.048794 -26.87066)
		(stroke
			(width 0.06477)
			(type default)
		)
		(layer "F.Cu")
	)
	(gr_line
		(start 114.048794 -26.87066)
		(end 114.048794 -27.097736)
		(stroke
			(width 0.06477)
			(type default)
		)
		(layer "F.Cu")
	)
	(gr_line
		(start 114.048794 -26.87066)
		(end 114.137694 -26.78176)
		(stroke
			(width 0.06477)
			(type default)
		)
		(layer "F.Cu")
	)
	(gr_line
		(start 114.137694 -26.78176)
		(end 114.048794 -26.87066)
		(stroke
			(width 0.06477)
			(type default)
		)
		(layer "F.Cu")
	)
	(gr_line
		(start 114.137694 -26.78176)
		(end 114.137694 -26.77922)
		(stroke
			(width 0.06477)
			(type default)
		)
		(layer "F.Cu")
	)
	(gr_line
		(start 114.137694 -26.77922)
		(end 114.137694 -26.78176)
		(stroke
			(width 0.06477)
			(type default)
		)
		(layer "F.Cu")
	)
	(gr_line
		(start 114.141504 -383.596896)
		(end 114.217958 -383.520442)
		(stroke
			(width 0.0508)
			(type default)
		)
		(layer "F.Cu")
	)
	(gr_line
		(start 114.20729 -382.943862)
		(end 113.915952 -383.2352)
		(stroke
			(width 0.0508)
			(type default)
		)
		(layer "F.Cu")
	)
	(gr_line
		(start 114.217958 -383.520442)
		(end 114.217958 -383.402586)
		(stroke
			(width 0.0508)
			(type default)
		)
		(layer "F.Cu")
	)
	(gr_line
		(start 114.30127 -391.36447)
		(end 114.217958 -391.281158)
		(stroke
			(width 0.0508)
			(type default)
		)
		(layer "F.Cu")
	)
	(gr_line
		(start 114.370612 -388.774432)
		(end 114.891312 -388.774432)
		(stroke
			(width 0.0635)
			(type default)
		)
		(layer "F.Cu")
	)
	(gr_line
		(start 114.370612 -385.31038)
		(end 114.891312 -385.31038)
		(stroke
			(width 0.0635)
			(type default)
		)
		(layer "F.Cu")
	)
	(gr_line
		(start 114.42446 -383.13741)
		(end 114.517932 -383.230882)
		(stroke
			(width 0.0508)
			(type default)
		)
		(layer "F.Cu")
	)
	(gr_line
		(start 114.42446 -382.942592)
		(end 114.42446 -383.13741)
		(stroke
			(width 0.0508)
			(type default)
		)
		(layer "F.Cu")
	)
	(gr_line
		(start 114.424714 -290.286186)
		(end 113.957862 -290.020248)
		(stroke
			(width 0.06477)
			(type default)
		)
		(layer "F.Cu")
	)
	(gr_line
		(start 114.424714 -288.666174)
		(end 113.957862 -288.400236)
		(stroke
			(width 0.06477)
			(type default)
		)
		(layer "F.Cu")
	)
	(gr_line
		(start 114.424714 -287.046162)
		(end 113.957862 -286.780478)
		(stroke
			(width 0.06477)
			(type default)
		)
		(layer "F.Cu")
	)
	(gr_line
		(start 114.424714 -285.426404)
		(end 113.957862 -285.160466)
		(stroke
			(width 0.06477)
			(type default)
		)
		(layer "F.Cu")
	)
	(gr_line
		(start 114.424714 -283.806392)
		(end 113.957862 -283.540454)
		(stroke
			(width 0.06477)
			(type default)
		)
		(layer "F.Cu")
	)
	(gr_line
		(start 114.424714 -282.18638)
		(end 113.957862 -281.920442)
		(stroke
			(width 0.06477)
			(type default)
		)
		(layer "F.Cu")
	)
	(gr_line
		(start 114.461544 -26.78049)
		(end 114.54892 -26.867866)
		(stroke
			(width 0.06477)
			(type default)
		)
		(layer "F.Cu")
	)
	(gr_line
		(start 114.517932 -383.230882)
		(end 114.517932 -383.92227)
		(stroke
			(width 0.0508)
			(type default)
		)
		(layer "F.Cu")
	)
	(gr_line
		(start 114.51844 -391.36574)
		(end 114.51844 -390.761982)
		(stroke
			(width 0.0508)
			(type default)
		)
		(layer "F.Cu")
	)
	(gr_line
		(start 114.51844 -390.761982)
		(end 114.517932 -390.761474)
		(stroke
			(width 0.0508)
			(type default)
		)
		(layer "F.Cu")
	)
	(gr_line
		(start 114.54892 -26.867866)
		(end 114.54892 -27.097736)
		(stroke
			(width 0.06477)
			(type default)
		)
		(layer "F.Cu")
	)
	(gr_line
		(start 114.770662 -389.467344)
		(end 115.291362 -389.467344)
		(stroke
			(width 0.0635)
			(type default)
		)
		(layer "F.Cu")
	)
	(gr_line
		(start 114.770662 -386.003292)
		(end 115.291362 -386.003292)
		(stroke
			(width 0.0635)
			(type default)
		)
		(layer "F.Cu")
	)
	(gr_line
		(start 114.777774 -392.977116)
		(end 114.775742 -392.977116)
		(stroke
			(width 0.0508)
			(type default)
		)
		(layer "F.Cu")
	)
	(gr_line
		(start 114.833908 -22.532594)
		(end 115.095274 -22.79396)
		(stroke
			(width 0.06477)
			(type default)
		)
		(layer "F.Cu")
	)
	(gr_line
		(start 114.868706 -408.784044)
		(end 115.164616 -409.079954)
		(stroke
			(width 0.06477)
			(type default)
		)
		(layer "F.Cu")
	)
	(gr_line
		(start 114.894106 -404.46452)
		(end 115.164616 -404.73503)
		(stroke
			(width 0.06477)
			(type default)
		)
		(layer "F.Cu")
	)
	(gr_line
		(start 114.897916 -278.680418)
		(end 115.364768 -278.946356)
		(stroke
			(width 0.06477)
			(type default)
		)
		(layer "F.Cu")
	)
	(gr_line
		(start 114.897916 -277.060406)
		(end 115.364768 -277.326344)
		(stroke
			(width 0.06477)
			(type default)
		)
		(layer "F.Cu")
	)
	(gr_line
		(start 114.897916 -275.440394)
		(end 115.364768 -275.706332)
		(stroke
			(width 0.06477)
			(type default)
		)
		(layer "F.Cu")
	)
	(gr_line
		(start 114.897916 -273.820382)
		(end 115.364768 -274.08632)
		(stroke
			(width 0.06477)
			(type default)
		)
		(layer "F.Cu")
	)
	(gr_line
		(start 114.897916 -272.20037)
		(end 115.364768 -272.466308)
		(stroke
			(width 0.06477)
			(type default)
		)
		(layer "F.Cu")
	)
	(gr_line
		(start 114.897916 -270.580358)
		(end 115.364768 -270.846296)
		(stroke
			(width 0.06477)
			(type default)
		)
		(layer "F.Cu")
	)
	(gr_line
		(start 114.897916 -268.960346)
		(end 115.364768 -269.226284)
		(stroke
			(width 0.06477)
			(type default)
		)
		(layer "F.Cu")
	)
	(gr_line
		(start 114.916458 -393.292838)
		(end 114.916458 -393.1158)
		(stroke
			(width 0.0508)
			(type default)
		)
		(layer "F.Cu")
	)
	(gr_line
		(start 114.916458 -393.1158)
		(end 114.777774 -392.977116)
		(stroke
			(width 0.0508)
			(type default)
		)
		(layer "F.Cu")
	)
	(gr_line
		(start 114.916458 -392.6205)
		(end 114.777012 -392.759946)
		(stroke
			(width 0.0508)
			(type default)
		)
		(layer "F.Cu")
	)
	(gr_line
		(start 114.916458 -392.429238)
		(end 114.916458 -392.6205)
		(stroke
			(width 0.0508)
			(type default)
		)
		(layer "F.Cu")
	)
	(gr_line
		(start 115.095274 -22.812248)
		(end 115.095274 -22.79396)
		(stroke
			(width 0.06477)
			(type default)
		)
		(layer "F.Cu")
	)
	(gr_line
		(start 115.095274 -22.79396)
		(end 114.833908 -22.532594)
		(stroke
			(width 0.06477)
			(type default)
		)
		(layer "F.Cu")
	)
	(gr_line
		(start 115.095274 -22.79396)
		(end 115.095274 -22.812248)
		(stroke
			(width 0.06477)
			(type default)
		)
		(layer "F.Cu")
	)
	(gr_line
		(start 115.115848 -383.50571)
		(end 115.207034 -383.596896)
		(stroke
			(width 0.0508)
			(type default)
		)
		(layer "F.Cu")
	)
	(gr_line
		(start 115.115848 -383.2352)
		(end 115.115848 -383.50571)
		(stroke
			(width 0.0508)
			(type default)
		)
		(layer "F.Cu")
	)
	(gr_line
		(start 115.164616 -412.299658)
		(end 114.894106 -412.570168)
		(stroke
			(width 0.06477)
			(type default)
		)
		(layer "F.Cu")
	)
	(gr_line
		(start 115.164616 -407.954734)
		(end 114.868706 -408.250644)
		(stroke
			(width 0.06477)
			(type default)
		)
		(layer "F.Cu")
	)
	(gr_line
		(start 115.195096 -375.76633)
		(end 115.544346 -376.11558)
		(stroke
			(width 0.0508)
			(type default)
		)
		(layer "F.Cu")
	)
	(gr_line
		(start 115.207034 -383.596896)
		(end 115.3414 -383.596896)
		(stroke
			(width 0.0508)
			(type default)
		)
		(layer "F.Cu")
	)
	(gr_line
		(start 115.220496 -373.96293)
		(end 115.491006 -374.23344)
		(stroke
			(width 0.06477)
			(type default)
		)
		(layer "F.Cu")
	)
	(gr_line
		(start 115.3414 -383.596896)
		(end 115.417854 -383.520442)
		(stroke
			(width 0.0508)
			(type default)
		)
		(layer "F.Cu")
	)
	(gr_line
		(start 115.364768 -290.286186)
		(end 114.897916 -290.020248)
		(stroke
			(width 0.06477)
			(type default)
		)
		(layer "F.Cu")
	)
	(gr_line
		(start 115.364768 -288.666174)
		(end 114.897916 -288.400236)
		(stroke
			(width 0.06477)
			(type default)
		)
		(layer "F.Cu")
	)
	(gr_line
		(start 115.364768 -287.046162)
		(end 114.897916 -286.780478)
		(stroke
			(width 0.06477)
			(type default)
		)
		(layer "F.Cu")
	)
	(gr_line
		(start 115.364768 -285.426404)
		(end 114.897916 -285.160466)
		(stroke
			(width 0.06477)
			(type default)
		)
		(layer "F.Cu")
	)
	(gr_line
		(start 115.364768 -283.806392)
		(end 114.897916 -283.540454)
		(stroke
			(width 0.06477)
			(type default)
		)
		(layer "F.Cu")
	)
	(gr_line
		(start 115.364768 -282.18638)
		(end 114.897916 -281.920442)
		(stroke
			(width 0.06477)
			(type default)
		)
		(layer "F.Cu")
	)
	(gr_line
		(start 115.407186 -382.943862)
		(end 115.115848 -383.2352)
		(stroke
			(width 0.0508)
			(type default)
		)
		(layer "F.Cu")
	)
	(gr_line
		(start 115.417854 -383.520442)
		(end 115.417854 -383.402586)
		(stroke
			(width 0.0508)
			(type default)
		)
		(layer "F.Cu")
	)
	(gr_line
		(start 115.487196 -412.299658)
		(end 115.757706 -412.570168)
		(stroke
			(width 0.06477)
			(type default)
		)
		(layer "F.Cu")
	)
	(gr_line
		(start 115.487196 -407.954734)
		(end 115.783106 -408.250644)
		(stroke
			(width 0.06477)
			(type default)
		)
		(layer "F.Cu")
	)
	(gr_line
		(start 115.491006 -374.93702)
		(end 115.195096 -375.23293)
		(stroke
			(width 0.06477)
			(type default)
		)
		(layer "F.Cu")
	)
	(gr_line
		(start 115.501166 -391.36447)
		(end 115.417854 -391.281158)
		(stroke
			(width 0.0508)
			(type default)
		)
		(layer "F.Cu")
	)
	(gr_line
		(start 115.570508 -388.774432)
		(end 116.091208 -388.774432)
		(stroke
			(width 0.0635)
			(type default)
		)
		(layer "F.Cu")
	)
	(gr_line
		(start 115.570508 -385.31038)
		(end 116.091208 -385.31038)
		(stroke
			(width 0.0635)
			(type default)
		)
		(layer "F.Cu")
	)
	(gr_line
		(start 115.624356 -383.13741)
		(end 115.717828 -383.230882)
		(stroke
			(width 0.0508)
			(type default)
		)
		(layer "F.Cu")
	)
	(gr_line
		(start 115.624356 -382.942592)
		(end 115.624356 -383.13741)
		(stroke
			(width 0.0508)
			(type default)
		)
		(layer "F.Cu")
	)
	(gr_line
		(start 115.697508 -22.532594)
		(end 115.419124 -22.810978)
		(stroke
			(width 0.06477)
			(type default)
		)
		(layer "F.Cu")
	)
	(gr_line
		(start 115.717828 -383.230882)
		(end 115.717828 -383.92227)
		(stroke
			(width 0.0508)
			(type default)
		)
		(layer "F.Cu")
	)
	(gr_line
		(start 115.718336 -391.36574)
		(end 115.718336 -390.761982)
		(stroke
			(width 0.0508)
			(type default)
		)
		(layer "F.Cu")
	)
	(gr_line
		(start 115.718336 -390.761982)
		(end 115.717828 -390.761474)
		(stroke
			(width 0.0508)
			(type default)
		)
		(layer "F.Cu")
	)
	(gr_line
		(start 115.757706 -404.46452)
		(end 115.487196 -404.73503)
		(stroke
			(width 0.06477)
			(type default)
		)
		(layer "F.Cu")
	)
	(gr_line
		(start 115.783106 -408.784044)
		(end 115.487196 -409.079954)
		(stroke
			(width 0.06477)
			(type default)
		)
		(layer "F.Cu")
	)
	(gr_line
		(start 115.813586 -374.93702)
		(end 116.109496 -375.23293)
		(stroke
			(width 0.06477)
			(type default)
		)
		(layer "F.Cu")
	)
	(gr_line
		(start 115.970558 -389.467344)
		(end 116.491258 -389.467344)
		(stroke
			(width 0.0635)
			(type default)
		)
		(layer "F.Cu")
	)
	(gr_line
		(start 115.970558 -386.003292)
		(end 116.491258 -386.003292)
		(stroke
			(width 0.0635)
			(type default)
		)
		(layer "F.Cu")
	)
	(gr_line
		(start 115.97767 -392.977116)
		(end 115.975638 -392.977116)
		(stroke
			(width 0.0508)
			(type default)
		)
		(layer "F.Cu")
	)
	(gr_line
		(start 116.084096 -373.96293)
		(end 115.813586 -374.23344)
		(stroke
			(width 0.06477)
			(type default)
		)
		(layer "F.Cu")
	)
	(gr_line
		(start 116.109496 -375.76633)
		(end 115.760246 -376.11558)
		(stroke
			(width 0.0508)
			(type default)
		)
		(layer "F.Cu")
	)
	(gr_line
		(start 116.116354 -393.292838)
		(end 116.116354 -393.1158)
		(stroke
			(width 0.0508)
			(type default)
		)
		(layer "F.Cu")
	)
	(gr_line
		(start 116.116354 -393.1158)
		(end 115.97767 -392.977116)
		(stroke
			(width 0.0508)
			(type default)
		)
		(layer "F.Cu")
	)
	(gr_line
		(start 116.116354 -392.6205)
		(end 115.976908 -392.759946)
		(stroke
			(width 0.0508)
			(type default)
		)
		(layer "F.Cu")
	)
	(gr_line
		(start 116.116354 -392.429238)
		(end 116.116354 -392.6205)
		(stroke
			(width 0.0508)
			(type default)
		)
		(layer "F.Cu")
	)
	(gr_line
		(start 116.30787 -279.490424)
		(end 116.774722 -279.756362)
		(stroke
			(width 0.06477)
			(type default)
		)
		(layer "F.Cu")
	)
	(gr_line
		(start 116.30787 -277.870412)
		(end 116.774722 -278.13635)
		(stroke
			(width 0.06477)
			(type default)
		)
		(layer "F.Cu")
	)
	(gr_line
		(start 116.30787 -276.2504)
		(end 116.774722 -276.516338)
		(stroke
			(width 0.06477)
			(type default)
		)
		(layer "F.Cu")
	)
	(gr_line
		(start 116.30787 -274.630388)
		(end 116.774722 -274.896326)
		(stroke
			(width 0.06477)
			(type default)
		)
		(layer "F.Cu")
	)
	(gr_line
		(start 116.30787 -273.010376)
		(end 116.774722 -273.276314)
		(stroke
			(width 0.06477)
			(type default)
		)
		(layer "F.Cu")
	)
	(gr_line
		(start 116.30787 -271.390364)
		(end 116.774722 -271.656302)
		(stroke
			(width 0.06477)
			(type default)
		)
		(layer "F.Cu")
	)
	(gr_line
		(start 116.30787 -269.770352)
		(end 116.774722 -270.03629)
		(stroke
			(width 0.06477)
			(type default)
		)
		(layer "F.Cu")
	)
	(gr_line
		(start 116.315998 -383.50571)
		(end 116.407184 -383.596896)
		(stroke
			(width 0.0508)
			(type default)
		)
		(layer "F.Cu")
	)
	(gr_line
		(start 116.315998 -383.2352)
		(end 116.315998 -383.50571)
		(stroke
			(width 0.0508)
			(type default)
		)
		(layer "F.Cu")
	)
	(gr_line
		(start 116.35105 -377.606814)
		(end 116.686584 -378.015754)
		(stroke
			(width 0.0508)
			(type default)
		)
		(layer "F.Cu")
	)
	(gr_line
		(start 116.407184 -383.596896)
		(end 116.54155 -383.596896)
		(stroke
			(width 0.0508)
			(type default)
		)
		(layer "F.Cu")
	)
	(gr_line
		(start 116.519706 -377.470162)
		(end 116.675154 -377.485402)
		(stroke
			(width 0.0508)
			(type default)
		)
		(layer "F.Cu")
	)
	(gr_line
		(start 116.54155 -383.596896)
		(end 116.618004 -383.520442)
		(stroke
			(width 0.0508)
			(type default)
		)
		(layer "F.Cu")
	)
	(gr_line
		(start 116.607336 -382.943862)
		(end 116.315998 -383.2352)
		(stroke
			(width 0.0508)
			(type default)
		)
		(layer "F.Cu")
	)
	(gr_line
		(start 116.618004 -383.520442)
		(end 116.618004 -383.402586)
		(stroke
			(width 0.0508)
			(type default)
		)
		(layer "F.Cu")
	)
	(gr_line
		(start 116.675154 -377.485402)
		(end 116.868702 -377.721114)
		(stroke
			(width 0.0508)
			(type default)
		)
		(layer "F.Cu")
	)
	(gr_line
		(start 116.701316 -391.36447)
		(end 116.618004 -391.281158)
		(stroke
			(width 0.0508)
			(type default)
		)
		(layer "F.Cu")
	)
	(gr_line
		(start 116.770658 -388.774432)
		(end 117.291358 -388.774432)
		(stroke
			(width 0.0635)
			(type default)
		)
		(layer "F.Cu")
	)
	(gr_line
		(start 116.770658 -385.31038)
		(end 117.291358 -385.31038)
		(stroke
			(width 0.0635)
			(type default)
		)
		(layer "F.Cu")
	)
	(gr_line
		(start 116.774722 -291.096192)
		(end 116.30787 -290.830254)
		(stroke
			(width 0.06477)
			(type default)
		)
		(layer "F.Cu")
	)
	(gr_line
		(start 116.774722 -289.47618)
		(end 116.30787 -289.210242)
		(stroke
			(width 0.06477)
			(type default)
		)
		(layer "F.Cu")
	)
	(gr_line
		(start 116.774722 -287.856422)
		(end 116.30787 -287.590484)
		(stroke
			(width 0.06477)
			(type default)
		)
		(layer "F.Cu")
	)
	(gr_line
		(start 116.774722 -286.23641)
		(end 116.30787 -285.970472)
		(stroke
			(width 0.06477)
			(type default)
		)
		(layer "F.Cu")
	)
	(gr_line
		(start 116.774722 -284.616398)
		(end 116.30787 -284.35046)
		(stroke
			(width 0.06477)
			(type default)
		)
		(layer "F.Cu")
	)
	(gr_line
		(start 116.774722 -282.996386)
		(end 116.30787 -282.730448)
		(stroke
			(width 0.06477)
			(type default)
		)
		(layer "F.Cu")
	)
	(gr_line
		(start 116.824506 -383.13741)
		(end 116.917978 -383.230882)
		(stroke
			(width 0.0508)
			(type default)
		)
		(layer "F.Cu")
	)
	(gr_line
		(start 116.824506 -382.942592)
		(end 116.824506 -383.13741)
		(stroke
			(width 0.0508)
			(type default)
		)
		(layer "F.Cu")
	)
	(gr_line
		(start 116.868702 -377.721114)
		(end 116.853716 -377.87707)
		(stroke
			(width 0.0508)
			(type default)
		)
		(layer "F.Cu")
	)
	(gr_line
		(start 116.896896 -373.30253)
		(end 117.246146 -373.65178)
		(stroke
			(width 0.0508)
			(type default)
		)
		(layer "F.Cu")
	)
	(gr_line
		(start 116.917978 -383.230882)
		(end 116.917978 -383.92227)
		(stroke
			(width 0.0508)
			(type default)
		)
		(layer "F.Cu")
	)
	(gr_line
		(start 116.918486 -391.36574)
		(end 116.918486 -390.761982)
		(stroke
			(width 0.0508)
			(type default)
		)
		(layer "F.Cu")
	)
	(gr_line
		(start 116.918486 -390.761982)
		(end 116.917978 -390.761474)
		(stroke
			(width 0.0508)
			(type default)
		)
		(layer "F.Cu")
	)
	(gr_line
		(start 116.922296 -371.49913)
		(end 117.192806 -371.76964)
		(stroke
			(width 0.06477)
			(type default)
		)
		(layer "F.Cu")
	)
	(gr_line
		(start 117.170454 -389.467344)
		(end 117.691154 -389.467344)
		(stroke
			(width 0.0635)
			(type default)
		)
		(layer "F.Cu")
	)
	(gr_line
		(start 117.170454 -386.003292)
		(end 117.691154 -386.003292)
		(stroke
			(width 0.0635)
			(type default)
		)
		(layer "F.Cu")
	)
	(gr_line
		(start 117.17782 -392.977116)
		(end 117.175788 -392.977116)
		(stroke
			(width 0.0508)
			(type default)
		)
		(layer "F.Cu")
	)
	(gr_line
		(start 117.192806 -372.47322)
		(end 116.896896 -372.76913)
		(stroke
			(width 0.06477)
			(type default)
		)
		(layer "F.Cu")
	)
	(gr_line
		(start 117.246146 -374.529096)
		(end 117.246146 -375.057416)
		(stroke
			(width 0.0508)
			(type default)
		)
		(layer "F.Cu")
	)
	(gr_line
		(start 117.247924 -279.490424)
		(end 117.714776 -279.756362)
		(stroke
			(width 0.06477)
			(type default)
		)
		(layer "F.Cu")
	)
	(gr_line
		(start 117.247924 -277.870412)
		(end 117.714776 -278.13635)
		(stroke
			(width 0.06477)
			(type default)
		)
		(layer "F.Cu")
	)
	(gr_line
		(start 117.247924 -276.2504)
		(end 117.714776 -276.516338)
		(stroke
			(width 0.06477)
			(type default)
		)
		(layer "F.Cu")
	)
	(gr_line
		(start 117.247924 -274.630388)
		(end 117.714776 -274.896326)
		(stroke
			(width 0.06477)
			(type default)
		)
		(layer "F.Cu")
	)
	(gr_line
		(start 117.247924 -273.010376)
		(end 117.714776 -273.276314)
		(stroke
			(width 0.06477)
			(type default)
		)
		(layer "F.Cu")
	)
	(gr_line
		(start 117.247924 -271.390364)
		(end 117.714776 -271.656302)
		(stroke
			(width 0.06477)
			(type default)
		)
		(layer "F.Cu")
	)
	(gr_line
		(start 117.247924 -269.770352)
		(end 117.714776 -270.03629)
		(stroke
			(width 0.06477)
			(type default)
		)
		(layer "F.Cu")
	)
	(gr_line
		(start 117.316504 -393.292838)
		(end 117.316504 -393.1158)
		(stroke
			(width 0.0508)
			(type default)
		)
		(layer "F.Cu")
	)
	(gr_line
		(start 117.316504 -393.1158)
		(end 117.17782 -392.977116)
		(stroke
			(width 0.0508)
			(type default)
		)
		(layer "F.Cu")
	)
	(gr_line
		(start 117.316504 -392.6205)
		(end 117.177058 -392.759946)
		(stroke
			(width 0.0508)
			(type default)
		)
		(layer "F.Cu")
	)
	(gr_line
		(start 117.316504 -392.429238)
		(end 117.316504 -392.6205)
		(stroke
			(width 0.0508)
			(type default)
		)
		(layer "F.Cu")
	)
	(gr_line
		(start 117.463316 -374.530366)
		(end 117.573806 -374.640856)
		(stroke
			(width 0.0508)
			(type default)
		)
		(layer "F.Cu")
	)
	(gr_line
		(start 117.515386 -372.47322)
		(end 117.811296 -372.76913)
		(stroke
			(width 0.06477)
			(type default)
		)
		(layer "F.Cu")
	)
	(gr_line
		(start 117.515894 -383.50571)
		(end 117.60708 -383.596896)
		(stroke
			(width 0.0508)
			(type default)
		)
		(layer "F.Cu")
	)
	(gr_line
		(start 117.515894 -383.2352)
		(end 117.515894 -383.50571)
		(stroke
			(width 0.0508)
			(type default)
		)
		(layer "F.Cu")
	)
	(gr_line
		(start 117.573806 -374.945656)
		(end 117.463316 -375.056146)
		(stroke
			(width 0.0508)
			(type default)
		)
		(layer "F.Cu")
	)
	(gr_line
		(start 117.573806 -374.640856)
		(end 117.573806 -374.945656)
		(stroke
			(width 0.0508)
			(type default)
		)
		(layer "F.Cu")
	)
	(gr_line
		(start 117.60708 -383.596896)
		(end 117.741446 -383.596896)
		(stroke
			(width 0.0508)
			(type default)
		)
		(layer "F.Cu")
	)
	(gr_line
		(start 117.714776 -291.096192)
		(end 117.247924 -290.830254)
		(stroke
			(width 0.06477)
			(type default)
		)
		(layer "F.Cu")
	)
	(gr_line
		(start 117.714776 -289.47618)
		(end 117.247924 -289.210242)
		(stroke
			(width 0.06477)
			(type default)
		)
		(layer "F.Cu")
	)
	(gr_line
		(start 117.714776 -287.856422)
		(end 117.247924 -287.590484)
		(stroke
			(width 0.06477)
			(type default)
		)
		(layer "F.Cu")
	)
	(gr_line
		(start 117.714776 -286.23641)
		(end 117.247924 -285.970472)
		(stroke
			(width 0.06477)
			(type default)
		)
		(layer "F.Cu")
	)
	(gr_line
		(start 117.714776 -284.616398)
		(end 117.247924 -284.35046)
		(stroke
			(width 0.06477)
			(type default)
		)
		(layer "F.Cu")
	)
	(gr_line
		(start 117.714776 -282.996386)
		(end 117.247924 -282.730448)
		(stroke
			(width 0.06477)
			(type default)
		)
		(layer "F.Cu")
	)
	(gr_line
		(start 117.741446 -383.596896)
		(end 117.8179 -383.520442)
		(stroke
			(width 0.0508)
			(type default)
		)
		(layer "F.Cu")
	)
	(gr_line
		(start 117.785896 -371.49913)
		(end 117.515386 -371.76964)
		(stroke
			(width 0.06477)
			(type default)
		)
		(layer "F.Cu")
	)
	(gr_line
		(start 117.807232 -382.943862)
		(end 117.515894 -383.2352)
		(stroke
			(width 0.0508)
			(type default)
		)
		(layer "F.Cu")
	)
	(gr_line
		(start 117.811296 -373.30253)
		(end 117.462046 -373.65178)
		(stroke
			(width 0.0508)
			(type default)
		)
		(layer "F.Cu")
	)
	(gr_line
		(start 117.8179 -383.520442)
		(end 117.8179 -383.402586)
		(stroke
			(width 0.0508)
			(type default)
		)
		(layer "F.Cu")
	)
	(gr_line
		(start 117.901212 -391.36447)
		(end 117.8179 -391.281158)
		(stroke
			(width 0.0508)
			(type default)
		)
		(layer "F.Cu")
	)
	(gr_line
		(start 117.931946 -408.784044)
		(end 118.227856 -409.079954)
		(stroke
			(width 0.06477)
			(type default)
		)
		(layer "F.Cu")
	)
	(gr_line
		(start 117.957346 -404.46452)
		(end 118.227856 -404.73503)
		(stroke
			(width 0.06477)
			(type default)
		)
		(layer "F.Cu")
	)
	(gr_line
		(start 117.970554 -388.774432)
		(end 118.491254 -388.774432)
		(stroke
			(width 0.0635)
			(type default)
		)
		(layer "F.Cu")
	)
	(gr_line
		(start 117.970554 -385.31038)
		(end 118.491254 -385.31038)
		(stroke
			(width 0.0635)
			(type default)
		)
		(layer "F.Cu")
	)
	(gr_line
		(start 118.024402 -383.13741)
		(end 118.117874 -383.230882)
		(stroke
			(width 0.0508)
			(type default)
		)
		(layer "F.Cu")
	)
	(gr_line
		(start 118.024402 -382.942592)
		(end 118.024402 -383.13741)
		(stroke
			(width 0.0508)
			(type default)
		)
		(layer "F.Cu")
	)
	(gr_line
		(start 118.117874 -383.230882)
		(end 118.117874 -383.92227)
		(stroke
			(width 0.0508)
			(type default)
		)
		(layer "F.Cu")
	)
	(gr_line
		(start 118.118382 -391.36574)
		(end 118.118382 -390.761982)
		(stroke
			(width 0.0508)
			(type default)
		)
		(layer "F.Cu")
	)
	(gr_line
		(start 118.118382 -390.761982)
		(end 118.117874 -390.761474)
		(stroke
			(width 0.0508)
			(type default)
		)
		(layer "F.Cu")
	)
	(gr_line
		(start 118.227856 -412.299658)
		(end 117.957346 -412.570168)
		(stroke
			(width 0.06477)
			(type default)
		)
		(layer "F.Cu")
	)
	(gr_line
		(start 118.227856 -407.954734)
		(end 117.931946 -408.250644)
		(stroke
			(width 0.06477)
			(type default)
		)
		(layer "F.Cu")
	)
	(gr_line
		(start 118.370604 -389.467344)
		(end 118.891304 -389.467344)
		(stroke
			(width 0.0635)
			(type default)
		)
		(layer "F.Cu")
	)
	(gr_line
		(start 118.370604 -386.003292)
		(end 118.891304 -386.003292)
		(stroke
			(width 0.0635)
			(type default)
		)
		(layer "F.Cu")
	)
	(gr_line
		(start 118.377716 -392.977116)
		(end 118.375684 -392.977116)
		(stroke
			(width 0.0508)
			(type default)
		)
		(layer "F.Cu")
	)
	(gr_line
		(start 118.5164 -393.292838)
		(end 118.5164 -393.1158)
		(stroke
			(width 0.0508)
			(type default)
		)
		(layer "F.Cu")
	)
	(gr_line
		(start 118.5164 -393.1158)
		(end 118.377716 -392.977116)
		(stroke
			(width 0.0508)
			(type default)
		)
		(layer "F.Cu")
	)
	(gr_line
		(start 118.5164 -392.6205)
		(end 118.376954 -392.759946)
		(stroke
			(width 0.0508)
			(type default)
		)
		(layer "F.Cu")
	)
	(gr_line
		(start 118.5164 -392.429238)
		(end 118.5164 -392.6205)
		(stroke
			(width 0.0508)
			(type default)
		)
		(layer "F.Cu")
	)
	(gr_line
		(start 118.550436 -412.299658)
		(end 118.820946 -412.570168)
		(stroke
			(width 0.06477)
			(type default)
		)
		(layer "F.Cu")
	)
	(gr_line
		(start 118.550436 -407.954734)
		(end 118.846346 -408.250644)
		(stroke
			(width 0.06477)
			(type default)
		)
		(layer "F.Cu")
	)
	(gr_line
		(start 118.598696 -370.83873)
		(end 118.947946 -371.18798)
		(stroke
			(width 0.0508)
			(type default)
		)
		(layer "F.Cu")
	)
	(gr_line
		(start 118.624096 -369.03533)
		(end 118.894606 -369.30584)
		(stroke
			(width 0.06477)
			(type default)
		)
		(layer "F.Cu")
	)
	(gr_line
		(start 118.716044 -383.50571)
		(end 118.80723 -383.596896)
		(stroke
			(width 0.0508)
			(type default)
		)
		(layer "F.Cu")
	)
	(gr_line
		(start 118.716044 -383.2352)
		(end 118.716044 -383.50571)
		(stroke
			(width 0.0508)
			(type default)
		)
		(layer "F.Cu")
	)
	(gr_line
		(start 118.80723 -383.596896)
		(end 118.941596 -383.596896)
		(stroke
			(width 0.0508)
			(type default)
		)
		(layer "F.Cu")
	)
	(gr_line
		(start 118.820946 -404.46452)
		(end 118.550436 -404.73503)
		(stroke
			(width 0.06477)
			(type default)
		)
		(layer "F.Cu")
	)
	(gr_line
		(start 118.846346 -408.784044)
		(end 118.550436 -409.079954)
		(stroke
			(width 0.06477)
			(type default)
		)
		(layer "F.Cu")
	)
	(gr_line
		(start 118.894606 -370.00942)
		(end 118.598696 -370.30533)
		(stroke
			(width 0.06477)
			(type default)
		)
		(layer "F.Cu")
	)
	(gr_line
		(start 118.941596 -383.596896)
		(end 119.01805 -383.520442)
		(stroke
			(width 0.0508)
			(type default)
		)
		(layer "F.Cu")
	)
	(gr_line
		(start 119.007382 -382.943862)
		(end 118.716044 -383.2352)
		(stroke
			(width 0.0508)
			(type default)
		)
		(layer "F.Cu")
	)
	(gr_line
		(start 119.01805 -383.520442)
		(end 119.01805 -383.402586)
		(stroke
			(width 0.0508)
			(type default)
		)
		(layer "F.Cu")
	)
	(gr_line
		(start 119.101362 -391.36447)
		(end 119.01805 -391.281158)
		(stroke
			(width 0.0508)
			(type default)
		)
		(layer "F.Cu")
	)
	(gr_line
		(start 119.127778 -277.870412)
		(end 119.59463 -278.13635)
		(stroke
			(width 0.06477)
			(type default)
		)
		(layer "F.Cu")
	)
	(gr_line
		(start 119.127778 -276.2504)
		(end 119.59463 -276.516338)
		(stroke
			(width 0.06477)
			(type default)
		)
		(layer "F.Cu")
	)
	(gr_line
		(start 119.127778 -274.630388)
		(end 119.59463 -274.896326)
		(stroke
			(width 0.06477)
			(type default)
		)
		(layer "F.Cu")
	)
	(gr_line
		(start 119.127778 -273.010376)
		(end 119.59463 -273.276314)
		(stroke
			(width 0.06477)
			(type default)
		)
		(layer "F.Cu")
	)
	(gr_line
		(start 119.127778 -271.390364)
		(end 119.59463 -271.656302)
		(stroke
			(width 0.06477)
			(type default)
		)
		(layer "F.Cu")
	)
	(gr_line
		(start 119.127778 -269.770352)
		(end 119.59463 -270.03629)
		(stroke
			(width 0.06477)
			(type default)
		)
		(layer "F.Cu")
	)
	(gr_line
		(start 119.17045 -388.774432)
		(end 119.69115 -388.774432)
		(stroke
			(width 0.0635)
			(type default)
		)
		(layer "F.Cu")
	)
	(gr_line
		(start 119.17045 -385.31038)
		(end 119.69115 -385.31038)
		(stroke
			(width 0.0635)
			(type default)
		)
		(layer "F.Cu")
	)
	(gr_line
		(start 119.217186 -370.00942)
		(end 119.513096 -370.30533)
		(stroke
			(width 0.06477)
			(type default)
		)
		(layer "F.Cu")
	)
	(gr_line
		(start 119.224552 -383.13741)
		(end 119.318024 -383.230882)
		(stroke
			(width 0.0508)
			(type default)
		)
		(layer "F.Cu")
	)
	(gr_line
		(start 119.224552 -382.942592)
		(end 119.224552 -383.13741)
		(stroke
			(width 0.0508)
			(type default)
		)
		(layer "F.Cu")
	)
	(gr_arc
		(start 119.224552 -381.5715)
		(mid 119.224552 -381.571881)
		(end 119.224552 -381.572262)
		(stroke
			(width 0.0508)
			(type default)
		)
		(layer "F.Cu")
	)
	(gr_line
		(start 119.318024 -383.230882)
		(end 119.318024 -383.92227)
		(stroke
			(width 0.0508)
			(type default)
		)
		(layer "F.Cu")
	)
	(gr_line
		(start 119.318532 -391.36574)
		(end 119.318532 -390.761982)
		(stroke
			(width 0.0508)
			(type default)
		)
		(layer "F.Cu")
	)
	(gr_line
		(start 119.318532 -390.761982)
		(end 119.318024 -390.761474)
		(stroke
			(width 0.0508)
			(type default)
		)
		(layer "F.Cu")
	)
	(gr_line
		(start 119.487696 -369.03533)
		(end 119.217186 -369.30584)
		(stroke
			(width 0.06477)
			(type default)
		)
		(layer "F.Cu")
	)
	(gr_line
		(start 119.513096 -370.83873)
		(end 119.163846 -371.18798)
		(stroke
			(width 0.0508)
			(type default)
		)
		(layer "F.Cu")
	)
	(gr_line
		(start 119.5705 -389.467344)
		(end 120.0912 -389.467344)
		(stroke
			(width 0.0635)
			(type default)
		)
		(layer "F.Cu")
	)
	(gr_line
		(start 119.5705 -386.003292)
		(end 120.0912 -386.003292)
		(stroke
			(width 0.0635)
			(type default)
		)
		(layer "F.Cu")
	)
	(gr_line
		(start 119.577866 -392.977116)
		(end 119.575834 -392.977116)
		(stroke
			(width 0.0508)
			(type default)
		)
		(layer "F.Cu")
	)
	(gr_line
		(start 119.59463 -291.096192)
		(end 119.127778 -290.830254)
		(stroke
			(width 0.06477)
			(type default)
		)
		(layer "F.Cu")
	)
	(gr_line
		(start 119.59463 -289.47618)
		(end 119.127778 -289.210242)
		(stroke
			(width 0.06477)
			(type default)
		)
		(layer "F.Cu")
	)
	(gr_line
		(start 119.59463 -287.856422)
		(end 119.127778 -287.590484)
		(stroke
			(width 0.06477)
			(type default)
		)
		(layer "F.Cu")
	)
	(gr_line
		(start 119.59463 -286.23641)
		(end 119.127778 -285.970472)
		(stroke
			(width 0.06477)
			(type default)
		)
		(layer "F.Cu")
	)
	(gr_line
		(start 119.59463 -284.616398)
		(end 119.127778 -284.35046)
		(stroke
			(width 0.06477)
			(type default)
		)
		(layer "F.Cu")
	)
	(gr_line
		(start 119.59463 -282.996386)
		(end 119.127778 -282.730448)
		(stroke
			(width 0.06477)
			(type default)
		)
		(layer "F.Cu")
	)
	(gr_line
		(start 119.71655 -393.292838)
		(end 119.71655 -393.1158)
		(stroke
			(width 0.0508)
			(type default)
		)
		(layer "F.Cu")
	)
	(gr_line
		(start 119.71655 -393.1158)
		(end 119.577866 -392.977116)
		(stroke
			(width 0.0508)
			(type default)
		)
		(layer "F.Cu")
	)
	(gr_line
		(start 119.71655 -392.6205)
		(end 119.577104 -392.759946)
		(stroke
			(width 0.0508)
			(type default)
		)
		(layer "F.Cu")
	)
	(gr_line
		(start 119.71655 -392.429238)
		(end 119.71655 -392.6205)
		(stroke
			(width 0.0508)
			(type default)
		)
		(layer "F.Cu")
	)
	(gr_line
		(start 119.91594 -383.50571)
		(end 120.007126 -383.596896)
		(stroke
			(width 0.0508)
			(type default)
		)
		(layer "F.Cu")
	)
	(gr_line
		(start 119.91594 -383.2352)
		(end 119.91594 -383.50571)
		(stroke
			(width 0.0508)
			(type default)
		)
		(layer "F.Cu")
	)
	(gr_line
		(start 120.007126 -383.596896)
		(end 120.141492 -383.596896)
		(stroke
			(width 0.0508)
			(type default)
		)
		(layer "F.Cu")
	)
	(gr_line
		(start 120.067832 -277.870412)
		(end 120.534684 -278.13635)
		(stroke
			(width 0.06477)
			(type default)
		)
		(layer "F.Cu")
	)
	(gr_line
		(start 120.067832 -276.2504)
		(end 120.534684 -276.516338)
		(stroke
			(width 0.06477)
			(type default)
		)
		(layer "F.Cu")
	)
	(gr_line
		(start 120.067832 -274.630388)
		(end 120.534684 -274.896326)
		(stroke
			(width 0.06477)
			(type default)
		)
		(layer "F.Cu")
	)
	(gr_line
		(start 120.067832 -273.010376)
		(end 120.534684 -273.276314)
		(stroke
			(width 0.06477)
			(type default)
		)
		(layer "F.Cu")
	)
	(gr_line
		(start 120.067832 -271.390364)
		(end 120.534684 -271.656302)
		(stroke
			(width 0.06477)
			(type default)
		)
		(layer "F.Cu")
	)
	(gr_line
		(start 120.067832 -269.770352)
		(end 120.534684 -270.03629)
		(stroke
			(width 0.06477)
			(type default)
		)
		(layer "F.Cu")
	)
	(gr_line
		(start 120.11533 -33.02508)
		(end 120.26138 -33.17113)
		(stroke
			(width 0.06477)
			(type default)
		)
		(layer "F.Cu")
	)
	(gr_line
		(start 120.141492 -383.596896)
		(end 120.217946 -383.520442)
		(stroke
			(width 0.0508)
			(type default)
		)
		(layer "F.Cu")
	)
	(gr_line
		(start 120.207278 -382.943862)
		(end 119.91594 -383.2352)
		(stroke
			(width 0.0508)
			(type default)
		)
		(layer "F.Cu")
	)
	(gr_line
		(start 120.217946 -383.520442)
		(end 120.217946 -383.402586)
		(stroke
			(width 0.0508)
			(type default)
		)
		(layer "F.Cu")
	)
	(gr_line
		(start 120.26138 -35.42665)
		(end 120.26138 -34.67481)
		(stroke
			(width 0.06477)
			(type default)
		)
		(layer "F.Cu")
	)
	(gr_line
		(start 120.26138 -34.67481)
		(end 120.26138 -35.42665)
		(stroke
			(width 0.06477)
			(type default)
		)
		(layer "F.Cu")
	)
	(gr_line
		(start 120.26138 -34.371026)
		(end 120.26138 -33.619186)
		(stroke
			(width 0.06477)
			(type default)
		)
		(layer "F.Cu")
	)
	(gr_line
		(start 120.26138 -33.619186)
		(end 120.26138 -34.371026)
		(stroke
			(width 0.06477)
			(type default)
		)
		(layer "F.Cu")
	)
	(gr_line
		(start 120.26138 -33.238186)
		(end 120.26138 -33.17113)
		(stroke
			(width 0.06477)
			(type default)
		)
		(layer "F.Cu")
	)
	(gr_line
		(start 120.26138 -33.17113)
		(end 120.11533 -33.02508)
		(stroke
			(width 0.06477)
			(type default)
		)
		(layer "F.Cu")
	)
	(gr_line
		(start 120.26138 -33.17113)
		(end 120.26138 -33.238186)
		(stroke
			(width 0.06477)
			(type default)
		)
		(layer "F.Cu")
	)
	(gr_line
		(start 120.301258 -391.36447)
		(end 120.217946 -391.281158)
		(stroke
			(width 0.0508)
			(type default)
		)
		(layer "F.Cu")
	)
	(gr_line
		(start 120.3706 -388.774432)
		(end 120.8913 -388.774432)
		(stroke
			(width 0.0635)
			(type default)
		)
		(layer "F.Cu")
	)
	(gr_line
		(start 120.3706 -385.31038)
		(end 120.8913 -385.31038)
		(stroke
			(width 0.0635)
			(type default)
		)
		(layer "F.Cu")
	)
	(gr_line
		(start 120.424448 -383.13741)
		(end 120.51792 -383.230882)
		(stroke
			(width 0.0508)
			(type default)
		)
		(layer "F.Cu")
	)
	(gr_line
		(start 120.424448 -382.942592)
		(end 120.424448 -383.13741)
		(stroke
			(width 0.0508)
			(type default)
		)
		(layer "F.Cu")
	)
	(gr_line
		(start 120.51792 -383.230882)
		(end 120.51792 -383.92227)
		(stroke
			(width 0.0508)
			(type default)
		)
		(layer "F.Cu")
	)
	(gr_line
		(start 120.518428 -391.36574)
		(end 120.518428 -390.761982)
		(stroke
			(width 0.0508)
			(type default)
		)
		(layer "F.Cu")
	)
	(gr_line
		(start 120.518428 -390.761982)
		(end 120.51792 -390.761474)
		(stroke
			(width 0.0508)
			(type default)
		)
		(layer "F.Cu")
	)
	(gr_line
		(start 120.523 -322.09105)
		(end 120.52935 -322.0974)
		(stroke
			(width 0.06477)
			(type default)
		)
		(layer "F.Cu")
	)
	(gr_line
		(start 120.534684 -291.096192)
		(end 120.067832 -290.830254)
		(stroke
			(width 0.06477)
			(type default)
		)
		(layer "F.Cu")
	)
	(gr_line
		(start 120.534684 -289.47618)
		(end 120.067832 -289.210242)
		(stroke
			(width 0.06477)
			(type default)
		)
		(layer "F.Cu")
	)
	(gr_line
		(start 120.534684 -287.856422)
		(end 120.067832 -287.590484)
		(stroke
			(width 0.06477)
			(type default)
		)
		(layer "F.Cu")
	)
	(gr_line
		(start 120.534684 -286.23641)
		(end 120.067832 -285.970472)
		(stroke
			(width 0.06477)
			(type default)
		)
		(layer "F.Cu")
	)
	(gr_line
		(start 120.534684 -284.616398)
		(end 120.067832 -284.35046)
		(stroke
			(width 0.06477)
			(type default)
		)
		(layer "F.Cu")
	)
	(gr_line
		(start 120.534684 -282.996386)
		(end 120.067832 -282.730448)
		(stroke
			(width 0.06477)
			(type default)
		)
		(layer "F.Cu")
	)
	(gr_line
		(start 120.58523 -35.42538)
		(end 120.76938 -35.24123)
		(stroke
			(width 0.06477)
			(type default)
		)
		(layer "F.Cu")
	)
	(gr_line
		(start 120.58523 -34.369756)
		(end 120.76938 -34.185606)
		(stroke
			(width 0.06477)
			(type default)
		)
		(layer "F.Cu")
	)
	(gr_line
		(start 120.58523 -33.236916)
		(end 120.797066 -33.02508)
		(stroke
			(width 0.06477)
			(type default)
		)
		(layer "F.Cu")
	)
	(gr_line
		(start 120.667272 -374.849136)
		(end 120.667272 -375.377456)
		(stroke
			(width 0.0508)
			(type default)
		)
		(layer "F.Cu")
	)
	(gr_line
		(start 120.76938 -35.24123)
		(end 120.76938 -34.86023)
		(stroke
			(width 0.06477)
			(type default)
		)
		(layer "F.Cu")
	)
	(gr_line
		(start 120.76938 -34.86023)
		(end 120.58523 -34.67608)
		(stroke
			(width 0.06477)
			(type default)
		)
		(layer "F.Cu")
	)
	(gr_line
		(start 120.76938 -34.185606)
		(end 120.76938 -33.804606)
		(stroke
			(width 0.06477)
			(type default)
		)
		(layer "F.Cu")
	)
	(gr_line
		(start 120.76938 -33.804606)
		(end 120.58523 -33.620456)
		(stroke
			(width 0.06477)
			(type default)
		)
		(layer "F.Cu")
	)
	(gr_line
		(start 120.77065 -389.467344)
		(end 121.29135 -389.467344)
		(stroke
			(width 0.0635)
			(type default)
		)
		(layer "F.Cu")
	)
	(gr_line
		(start 120.77065 -386.003292)
		(end 121.29135 -386.003292)
		(stroke
			(width 0.0635)
			(type default)
		)
		(layer "F.Cu")
	)
	(gr_line
		(start 120.777762 -392.977116)
		(end 120.77573 -392.977116)
		(stroke
			(width 0.0508)
			(type default)
		)
		(layer "F.Cu")
	)
	(gr_line
		(start 120.797066 -33.02508)
		(end 120.97893 -33.02508)
		(stroke
			(width 0.06477)
			(type default)
		)
		(layer "F.Cu")
	)
	(gr_line
		(start 120.884442 -374.850406)
		(end 120.994932 -374.960896)
		(stroke
			(width 0.0508)
			(type default)
		)
		(layer "F.Cu")
	)
	(gr_line
		(start 120.916446 -393.292838)
		(end 120.916446 -393.1158)
		(stroke
			(width 0.0508)
			(type default)
		)
		(layer "F.Cu")
	)
	(gr_line
		(start 120.916446 -393.1158)
		(end 120.777762 -392.977116)
		(stroke
			(width 0.0508)
			(type default)
		)
		(layer "F.Cu")
	)
	(gr_line
		(start 120.916446 -392.6205)
		(end 120.777 -392.759946)
		(stroke
			(width 0.0508)
			(type default)
		)
		(layer "F.Cu")
	)
	(gr_line
		(start 120.916446 -392.429238)
		(end 120.916446 -392.6205)
		(stroke
			(width 0.0508)
			(type default)
		)
		(layer "F.Cu")
	)
	(gr_line
		(start 120.994932 -375.265696)
		(end 120.884442 -375.376186)
		(stroke
			(width 0.0508)
			(type default)
		)
		(layer "F.Cu")
	)
	(gr_line
		(start 120.994932 -374.960896)
		(end 120.994932 -375.265696)
		(stroke
			(width 0.0508)
			(type default)
		)
		(layer "F.Cu")
	)
	(gr_line
		(start 120.995186 -408.784044)
		(end 121.291096 -409.079954)
		(stroke
			(width 0.06477)
			(type default)
		)
		(layer "F.Cu")
	)
	(gr_line
		(start 121.020586 -404.46452)
		(end 121.291096 -404.73503)
		(stroke
			(width 0.06477)
			(type default)
		)
		(layer "F.Cu")
	)
	(gr_line
		(start 121.115836 -383.50571)
		(end 121.207022 -383.596896)
		(stroke
			(width 0.0508)
			(type default)
		)
		(layer "F.Cu")
	)
	(gr_line
		(start 121.115836 -383.2352)
		(end 121.115836 -383.50571)
		(stroke
			(width 0.0508)
			(type default)
		)
		(layer "F.Cu")
	)
	(gr_line
		(start 121.207022 -383.596896)
		(end 121.341388 -383.596896)
		(stroke
			(width 0.0508)
			(type default)
		)
		(layer "F.Cu")
	)
	(gr_line
		(start 121.26341 -36.24453)
		(end 121.694448 -36.675568)
		(stroke
			(width 0.06477)
			(type default)
		)
		(layer "F.Cu")
	)
	(gr_line
		(start 121.266966 -35.92068)
		(end 121.26214 -35.92068)
		(stroke
			(width 0.06477)
			(type default)
		)
		(layer "F.Cu")
	)
	(gr_line
		(start 121.291096 -412.299658)
		(end 121.020586 -412.570168)
		(stroke
			(width 0.06477)
			(type default)
		)
		(layer "F.Cu")
	)
	(gr_line
		(start 121.291096 -407.954734)
		(end 120.995186 -408.250644)
		(stroke
			(width 0.06477)
			(type default)
		)
		(layer "F.Cu")
	)
	(gr_line
		(start 121.341388 -383.596896)
		(end 121.417842 -383.520442)
		(stroke
			(width 0.0508)
			(type default)
		)
		(layer "F.Cu")
	)
	(gr_line
		(start 121.407174 -382.943862)
		(end 121.115836 -383.2352)
		(stroke
			(width 0.0508)
			(type default)
		)
		(layer "F.Cu")
	)
	(gr_line
		(start 121.417842 -383.520442)
		(end 121.417842 -383.402586)
		(stroke
			(width 0.0508)
			(type default)
		)
		(layer "F.Cu")
	)
	(gr_line
		(start 121.501408 -391.364724)
		(end 121.417842 -391.281158)
		(stroke
			(width 0.0508)
			(type default)
		)
		(layer "F.Cu")
	)
	(gr_line
		(start 121.5136 -321.26555)
		(end 121.539 -321.29095)
		(stroke
			(width 0.06477)
			(type default)
		)
		(layer "F.Cu")
	)
	(gr_line
		(start 121.539 -322.09105)
		(end 121.53265 -322.0974)
		(stroke
			(width 0.06477)
			(type default)
		)
		(layer "F.Cu")
	)
	(gr_line
		(start 121.570496 -388.774432)
		(end 122.091196 -388.774432)
		(stroke
			(width 0.0635)
			(type default)
		)
		(layer "F.Cu")
	)
	(gr_line
		(start 121.570496 -385.31038)
		(end 122.091196 -385.31038)
		(stroke
			(width 0.0635)
			(type default)
		)
		(layer "F.Cu")
	)
	(gr_line
		(start 121.613676 -412.299658)
		(end 121.884186 -412.570168)
		(stroke
			(width 0.06477)
			(type default)
		)
		(layer "F.Cu")
	)
	(gr_line
		(start 121.613676 -407.954734)
		(end 121.909586 -408.250644)
		(stroke
			(width 0.06477)
			(type default)
		)
		(layer "F.Cu")
	)
	(gr_line
		(start 121.624344 -383.13741)
		(end 121.71807 -383.231136)
		(stroke
			(width 0.0508)
			(type default)
		)
		(layer "F.Cu")
	)
	(gr_line
		(start 121.624344 -382.942592)
		(end 121.624344 -383.13741)
		(stroke
			(width 0.0508)
			(type default)
		)
		(layer "F.Cu")
	)
	(gr_line
		(start 121.694448 -36.675568)
		(end 121.26341 -36.24453)
		(stroke
			(width 0.06477)
			(type default)
		)
		(layer "F.Cu")
	)
	(gr_line
		(start 121.694448 -36.675568)
		(end 122.15622 -36.675568)
		(stroke
			(width 0.06477)
			(type default)
		)
		(layer "F.Cu")
	)
	(gr_line
		(start 121.71807 -383.231136)
		(end 121.71807 -383.92227)
		(stroke
			(width 0.0508)
			(type default)
		)
		(layer "F.Cu")
	)
	(gr_line
		(start 121.718578 -391.365486)
		(end 121.718324 -391.36574)
		(stroke
			(width 0.0508)
			(type default)
		)
		(layer "F.Cu")
	)
	(gr_line
		(start 121.718578 -391.365486)
		(end 121.718578 -390.761982)
		(stroke
			(width 0.0508)
			(type default)
		)
		(layer "F.Cu")
	)
	(gr_line
		(start 121.718578 -390.761982)
		(end 121.71807 -390.761474)
		(stroke
			(width 0.0508)
			(type default)
		)
		(layer "F.Cu")
	)
	(gr_line
		(start 121.756678 -35.430968)
		(end 121.266966 -35.92068)
		(stroke
			(width 0.06477)
			(type default)
		)
		(layer "F.Cu")
	)
	(gr_line
		(start 121.884186 -404.46452)
		(end 121.613676 -404.73503)
		(stroke
			(width 0.06477)
			(type default)
		)
		(layer "F.Cu")
	)
	(gr_line
		(start 121.909586 -408.784044)
		(end 121.613676 -409.079954)
		(stroke
			(width 0.06477)
			(type default)
		)
		(layer "F.Cu")
	)
	(gr_line
		(start 121.94794 -277.870412)
		(end 122.414792 -278.13635)
		(stroke
			(width 0.06477)
			(type default)
		)
		(layer "F.Cu")
	)
	(gr_line
		(start 121.94794 -276.2504)
		(end 122.414792 -276.516338)
		(stroke
			(width 0.06477)
			(type default)
		)
		(layer "F.Cu")
	)
	(gr_line
		(start 121.94794 -274.630388)
		(end 122.414792 -274.896326)
		(stroke
			(width 0.06477)
			(type default)
		)
		(layer "F.Cu")
	)
	(gr_line
		(start 121.94794 -273.010376)
		(end 122.414792 -273.276314)
		(stroke
			(width 0.06477)
			(type default)
		)
		(layer "F.Cu")
	)
	(gr_line
		(start 121.94794 -271.390364)
		(end 122.414792 -271.656302)
		(stroke
			(width 0.06477)
			(type default)
		)
		(layer "F.Cu")
	)
	(gr_line
		(start 121.94794 -269.770352)
		(end 122.414792 -270.03629)
		(stroke
			(width 0.06477)
			(type default)
		)
		(layer "F.Cu")
	)
	(gr_line
		(start 121.970546 -389.467344)
		(end 122.491246 -389.467344)
		(stroke
			(width 0.0635)
			(type default)
		)
		(layer "F.Cu")
	)
	(gr_line
		(start 121.970546 -386.003292)
		(end 122.491246 -386.003292)
		(stroke
			(width 0.0635)
			(type default)
		)
		(layer "F.Cu")
	)
	(gr_line
		(start 121.977658 -392.977116)
		(end 121.97588 -392.977116)
		(stroke
			(width 0.0508)
			(type default)
		)
		(layer "F.Cu")
	)
	(gr_line
		(start 122.002296 -375.76633)
		(end 122.304048 -376.068082)
		(stroke
			(width 0.0508)
			(type default)
		)
		(layer "F.Cu")
	)
	(gr_line
		(start 122.027696 -373.96293)
		(end 122.298206 -374.23344)
		(stroke
			(width 0.06477)
			(type default)
		)
		(layer "F.Cu")
	)
	(gr_line
		(start 122.116596 -393.292838)
		(end 122.116596 -393.116054)
		(stroke
			(width 0.0508)
			(type default)
		)
		(layer "F.Cu")
	)
	(gr_line
		(start 122.116596 -393.116054)
		(end 121.977658 -392.977116)
		(stroke
			(width 0.0508)
			(type default)
		)
		(layer "F.Cu")
	)
	(gr_line
		(start 122.116596 -392.6205)
		(end 121.97715 -392.759946)
		(stroke
			(width 0.0508)
			(type default)
		)
		(layer "F.Cu")
	)
	(gr_line
		(start 122.116596 -392.429238)
		(end 122.116596 -392.6205)
		(stroke
			(width 0.0508)
			(type default)
		)
		(layer "F.Cu")
	)
	(gr_line
		(start 122.15622 -36.675568)
		(end 121.694448 -36.675568)
		(stroke
			(width 0.06477)
			(type default)
		)
		(layer "F.Cu")
	)
	(gr_line
		(start 122.15622 -35.430968)
		(end 121.756678 -35.430968)
		(stroke
			(width 0.06477)
			(type default)
		)
		(layer "F.Cu")
	)
	(gr_line
		(start 122.298206 -374.93702)
		(end 122.002296 -375.23293)
		(stroke
			(width 0.06477)
			(type default)
		)
		(layer "F.Cu")
	)
	(gr_line
		(start 122.315986 -383.50571)
		(end 122.407172 -383.596896)
		(stroke
			(width 0.0508)
			(type default)
		)
		(layer "F.Cu")
	)
	(gr_line
		(start 122.315986 -383.2352)
		(end 122.315986 -383.50571)
		(stroke
			(width 0.0508)
			(type default)
		)
		(layer "F.Cu")
	)
	(gr_arc
		(start 122.35053 -376.165872)
		(mid 122.335655 -376.113)
		(end 122.304048 -376.068082)
		(stroke
			(width 0.0508)
			(type default)
		)
		(layer "F.Cu")
	)
	(gr_line
		(start 122.351546 -377.07443)
		(end 122.351546 -377.60275)
		(stroke
			(width 0.0508)
			(type default)
		)
		(layer "F.Cu")
	)
	(gr_line
		(start 122.407172 -383.596896)
		(end 122.541538 -383.596896)
		(stroke
			(width 0.0508)
			(type default)
		)
		(layer "F.Cu")
	)
	(gr_line
		(start 122.414792 -291.096192)
		(end 121.94794 -290.830254)
		(stroke
			(width 0.06477)
			(type default)
		)
		(layer "F.Cu")
	)
	(gr_line
		(start 122.414792 -289.47618)
		(end 121.94794 -289.210242)
		(stroke
			(width 0.06477)
			(type default)
		)
		(layer "F.Cu")
	)
	(gr_line
		(start 122.414792 -287.856422)
		(end 121.94794 -287.590484)
		(stroke
			(width 0.06477)
			(type default)
		)
		(layer "F.Cu")
	)
	(gr_line
		(start 122.414792 -286.23641)
		(end 121.94794 -285.970472)
		(stroke
			(width 0.06477)
			(type default)
		)
		(layer "F.Cu")
	)
	(gr_line
		(start 122.414792 -284.616398)
		(end 121.94794 -284.35046)
		(stroke
			(width 0.06477)
			(type default)
		)
		(layer "F.Cu")
	)
	(gr_line
		(start 122.414792 -282.996386)
		(end 121.94794 -282.730448)
		(stroke
			(width 0.06477)
			(type default)
		)
		(layer "F.Cu")
	)
	(gr_line
		(start 122.414792 -281.376374)
		(end 121.94794 -281.110436)
		(stroke
			(width 0.06477)
			(type default)
		)
		(layer "F.Cu")
	)
	(gr_line
		(start 122.52452 -36.053268)
		(end 122.95632 -36.485068)
		(stroke
			(width 0.06477)
			(type default)
		)
		(layer "F.Cu")
	)
	(gr_line
		(start 122.541538 -383.596896)
		(end 122.617992 -383.520442)
		(stroke
			(width 0.0508)
			(type default)
		)
		(layer "F.Cu")
	)
	(gr_line
		(start 122.568716 -377.0757)
		(end 122.679206 -377.18619)
		(stroke
			(width 0.0508)
			(type default)
		)
		(layer "F.Cu")
	)
	(gr_line
		(start 122.607324 -382.943862)
		(end 122.315986 -383.2352)
		(stroke
			(width 0.0508)
			(type default)
		)
		(layer "F.Cu")
	)
	(gr_arc
		(start 122.61469 -376.068336)
		(mid 122.5831 -376.112985)
		(end 122.568208 -376.165618)
		(stroke
			(width 0.0508)
			(type default)
		)
		(layer "F.Cu")
	)
	(gr_line
		(start 122.617992 -383.520442)
		(end 122.617992 -383.402586)
		(stroke
			(width 0.0508)
			(type default)
		)
		(layer "F.Cu")
	)
	(gr_line
		(start 122.620786 -374.93702)
		(end 122.916696 -375.23293)
		(stroke
			(width 0.06477)
			(type default)
		)
		(layer "F.Cu")
	)
	(gr_line
		(start 122.679206 -377.49099)
		(end 122.568716 -377.60148)
		(stroke
			(width 0.0508)
			(type default)
		)
		(layer "F.Cu")
	)
	(gr_line
		(start 122.679206 -377.18619)
		(end 122.679206 -377.49099)
		(stroke
			(width 0.0508)
			(type default)
		)
		(layer "F.Cu")
	)
	(gr_line
		(start 122.701304 -391.36447)
		(end 122.617992 -391.281158)
		(stroke
			(width 0.0508)
			(type default)
		)
		(layer "F.Cu")
	)
	(gr_line
		(start 122.770646 -388.774432)
		(end 123.291346 -388.774432)
		(stroke
			(width 0.0635)
			(type default)
		)
		(layer "F.Cu")
	)
	(gr_line
		(start 122.770646 -385.31038)
		(end 123.291346 -385.31038)
		(stroke
			(width 0.0635)
			(type default)
		)
		(layer "F.Cu")
	)
	(gr_line
		(start 122.809 -322.055998)
		(end 122.825002 -322.072)
		(stroke
			(width 0.06477)
			(type default)
		)
		(layer "F.Cu")
	)
	(gr_line
		(start 122.824494 -383.13741)
		(end 122.917966 -383.230882)
		(stroke
			(width 0.0508)
			(type default)
		)
		(layer "F.Cu")
	)
	(gr_line
		(start 122.824494 -382.94183)
		(end 122.824494 -383.13741)
		(stroke
			(width 0.0508)
			(type default)
		)
		(layer "F.Cu")
	)
	(gr_line
		(start 122.831098 -321.2338)
		(end 122.809 -321.255898)
		(stroke
			(width 0.06477)
			(type default)
		)
		(layer "F.Cu")
	)
	(gr_line
		(start 122.887994 -277.870412)
		(end 123.354846 -278.13635)
		(stroke
			(width 0.06477)
			(type default)
		)
		(layer "F.Cu")
	)
	(gr_line
		(start 122.887994 -276.2504)
		(end 123.354846 -276.516338)
		(stroke
			(width 0.06477)
			(type default)
		)
		(layer "F.Cu")
	)
	(gr_line
		(start 122.887994 -274.630388)
		(end 123.354846 -274.896326)
		(stroke
			(width 0.06477)
			(type default)
		)
		(layer "F.Cu")
	)
	(gr_line
		(start 122.887994 -273.010376)
		(end 123.354846 -273.276314)
		(stroke
			(width 0.06477)
			(type default)
		)
		(layer "F.Cu")
	)
	(gr_line
		(start 122.887994 -271.390364)
		(end 123.354846 -271.656302)
		(stroke
			(width 0.06477)
			(type default)
		)
		(layer "F.Cu")
	)
	(gr_line
		(start 122.887994 -269.770352)
		(end 123.354846 -270.03629)
		(stroke
			(width 0.06477)
			(type default)
		)
		(layer "F.Cu")
	)
	(gr_line
		(start 122.891296 -373.96293)
		(end 122.620786 -374.23344)
		(stroke
			(width 0.06477)
			(type default)
		)
		(layer "F.Cu")
	)
	(gr_line
		(start 122.916696 -375.76633)
		(end 122.61469 -376.068336)
		(stroke
			(width 0.0508)
			(type default)
		)
		(layer "F.Cu")
	)
	(gr_line
		(start 122.917966 -383.230882)
		(end 122.917966 -383.92227)
		(stroke
			(width 0.0508)
			(type default)
		)
		(layer "F.Cu")
	)
	(gr_line
		(start 122.918474 -391.36574)
		(end 122.918474 -390.761982)
		(stroke
			(width 0.0508)
			(type default)
		)
		(layer "F.Cu")
	)
	(gr_line
		(start 122.918474 -390.761982)
		(end 122.917966 -390.761474)
		(stroke
			(width 0.0508)
			(type default)
		)
		(layer "F.Cu")
	)
	(gr_line
		(start 122.95632 -36.485068)
		(end 122.95632 -36.675568)
		(stroke
			(width 0.06477)
			(type default)
		)
		(layer "F.Cu")
	)
	(gr_line
		(start 122.95632 -35.621468)
		(end 122.95632 -35.430968)
		(stroke
			(width 0.06477)
			(type default)
		)
		(layer "F.Cu")
	)
	(gr_line
		(start 123.15571 -348.710758)
		(end 123.15571 -349.480378)
		(stroke
			(width 0.06477)
			(type default)
		)
		(layer "F.Cu")
	)
	(gr_line
		(start 123.15571 -347.552518)
		(end 123.15571 -348.322138)
		(stroke
			(width 0.06477)
			(type default)
		)
		(layer "F.Cu")
	)
	(gr_line
		(start 123.15571 -346.394278)
		(end 123.15571 -347.163898)
		(stroke
			(width 0.06477)
			(type default)
		)
		(layer "F.Cu")
	)
	(gr_line
		(start 123.170442 -389.467344)
		(end 123.691142 -389.467344)
		(stroke
			(width 0.0635)
			(type default)
		)
		(layer "F.Cu")
	)
	(gr_line
		(start 123.170442 -386.003292)
		(end 123.691142 -386.003292)
		(stroke
			(width 0.0635)
			(type default)
		)
		(layer "F.Cu")
	)
	(gr_line
		(start 123.177808 -392.977116)
		(end 123.175776 -392.977116)
		(stroke
			(width 0.0508)
			(type default)
		)
		(layer "F.Cu")
	)
	(gr_line
		(start 123.316492 -393.292838)
		(end 123.316492 -393.1158)
		(stroke
			(width 0.0508)
			(type default)
		)
		(layer "F.Cu")
	)
	(gr_line
		(start 123.316492 -393.1158)
		(end 123.177808 -392.977116)
		(stroke
			(width 0.0508)
			(type default)
		)
		(layer "F.Cu")
	)
	(gr_line
		(start 123.316492 -392.6205)
		(end 123.177046 -392.759946)
		(stroke
			(width 0.0508)
			(type default)
		)
		(layer "F.Cu")
	)
	(gr_line
		(start 123.316492 -392.429238)
		(end 123.316492 -392.6205)
		(stroke
			(width 0.0508)
			(type default)
		)
		(layer "F.Cu")
	)
	(gr_line
		(start 123.354846 -291.096192)
		(end 122.887994 -290.830254)
		(stroke
			(width 0.06477)
			(type default)
		)
		(layer "F.Cu")
	)
	(gr_line
		(start 123.354846 -289.47618)
		(end 122.887994 -289.210242)
		(stroke
			(width 0.06477)
			(type default)
		)
		(layer "F.Cu")
	)
	(gr_line
		(start 123.354846 -287.856422)
		(end 122.887994 -287.590484)
		(stroke
			(width 0.06477)
			(type default)
		)
		(layer "F.Cu")
	)
	(gr_line
		(start 123.354846 -286.23641)
		(end 122.887994 -285.970472)
		(stroke
			(width 0.06477)
			(type default)
		)
		(layer "F.Cu")
	)
	(gr_line
		(start 123.354846 -284.616398)
		(end 122.887994 -284.35046)
		(stroke
			(width 0.06477)
			(type default)
		)
		(layer "F.Cu")
	)
	(gr_line
		(start 123.354846 -282.996386)
		(end 122.887994 -282.730448)
		(stroke
			(width 0.06477)
			(type default)
		)
		(layer "F.Cu")
	)
	(gr_line
		(start 123.354846 -281.376374)
		(end 122.887994 -281.110436)
		(stroke
			(width 0.06477)
			(type default)
		)
		(layer "F.Cu")
	)
	(gr_line
		(start 123.38812 -36.053268)
		(end 122.95632 -35.621468)
		(stroke
			(width 0.06477)
			(type default)
		)
		(layer "F.Cu")
	)
	(gr_line
		(start 123.47956 -348.712028)
		(end 123.66879 -348.901258)
		(stroke
			(width 0.06477)
			(type default)
		)
		(layer "F.Cu")
	)
	(gr_line
		(start 123.47956 -347.553788)
		(end 123.66879 -347.743018)
		(stroke
			(width 0.06477)
			(type default)
		)
		(layer "F.Cu")
	)
	(gr_line
		(start 123.47956 -346.395548)
		(end 123.66879 -346.584778)
		(stroke
			(width 0.06477)
			(type default)
		)
		(layer "F.Cu")
	)
	(gr_line
		(start 123.515882 -383.50571)
		(end 123.607068 -383.596896)
		(stroke
			(width 0.0508)
			(type default)
		)
		(layer "F.Cu")
	)
	(gr_line
		(start 123.515882 -383.2352)
		(end 123.515882 -383.50571)
		(stroke
			(width 0.0508)
			(type default)
		)
		(layer "F.Cu")
	)
	(gr_line
		(start 123.607068 -383.596896)
		(end 123.741434 -383.596896)
		(stroke
			(width 0.0508)
			(type default)
		)
		(layer "F.Cu")
	)
	(gr_line
		(start 123.66879 -349.289878)
		(end 123.47956 -349.479108)
		(stroke
			(width 0.06477)
			(type default)
		)
		(layer "F.Cu")
	)
	(gr_line
		(start 123.66879 -348.901258)
		(end 123.66879 -349.289878)
		(stroke
			(width 0.06477)
			(type default)
		)
		(layer "F.Cu")
	)
	(gr_line
		(start 123.66879 -348.131638)
		(end 123.47956 -348.320868)
		(stroke
			(width 0.06477)
			(type default)
		)
		(layer "F.Cu")
	)
	(gr_line
		(start 123.66879 -347.743018)
		(end 123.66879 -348.131638)
		(stroke
			(width 0.06477)
			(type default)
		)
		(layer "F.Cu")
	)
	(gr_line
		(start 123.66879 -346.973398)
		(end 123.47956 -347.162628)
		(stroke
			(width 0.06477)
			(type default)
		)
		(layer "F.Cu")
	)
	(gr_line
		(start 123.66879 -346.584778)
		(end 123.66879 -346.973398)
		(stroke
			(width 0.06477)
			(type default)
		)
		(layer "F.Cu")
	)
	(gr_line
		(start 123.704096 -373.30253)
		(end 124.005848 -373.604282)
		(stroke
			(width 0.0508)
			(type default)
		)
		(layer "F.Cu")
	)
	(gr_line
		(start 123.729496 -371.49913)
		(end 124.000006 -371.76964)
		(stroke
			(width 0.06477)
			(type default)
		)
		(layer "F.Cu")
	)
	(gr_line
		(start 123.741434 -383.596896)
		(end 123.817888 -383.520442)
		(stroke
			(width 0.0508)
			(type default)
		)
		(layer "F.Cu")
	)
	(gr_line
		(start 123.75642 -36.675568)
		(end 124.172218 -36.675568)
		(stroke
			(width 0.06477)
			(type default)
		)
		(layer "F.Cu")
	)
	(gr_line
		(start 123.75642 -35.430968)
		(end 124.160788 -35.430968)
		(stroke
			(width 0.06477)
			(type default)
		)
		(layer "F.Cu")
	)
	(gr_line
		(start 123.802902 -321.2338)
		(end 123.825 -321.255898)
		(stroke
			(width 0.06477)
			(type default)
		)
		(layer "F.Cu")
	)
	(gr_line
		(start 123.80722 -382.943862)
		(end 123.515882 -383.2352)
		(stroke
			(width 0.0508)
			(type default)
		)
		(layer "F.Cu")
	)
	(gr_line
		(start 123.817888 -383.520442)
		(end 123.817888 -383.402586)
		(stroke
			(width 0.0508)
			(type default)
		)
		(layer "F.Cu")
	)
	(gr_line
		(start 123.825 -322.055998)
		(end 123.808998 -322.072)
		(stroke
			(width 0.06477)
			(type default)
		)
		(layer "F.Cu")
	)
	(gr_line
		(start 123.9012 -391.36447)
		(end 123.817888 -391.281158)
		(stroke
			(width 0.0508)
			(type default)
		)
		(layer "F.Cu")
	)
	(gr_line
		(start 123.970542 -388.774432)
		(end 124.491242 -388.774432)
		(stroke
			(width 0.0635)
			(type default)
		)
		(layer "F.Cu")
	)
	(gr_line
		(start 123.970542 -385.31038)
		(end 124.491242 -385.31038)
		(stroke
			(width 0.0635)
			(type default)
		)
		(layer "F.Cu")
	)
	(gr_line
		(start 124.000006 -372.47322)
		(end 123.704096 -372.76913)
		(stroke
			(width 0.06477)
			(type default)
		)
		(layer "F.Cu")
	)
	(gr_line
		(start 124.02439 -383.13741)
		(end 124.117862 -383.230882)
		(stroke
			(width 0.0508)
			(type default)
		)
		(layer "F.Cu")
	)
	(gr_line
		(start 124.02439 -382.942592)
		(end 124.02439 -383.13741)
		(stroke
			(width 0.0508)
			(type default)
		)
		(layer "F.Cu")
	)
	(gr_arc
		(start 124.05233 -373.702072)
		(mid 124.037455 -373.6492)
		(end 124.005848 -373.604282)
		(stroke
			(width 0.0508)
			(type default)
		)
		(layer "F.Cu")
	)
	(gr_line
		(start 124.053346 -374.84304)
		(end 124.053346 -375.37136)
		(stroke
			(width 0.0508)
			(type default)
		)
		(layer "F.Cu")
	)
	(gr_line
		(start 124.058426 -408.784044)
		(end 124.354336 -409.079954)
		(stroke
			(width 0.06477)
			(type default)
		)
		(layer "F.Cu")
	)
	(gr_line
		(start 124.083826 -404.46452)
		(end 124.354336 -404.73503)
		(stroke
			(width 0.06477)
			(type default)
		)
		(layer "F.Cu")
	)
	(gr_line
		(start 124.117862 -383.230882)
		(end 124.117862 -383.92227)
		(stroke
			(width 0.0508)
			(type default)
		)
		(layer "F.Cu")
	)
	(gr_line
		(start 124.11837 -391.36574)
		(end 124.11837 -390.761982)
		(stroke
			(width 0.0508)
			(type default)
		)
		(layer "F.Cu")
	)
	(gr_line
		(start 124.11837 -390.761982)
		(end 124.117862 -390.761474)
		(stroke
			(width 0.0508)
			(type default)
		)
		(layer "F.Cu")
	)
	(gr_line
		(start 124.160788 -35.430968)
		(end 123.75642 -35.430968)
		(stroke
			(width 0.06477)
			(type default)
		)
		(layer "F.Cu")
	)
	(gr_line
		(start 124.160788 -35.430968)
		(end 124.64161 -35.91179)
		(stroke
			(width 0.06477)
			(type default)
		)
		(layer "F.Cu")
	)
	(gr_line
		(start 124.172218 -36.675568)
		(end 123.75642 -36.675568)
		(stroke
			(width 0.06477)
			(type default)
		)
		(layer "F.Cu")
	)
	(gr_line
		(start 124.172218 -36.675568)
		(end 124.612146 -36.23564)
		(stroke
			(width 0.06477)
			(type default)
		)
		(layer "F.Cu")
	)
	(gr_line
		(start 124.270516 -374.84431)
		(end 124.381006 -374.9548)
		(stroke
			(width 0.0508)
			(type default)
		)
		(layer "F.Cu")
	)
	(gr_arc
		(start 124.316744 -373.604282)
		(mid 124.285097 -373.64918)
		(end 124.270262 -373.702072)
		(stroke
			(width 0.0508)
			(type default)
		)
		(layer "F.Cu")
	)
	(gr_line
		(start 124.322586 -372.47322)
		(end 124.618496 -372.76913)
		(stroke
			(width 0.06477)
			(type default)
		)
		(layer "F.Cu")
	)
	(gr_line
		(start 124.354336 -412.299658)
		(end 124.083826 -412.570168)
		(stroke
			(width 0.06477)
			(type default)
		)
		(layer "F.Cu")
	)
	(gr_line
		(start 124.354336 -407.954734)
		(end 124.058426 -408.250644)
		(stroke
			(width 0.06477)
			(type default)
		)
		(layer "F.Cu")
	)
	(gr_line
		(start 124.370592 -389.467344)
		(end 124.891292 -389.467344)
		(stroke
			(width 0.0635)
			(type default)
		)
		(layer "F.Cu")
	)
	(gr_line
		(start 124.370592 -386.003292)
		(end 124.891292 -386.003292)
		(stroke
			(width 0.0635)
			(type default)
		)
		(layer "F.Cu")
	)
	(gr_line
		(start 124.377704 -392.977116)
		(end 124.375672 -392.977116)
		(stroke
			(width 0.0508)
			(type default)
		)
		(layer "F.Cu")
	)
	(gr_line
		(start 124.381006 -375.2596)
		(end 124.270516 -375.37009)
		(stroke
			(width 0.0508)
			(type default)
		)
		(layer "F.Cu")
	)
	(gr_line
		(start 124.381006 -374.9548)
		(end 124.381006 -375.2596)
		(stroke
			(width 0.0508)
			(type default)
		)
		(layer "F.Cu")
	)
	(gr_line
		(start 124.516642 -393.292838)
		(end 124.516642 -393.116054)
		(stroke
			(width 0.0508)
			(type default)
		)
		(layer "F.Cu")
	)
	(gr_line
		(start 124.516642 -393.116054)
		(end 124.377704 -392.977116)
		(stroke
			(width 0.0508)
			(type default)
		)
		(layer "F.Cu")
	)
	(gr_line
		(start 124.516642 -392.620246)
		(end 124.376942 -392.759946)
		(stroke
			(width 0.0508)
			(type default)
		)
		(layer "F.Cu")
	)
	(gr_line
		(start 124.516642 -392.429238)
		(end 124.516642 -392.620246)
		(stroke
			(width 0.0508)
			(type default)
		)
		(layer "F.Cu")
	)
	(gr_line
		(start 124.593096 -371.49913)
		(end 124.322586 -371.76964)
		(stroke
			(width 0.06477)
			(type default)
		)
		(layer "F.Cu")
	)
	(gr_line
		(start 124.612146 -36.23564)
		(end 124.172218 -36.675568)
		(stroke
			(width 0.06477)
			(type default)
		)
		(layer "F.Cu")
	)
	(gr_line
		(start 124.612146 -36.23564)
		(end 124.64288 -36.23564)
		(stroke
			(width 0.06477)
			(type default)
		)
		(layer "F.Cu")
	)
	(gr_line
		(start 124.618496 -373.30253)
		(end 124.316744 -373.604282)
		(stroke
			(width 0.0508)
			(type default)
		)
		(layer "F.Cu")
	)
	(gr_line
		(start 124.64161 -35.91179)
		(end 124.160788 -35.430968)
		(stroke
			(width 0.06477)
			(type default)
		)
		(layer "F.Cu")
	)
	(gr_line
		(start 124.64288 -36.23564)
		(end 124.612146 -36.23564)
		(stroke
			(width 0.06477)
			(type default)
		)
		(layer "F.Cu")
	)
	(gr_line
		(start 124.676916 -412.299658)
		(end 124.947426 -412.570168)
		(stroke
			(width 0.06477)
			(type default)
		)
		(layer "F.Cu")
	)
	(gr_line
		(start 124.676916 -407.954734)
		(end 124.972826 -408.250644)
		(stroke
			(width 0.06477)
			(type default)
		)
		(layer "F.Cu")
	)
	(gr_line
		(start 124.716032 -383.50571)
		(end 124.807218 -383.596896)
		(stroke
			(width 0.0508)
			(type default)
		)
		(layer "F.Cu")
	)
	(gr_line
		(start 124.716032 -383.2352)
		(end 124.716032 -383.50571)
		(stroke
			(width 0.0508)
			(type default)
		)
		(layer "F.Cu")
	)
	(gr_line
		(start 124.767848 -277.870412)
		(end 125.2347 -278.13635)
		(stroke
			(width 0.06477)
			(type default)
		)
		(layer "F.Cu")
	)
	(gr_line
		(start 124.767848 -276.2504)
		(end 125.2347 -276.516338)
		(stroke
			(width 0.06477)
			(type default)
		)
		(layer "F.Cu")
	)
	(gr_line
		(start 124.767848 -274.630388)
		(end 125.2347 -274.896326)
		(stroke
			(width 0.06477)
			(type default)
		)
		(layer "F.Cu")
	)
	(gr_line
		(start 124.767848 -273.010376)
		(end 125.2347 -273.276314)
		(stroke
			(width 0.06477)
			(type default)
		)
		(layer "F.Cu")
	)
	(gr_line
		(start 124.767848 -271.390364)
		(end 125.2347 -271.656302)
		(stroke
			(width 0.06477)
			(type default)
		)
		(layer "F.Cu")
	)
	(gr_line
		(start 124.767848 -269.770352)
		(end 125.2347 -270.03629)
		(stroke
			(width 0.06477)
			(type default)
		)
		(layer "F.Cu")
	)
	(gr_line
		(start 124.807218 -383.596896)
		(end 124.941584 -383.596896)
		(stroke
			(width 0.0508)
			(type default)
		)
		(layer "F.Cu")
	)
	(gr_line
		(start 124.941584 -383.596896)
		(end 125.018038 -383.520442)
		(stroke
			(width 0.0508)
			(type default)
		)
		(layer "F.Cu")
	)
	(gr_line
		(start 124.947426 -404.46452)
		(end 124.676916 -404.73503)
		(stroke
			(width 0.06477)
			(type default)
		)
		(layer "F.Cu")
	)
	(gr_line
		(start 124.972826 -408.784044)
		(end 124.676916 -409.079954)
		(stroke
			(width 0.06477)
			(type default)
		)
		(layer "F.Cu")
	)
	(gr_line
		(start 124.976128 -36.07435)
		(end 126.300484 -35.352228)
		(stroke
			(width 0.19304)
			(type default)
		)
		(layer "F.Cu")
	)
	(gr_line
		(start 124.976128 -36.07435)
		(end 129.350008 -36.574476)
		(stroke
			(width 0.19304)
			(type default)
		)
		(layer "F.Cu")
	)
	(gr_line
		(start 124.98832 -34.021268)
		(end 124.98832 -33.818068)
		(stroke
			(width 0.06477)
			(type default)
		)
		(layer "F.Cu")
	)
	(gr_line
		(start 124.98832 -33.818068)
		(end 124.55652 -33.386268)
		(stroke
			(width 0.06477)
			(type default)
		)
		(layer "F.Cu")
	)
	(gr_line
		(start 124.98832 -32.954468)
		(end 125.42012 -33.386268)
		(stroke
			(width 0.06477)
			(type default)
		)
		(layer "F.Cu")
	)
	(gr_line
		(start 124.98832 -32.751268)
		(end 124.98832 -32.954468)
		(stroke
			(width 0.06477)
			(type default)
		)
		(layer "F.Cu")
	)
	(gr_line
		(start 125.00737 -382.943862)
		(end 124.716032 -383.2352)
		(stroke
			(width 0.0508)
			(type default)
		)
		(layer "F.Cu")
	)
	(gr_line
		(start 125.018038 -383.520442)
		(end 125.018038 -383.402586)
		(stroke
			(width 0.0508)
			(type default)
		)
		(layer "F.Cu")
	)
	(gr_line
		(start 125.095 -322.055998)
		(end 125.1458 -322.106798)
		(stroke
			(width 0.06477)
			(type default)
		)
		(layer "F.Cu")
	)
	(gr_line
		(start 125.10135 -391.36447)
		(end 125.018038 -391.281158)
		(stroke
			(width 0.0508)
			(type default)
		)
		(layer "F.Cu")
	)
	(gr_line
		(start 125.170438 -388.774432)
		(end 125.691138 -388.774432)
		(stroke
			(width 0.0635)
			(type default)
		)
		(layer "F.Cu")
	)
	(gr_line
		(start 125.170438 -385.31038)
		(end 125.691138 -385.31038)
		(stroke
			(width 0.0635)
			(type default)
		)
		(layer "F.Cu")
	)
	(gr_line
		(start 125.22454 -383.13741)
		(end 125.318012 -383.230882)
		(stroke
			(width 0.0508)
			(type default)
		)
		(layer "F.Cu")
	)
	(gr_line
		(start 125.22454 -382.942592)
		(end 125.22454 -383.13741)
		(stroke
			(width 0.0508)
			(type default)
		)
		(layer "F.Cu")
	)
	(gr_line
		(start 125.2347 -291.096192)
		(end 124.767848 -290.830254)
		(stroke
			(width 0.06477)
			(type default)
		)
		(layer "F.Cu")
	)
	(gr_line
		(start 125.2347 -289.47618)
		(end 124.767848 -289.210242)
		(stroke
			(width 0.06477)
			(type default)
		)
		(layer "F.Cu")
	)
	(gr_line
		(start 125.2347 -287.856422)
		(end 124.767848 -287.590484)
		(stroke
			(width 0.06477)
			(type default)
		)
		(layer "F.Cu")
	)
	(gr_line
		(start 125.2347 -286.23641)
		(end 124.767848 -285.970472)
		(stroke
			(width 0.06477)
			(type default)
		)
		(layer "F.Cu")
	)
	(gr_line
		(start 125.2347 -284.616398)
		(end 124.767848 -284.35046)
		(stroke
			(width 0.06477)
			(type default)
		)
		(layer "F.Cu")
	)
	(gr_line
		(start 125.2347 -282.996386)
		(end 124.767848 -282.730448)
		(stroke
			(width 0.06477)
			(type default)
		)
		(layer "F.Cu")
	)
	(gr_line
		(start 125.2347 -281.376374)
		(end 124.767848 -281.110436)
		(stroke
			(width 0.06477)
			(type default)
		)
		(layer "F.Cu")
	)
	(gr_line
		(start 125.318012 -383.230882)
		(end 125.318012 -383.92227)
		(stroke
			(width 0.0508)
			(type default)
		)
		(layer "F.Cu")
	)
	(gr_line
		(start 125.31852 -391.36574)
		(end 125.31852 -390.761982)
		(stroke
			(width 0.0508)
			(type default)
		)
		(layer "F.Cu")
	)
	(gr_line
		(start 125.31852 -390.761982)
		(end 125.318012 -390.761474)
		(stroke
			(width 0.0508)
			(type default)
		)
		(layer "F.Cu")
	)
	(gr_line
		(start 125.405896 -370.83873)
		(end 125.755146 -371.18798)
		(stroke
			(width 0.0508)
			(type default)
		)
		(layer "F.Cu")
	)
	(gr_line
		(start 125.431296 -369.03533)
		(end 125.701806 -369.30584)
		(stroke
			(width 0.06477)
			(type default)
		)
		(layer "F.Cu")
	)
	(gr_line
		(start 125.570488 -389.467344)
		(end 126.091188 -389.467344)
		(stroke
			(width 0.0635)
			(type default)
		)
		(layer "F.Cu")
	)
	(gr_line
		(start 125.570488 -386.003292)
		(end 126.091188 -386.003292)
		(stroke
			(width 0.0635)
			(type default)
		)
		(layer "F.Cu")
	)
	(gr_line
		(start 125.577854 -392.977116)
		(end 125.575822 -392.977116)
		(stroke
			(width 0.0508)
			(type default)
		)
		(layer "F.Cu")
	)
	(gr_line
		(start 125.701806 -370.00942)
		(end 125.405896 -370.30533)
		(stroke
			(width 0.06477)
			(type default)
		)
		(layer "F.Cu")
	)
	(gr_line
		(start 125.707902 -277.870412)
		(end 126.174754 -278.13635)
		(stroke
			(width 0.06477)
			(type default)
		)
		(layer "F.Cu")
	)
	(gr_line
		(start 125.707902 -276.2504)
		(end 126.174754 -276.516338)
		(stroke
			(width 0.06477)
			(type default)
		)
		(layer "F.Cu")
	)
	(gr_line
		(start 125.707902 -274.630388)
		(end 126.174754 -274.896326)
		(stroke
			(width 0.06477)
			(type default)
		)
		(layer "F.Cu")
	)
	(gr_line
		(start 125.707902 -273.010376)
		(end 126.174754 -273.276314)
		(stroke
			(width 0.06477)
			(type default)
		)
		(layer "F.Cu")
	)
	(gr_line
		(start 125.707902 -271.390364)
		(end 126.174754 -271.656302)
		(stroke
			(width 0.06477)
			(type default)
		)
		(layer "F.Cu")
	)
	(gr_line
		(start 125.707902 -269.770352)
		(end 126.174754 -270.03629)
		(stroke
			(width 0.06477)
			(type default)
		)
		(layer "F.Cu")
	)
	(gr_line
		(start 125.716538 -393.292838)
		(end 125.716538 -393.1158)
		(stroke
			(width 0.0508)
			(type default)
		)
		(layer "F.Cu")
	)
	(gr_line
		(start 125.716538 -393.1158)
		(end 125.577854 -392.977116)
		(stroke
			(width 0.0508)
			(type default)
		)
		(layer "F.Cu")
	)
	(gr_line
		(start 125.716538 -392.6205)
		(end 125.577092 -392.759946)
		(stroke
			(width 0.0508)
			(type default)
		)
		(layer "F.Cu")
	)
	(gr_line
		(start 125.716538 -392.429238)
		(end 125.716538 -392.6205)
		(stroke
			(width 0.0508)
			(type default)
		)
		(layer "F.Cu")
	)
	(gr_line
		(start 125.76429 -320.909188)
		(end 126.111 -321.255898)
		(stroke
			(width 0.06477)
			(type default)
		)
		(layer "F.Cu")
	)
	(gr_line
		(start 125.913388 -32.6263)
		(end 125.78842 -32.751268)
		(stroke
			(width 0.06477)
			(type default)
		)
		(layer "F.Cu")
	)
	(gr_line
		(start 125.915928 -383.50571)
		(end 126.007114 -383.596896)
		(stroke
			(width 0.0508)
			(type default)
		)
		(layer "F.Cu")
	)
	(gr_line
		(start 125.915928 -383.2352)
		(end 125.915928 -383.50571)
		(stroke
			(width 0.0508)
			(type default)
		)
		(layer "F.Cu")
	)
	(gr_line
		(start 126.007114 -383.596896)
		(end 126.14148 -383.596896)
		(stroke
			(width 0.0508)
			(type default)
		)
		(layer "F.Cu")
	)
	(gr_line
		(start 126.024386 -370.00942)
		(end 126.320296 -370.30533)
		(stroke
			(width 0.06477)
			(type default)
		)
		(layer "F.Cu")
	)
	(gr_line
		(start 126.110492 -32.6263)
		(end 125.913388 -32.6263)
		(stroke
			(width 0.06477)
			(type default)
		)
		(layer "F.Cu")
	)
	(gr_line
		(start 126.111 -322.055998)
		(end 125.76429 -322.402708)
		(stroke
			(width 0.06477)
			(type default)
		)
		(layer "F.Cu")
	)
	(gr_line
		(start 126.14148 -383.596896)
		(end 126.217934 -383.520442)
		(stroke
			(width 0.0508)
			(type default)
		)
		(layer "F.Cu")
	)
	(gr_line
		(start 126.14148 -325.812404)
		(end 126.686056 -326.35698)
		(stroke
			(width 0.06477)
			(type default)
		)
		(layer "F.Cu")
	)
	(gr_line
		(start 126.174754 -291.096192)
		(end 125.707902 -290.830254)
		(stroke
			(width 0.06477)
			(type default)
		)
		(layer "F.Cu")
	)
	(gr_line
		(start 126.174754 -289.47618)
		(end 125.707902 -289.210242)
		(stroke
			(width 0.06477)
			(type default)
		)
		(layer "F.Cu")
	)
	(gr_line
		(start 126.174754 -287.856422)
		(end 125.707902 -287.590484)
		(stroke
			(width 0.06477)
			(type default)
		)
		(layer "F.Cu")
	)
	(gr_line
		(start 126.174754 -286.23641)
		(end 125.707902 -285.970472)
		(stroke
			(width 0.06477)
			(type default)
		)
		(layer "F.Cu")
	)
	(gr_line
		(start 126.174754 -284.616398)
		(end 125.707902 -284.35046)
		(stroke
			(width 0.06477)
			(type default)
		)
		(layer "F.Cu")
	)
	(gr_line
		(start 126.174754 -282.996386)
		(end 125.707902 -282.730448)
		(stroke
			(width 0.06477)
			(type default)
		)
		(layer "F.Cu")
	)
	(gr_line
		(start 126.174754 -281.376374)
		(end 125.707902 -281.110436)
		(stroke
			(width 0.06477)
			(type default)
		)
		(layer "F.Cu")
	)
	(gr_line
		(start 126.18339 -34.021268)
		(end 125.78842 -34.021268)
		(stroke
			(width 0.06477)
			(type default)
		)
		(layer "F.Cu")
	)
	(gr_line
		(start 126.207266 -382.943862)
		(end 125.915928 -383.2352)
		(stroke
			(width 0.0508)
			(type default)
		)
		(layer "F.Cu")
	)
	(gr_line
		(start 126.217934 -383.520442)
		(end 126.217934 -383.402586)
		(stroke
			(width 0.0508)
			(type default)
		)
		(layer "F.Cu")
	)
	(gr_line
		(start 126.294896 -369.03533)
		(end 126.024386 -369.30584)
		(stroke
			(width 0.06477)
			(type default)
		)
		(layer "F.Cu")
	)
	(gr_line
		(start 126.300738 -391.363962)
		(end 126.217934 -391.281158)
		(stroke
			(width 0.0508)
			(type default)
		)
		(layer "F.Cu")
	)
	(gr_line
		(start 126.320296 -370.83873)
		(end 125.971046 -371.18798)
		(stroke
			(width 0.0508)
			(type default)
		)
		(layer "F.Cu")
	)
	(gr_line
		(start 126.370588 -388.774432)
		(end 126.891288 -388.774432)
		(stroke
			(width 0.0635)
			(type default)
		)
		(layer "F.Cu")
	)
	(gr_line
		(start 126.370588 -385.31038)
		(end 126.891288 -385.31038)
		(stroke
			(width 0.0635)
			(type default)
		)
		(layer "F.Cu")
	)
	(gr_line
		(start 126.371096 -325.584058)
		(end 126.63932 -325.584058)
		(stroke
			(width 0.06477)
			(type default)
		)
		(layer "F.Cu")
	)
	(gr_line
		(start 126.424436 -383.13741)
		(end 126.517908 -383.230882)
		(stroke
			(width 0.0508)
			(type default)
		)
		(layer "F.Cu")
	)
	(gr_line
		(start 126.424436 -382.942592)
		(end 126.424436 -383.13741)
		(stroke
			(width 0.0508)
			(type default)
		)
		(layer "F.Cu")
	)
	(gr_line
		(start 126.438406 -376.553984)
		(end 126.281688 -376.553984)
		(stroke
			(width 0.0508)
			(type default)
		)
		(layer "F.Cu")
	)
	(gr_line
		(start 126.487936 -378.48286)
		(end 126.487682 -378.48286)
		(stroke
			(width 0.0508)
			(type default)
		)
		(layer "F.Cu")
	)
	(gr_line
		(start 126.501398 -376.027188)
		(end 126.12751 -376.401076)
		(stroke
			(width 0.0508)
			(type default)
		)
		(layer "F.Cu")
	)
	(gr_line
		(start 126.517908 -391.365232)
		(end 126.517908 -390.761474)
		(stroke
			(width 0.0508)
			(type default)
		)
		(layer "F.Cu")
	)
	(gr_line
		(start 126.517908 -383.230882)
		(end 126.517908 -383.92227)
		(stroke
			(width 0.0508)
			(type default)
		)
		(layer "F.Cu")
	)
	(gr_line
		(start 126.63932 -325.584058)
		(end 126.914402 -325.85914)
		(stroke
			(width 0.06477)
			(type default)
		)
		(layer "F.Cu")
	)
	(gr_line
		(start 126.654306 -376.338084)
		(end 126.438406 -376.553984)
		(stroke
			(width 0.0508)
			(type default)
		)
		(layer "F.Cu")
	)
	(gr_line
		(start 126.654306 -376.181366)
		(end 126.654306 -376.338084)
		(stroke
			(width 0.0508)
			(type default)
		)
		(layer "F.Cu")
	)
	(gr_line
		(start 126.67742 -33.527238)
		(end 126.18339 -34.021268)
		(stroke
			(width 0.06477)
			(type default)
		)
		(layer "F.Cu")
	)
	(gr_line
		(start 126.68758 -33.203388)
		(end 126.110492 -32.6263)
		(stroke
			(width 0.06477)
			(type default)
		)
		(layer "F.Cu")
	)
	(gr_line
		(start 126.68885 -33.527238)
		(end 126.67742 -33.527238)
		(stroke
			(width 0.06477)
			(type default)
		)
		(layer "F.Cu")
	)
	(gr_line
		(start 126.770638 -389.467344)
		(end 127.291338 -389.467344)
		(stroke
			(width 0.0635)
			(type default)
		)
		(layer "F.Cu")
	)
	(gr_line
		(start 126.770638 -386.003292)
		(end 127.291338 -386.003292)
		(stroke
			(width 0.0635)
			(type default)
		)
		(layer "F.Cu")
	)
	(gr_line
		(start 126.77775 -392.977116)
		(end 126.775718 -392.977116)
		(stroke
			(width 0.0508)
			(type default)
		)
		(layer "F.Cu")
	)
	(gr_line
		(start 126.798578 -378.635768)
		(end 126.642114 -378.635768)
		(stroke
			(width 0.0508)
			(type default)
		)
		(layer "F.Cu")
	)
	(gr_line
		(start 126.861316 -378.10948)
		(end 126.487936 -378.48286)
		(stroke
			(width 0.0508)
			(type default)
		)
		(layer "F.Cu")
	)
	(gr_line
		(start 126.914402 -325.85914)
		(end 126.914402 -326.127364)
		(stroke
			(width 0.06477)
			(type default)
		)
		(layer "F.Cu")
	)
	(gr_line
		(start 126.916688 -393.292838)
		(end 126.916688 -393.116054)
		(stroke
			(width 0.0508)
			(type default)
		)
		(layer "F.Cu")
	)
	(gr_line
		(start 126.916688 -393.116054)
		(end 126.77775 -392.977116)
		(stroke
			(width 0.0508)
			(type default)
		)
		(layer "F.Cu")
	)
	(gr_line
		(start 126.916688 -392.620246)
		(end 126.776988 -392.759946)
		(stroke
			(width 0.0508)
			(type default)
		)
		(layer "F.Cu")
	)
	(gr_line
		(start 126.916688 -392.429238)
		(end 126.916688 -392.620246)
		(stroke
			(width 0.0508)
			(type default)
		)
		(layer "F.Cu")
	)
	(gr_line
		(start 126.96063 -326.631554)
		(end 127.505206 -327.17613)
		(stroke
			(width 0.06477)
			(type default)
		)
		(layer "F.Cu")
	)
	(gr_line
		(start 127.014224 -378.420122)
		(end 126.798578 -378.635768)
		(stroke
			(width 0.0508)
			(type default)
		)
		(layer "F.Cu")
	)
	(gr_line
		(start 127.014224 -378.263658)
		(end 127.014224 -378.420122)
		(stroke
			(width 0.0508)
			(type default)
		)
		(layer "F.Cu")
	)
	(gr_line
		(start 127.115824 -383.50571)
		(end 127.20701 -383.596896)
		(stroke
			(width 0.0508)
			(type default)
		)
		(layer "F.Cu")
	)
	(gr_line
		(start 127.115824 -383.2352)
		(end 127.115824 -383.50571)
		(stroke
			(width 0.0508)
			(type default)
		)
		(layer "F.Cu")
	)
	(gr_line
		(start 127.121666 -408.784044)
		(end 127.417576 -409.079954)
		(stroke
			(width 0.06477)
			(type default)
		)
		(layer "F.Cu")
	)
	(gr_line
		(start 127.147066 -404.46452)
		(end 127.417576 -404.73503)
		(stroke
			(width 0.06477)
			(type default)
		)
		(layer "F.Cu")
	)
	(gr_line
		(start 127.190246 -326.403208)
		(end 127.45847 -326.403208)
		(stroke
			(width 0.06477)
			(type default)
		)
		(layer "F.Cu")
	)
	(gr_line
		(start 127.20701 -383.596896)
		(end 127.341376 -383.596896)
		(stroke
			(width 0.0508)
			(type default)
		)
		(layer "F.Cu")
	)
	(gr_line
		(start 127.341376 -383.596896)
		(end 127.41783 -383.520442)
		(stroke
			(width 0.0508)
			(type default)
		)
		(layer "F.Cu")
	)
	(gr_line
		(start 127.407162 -382.943862)
		(end 127.115824 -383.2352)
		(stroke
			(width 0.0508)
			(type default)
		)
		(layer "F.Cu")
	)
	(gr_line
		(start 127.417576 -412.299658)
		(end 127.147066 -412.570168)
		(stroke
			(width 0.06477)
			(type default)
		)
		(layer "F.Cu")
	)
	(gr_line
		(start 127.417576 -407.954734)
		(end 127.121666 -408.250644)
		(stroke
			(width 0.06477)
			(type default)
		)
		(layer "F.Cu")
	)
	(gr_line
		(start 127.41783 -383.520442)
		(end 127.41783 -383.402586)
		(stroke
			(width 0.0508)
			(type default)
		)
		(layer "F.Cu")
	)
	(gr_line
		(start 127.45847 -326.403208)
		(end 127.733552 -326.67829)
		(stroke
			(width 0.06477)
			(type default)
		)
		(layer "F.Cu")
	)
	(gr_line
		(start 127.501142 -391.36447)
		(end 127.41783 -391.281158)
		(stroke
			(width 0.0508)
			(type default)
		)
		(layer "F.Cu")
	)
	(gr_line
		(start 127.570484 -388.774432)
		(end 128.091184 -388.774432)
		(stroke
			(width 0.0635)
			(type default)
		)
		(layer "F.Cu")
	)
	(gr_line
		(start 127.570484 -385.31038)
		(end 128.091184 -385.31038)
		(stroke
			(width 0.0635)
			(type default)
		)
		(layer "F.Cu")
	)
	(gr_line
		(start 127.624332 -383.13741)
		(end 127.718058 -383.231136)
		(stroke
			(width 0.0508)
			(type default)
		)
		(layer "F.Cu")
	)
	(gr_line
		(start 127.624332 -382.942592)
		(end 127.624332 -383.13741)
		(stroke
			(width 0.0508)
			(type default)
		)
		(layer "F.Cu")
	)
	(gr_line
		(start 127.718058 -383.231136)
		(end 127.718058 -383.92227)
		(stroke
			(width 0.0508)
			(type default)
		)
		(layer "F.Cu")
	)
	(gr_line
		(start 127.718312 -391.36574)
		(end 127.718312 -390.761728)
		(stroke
			(width 0.0508)
			(type default)
		)
		(layer "F.Cu")
	)
	(gr_line
		(start 127.718312 -390.761728)
		(end 127.718058 -390.761474)
		(stroke
			(width 0.0508)
			(type default)
		)
		(layer "F.Cu")
	)
	(gr_line
		(start 127.733552 -326.67829)
		(end 127.733552 -326.946514)
		(stroke
			(width 0.06477)
			(type default)
		)
		(layer "F.Cu")
	)
	(gr_line
		(start 127.740156 -412.299658)
		(end 128.010666 -412.570168)
		(stroke
			(width 0.06477)
			(type default)
		)
		(layer "F.Cu")
	)
	(gr_line
		(start 127.740156 -407.954734)
		(end 128.036066 -408.250644)
		(stroke
			(width 0.06477)
			(type default)
		)
		(layer "F.Cu")
	)
	(gr_line
		(start 127.77978 -327.450704)
		(end 128.324356 -327.99528)
		(stroke
			(width 0.06477)
			(type default)
		)
		(layer "F.Cu")
	)
	(gr_line
		(start 127.970534 -389.467344)
		(end 128.491234 -389.467344)
		(stroke
			(width 0.0635)
			(type default)
		)
		(layer "F.Cu")
	)
	(gr_line
		(start 127.970534 -386.003292)
		(end 128.491234 -386.003292)
		(stroke
			(width 0.0635)
			(type default)
		)
		(layer "F.Cu")
	)
	(gr_line
		(start 127.977646 -392.977116)
		(end 127.975614 -392.977116)
		(stroke
			(width 0.0508)
			(type default)
		)
		(layer "F.Cu")
	)
	(gr_line
		(start 128.009396 -327.222358)
		(end 128.27762 -327.222358)
		(stroke
			(width 0.06477)
			(type default)
		)
		(layer "F.Cu")
	)
	(gr_line
		(start 128.010666 -404.46452)
		(end 127.740156 -404.73503)
		(stroke
			(width 0.06477)
			(type default)
		)
		(layer "F.Cu")
	)
	(gr_line
		(start 128.036066 -408.784044)
		(end 127.740156 -409.079954)
		(stroke
			(width 0.06477)
			(type default)
		)
		(layer "F.Cu")
	)
	(gr_line
		(start 128.116584 -393.292838)
		(end 128.116584 -393.116054)
		(stroke
			(width 0.0508)
			(type default)
		)
		(layer "F.Cu")
	)
	(gr_line
		(start 128.116584 -393.116054)
		(end 127.977646 -392.977116)
		(stroke
			(width 0.0508)
			(type default)
		)
		(layer "F.Cu")
	)
	(gr_line
		(start 128.116584 -392.620246)
		(end 127.976884 -392.759946)
		(stroke
			(width 0.0508)
			(type default)
		)
		(layer "F.Cu")
	)
	(gr_line
		(start 128.116584 -392.429238)
		(end 128.116584 -392.620246)
		(stroke
			(width 0.0508)
			(type default)
		)
		(layer "F.Cu")
	)
	(gr_line
		(start 128.167384 -35.23488)
		(end 128.205992 -35.273488)
		(stroke
			(width 0.06477)
			(type default)
		)
		(layer "F.Cu")
	)
	(gr_line
		(start 128.167384 -34.9123)
		(end 128.206246 -34.873438)
		(stroke
			(width 0.06477)
			(type default)
		)
		(layer "F.Cu")
	)
	(gr_line
		(start 128.173988 -33.705546)
		(end 128.16078 -33.705546)
		(stroke
			(width 0.06477)
			(type default)
		)
		(layer "F.Cu")
	)
	(gr_line
		(start 128.205992 -35.273488)
		(end 128.167384 -35.23488)
		(stroke
			(width 0.06477)
			(type default)
		)
		(layer "F.Cu")
	)
	(gr_line
		(start 128.205992 -35.273488)
		(end 128.844294 -35.273488)
		(stroke
			(width 0.06477)
			(type default)
		)
		(layer "F.Cu")
	)
	(gr_line
		(start 128.205992 -34.073338)
		(end 128.16205 -34.029396)
		(stroke
			(width 0.06477)
			(type default)
		)
		(layer "F.Cu")
	)
	(gr_line
		(start 128.206246 -34.873438)
		(end 128.167384 -34.9123)
		(stroke
			(width 0.06477)
			(type default)
		)
		(layer "F.Cu")
	)
	(gr_line
		(start 128.206246 -34.873438)
		(end 128.844294 -34.873438)
		(stroke
			(width 0.06477)
			(type default)
		)
		(layer "F.Cu")
	)
	(gr_line
		(start 128.206246 -33.673288)
		(end 128.173988 -33.705546)
		(stroke
			(width 0.06477)
			(type default)
		)
		(layer "F.Cu")
	)
	(gr_line
		(start 128.27762 -327.222358)
		(end 128.552702 -327.49744)
		(stroke
			(width 0.06477)
			(type default)
		)
		(layer "F.Cu")
	)
	(gr_line
		(start 128.315974 -383.50571)
		(end 128.40716 -383.596896)
		(stroke
			(width 0.0508)
			(type default)
		)
		(layer "F.Cu")
	)
	(gr_line
		(start 128.315974 -383.2352)
		(end 128.315974 -383.50571)
		(stroke
			(width 0.0508)
			(type default)
		)
		(layer "F.Cu")
	)
	(gr_line
		(start 128.40716 -383.596896)
		(end 128.541526 -383.596896)
		(stroke
			(width 0.0508)
			(type default)
		)
		(layer "F.Cu")
	)
	(gr_line
		(start 128.50368 -33.673288)
		(end 128.206246 -33.673288)
		(stroke
			(width 0.06477)
			(type default)
		)
		(layer "F.Cu")
	)
	(gr_line
		(start 128.50368 -33.673288)
		(end 128.503934 -33.673542)
		(stroke
			(width 0.06477)
			(type default)
		)
		(layer "F.Cu")
	)
	(gr_line
		(start 128.536446 -221.761812)
		(end 128.227836 -222.070422)
		(stroke
			(width 0.06477)
			(type default)
		)
		(layer "F.Cu")
	)
	(gr_line
		(start 128.541526 -383.596896)
		(end 128.61798 -383.520442)
		(stroke
			(width 0.0508)
			(type default)
		)
		(layer "F.Cu")
	)
	(gr_line
		(start 128.552702 -327.49744)
		(end 128.552702 -327.765664)
		(stroke
			(width 0.06477)
			(type default)
		)
		(layer "F.Cu")
	)
	(gr_line
		(start 128.607312 -382.943862)
		(end 128.315974 -383.2352)
		(stroke
			(width 0.0508)
			(type default)
		)
		(layer "F.Cu")
	)
	(gr_line
		(start 128.61798 -383.520442)
		(end 128.61798 -383.402586)
		(stroke
			(width 0.0508)
			(type default)
		)
		(layer "F.Cu")
	)
	(gr_line
		(start 128.69418 -33.673542)
		(end 128.503934 -33.673542)
		(stroke
			(width 0.06477)
			(type default)
		)
		(layer "F.Cu")
	)
	(gr_line
		(start 128.701292 -391.36447)
		(end 128.61798 -391.281158)
		(stroke
			(width 0.0508)
			(type default)
		)
		(layer "F.Cu")
	)
	(gr_line
		(start 128.770634 -388.774432)
		(end 129.291334 -388.774432)
		(stroke
			(width 0.0635)
			(type default)
		)
		(layer "F.Cu")
	)
	(gr_line
		(start 128.770634 -385.31038)
		(end 129.291334 -385.31038)
		(stroke
			(width 0.0635)
			(type default)
		)
		(layer "F.Cu")
	)
	(gr_line
		(start 128.809496 -375.76633)
		(end 129.15773 -376.114564)
		(stroke
			(width 0.0508)
			(type default)
		)
		(layer "F.Cu")
	)
	(gr_line
		(start 128.824482 -383.13741)
		(end 128.917954 -383.230882)
		(stroke
			(width 0.0508)
			(type default)
		)
		(layer "F.Cu")
	)
	(gr_line
		(start 128.824482 -382.942592)
		(end 128.824482 -383.13741)
		(stroke
			(width 0.0508)
			(type default)
		)
		(layer "F.Cu")
	)
	(gr_line
		(start 128.834896 -373.96293)
		(end 129.105406 -374.23344)
		(stroke
			(width 0.06477)
			(type default)
		)
		(layer "F.Cu")
	)
	(gr_line
		(start 128.844294 -35.273488)
		(end 128.205992 -35.273488)
		(stroke
			(width 0.06477)
			(type default)
		)
		(layer "F.Cu")
	)
	(gr_line
		(start 128.844294 -34.873438)
		(end 128.206246 -34.873438)
		(stroke
			(width 0.06477)
			(type default)
		)
		(layer "F.Cu")
	)
	(gr_line
		(start 128.844294 -34.073338)
		(end 128.205992 -34.073338)
		(stroke
			(width 0.06477)
			(type default)
		)
		(layer "F.Cu")
	)
	(gr_line
		(start 128.917954 -383.230882)
		(end 128.917954 -383.92227)
		(stroke
			(width 0.0508)
			(type default)
		)
		(layer "F.Cu")
	)
	(gr_line
		(start 128.918462 -391.36574)
		(end 128.918462 -390.761982)
		(stroke
			(width 0.0508)
			(type default)
		)
		(layer "F.Cu")
	)
	(gr_line
		(start 128.918462 -390.761982)
		(end 128.917954 -390.761474)
		(stroke
			(width 0.0508)
			(type default)
		)
		(layer "F.Cu")
	)
	(gr_line
		(start 129.105406 -374.93702)
		(end 128.809496 -375.23293)
		(stroke
			(width 0.06477)
			(type default)
		)
		(layer "F.Cu")
	)
	(gr_line
		(start 129.15773 -376.114564)
		(end 129.15773 -376.116596)
		(stroke
			(width 0.0508)
			(type default)
		)
		(layer "F.Cu")
	)
	(gr_line
		(start 129.16789 -222.070422)
		(end 128.85928 -221.761812)
		(stroke
			(width 0.06477)
			(type default)
		)
		(layer "F.Cu")
	)
	(gr_line
		(start 129.17043 -389.467344)
		(end 129.69113 -389.467344)
		(stroke
			(width 0.0635)
			(type default)
		)
		(layer "F.Cu")
	)
	(gr_line
		(start 129.17043 -386.003292)
		(end 129.69113 -386.003292)
		(stroke
			(width 0.0635)
			(type default)
		)
		(layer "F.Cu")
	)
	(gr_line
		(start 129.174494 -392.977116)
		(end 129.151126 -392.977116)
		(stroke
			(width 0.0508)
			(type default)
		)
		(layer "F.Cu")
	)
	(gr_line
		(start 129.31648 -393.292838)
		(end 129.31648 -393.119102)
		(stroke
			(width 0.0508)
			(type default)
		)
		(layer "F.Cu")
	)
	(gr_line
		(start 129.31648 -393.119102)
		(end 129.174494 -392.977116)
		(stroke
			(width 0.0508)
			(type default)
		)
		(layer "F.Cu")
	)
	(gr_line
		(start 129.31648 -392.595862)
		(end 129.152396 -392.759946)
		(stroke
			(width 0.0508)
			(type default)
		)
		(layer "F.Cu")
	)
	(gr_line
		(start 129.31648 -392.429238)
		(end 129.31648 -392.595862)
		(stroke
			(width 0.0508)
			(type default)
		)
		(layer "F.Cu")
	)
	(gr_line
		(start 129.350008 -36.574476)
		(end 124.976128 -36.07435)
		(stroke
			(width 0.19304)
			(type default)
		)
		(layer "F.Cu")
	)
	(gr_line
		(start 129.427986 -374.93702)
		(end 129.723896 -375.23293)
		(stroke
			(width 0.06477)
			(type default)
		)
		(layer "F.Cu")
	)
	(gr_line
		(start 129.431288 -219.793058)
		(end 129.777998 -220.139768)
		(stroke
			(width 0.06477)
			(type default)
		)
		(layer "F.Cu")
	)
	(gr_line
		(start 129.51587 -383.50571)
		(end 129.607056 -383.596896)
		(stroke
			(width 0.0508)
			(type default)
		)
		(layer "F.Cu")
	)
	(gr_line
		(start 129.51587 -383.2352)
		(end 129.51587 -383.50571)
		(stroke
			(width 0.0508)
			(type default)
		)
		(layer "F.Cu")
	)
	(gr_line
		(start 129.607056 -383.596896)
		(end 129.741422 -383.596896)
		(stroke
			(width 0.0508)
			(type default)
		)
		(layer "F.Cu")
	)
	(gr_line
		(start 129.698496 -373.96293)
		(end 129.427986 -374.23344)
		(stroke
			(width 0.06477)
			(type default)
		)
		(layer "F.Cu")
	)
	(gr_line
		(start 129.723896 -375.76633)
		(end 129.3749 -376.115326)
		(stroke
			(width 0.0508)
			(type default)
		)
		(layer "F.Cu")
	)
	(gr_line
		(start 129.741422 -383.596896)
		(end 129.817876 -383.520442)
		(stroke
			(width 0.0508)
			(type default)
		)
		(layer "F.Cu")
	)
	(gr_line
		(start 129.807208 -382.943862)
		(end 129.51587 -383.2352)
		(stroke
			(width 0.0508)
			(type default)
		)
		(layer "F.Cu")
	)
	(gr_line
		(start 129.817876 -383.520442)
		(end 129.817876 -383.402586)
		(stroke
			(width 0.0508)
			(type default)
		)
		(layer "F.Cu")
	)
	(gr_line
		(start 129.901188 -391.36447)
		(end 129.817876 -391.281158)
		(stroke
			(width 0.0508)
			(type default)
		)
		(layer "F.Cu")
	)
	(gr_line
		(start 129.97053 -388.774432)
		(end 130.49123 -388.774432)
		(stroke
			(width 0.0635)
			(type default)
		)
		(layer "F.Cu")
	)
	(gr_line
		(start 129.97053 -385.31038)
		(end 130.49123 -385.31038)
		(stroke
			(width 0.0635)
			(type default)
		)
		(layer "F.Cu")
	)
	(gr_line
		(start 130.024378 -383.13741)
		(end 130.11785 -383.230882)
		(stroke
			(width 0.0508)
			(type default)
		)
		(layer "F.Cu")
	)
	(gr_line
		(start 130.024378 -382.942592)
		(end 130.024378 -383.13741)
		(stroke
			(width 0.0508)
			(type default)
		)
		(layer "F.Cu")
	)
	(gr_line
		(start 130.100578 -220.139768)
		(end 130.447288 -219.793058)
		(stroke
			(width 0.06477)
			(type default)
		)
		(layer "F.Cu")
	)
	(gr_line
		(start 130.11785 -383.230882)
		(end 130.11785 -383.92227)
		(stroke
			(width 0.0508)
			(type default)
		)
		(layer "F.Cu")
	)
	(gr_line
		(start 130.118358 -391.36574)
		(end 130.118358 -390.761982)
		(stroke
			(width 0.0508)
			(type default)
		)
		(layer "F.Cu")
	)
	(gr_line
		(start 130.118358 -390.761982)
		(end 130.11785 -390.761474)
		(stroke
			(width 0.0508)
			(type default)
		)
		(layer "F.Cu")
	)
	(gr_line
		(start 130.184906 -408.784044)
		(end 130.480816 -409.079954)
		(stroke
			(width 0.06477)
			(type default)
		)
		(layer "F.Cu")
	)
	(gr_line
		(start 130.210306 -404.46452)
		(end 130.480816 -404.73503)
		(stroke
			(width 0.06477)
			(type default)
		)
		(layer "F.Cu")
	)
	(gr_line
		(start 130.215132 -11.839702)
		(end 130.485642 -12.110212)
		(stroke
			(width 0.06477)
			(type default)
		)
		(layer "F.Cu")
	)
	(gr_line
		(start 130.346958 -13.02512)
		(end 130.346958 -13.599922)
		(stroke
			(width 0.06477)
			(type default)
		)
		(layer "F.Cu")
	)
	(gr_line
		(start 130.37058 -389.467344)
		(end 130.89128 -389.467344)
		(stroke
			(width 0.0635)
			(type default)
		)
		(layer "F.Cu")
	)
	(gr_line
		(start 130.37058 -386.003292)
		(end 130.89128 -386.003292)
		(stroke
			(width 0.0635)
			(type default)
		)
		(layer "F.Cu")
	)
	(gr_line
		(start 130.377692 -392.977116)
		(end 130.37566 -392.977116)
		(stroke
			(width 0.0508)
			(type default)
		)
		(layer "F.Cu")
	)
	(gr_line
		(start 130.480816 -412.299658)
		(end 130.210306 -412.570168)
		(stroke
			(width 0.06477)
			(type default)
		)
		(layer "F.Cu")
	)
	(gr_line
		(start 130.480816 -407.954734)
		(end 130.184906 -408.250644)
		(stroke
			(width 0.06477)
			(type default)
		)
		(layer "F.Cu")
	)
	(gr_line
		(start 130.485642 -12.886436)
		(end 130.346958 -13.02512)
		(stroke
			(width 0.06477)
			(type default)
		)
		(layer "F.Cu")
	)
	(gr_line
		(start 130.485642 -12.88034)
		(end 130.485642 -12.886436)
		(stroke
			(width 0.06477)
			(type default)
		)
		(layer "F.Cu")
	)
	(gr_line
		(start 130.49758 -28.534106)
		(end 130.49758 -27.79268)
		(stroke
			(width 0.06477)
			(type default)
		)
		(layer "F.Cu")
	)
	(gr_line
		(start 130.49758 -27.25928)
		(end 130.6322 -27.25928)
		(stroke
			(width 0.06477)
			(type default)
		)
		(layer "F.Cu")
	)
	(gr_line
		(start 130.511296 -373.30253)
		(end 130.860546 -373.65178)
		(stroke
			(width 0.0508)
			(type default)
		)
		(layer "F.Cu")
	)
	(gr_line
		(start 130.516376 -393.292838)
		(end 130.516376 -393.1158)
		(stroke
			(width 0.0508)
			(type default)
		)
		(layer "F.Cu")
	)
	(gr_line
		(start 130.516376 -393.1158)
		(end 130.377692 -392.977116)
		(stroke
			(width 0.0508)
			(type default)
		)
		(layer "F.Cu")
	)
	(gr_line
		(start 130.516376 -392.6205)
		(end 130.37693 -392.759946)
		(stroke
			(width 0.0508)
			(type default)
		)
		(layer "F.Cu")
	)
	(gr_line
		(start 130.516376 -392.429238)
		(end 130.516376 -392.6205)
		(stroke
			(width 0.0508)
			(type default)
		)
		(layer "F.Cu")
	)
	(gr_line
		(start 130.536696 -371.49913)
		(end 130.807206 -371.76964)
		(stroke
			(width 0.06477)
			(type default)
		)
		(layer "F.Cu")
	)
	(gr_line
		(start 130.6322 -27.25928)
		(end 131.06908 -27.69616)
		(stroke
			(width 0.06477)
			(type default)
		)
		(layer "F.Cu")
	)
	(gr_line
		(start 130.803396 -412.299658)
		(end 131.073906 -412.570168)
		(stroke
			(width 0.06477)
			(type default)
		)
		(layer "F.Cu")
	)
	(gr_line
		(start 130.803396 -407.954734)
		(end 131.099306 -408.250644)
		(stroke
			(width 0.06477)
			(type default)
		)
		(layer "F.Cu")
	)
	(gr_line
		(start 130.807206 -372.47322)
		(end 130.511296 -372.76913)
		(stroke
			(width 0.06477)
			(type default)
		)
		(layer "F.Cu")
	)
	(gr_line
		(start 130.809492 -12.88161)
		(end 130.946906 -13.019024)
		(stroke
			(width 0.06477)
			(type default)
		)
		(layer "F.Cu")
	)
	(gr_line
		(start 130.860546 -375.021856)
		(end 130.860546 -375.550176)
		(stroke
			(width 0.0508)
			(type default)
		)
		(layer "F.Cu")
	)
	(gr_line
		(start 130.90779 -28.96743)
		(end 130.90779 -28.944316)
		(stroke
			(width 0.06477)
			(type default)
		)
		(layer "F.Cu")
	)
	(gr_line
		(start 130.90779 -28.944316)
		(end 130.49758 -28.534106)
		(stroke
			(width 0.06477)
			(type default)
		)
		(layer "F.Cu")
	)
	(gr_line
		(start 130.946906 -13.019024)
		(end 130.946906 -13.599922)
		(stroke
			(width 0.06477)
			(type default)
		)
		(layer "F.Cu")
	)
	(gr_line
		(start 131.06908 -27.69616)
		(end 131.06908 -27.75458)
		(stroke
			(width 0.06477)
			(type default)
		)
		(layer "F.Cu")
	)
	(gr_line
		(start 131.06908 -26.81478)
		(end 131.06908 -26.76398)
		(stroke
			(width 0.06477)
			(type default)
		)
		(layer "F.Cu")
	)
	(gr_line
		(start 131.073906 -404.46452)
		(end 130.803396 -404.73503)
		(stroke
			(width 0.06477)
			(type default)
		)
		(layer "F.Cu")
	)
	(gr_line
		(start 131.077716 -375.023126)
		(end 131.188206 -375.133616)
		(stroke
			(width 0.0508)
			(type default)
		)
		(layer "F.Cu")
	)
	(gr_line
		(start 131.078732 -11.839702)
		(end 130.808222 -12.110212)
		(stroke
			(width 0.06477)
			(type default)
		)
		(layer "F.Cu")
	)
	(gr_line
		(start 131.099306 -408.784044)
		(end 130.803396 -409.079954)
		(stroke
			(width 0.06477)
			(type default)
		)
		(layer "F.Cu")
	)
	(gr_line
		(start 131.101338 -391.36447)
		(end 131.018026 -391.281158)
		(stroke
			(width 0.0508)
			(type default)
		)
		(layer "F.Cu")
	)
	(gr_line
		(start 131.101338 -383.319274)
		(end 131.018026 -383.402586)
		(stroke
			(width 0.0508)
			(type default)
		)
		(layer "F.Cu")
	)
	(gr_line
		(start 131.129786 -372.47322)
		(end 131.425696 -372.76913)
		(stroke
			(width 0.06477)
			(type default)
		)
		(layer "F.Cu")
	)
	(gr_line
		(start 131.17068 -388.774432)
		(end 131.69138 -388.774432)
		(stroke
			(width 0.0635)
			(type default)
		)
		(layer "F.Cu")
	)
	(gr_line
		(start 131.17068 -385.31038)
		(end 131.69138 -385.31038)
		(stroke
			(width 0.0635)
			(type default)
		)
		(layer "F.Cu")
	)
	(gr_line
		(start 131.188206 -375.438416)
		(end 131.077716 -375.548906)
		(stroke
			(width 0.0508)
			(type default)
		)
		(layer "F.Cu")
	)
	(gr_line
		(start 131.188206 -375.133616)
		(end 131.188206 -375.438416)
		(stroke
			(width 0.0508)
			(type default)
		)
		(layer "F.Cu")
	)
	(gr_line
		(start 131.224782 -381.689102)
		(end 131.224528 -381.688848)
		(stroke
			(width 0.0508)
			(type default)
		)
		(layer "F.Cu")
	)
	(gr_line
		(start 131.23164 -28.96616)
		(end 131.64058 -28.55722)
		(stroke
			(width 0.06477)
			(type default)
		)
		(layer "F.Cu")
	)
	(gr_line
		(start 131.318508 -391.36574)
		(end 131.318508 -390.761982)
		(stroke
			(width 0.0508)
			(type default)
		)
		(layer "F.Cu")
	)
	(gr_line
		(start 131.318508 -390.761982)
		(end 131.318 -390.761474)
		(stroke
			(width 0.0508)
			(type default)
		)
		(layer "F.Cu")
	)
	(gr_line
		(start 131.318508 -383.921762)
		(end 131.318 -383.92227)
		(stroke
			(width 0.0508)
			(type default)
		)
		(layer "F.Cu")
	)
	(gr_line
		(start 131.318508 -383.318004)
		(end 131.318508 -383.921762)
		(stroke
			(width 0.0508)
			(type default)
		)
		(layer "F.Cu")
	)
	(gr_line
		(start 131.400296 -371.49913)
		(end 131.129786 -371.76964)
		(stroke
			(width 0.06477)
			(type default)
		)
		(layer "F.Cu")
	)
	(gr_line
		(start 131.425696 -373.30253)
		(end 131.076446 -373.65178)
		(stroke
			(width 0.0508)
			(type default)
		)
		(layer "F.Cu")
	)
	(gr_line
		(start 131.494276 -33.023556)
		(end 131.494276 -32.385254)
		(stroke
			(width 0.06477)
			(type default)
		)
		(layer "F.Cu")
	)
	(gr_line
		(start 131.494276 -32.385254)
		(end 131.532884 -32.346646)
		(stroke
			(width 0.06477)
			(type default)
		)
		(layer "F.Cu")
	)
	(gr_line
		(start 131.51358 -27.25928)
		(end 131.06908 -26.81478)
		(stroke
			(width 0.06477)
			(type default)
		)
		(layer "F.Cu")
	)
	(gr_line
		(start 131.559808 -392.977116)
		(end 131.54914 -392.977116)
		(stroke
			(width 0.0508)
			(type default)
		)
		(layer "F.Cu")
	)
	(gr_line
		(start 131.570476 -389.467344)
		(end 132.091176 -389.467344)
		(stroke
			(width 0.0635)
			(type default)
		)
		(layer "F.Cu")
	)
	(gr_line
		(start 131.570476 -386.003292)
		(end 132.091176 -386.003292)
		(stroke
			(width 0.0635)
			(type default)
		)
		(layer "F.Cu")
	)
	(gr_line
		(start 131.64058 -28.55722)
		(end 131.64058 -27.79268)
		(stroke
			(width 0.06477)
			(type default)
		)
		(layer "F.Cu")
	)
	(gr_line
		(start 131.64058 -27.25928)
		(end 131.51358 -27.25928)
		(stroke
			(width 0.06477)
			(type default)
		)
		(layer "F.Cu")
	)
	(gr_line
		(start 131.716526 -393.292838)
		(end 131.716526 -393.133834)
		(stroke
			(width 0.0508)
			(type default)
		)
		(layer "F.Cu")
	)
	(gr_line
		(start 131.716526 -393.133834)
		(end 131.559808 -392.977116)
		(stroke
			(width 0.0508)
			(type default)
		)
		(layer "F.Cu")
	)
	(gr_line
		(start 131.716526 -392.59383)
		(end 131.55041 -392.759946)
		(stroke
			(width 0.0508)
			(type default)
		)
		(layer "F.Cu")
	)
	(gr_line
		(start 131.716526 -392.429238)
		(end 131.716526 -392.59383)
		(stroke
			(width 0.0508)
			(type default)
		)
		(layer "F.Cu")
	)
	(gr_line
		(start 131.894072 -33.023556)
		(end 131.894072 -32.385254)
		(stroke
			(width 0.06477)
			(type default)
		)
		(layer "F.Cu")
	)
	(gr_line
		(start 131.894072 -32.385254)
		(end 131.855464 -32.346646)
		(stroke
			(width 0.06477)
			(type default)
		)
		(layer "F.Cu")
	)
	(gr_line
		(start 132.02031 -10.243312)
		(end 132.28574 -10.508742)
		(stroke
			(width 0.06477)
			(type default)
		)
		(layer "F.Cu")
	)
	(gr_line
		(start 132.147056 -17.090898)
		(end 132.28574 -17.229582)
		(stroke
			(width 0.06477)
			(type default)
		)
		(layer "F.Cu")
	)
	(gr_line
		(start 132.147056 -16.549878)
		(end 132.147056 -17.090898)
		(stroke
			(width 0.06477)
			(type default)
		)
		(layer "F.Cu")
	)
	(gr_line
		(start 132.147056 -13.062204)
		(end 132.147056 -13.599922)
		(stroke
			(width 0.06477)
			(type default)
		)
		(layer "F.Cu")
	)
	(gr_line
		(start 132.213096 -370.83873)
		(end 132.562346 -371.18798)
		(stroke
			(width 0.0508)
			(type default)
		)
		(layer "F.Cu")
	)
	(gr_line
		(start 132.238496 -369.03533)
		(end 132.509006 -369.30584)
		(stroke
			(width 0.06477)
			(type default)
		)
		(layer "F.Cu")
	)
	(gr_line
		(start 132.284724 -17.874742)
		(end 132.014722 -18.144744)
		(stroke
			(width 0.06477)
			(type default)
		)
		(layer "F.Cu")
	)
	(gr_line
		(start 132.28574 -17.229582)
		(end 132.28574 -17.251934)
		(stroke
			(width 0.06477)
			(type default)
		)
		(layer "F.Cu")
	)
	(gr_line
		(start 132.28574 -12.92352)
		(end 132.147056 -13.062204)
		(stroke
			(width 0.06477)
			(type default)
		)
		(layer "F.Cu")
	)
	(gr_line
		(start 132.28574 -12.856464)
		(end 132.28574 -12.92352)
		(stroke
			(width 0.06477)
			(type default)
		)
		(layer "F.Cu")
	)
	(gr_line
		(start 132.28574 -10.508742)
		(end 132.28574 -10.518902)
		(stroke
			(width 0.06477)
			(type default)
		)
		(layer "F.Cu")
	)
	(gr_line
		(start 132.294122 -32.385254)
		(end 132.294122 -33.023556)
		(stroke
			(width 0.06477)
			(type default)
		)
		(layer "F.Cu")
	)
	(gr_line
		(start 132.301234 -391.36447)
		(end 132.217922 -391.281158)
		(stroke
			(width 0.0508)
			(type default)
		)
		(layer "F.Cu")
	)
	(gr_line
		(start 132.301234 -383.319274)
		(end 132.217922 -383.402586)
		(stroke
			(width 0.0508)
			(type default)
		)
		(layer "F.Cu")
	)
	(gr_line
		(start 132.33273 -32.346646)
		(end 132.294122 -32.385254)
		(stroke
			(width 0.06477)
			(type default)
		)
		(layer "F.Cu")
	)
	(gr_line
		(start 132.370576 -388.774432)
		(end 132.891276 -388.774432)
		(stroke
			(width 0.0635)
			(type default)
		)
		(layer "F.Cu")
	)
	(gr_line
		(start 132.370576 -385.31038)
		(end 132.891276 -385.31038)
		(stroke
			(width 0.0635)
			(type default)
		)
		(layer "F.Cu")
	)
	(gr_line
		(start 132.509006 -370.00942)
		(end 132.213096 -370.30533)
		(stroke
			(width 0.06477)
			(type default)
		)
		(layer "F.Cu")
	)
	(gr_line
		(start 132.518404 -391.36574)
		(end 132.518404 -390.761982)
		(stroke
			(width 0.0508)
			(type default)
		)
		(layer "F.Cu")
	)
	(gr_line
		(start 132.518404 -390.761982)
		(end 132.517896 -390.761474)
		(stroke
			(width 0.0508)
			(type default)
		)
		(layer "F.Cu")
	)
	(gr_line
		(start 132.518404 -383.921762)
		(end 132.517896 -383.92227)
		(stroke
			(width 0.0508)
			(type default)
		)
		(layer "F.Cu")
	)
	(gr_line
		(start 132.518404 -383.318004)
		(end 132.518404 -383.921762)
		(stroke
			(width 0.0508)
			(type default)
		)
		(layer "F.Cu")
	)
	(gr_line
		(start 132.60832 -17.874742)
		(end 132.878322 -18.144744)
		(stroke
			(width 0.06477)
			(type default)
		)
		(layer "F.Cu")
	)
	(gr_line
		(start 132.60832 -17.873726)
		(end 132.60832 -17.874742)
		(stroke
			(width 0.06477)
			(type default)
		)
		(layer "F.Cu")
	)
	(gr_line
		(start 132.60959 -12.857734)
		(end 132.747004 -12.995148)
		(stroke
			(width 0.06477)
			(type default)
		)
		(layer "F.Cu")
	)
	(gr_line
		(start 132.65531 -32.346646)
		(end 132.694172 -32.385508)
		(stroke
			(width 0.06477)
			(type default)
		)
		(layer "F.Cu")
	)
	(gr_line
		(start 132.694172 -32.385508)
		(end 132.694172 -33.023556)
		(stroke
			(width 0.06477)
			(type default)
		)
		(layer "F.Cu")
	)
	(gr_line
		(start 132.747004 -17.11325)
		(end 132.60959 -17.250664)
		(stroke
			(width 0.06477)
			(type default)
		)
		(layer "F.Cu")
	)
	(gr_line
		(start 132.747004 -16.549878)
		(end 132.747004 -17.11325)
		(stroke
			(width 0.06477)
			(type default)
		)
		(layer "F.Cu")
	)
	(gr_line
		(start 132.747004 -12.995148)
		(end 132.747004 -13.599922)
		(stroke
			(width 0.06477)
			(type default)
		)
		(layer "F.Cu")
	)
	(gr_line
		(start 132.761228 -392.977116)
		(end 132.755132 -392.977116)
		(stroke
			(width 0.0508)
			(type default)
		)
		(layer "F.Cu")
	)
	(gr_line
		(start 132.770626 -389.467344)
		(end 133.291326 -389.467344)
		(stroke
			(width 0.0635)
			(type default)
		)
		(layer "F.Cu")
	)
	(gr_line
		(start 132.770626 -386.003292)
		(end 133.291326 -386.003292)
		(stroke
			(width 0.0635)
			(type default)
		)
		(layer "F.Cu")
	)
	(gr_line
		(start 132.831586 -370.00942)
		(end 133.127496 -370.30533)
		(stroke
			(width 0.06477)
			(type default)
		)
		(layer "F.Cu")
	)
	(gr_line
		(start 132.88391 -10.243312)
		(end 132.60959 -10.517632)
		(stroke
			(width 0.06477)
			(type default)
		)
		(layer "F.Cu")
	)
	(gr_line
		(start 132.916422 -393.292838)
		(end 132.916422 -393.13231)
		(stroke
			(width 0.0508)
			(type default)
		)
		(layer "F.Cu")
	)
	(gr_line
		(start 132.916422 -393.13231)
		(end 132.761228 -392.977116)
		(stroke
			(width 0.0508)
			(type default)
		)
		(layer "F.Cu")
	)
	(gr_line
		(start 132.916422 -392.599926)
		(end 132.756402 -392.759946)
		(stroke
			(width 0.0508)
			(type default)
		)
		(layer "F.Cu")
	)
	(gr_line
		(start 132.916422 -392.429238)
		(end 132.916422 -392.599926)
		(stroke
			(width 0.0508)
			(type default)
		)
		(layer "F.Cu")
	)
	(gr_line
		(start 133.102096 -369.03533)
		(end 132.831586 -369.30584)
		(stroke
			(width 0.06477)
			(type default)
		)
		(layer "F.Cu")
	)
	(gr_line
		(start 133.127496 -370.83873)
		(end 132.778246 -371.18798)
		(stroke
			(width 0.0508)
			(type default)
		)
		(layer "F.Cu")
	)
	(gr_line
		(start 133.248146 -408.784044)
		(end 133.544056 -409.079954)
		(stroke
			(width 0.06477)
			(type default)
		)
		(layer "F.Cu")
	)
	(gr_line
		(start 133.273546 -404.46452)
		(end 133.544056 -404.73503)
		(stroke
			(width 0.06477)
			(type default)
		)
		(layer "F.Cu")
	)
	(gr_line
		(start 133.544056 -412.299658)
		(end 133.273546 -412.570168)
		(stroke
			(width 0.06477)
			(type default)
		)
		(layer "F.Cu")
	)
	(gr_line
		(start 133.544056 -407.954734)
		(end 133.248146 -408.250644)
		(stroke
			(width 0.06477)
			(type default)
		)
		(layer "F.Cu")
	)
	(gr_line
		(start 133.745732 -373.078502)
		(end 134.11962 -373.45239)
		(stroke
			(width 0.0508)
			(type default)
		)
		(layer "F.Cu")
	)
	(gr_line
		(start 133.866636 -412.299658)
		(end 134.137146 -412.570168)
		(stroke
			(width 0.06477)
			(type default)
		)
		(layer "F.Cu")
	)
	(gr_line
		(start 133.866636 -407.954734)
		(end 134.162546 -408.250644)
		(stroke
			(width 0.06477)
			(type default)
		)
		(layer "F.Cu")
	)
	(gr_line
		(start 133.900164 -372.925594)
		(end 134.056628 -372.925594)
		(stroke
			(width 0.0508)
			(type default)
		)
		(layer "F.Cu")
	)
	(gr_line
		(start 134.020052 -25.328118)
		(end 133.72084 -25.62733)
		(stroke
			(width 0.06477)
			(type default)
		)
		(layer "F.Cu")
	)
	(gr_line
		(start 134.056628 -372.925594)
		(end 134.272528 -373.141494)
		(stroke
			(width 0.0508)
			(type default)
		)
		(layer "F.Cu")
	)
	(gr_line
		(start 134.137146 -404.46452)
		(end 133.866636 -404.73503)
		(stroke
			(width 0.06477)
			(type default)
		)
		(layer "F.Cu")
	)
	(gr_line
		(start 134.162546 -408.784044)
		(end 133.866636 -409.079954)
		(stroke
			(width 0.06477)
			(type default)
		)
		(layer "F.Cu")
	)
	(gr_line
		(start 134.272528 -373.141494)
		(end 134.272528 -373.297958)
		(stroke
			(width 0.0508)
			(type default)
		)
		(layer "F.Cu")
	)
	(gr_line
		(start 135.346694 -379.708918)
		(end 135.236204 -379.819408)
		(stroke
			(width 0.0508)
			(type default)
		)
		(layer "F.Cu")
	)
	(gr_line
		(start 135.36168 -29.992066)
		(end 135.79094 -30.421326)
		(stroke
			(width 0.06477)
			(type default)
		)
		(layer "F.Cu")
	)
	(gr_line
		(start 135.36168 -29.28112)
		(end 135.36168 -29.992066)
		(stroke
			(width 0.06477)
			(type default)
		)
		(layer "F.Cu")
	)
	(gr_line
		(start 135.36168 -28.21432)
		(end 135.36168 -27.50566)
		(stroke
			(width 0.06477)
			(type default)
		)
		(layer "F.Cu")
	)
	(gr_line
		(start 135.36168 -27.50566)
		(end 135.773414 -27.093926)
		(stroke
			(width 0.06477)
			(type default)
		)
		(layer "F.Cu")
	)
	(gr_line
		(start 135.50138 -28.74772)
		(end 135.36168 -28.74772)
		(stroke
			(width 0.06477)
			(type default)
		)
		(layer "F.Cu")
	)
	(gr_line
		(start 135.615172 -11.955018)
		(end 135.885682 -12.225528)
		(stroke
			(width 0.06477)
			(type default)
		)
		(layer "F.Cu")
	)
	(gr_line
		(start 135.616696 -370.83873)
		(end 135.965946 -371.18798)
		(stroke
			(width 0.0508)
			(type default)
		)
		(layer "F.Cu")
	)
	(gr_line
		(start 135.642096 -369.03533)
		(end 135.912606 -369.30584)
		(stroke
			(width 0.06477)
			(type default)
		)
		(layer "F.Cu")
	)
	(gr_line
		(start 135.651494 -379.708918)
		(end 135.346694 -379.708918)
		(stroke
			(width 0.0508)
			(type default)
		)
		(layer "F.Cu")
	)
	(gr_line
		(start 135.703056 -24.72944)
		(end 135.513826 -24.54021)
		(stroke
			(width 0.06477)
			(type default)
		)
		(layer "F.Cu")
	)
	(gr_line
		(start 135.746998 -17.112234)
		(end 135.885682 -17.250918)
		(stroke
			(width 0.06477)
			(type default)
		)
		(layer "F.Cu")
	)
	(gr_line
		(start 135.746998 -16.549878)
		(end 135.746998 -17.112234)
		(stroke
			(width 0.06477)
			(type default)
		)
		(layer "F.Cu")
	)
	(gr_line
		(start 135.746998 -13.062204)
		(end 135.746998 -13.599922)
		(stroke
			(width 0.06477)
			(type default)
		)
		(layer "F.Cu")
	)
	(gr_line
		(start 135.761984 -379.819408)
		(end 135.651494 -379.708918)
		(stroke
			(width 0.0508)
			(type default)
		)
		(layer "F.Cu")
	)
	(gr_line
		(start 135.763254 -380.036578)
		(end 135.234934 -380.036578)
		(stroke
			(width 0.0508)
			(type default)
		)
		(layer "F.Cu")
	)
	(gr_line
		(start 135.773414 -27.093926)
		(end 135.773414 -27.089354)
		(stroke
			(width 0.06477)
			(type default)
		)
		(layer "F.Cu")
	)
	(gr_line
		(start 135.885682 -20.564856)
		(end 135.885682 -21.316696)
		(stroke
			(width 0.06477)
			(type default)
		)
		(layer "F.Cu")
	)
	(gr_line
		(start 135.885682 -19.432016)
		(end 135.885682 -20.183856)
		(stroke
			(width 0.06477)
			(type default)
		)
		(layer "F.Cu")
	)
	(gr_line
		(start 135.885682 -17.250918)
		(end 135.885682 -17.255998)
		(stroke
			(width 0.06477)
			(type default)
		)
		(layer "F.Cu")
	)
	(gr_line
		(start 135.885682 -12.92352)
		(end 135.746998 -13.062204)
		(stroke
			(width 0.06477)
			(type default)
		)
		(layer "F.Cu")
	)
	(gr_line
		(start 135.885682 -12.856464)
		(end 135.885682 -12.92352)
		(stroke
			(width 0.06477)
			(type default)
		)
		(layer "F.Cu")
	)
	(gr_line
		(start 135.9027 -221.353634)
		(end 135.9027 -221.334584)
		(stroke
			(width 0.0381)
			(type default)
		)
		(layer "F.Cu")
	)
	(gr_line
		(start 135.90651 -223.41713)
		(end 135.748014 -223.690434)
		(stroke
			(width 0.0381)
			(type default)
		)
		(layer "F.Cu")
	)
	(gr_line
		(start 135.912606 -370.00942)
		(end 135.616696 -370.30533)
		(stroke
			(width 0.06477)
			(type default)
		)
		(layer "F.Cu")
	)
	(gr_line
		(start 135.93318 -29.24302)
		(end 135.93318 -29.17952)
		(stroke
			(width 0.06477)
			(type default)
		)
		(layer "F.Cu")
	)
	(gr_line
		(start 135.93318 -29.17952)
		(end 136.36498 -28.74772)
		(stroke
			(width 0.06477)
			(type default)
		)
		(layer "F.Cu")
	)
	(gr_line
		(start 135.93318 -28.31592)
		(end 135.50138 -28.74772)
		(stroke
			(width 0.06477)
			(type default)
		)
		(layer "F.Cu")
	)
	(gr_line
		(start 135.93318 -28.25242)
		(end 135.93318 -28.31592)
		(stroke
			(width 0.06477)
			(type default)
		)
		(layer "F.Cu")
	)
	(gr_line
		(start 135.96874 -221.419674)
		(end 135.9027 -221.353634)
		(stroke
			(width 0.0381)
			(type default)
		)
		(layer "F.Cu")
	)
	(gr_line
		(start 135.988552 -223.39554)
		(end 135.90651 -223.41713)
		(stroke
			(width 0.0381)
			(type default)
		)
		(layer "F.Cu")
	)
	(gr_arc
		(start 135.988552 -223.39554)
		(mid 135.997914 -223.399564)
		(end 136.007348 -223.403414)
		(stroke
			(width 0.0381)
			(type default)
		)
		(layer "F.Cu")
	)
	(gr_line
		(start 136.059418 -223.153732)
		(end 136.078468 -223.22536)
		(stroke
			(width 0.0381)
			(type default)
		)
		(layer "F.Cu")
	)
	(gr_line
		(start 136.089136 -24.72944)
		(end 135.703056 -24.72944)
		(stroke
			(width 0.06477)
			(type default)
		)
		(layer "F.Cu")
	)
	(gr_line
		(start 136.11479 -30.37713)
		(end 136.11479 -30.422596)
		(stroke
			(width 0.06477)
			(type default)
		)
		(layer "F.Cu")
	)
	(gr_line
		(start 136.181846 -371.527832)
		(end 136.1821 -371.527578)
		(stroke
			(width 0.0508)
			(type default)
		)
		(layer "F.Cu")
	)
	(gr_line
		(start 136.209532 -20.566126)
		(end 136.393682 -20.750276)
		(stroke
			(width 0.06477)
			(type default)
		)
		(layer "F.Cu")
	)
	(gr_line
		(start 136.209532 -19.433286)
		(end 136.393682 -19.617436)
		(stroke
			(width 0.06477)
			(type default)
		)
		(layer "F.Cu")
	)
	(gr_line
		(start 136.209532 -12.857734)
		(end 136.346946 -12.995148)
		(stroke
			(width 0.06477)
			(type default)
		)
		(layer "F.Cu")
	)
	(gr_line
		(start 136.217914 -222.880428)
		(end 136.059418 -223.153732)
		(stroke
			(width 0.0381)
			(type default)
		)
		(layer "F.Cu")
	)
	(gr_line
		(start 136.22528 -221.353634)
		(end 136.15924 -221.419674)
		(stroke
			(width 0.0381)
			(type default)
		)
		(layer "F.Cu")
	)
	(gr_line
		(start 136.22528 -221.334584)
		(end 136.22528 -221.353634)
		(stroke
			(width 0.0381)
			(type default)
		)
		(layer "F.Cu")
	)
	(gr_line
		(start 136.22909 -376.71883)
		(end 136.139174 -376.71883)
		(stroke
			(width 0.0508)
			(type default)
		)
		(layer "F.Cu")
	)
	(gr_line
		(start 136.235186 -370.00942)
		(end 136.531096 -370.30533)
		(stroke
			(width 0.06477)
			(type default)
		)
		(layer "F.Cu")
	)
	(gr_line
		(start 136.278366 -24.54021)
		(end 136.089136 -24.72944)
		(stroke
			(width 0.06477)
			(type default)
		)
		(layer "F.Cu")
	)
	(gr_line
		(start 136.311386 -408.784044)
		(end 136.607296 -409.079954)
		(stroke
			(width 0.06477)
			(type default)
		)
		(layer "F.Cu")
	)
	(gr_line
		(start 136.336786 -404.46452)
		(end 136.607296 -404.73503)
		(stroke
			(width 0.06477)
			(type default)
		)
		(layer "F.Cu")
	)
	(gr_line
		(start 136.346946 -17.117314)
		(end 136.209532 -17.254728)
		(stroke
			(width 0.06477)
			(type default)
		)
		(layer "F.Cu")
	)
	(gr_line
		(start 136.346946 -16.549878)
		(end 136.346946 -17.117314)
		(stroke
			(width 0.06477)
			(type default)
		)
		(layer "F.Cu")
	)
	(gr_line
		(start 136.346946 -12.995148)
		(end 136.346946 -13.599922)
		(stroke
			(width 0.06477)
			(type default)
		)
		(layer "F.Cu")
	)
	(gr_line
		(start 136.36498 -28.74772)
		(end 136.50468 -28.74772)
		(stroke
			(width 0.06477)
			(type default)
		)
		(layer "F.Cu")
	)
	(gr_line
		(start 136.36879 -376.776742)
		(end 136.22909 -376.71883)
		(stroke
			(width 0.0508)
			(type default)
		)
		(layer "F.Cu")
	)
	(gr_line
		(start 136.393682 -21.131276)
		(end 136.209532 -21.315426)
		(stroke
			(width 0.06477)
			(type default)
		)
		(layer "F.Cu")
	)
	(gr_line
		(start 136.393682 -20.750276)
		(end 136.393682 -21.131276)
		(stroke
			(width 0.06477)
			(type default)
		)
		(layer "F.Cu")
	)
	(gr_line
		(start 136.393682 -19.998436)
		(end 136.209532 -20.182586)
		(stroke
			(width 0.06477)
			(type default)
		)
		(layer "F.Cu")
	)
	(gr_line
		(start 136.393682 -19.617436)
		(end 136.393682 -19.998436)
		(stroke
			(width 0.06477)
			(type default)
		)
		(layer "F.Cu")
	)
	(gr_line
		(start 136.404858 -223.203008)
		(end 136.40562 -223.2025)
		(stroke
			(width 0.0381)
			(type default)
		)
		(layer "F.Cu")
	)
	(gr_line
		(start 136.40562 -223.2025)
		(end 136.40689 -223.201738)
		(stroke
			(width 0.0381)
			(type default)
		)
		(layer "F.Cu")
	)
	(gr_line
		(start 136.478772 -11.955018)
		(end 136.208262 -12.225528)
		(stroke
			(width 0.06477)
			(type default)
		)
		(layer "F.Cu")
	)
	(gr_line
		(start 136.50087 -223.367854)
		(end 136.500362 -223.368108)
		(stroke
			(width 0.0381)
			(type default)
		)
		(layer "F.Cu")
	)
	(gr_line
		(start 136.501886 -223.367346)
		(end 136.50087 -223.367854)
		(stroke
			(width 0.0381)
			(type default)
		)
		(layer "F.Cu")
	)
	(gr_line
		(start 136.50468 -29.98724)
		(end 136.11479 -30.37713)
		(stroke
			(width 0.06477)
			(type default)
		)
		(layer "F.Cu")
	)
	(gr_line
		(start 136.50468 -29.28112)
		(end 136.50468 -29.98724)
		(stroke
			(width 0.06477)
			(type default)
		)
		(layer "F.Cu")
	)
	(gr_line
		(start 136.505696 -369.03533)
		(end 136.235186 -369.30584)
		(stroke
			(width 0.06477)
			(type default)
		)
		(layer "F.Cu")
	)
	(gr_line
		(start 136.531096 -370.83873)
		(end 136.181846 -371.18798)
		(stroke
			(width 0.0508)
			(type default)
		)
		(layer "F.Cu")
	)
	(gr_line
		(start 136.54405 -36.873434)
		(end 137.182098 -36.873434)
		(stroke
			(width 0.06477)
			(type default)
		)
		(layer "F.Cu")
	)
	(gr_line
		(start 136.54405 -36.473384)
		(end 137.182352 -36.473384)
		(stroke
			(width 0.06477)
			(type default)
		)
		(layer "F.Cu")
	)
	(gr_line
		(start 136.574276 -380.385828)
		(end 136.225026 -380.036578)
		(stroke
			(width 0.0508)
			(type default)
		)
		(layer "F.Cu")
	)
	(gr_line
		(start 136.574276 -379.471428)
		(end 136.225026 -379.820678)
		(stroke
			(width 0.0508)
			(type default)
		)
		(layer "F.Cu")
	)
	(gr_line
		(start 136.574276 -376.982228)
		(end 136.36879 -376.776742)
		(stroke
			(width 0.0508)
			(type default)
		)
		(layer "F.Cu")
	)
	(gr_line
		(start 136.574276 -376.067828)
		(end 136.140444 -376.50166)
		(stroke
			(width 0.0508)
			(type default)
		)
		(layer "F.Cu")
	)
	(gr_line
		(start 136.607296 -412.299658)
		(end 136.336786 -412.570168)
		(stroke
			(width 0.06477)
			(type default)
		)
		(layer "F.Cu")
	)
	(gr_line
		(start 136.607296 -407.954734)
		(end 136.311386 -408.250644)
		(stroke
			(width 0.06477)
			(type default)
		)
		(layer "F.Cu")
	)
	(gr_line
		(start 136.680956 -22.634448)
		(end 136.70534 -22.658832)
		(stroke
			(width 0.06477)
			(type default)
		)
		(layer "F.Cu")
	)
	(gr_line
		(start 136.70534 -22.658832)
		(end 136.70534 -23.016972)
		(stroke
			(width 0.06477)
			(type default)
		)
		(layer "F.Cu")
	)
	(gr_line
		(start 136.781794 -365.45012)
		(end 137.056876 -365.725202)
		(stroke
			(width 0.06477)
			(type default)
		)
		(layer "F.Cu")
	)
	(gr_line
		(start 136.781794 -365.18215)
		(end 136.781794 -365.45012)
		(stroke
			(width 0.06477)
			(type default)
		)
		(layer "F.Cu")
	)
	(gr_line
		(start 136.856216 -24.72944)
		(end 136.666986 -24.54021)
		(stroke
			(width 0.06477)
			(type default)
		)
		(layer "F.Cu")
	)
	(gr_line
		(start 136.896348 -372.904258)
		(end 137.270236 -373.278146)
		(stroke
			(width 0.0508)
			(type default)
		)
		(layer "F.Cu")
	)
	(gr_line
		(start 136.910572 -22.406102)
		(end 137.31621 -22.406102)
		(stroke
			(width 0.06477)
			(type default)
		)
		(layer "F.Cu")
	)
	(gr_line
		(start 136.929876 -412.299658)
		(end 137.200386 -412.570168)
		(stroke
			(width 0.06477)
			(type default)
		)
		(layer "F.Cu")
	)
	(gr_line
		(start 136.929876 -407.954734)
		(end 137.225786 -408.250644)
		(stroke
			(width 0.06477)
			(type default)
		)
		(layer "F.Cu")
	)
	(gr_line
		(start 136.996424 -221.761812)
		(end 136.687814 -222.070422)
		(stroke
			(width 0.06477)
			(type default)
		)
		(layer "F.Cu")
	)
	(gr_line
		(start 136.996932 -26.40965)
		(end 137.186162 -26.22042)
		(stroke
			(width 0.06477)
			(type default)
		)
		(layer "F.Cu")
	)
	(gr_line
		(start 137.01014 -364.952534)
		(end 137.554716 -365.496856)
		(stroke
			(width 0.06477)
			(type default)
		)
		(layer "F.Cu")
	)
	(gr_line
		(start 137.050526 -372.75135)
		(end 137.207244 -372.75135)
		(stroke
			(width 0.0508)
			(type default)
		)
		(layer "F.Cu")
	)
	(gr_line
		(start 137.056876 -365.725202)
		(end 137.324846 -365.725202)
		(stroke
			(width 0.06477)
			(type default)
		)
		(layer "F.Cu")
	)
	(gr_line
		(start 137.182098 -36.873434)
		(end 136.54405 -36.873434)
		(stroke
			(width 0.06477)
			(type default)
		)
		(layer "F.Cu")
	)
	(gr_line
		(start 137.182098 -36.873434)
		(end 137.213848 -36.841684)
		(stroke
			(width 0.06477)
			(type default)
		)
		(layer "F.Cu")
	)
	(gr_line
		(start 137.182098 -35.673538)
		(end 136.54405 -35.673538)
		(stroke
			(width 0.06477)
			(type default)
		)
		(layer "F.Cu")
	)
	(gr_line
		(start 137.182352 -36.473384)
		(end 136.54405 -36.473384)
		(stroke
			(width 0.06477)
			(type default)
		)
		(layer "F.Cu")
	)
	(gr_line
		(start 137.182352 -36.473384)
		(end 137.226802 -36.517834)
		(stroke
			(width 0.06477)
			(type default)
		)
		(layer "F.Cu")
	)
	(gr_line
		(start 137.182352 -35.273488)
		(end 136.54405 -35.273488)
		(stroke
			(width 0.06477)
			(type default)
		)
		(layer "F.Cu")
	)
	(gr_line
		(start 137.186162 -26.22042)
		(end 137.572242 -26.22042)
		(stroke
			(width 0.06477)
			(type default)
		)
		(layer "F.Cu")
	)
	(gr_line
		(start 137.200386 -404.46452)
		(end 136.929876 -404.73503)
		(stroke
			(width 0.06477)
			(type default)
		)
		(layer "F.Cu")
	)
	(gr_line
		(start 137.207244 -372.75135)
		(end 137.423144 -372.96725)
		(stroke
			(width 0.0508)
			(type default)
		)
		(layer "F.Cu")
	)
	(gr_line
		(start 137.213848 -36.841684)
		(end 137.182098 -36.873434)
		(stroke
			(width 0.06477)
			(type default)
		)
		(layer "F.Cu")
	)
	(gr_line
		(start 137.213848 -36.841684)
		(end 137.228072 -36.841684)
		(stroke
			(width 0.06477)
			(type default)
		)
		(layer "F.Cu")
	)
	(gr_line
		(start 137.213848 -35.304984)
		(end 137.182352 -35.273488)
		(stroke
			(width 0.06477)
			(type default)
		)
		(layer "F.Cu")
	)
	(gr_line
		(start 137.225786 -408.784044)
		(end 136.929876 -409.079954)
		(stroke
			(width 0.06477)
			(type default)
		)
		(layer "F.Cu")
	)
	(gr_line
		(start 137.226802 -36.517834)
		(end 137.182352 -36.473384)
		(stroke
			(width 0.06477)
			(type default)
		)
		(layer "F.Cu")
	)
	(gr_line
		(start 137.226802 -35.628834)
		(end 137.182098 -35.673538)
		(stroke
			(width 0.06477)
			(type default)
		)
		(layer "F.Cu")
	)
	(gr_line
		(start 137.228072 -36.841684)
		(end 137.213848 -36.841684)
		(stroke
			(width 0.06477)
			(type default)
		)
		(layer "F.Cu")
	)
	(gr_line
		(start 137.228072 -35.304984)
		(end 137.213848 -35.304984)
		(stroke
			(width 0.06477)
			(type default)
		)
		(layer "F.Cu")
	)
	(gr_line
		(start 137.242296 -24.72944)
		(end 136.856216 -24.72944)
		(stroke
			(width 0.06477)
			(type default)
		)
		(layer "F.Cu")
	)
	(gr_line
		(start 137.403586 -380.089918)
		(end 137.107676 -380.385828)
		(stroke
			(width 0.06477)
			(type default)
		)
		(layer "F.Cu")
	)
	(gr_line
		(start 137.403586 -379.767338)
		(end 137.107676 -379.471428)
		(stroke
			(width 0.06477)
			(type default)
		)
		(layer "F.Cu")
	)
	(gr_line
		(start 137.403586 -376.686318)
		(end 137.107676 -376.982228)
		(stroke
			(width 0.06477)
			(type default)
		)
		(layer "F.Cu")
	)
	(gr_line
		(start 137.403586 -376.363738)
		(end 137.107676 -376.067828)
		(stroke
			(width 0.06477)
			(type default)
		)
		(layer "F.Cu")
	)
	(gr_line
		(start 137.423144 -372.96725)
		(end 137.423144 -373.123968)
		(stroke
			(width 0.0508)
			(type default)
		)
		(layer "F.Cu")
	)
	(gr_line
		(start 137.431526 -24.54021)
		(end 137.242296 -24.72944)
		(stroke
			(width 0.06477)
			(type default)
		)
		(layer "F.Cu")
	)
	(gr_line
		(start 137.547096 -17.090898)
		(end 137.68578 -17.229582)
		(stroke
			(width 0.06477)
			(type default)
		)
		(layer "F.Cu")
	)
	(gr_line
		(start 137.547096 -16.549878)
		(end 137.547096 -17.090898)
		(stroke
			(width 0.06477)
			(type default)
		)
		(layer "F.Cu")
	)
	(gr_line
		(start 137.572242 -26.22042)
		(end 137.761472 -26.40965)
		(stroke
			(width 0.06477)
			(type default)
		)
		(layer "F.Cu")
	)
	(gr_line
		(start 137.600944 -366.26927)
		(end 137.876026 -366.544352)
		(stroke
			(width 0.06477)
			(type default)
		)
		(layer "F.Cu")
	)
	(gr_line
		(start 137.600944 -366.0013)
		(end 137.600944 -366.26927)
		(stroke
			(width 0.06477)
			(type default)
		)
		(layer "F.Cu")
	)
	(gr_line
		(start 137.627868 -222.070422)
		(end 137.319258 -221.761812)
		(stroke
			(width 0.06477)
			(type default)
		)
		(layer "F.Cu")
	)
	(gr_line
		(start 137.684764 -17.874742)
		(end 137.414762 -18.144744)
		(stroke
			(width 0.06477)
			(type default)
		)
		(layer "F.Cu")
	)
	(gr_line
		(start 137.68578 -17.229582)
		(end 137.68578 -17.251934)
		(stroke
			(width 0.06477)
			(type default)
		)
		(layer "F.Cu")
	)
	(gr_line
		(start 137.829036 -365.771684)
		(end 138.373866 -366.31626)
		(stroke
			(width 0.06477)
			(type default)
		)
		(layer "F.Cu")
	)
	(gr_line
		(start 137.876026 -366.544352)
		(end 138.143996 -366.544352)
		(stroke
			(width 0.06477)
			(type default)
		)
		(layer "F.Cu")
	)
	(gr_line
		(start 138.00836 -17.874742)
		(end 138.278362 -18.144744)
		(stroke
			(width 0.06477)
			(type default)
		)
		(layer "F.Cu")
	)
	(gr_line
		(start 138.00836 -17.873726)
		(end 138.00836 -17.874742)
		(stroke
			(width 0.06477)
			(type default)
		)
		(layer "F.Cu")
	)
	(gr_line
		(start 138.147044 -17.11325)
		(end 138.00963 -17.250664)
		(stroke
			(width 0.06477)
			(type default)
		)
		(layer "F.Cu")
	)
	(gr_line
		(start 138.147044 -16.549878)
		(end 138.147044 -17.11325)
		(stroke
			(width 0.06477)
			(type default)
		)
		(layer "F.Cu")
	)
	(gr_line
		(start 138.377676 -380.360428)
		(end 138.107166 -380.089918)
		(stroke
			(width 0.06477)
			(type default)
		)
		(layer "F.Cu")
	)
	(gr_line
		(start 138.377676 -379.496828)
		(end 138.107166 -379.767338)
		(stroke
			(width 0.06477)
			(type default)
		)
		(layer "F.Cu")
	)
	(gr_line
		(start 138.377676 -376.956828)
		(end 138.107166 -376.686318)
		(stroke
			(width 0.06477)
			(type default)
		)
		(layer "F.Cu")
	)
	(gr_line
		(start 138.377676 -376.093228)
		(end 138.107166 -376.363738)
		(stroke
			(width 0.06477)
			(type default)
		)
		(layer "F.Cu")
	)
	(gr_line
		(start 138.420094 -367.088166)
		(end 138.695176 -367.363248)
		(stroke
			(width 0.06477)
			(type default)
		)
		(layer "F.Cu")
	)
	(gr_line
		(start 138.420094 -366.82045)
		(end 138.420094 -367.088166)
		(stroke
			(width 0.06477)
			(type default)
		)
		(layer "F.Cu")
	)
	(gr_line
		(start 138.442192 -35.114484)
		(end 138.252962 -35.303714)
		(stroke
			(width 0.06477)
			(type default)
		)
		(layer "F.Cu")
	)
	(gr_line
		(start 138.64844 -366.590834)
		(end 139.192762 -367.135156)
		(stroke
			(width 0.06477)
			(type default)
		)
		(layer "F.Cu")
	)
	(gr_line
		(start 138.675872 -220.08211)
		(end 138.675872 -219.69603)
		(stroke
			(width 0.06477)
			(type default)
		)
		(layer "F.Cu")
	)
	(gr_line
		(start 138.675872 -219.69603)
		(end 138.865102 -219.5068)
		(stroke
			(width 0.06477)
			(type default)
		)
		(layer "F.Cu")
	)
	(gr_line
		(start 138.675872 -218.92895)
		(end 138.675872 -218.54287)
		(stroke
			(width 0.06477)
			(type default)
		)
		(layer "F.Cu")
	)
	(gr_line
		(start 138.675872 -218.54287)
		(end 138.865102 -218.35364)
		(stroke
			(width 0.06477)
			(type default)
		)
		(layer "F.Cu")
	)
	(gr_line
		(start 138.695176 -367.363248)
		(end 138.962892 -367.363248)
		(stroke
			(width 0.06477)
			(type default)
		)
		(layer "F.Cu")
	)
	(gr_line
		(start 138.726418 -223.41713)
		(end 138.567922 -223.690434)
		(stroke
			(width 0.0381)
			(type default)
		)
		(layer "F.Cu")
	)
	(gr_line
		(start 138.80846 -223.39554)
		(end 138.726418 -223.41713)
		(stroke
			(width 0.0381)
			(type default)
		)
		(layer "F.Cu")
	)
	(gr_arc
		(start 138.80846 -223.39554)
		(mid 138.817947 -223.399693)
		(end 138.82751 -223.403668)
		(stroke
			(width 0.0381)
			(type default)
		)
		(layer "F.Cu")
	)
	(gr_line
		(start 138.828272 -35.114484)
		(end 138.442192 -35.114484)
		(stroke
			(width 0.06477)
			(type default)
		)
		(layer "F.Cu")
	)
	(gr_line
		(start 138.865102 -220.27134)
		(end 138.675872 -220.08211)
		(stroke
			(width 0.06477)
			(type default)
		)
		(layer "F.Cu")
	)
	(gr_line
		(start 138.865102 -219.11818)
		(end 138.675872 -218.92895)
		(stroke
			(width 0.06477)
			(type default)
		)
		(layer "F.Cu")
	)
	(gr_line
		(start 138.866372 -221.193614)
		(end 138.866372 -221.174564)
		(stroke
			(width 0.0381)
			(type default)
		)
		(layer "F.Cu")
	)
	(gr_line
		(start 138.879326 -223.153732)
		(end 138.89863 -223.225614)
		(stroke
			(width 0.0381)
			(type default)
		)
		(layer "F.Cu")
	)
	(gr_line
		(start 138.932412 -221.259654)
		(end 138.866372 -221.193614)
		(stroke
			(width 0.0381)
			(type default)
		)
		(layer "F.Cu")
	)
	(gr_line
		(start 138.942572 -222.070422)
		(end 138.942826 -222.070422)
		(stroke
			(width 0.0381)
			(type default)
		)
		(layer "F.Cu")
	)
	(gr_line
		(start 138.984482 -369.579398)
		(end 138.748262 -369.343178)
		(stroke
			(width 0.06477)
			(type default)
		)
		(layer "F.Cu")
	)
	(gr_line
		(start 139.017502 -35.303714)
		(end 138.828272 -35.114484)
		(stroke
			(width 0.06477)
			(type default)
		)
		(layer "F.Cu")
	)
	(gr_line
		(start 139.018772 -35.627564)
		(end 138.251692 -35.627564)
		(stroke
			(width 0.06477)
			(type default)
		)
		(layer "F.Cu")
	)
	(gr_line
		(start 139.037822 -222.880428)
		(end 138.879326 -223.153732)
		(stroke
			(width 0.0381)
			(type default)
		)
		(layer "F.Cu")
	)
	(gr_line
		(start 139.051792 -369.903248)
		(end 138.748262 -370.206778)
		(stroke
			(width 0.06477)
			(type default)
		)
		(layer "F.Cu")
	)
	(gr_line
		(start 139.053062 -369.579398)
		(end 138.984482 -369.579398)
		(stroke
			(width 0.06477)
			(type default)
		)
		(layer "F.Cu")
	)
	(gr_line
		(start 139.188952 -221.193614)
		(end 139.122912 -221.259654)
		(stroke
			(width 0.0381)
			(type default)
		)
		(layer "F.Cu")
	)
	(gr_line
		(start 139.188952 -221.174564)
		(end 139.188952 -221.193614)
		(stroke
			(width 0.0381)
			(type default)
		)
		(layer "F.Cu")
	)
	(gr_line
		(start 139.188952 -219.50553)
		(end 139.188952 -220.27261)
		(stroke
			(width 0.06477)
			(type default)
		)
		(layer "F.Cu")
	)
	(gr_line
		(start 139.188952 -218.35237)
		(end 139.188952 -219.11945)
		(stroke
			(width 0.06477)
			(type default)
		)
		(layer "F.Cu")
	)
	(gr_line
		(start 139.251182 -222.57258)
		(end 139.232132 -222.561912)
		(stroke
			(width 0.0381)
			(type default)
		)
		(layer "F.Cu")
	)
	(gr_line
		(start 139.327128 -222.396812)
		(end 139.3444 -222.406972)
		(stroke
			(width 0.0381)
			(type default)
		)
		(layer "F.Cu")
	)
	(gr_line
		(start 139.3444 -222.406972)
		(end 139.359386 -222.415608)
		(stroke
			(width 0.0381)
			(type default)
		)
		(layer "F.Cu")
	)
	(gr_line
		(start 139.353544 -223.348804)
		(end 139.351512 -223.34982)
		(stroke
			(width 0.0381)
			(type default)
		)
		(layer "F.Cu")
	)
	(gr_line
		(start 139.374626 -408.784044)
		(end 139.670536 -409.079954)
		(stroke
			(width 0.06477)
			(type default)
		)
		(layer "F.Cu")
	)
	(gr_line
		(start 139.400026 -404.46452)
		(end 139.670536 -404.73503)
		(stroke
			(width 0.06477)
			(type default)
		)
		(layer "F.Cu")
	)
	(gr_line
		(start 139.507976 -222.070422)
		(end 139.816586 -221.761812)
		(stroke
			(width 0.06477)
			(type default)
		)
		(layer "F.Cu")
	)
	(gr_line
		(start 139.670536 -412.299658)
		(end 139.400026 -412.570168)
		(stroke
			(width 0.06477)
			(type default)
		)
		(layer "F.Cu")
	)
	(gr_line
		(start 139.670536 -407.954734)
		(end 139.374626 -408.250644)
		(stroke
			(width 0.06477)
			(type default)
		)
		(layer "F.Cu")
	)
	(gr_line
		(start 139.677648 -34.762694)
		(end 139.677648 -35.030664)
		(stroke
			(width 0.06477)
			(type default)
		)
		(layer "F.Cu")
	)
	(gr_line
		(start 139.950952 -34.48939)
		(end 139.677648 -34.762694)
		(stroke
			(width 0.06477)
			(type default)
		)
		(layer "F.Cu")
	)
	(gr_line
		(start 139.993116 -412.299658)
		(end 140.263626 -412.570168)
		(stroke
			(width 0.06477)
			(type default)
		)
		(layer "F.Cu")
	)
	(gr_line
		(start 139.993116 -407.954734)
		(end 140.289026 -408.250644)
		(stroke
			(width 0.06477)
			(type default)
		)
		(layer "F.Cu")
	)
	(gr_line
		(start 140.02512 -32.354774)
		(end 140.51915 -32.848804)
		(stroke
			(width 0.06477)
			(type default)
		)
		(layer "F.Cu")
	)
	(gr_line
		(start 140.02512 -32.02686)
		(end 140.02512 -32.354774)
		(stroke
			(width 0.06477)
			(type default)
		)
		(layer "F.Cu")
	)
	(gr_line
		(start 140.07338 -36.841684)
		(end 140.84046 -36.841684)
		(stroke
			(width 0.06477)
			(type default)
		)
		(layer "F.Cu")
	)
	(gr_line
		(start 140.07465 -36.517834)
		(end 140.26388 -36.328604)
		(stroke
			(width 0.06477)
			(type default)
		)
		(layer "F.Cu")
	)
	(gr_line
		(start 140.218922 -34.48939)
		(end 139.950952 -34.48939)
		(stroke
			(width 0.06477)
			(type default)
		)
		(layer "F.Cu")
	)
	(gr_line
		(start 140.22832 -31.22676)
		(end 140.02512 -31.22676)
		(stroke
			(width 0.06477)
			(type default)
		)
		(layer "F.Cu")
	)
	(gr_line
		(start 140.263626 -404.46452)
		(end 139.993116 -404.73503)
		(stroke
			(width 0.06477)
			(type default)
		)
		(layer "F.Cu")
	)
	(gr_line
		(start 140.26388 -36.328604)
		(end 140.07465 -36.517834)
		(stroke
			(width 0.06477)
			(type default)
		)
		(layer "F.Cu")
	)
	(gr_line
		(start 140.26388 -36.328604)
		(end 140.64996 -36.328604)
		(stroke
			(width 0.06477)
			(type default)
		)
		(layer "F.Cu")
	)
	(gr_line
		(start 140.289026 -408.784044)
		(end 139.993116 -409.079954)
		(stroke
			(width 0.06477)
			(type default)
		)
		(layer "F.Cu")
	)
	(gr_line
		(start 140.32865 -33.639506)
		(end 140.51788 -33.828736)
		(stroke
			(width 0.06477)
			(type default)
		)
		(layer "F.Cu")
	)
	(gr_line
		(start 140.32865 -33.253426)
		(end 140.32865 -33.639506)
		(stroke
			(width 0.06477)
			(type default)
		)
		(layer "F.Cu")
	)
	(gr_line
		(start 140.447776 -222.070422)
		(end 140.139166 -221.761812)
		(stroke
			(width 0.06477)
			(type default)
		)
		(layer "F.Cu")
	)
	(gr_line
		(start 140.448538 -34.717736)
		(end 139.90574 -35.26028)
		(stroke
			(width 0.06477)
			(type default)
		)
		(layer "F.Cu")
	)
	(gr_line
		(start 140.51788 -33.064196)
		(end 140.32865 -33.253426)
		(stroke
			(width 0.06477)
			(type default)
		)
		(layer "F.Cu")
	)
	(gr_line
		(start 140.51915 -32.848804)
		(end 140.51915 -32.85109)
		(stroke
			(width 0.06477)
			(type default)
		)
		(layer "F.Cu")
	)
	(gr_line
		(start 140.64996 -36.328604)
		(end 140.26388 -36.328604)
		(stroke
			(width 0.06477)
			(type default)
		)
		(layer "F.Cu")
	)
	(gr_line
		(start 140.64996 -36.328604)
		(end 140.83919 -36.517834)
		(stroke
			(width 0.06477)
			(type default)
		)
		(layer "F.Cu")
	)
	(gr_line
		(start 140.66012 -31.65856)
		(end 140.22832 -31.22676)
		(stroke
			(width 0.06477)
			(type default)
		)
		(layer "F.Cu")
	)
	(gr_line
		(start 140.66012 -30.79496)
		(end 141.09192 -31.22676)
		(stroke
			(width 0.06477)
			(type default)
		)
		(layer "F.Cu")
	)
	(gr_line
		(start 140.83919 -36.517834)
		(end 140.64996 -36.328604)
		(stroke
			(width 0.06477)
			(type default)
		)
		(layer "F.Cu")
	)
	(gr_line
		(start 140.84046 -36.841684)
		(end 140.07338 -36.841684)
		(stroke
			(width 0.06477)
			(type default)
		)
		(layer "F.Cu")
	)
	(gr_line
		(start 140.84173 -33.062926)
		(end 140.84173 -33.830006)
		(stroke
			(width 0.06477)
			(type default)
		)
		(layer "F.Cu")
	)
	(gr_line
		(start 140.910564 -387.789674)
		(end 141.181074 -387.519164)
		(stroke
			(width 0.06477)
			(type default)
		)
		(layer "F.Cu")
	)
	(gr_line
		(start 140.910564 -386.926074)
		(end 141.181074 -387.196584)
		(stroke
			(width 0.06477)
			(type default)
		)
		(layer "F.Cu")
	)
	(gr_line
		(start 141.058392 -382.36906)
		(end 141.328902 -382.09855)
		(stroke
			(width 0.06477)
			(type default)
		)
		(layer "F.Cu")
	)
	(gr_line
		(start 141.058392 -381.50546)
		(end 141.328902 -381.77597)
		(stroke
			(width 0.06477)
			(type default)
		)
		(layer "F.Cu")
	)
	(gr_line
		(start 141.058392 -376.83186)
		(end 141.328902 -376.56135)
		(stroke
			(width 0.06477)
			(type default)
		)
		(layer "F.Cu")
	)
	(gr_line
		(start 141.058392 -375.96826)
		(end 141.328902 -376.23877)
		(stroke
			(width 0.06477)
			(type default)
		)
		(layer "F.Cu")
	)
	(gr_line
		(start 141.09192 -31.22676)
		(end 141.29512 -31.22676)
		(stroke
			(width 0.06477)
			(type default)
		)
		(layer "F.Cu")
	)
	(gr_line
		(start 141.147038 -17.161002)
		(end 141.285722 -17.299686)
		(stroke
			(width 0.06477)
			(type default)
		)
		(layer "F.Cu")
	)
	(gr_line
		(start 141.147038 -16.549878)
		(end 141.147038 -17.161002)
		(stroke
			(width 0.06477)
			(type default)
		)
		(layer "F.Cu")
	)
	(gr_line
		(start 141.284706 -17.874742)
		(end 141.014704 -18.144744)
		(stroke
			(width 0.06477)
			(type default)
		)
		(layer "F.Cu")
	)
	(gr_line
		(start 141.29512 -32.3977)
		(end 140.843 -32.84982)
		(stroke
			(width 0.06477)
			(type default)
		)
		(layer "F.Cu")
	)
	(gr_line
		(start 141.29512 -32.02686)
		(end 141.29512 -32.3977)
		(stroke
			(width 0.06477)
			(type default)
		)
		(layer "F.Cu")
	)
	(gr_line
		(start 141.38783 -223.690434)
		(end 141.546326 -223.41713)
		(stroke
			(width 0.0381)
			(type default)
		)
		(layer "F.Cu")
	)
	(gr_line
		(start 141.546326 -223.41713)
		(end 141.628368 -223.39554)
		(stroke
			(width 0.0381)
			(type default)
		)
		(layer "F.Cu")
	)
	(gr_line
		(start 141.608302 -17.874742)
		(end 141.878304 -18.144744)
		(stroke
			(width 0.06477)
			(type default)
		)
		(layer "F.Cu")
	)
	(gr_line
		(start 141.608302 -17.873726)
		(end 141.608302 -17.874742)
		(stroke
			(width 0.06477)
			(type default)
		)
		(layer "F.Cu")
	)
	(gr_arc
		(start 141.628368 -223.39554)
		(mid 141.637855 -223.399693)
		(end 141.647418 -223.403668)
		(stroke
			(width 0.0381)
			(type default)
		)
		(layer "F.Cu")
	)
	(gr_line
		(start 141.643862 -387.519164)
		(end 141.888972 -387.764274)
		(stroke
			(width 0.06477)
			(type default)
		)
		(layer "F.Cu")
	)
	(gr_line
		(start 141.643862 -387.196584)
		(end 141.888972 -386.951474)
		(stroke
			(width 0.06477)
			(type default)
		)
		(layer "F.Cu")
	)
	(gr_line
		(start 141.66088 -221.401132)
		(end 141.66088 -221.382082)
		(stroke
			(width 0.06477)
			(type default)
		)
		(layer "F.Cu")
	)
	(gr_line
		(start 141.683994 -370.13896)
		(end 141.954504 -370.40947)
		(stroke
			(width 0.06477)
			(type default)
		)
		(layer "F.Cu")
	)
	(gr_line
		(start 141.683994 -369.81638)
		(end 141.954504 -369.54587)
		(stroke
			(width 0.06477)
			(type default)
		)
		(layer "F.Cu")
	)
	(gr_line
		(start 141.699234 -223.153732)
		(end 141.718538 -223.225614)
		(stroke
			(width 0.0381)
			(type default)
		)
		(layer "F.Cu")
	)
	(gr_line
		(start 141.72692 -222.063564)
		(end 141.72692 -222.05315)
		(stroke
			(width 0.0381)
			(type default)
		)
		(layer "F.Cu")
	)
	(gr_line
		(start 141.72692 -221.467172)
		(end 141.66088 -221.401132)
		(stroke
			(width 0.0381)
			(type default)
		)
		(layer "F.Cu")
	)
	(gr_line
		(start 141.727174 -222.066358)
		(end 141.72692 -222.063564)
		(stroke
			(width 0.0381)
			(type default)
		)
		(layer "F.Cu")
	)
	(gr_arc
		(start 141.727174 -222.066358)
		(mid 141.727788 -222.071568)
		(end 141.728444 -222.076772)
		(stroke
			(width 0.0381)
			(type default)
		)
		(layer "F.Cu")
	)
	(gr_line
		(start 141.746986 -17.161002)
		(end 141.608302 -17.299686)
		(stroke
			(width 0.06477)
			(type default)
		)
		(layer "F.Cu")
	)
	(gr_line
		(start 141.746986 -16.549878)
		(end 141.746986 -17.161002)
		(stroke
			(width 0.06477)
			(type default)
		)
		(layer "F.Cu")
	)
	(gr_line
		(start 141.818106 -222.948754)
		(end 141.699234 -223.153732)
		(stroke
			(width 0.0381)
			(type default)
		)
		(layer "F.Cu")
	)
	(gr_line
		(start 141.857984 -222.880428)
		(end 141.818106 -222.948754)
		(stroke
			(width 0.0381)
			(type default)
		)
		(layer "F.Cu")
	)
	(gr_line
		(start 142.032482 -382.09855)
		(end 142.328392 -382.39446)
		(stroke
			(width 0.06477)
			(type default)
		)
		(layer "F.Cu")
	)
	(gr_line
		(start 142.032482 -381.77597)
		(end 142.328392 -381.48006)
		(stroke
			(width 0.06477)
			(type default)
		)
		(layer "F.Cu")
	)
	(gr_line
		(start 142.032482 -376.56135)
		(end 142.328392 -376.85726)
		(stroke
			(width 0.06477)
			(type default)
		)
		(layer "F.Cu")
	)
	(gr_line
		(start 142.032482 -376.23877)
		(end 142.328392 -375.94286)
		(stroke
			(width 0.06477)
			(type default)
		)
		(layer "F.Cu")
	)
	(gr_line
		(start 142.044928 -222.557848)
		(end 142.044674 -222.557594)
		(stroke
			(width 0.0381)
			(type default)
		)
		(layer "F.Cu")
	)
	(gr_line
		(start 142.07109 -222.57258)
		(end 142.052802 -222.56242)
		(stroke
			(width 0.0381)
			(type default)
		)
		(layer "F.Cu")
	)
	(gr_line
		(start 142.164308 -222.406972)
		(end 142.147798 -222.397066)
		(stroke
			(width 0.0381)
			(type default)
		)
		(layer "F.Cu")
	)
	(gr_line
		(start 142.17142 -223.34982)
		(end 142.173452 -223.348804)
		(stroke
			(width 0.0381)
			(type default)
		)
		(layer "F.Cu")
	)
	(gr_line
		(start 142.264892 -36.244784)
		(end 142.264892 -35.976814)
		(stroke
			(width 0.06477)
			(type default)
		)
		(layer "F.Cu")
	)
	(gr_line
		(start 142.264892 -35.976814)
		(end 142.264892 -36.244784)
		(stroke
			(width 0.06477)
			(type default)
		)
		(layer "F.Cu")
	)
	(gr_line
		(start 142.264892 -35.976814)
		(end 142.538196 -35.70351)
		(stroke
			(width 0.06477)
			(type default)
		)
		(layer "F.Cu")
	)
	(gr_line
		(start 142.422372 -387.764274)
		(end 142.666974 -387.519672)
		(stroke
			(width 0.06477)
			(type default)
		)
		(layer "F.Cu")
	)
	(gr_line
		(start 142.422372 -386.951474)
		(end 142.66672 -387.195822)
		(stroke
			(width 0.06477)
			(type default)
		)
		(layer "F.Cu")
	)
	(gr_line
		(start 142.437866 -408.784044)
		(end 142.733776 -409.079954)
		(stroke
			(width 0.06477)
			(type default)
		)
		(layer "F.Cu")
	)
	(gr_line
		(start 142.463266 -404.46452)
		(end 142.733776 -404.73503)
		(stroke
			(width 0.06477)
			(type default)
		)
		(layer "F.Cu")
	)
	(gr_line
		(start 142.492984 -36.4744)
		(end 143.036036 -35.931856)
		(stroke
			(width 0.06477)
			(type default)
		)
		(layer "F.Cu")
	)
	(gr_line
		(start 142.538196 -35.70351)
		(end 142.264892 -35.976814)
		(stroke
			(width 0.06477)
			(type default)
		)
		(layer "F.Cu")
	)
	(gr_line
		(start 142.538196 -35.70351)
		(end 142.806166 -35.70351)
		(stroke
			(width 0.06477)
			(type default)
		)
		(layer "F.Cu")
	)
	(gr_line
		(start 142.617444 -373.30253)
		(end 142.966694 -373.65178)
		(stroke
			(width 0.0508)
			(type default)
		)
		(layer "F.Cu")
	)
	(gr_line
		(start 142.642844 -371.49913)
		(end 142.913354 -371.76964)
		(stroke
			(width 0.06477)
			(type default)
		)
		(layer "F.Cu")
	)
	(gr_line
		(start 142.66672 -387.195822)
		(end 142.668244 -387.195822)
		(stroke
			(width 0.06477)
			(type default)
		)
		(layer "F.Cu")
	)
	(gr_line
		(start 142.733776 -412.299658)
		(end 142.463266 -412.570168)
		(stroke
			(width 0.06477)
			(type default)
		)
		(layer "F.Cu")
	)
	(gr_line
		(start 142.733776 -407.954734)
		(end 142.437866 -408.250644)
		(stroke
			(width 0.06477)
			(type default)
		)
		(layer "F.Cu")
	)
	(gr_line
		(start 142.806166 -35.70351)
		(end 142.538196 -35.70351)
		(stroke
			(width 0.06477)
			(type default)
		)
		(layer "F.Cu")
	)
	(gr_line
		(start 142.861792 -382.39446)
		(end 143.21155 -382.044702)
		(stroke
			(width 0.0508)
			(type default)
		)
		(layer "F.Cu")
	)
	(gr_line
		(start 142.861792 -381.48006)
		(end 143.209264 -381.827532)
		(stroke
			(width 0.0508)
			(type default)
		)
		(layer "F.Cu")
	)
	(gr_line
		(start 142.861792 -376.85726)
		(end 143.231616 -376.487436)
		(stroke
			(width 0.0508)
			(type default)
		)
		(layer "F.Cu")
	)
	(gr_line
		(start 142.861792 -375.94286)
		(end 143.189198 -376.270266)
		(stroke
			(width 0.0508)
			(type default)
		)
		(layer "F.Cu")
	)
	(gr_line
		(start 142.913354 -372.47322)
		(end 142.617444 -372.76913)
		(stroke
			(width 0.06477)
			(type default)
		)
		(layer "F.Cu")
	)
	(gr_line
		(start 142.9258 -387.195822)
		(end 142.927324 -387.195822)
		(stroke
			(width 0.06477)
			(type default)
		)
		(layer "F.Cu")
	)
	(gr_line
		(start 142.92707 -387.519672)
		(end 143.171672 -387.764274)
		(stroke
			(width 0.06477)
			(type default)
		)
		(layer "F.Cu")
	)
	(gr_line
		(start 142.927324 -387.195822)
		(end 143.171672 -386.951474)
		(stroke
			(width 0.06477)
			(type default)
		)
		(layer "F.Cu")
	)
	(gr_line
		(start 143.036036 -35.931856)
		(end 142.492984 -36.4744)
		(stroke
			(width 0.06477)
			(type default)
		)
		(layer "F.Cu")
	)
	(gr_line
		(start 143.056356 -412.299658)
		(end 143.326866 -412.570168)
		(stroke
			(width 0.06477)
			(type default)
		)
		(layer "F.Cu")
	)
	(gr_line
		(start 143.056356 -407.954734)
		(end 143.352266 -408.250644)
		(stroke
			(width 0.06477)
			(type default)
		)
		(layer "F.Cu")
	)
	(gr_line
		(start 143.080486 -35.42919)
		(end 143.080486 -35.16122)
		(stroke
			(width 0.06477)
			(type default)
		)
		(layer "F.Cu")
	)
	(gr_line
		(start 143.080486 -35.16122)
		(end 143.080486 -35.42919)
		(stroke
			(width 0.06477)
			(type default)
		)
		(layer "F.Cu")
	)
	(gr_line
		(start 143.080486 -35.16122)
		(end 143.35379 -34.887916)
		(stroke
			(width 0.06477)
			(type default)
		)
		(layer "F.Cu")
	)
	(gr_line
		(start 143.171672 -387.764274)
		(end 143.427704 -387.508242)
		(stroke
			(width 0.06477)
			(type default)
		)
		(layer "F.Cu")
	)
	(gr_line
		(start 143.171672 -386.951474)
		(end 143.40459 -387.184392)
		(stroke
			(width 0.06477)
			(type default)
		)
		(layer "F.Cu")
	)
	(gr_line
		(start 143.189198 -376.270266)
		(end 143.232886 -376.270266)
		(stroke
			(width 0.0508)
			(type default)
		)
		(layer "F.Cu")
	)
	(gr_line
		(start 143.209264 -381.827532)
		(end 143.21282 -381.827532)
		(stroke
			(width 0.0508)
			(type default)
		)
		(layer "F.Cu")
	)
	(gr_line
		(start 143.235934 -372.47322)
		(end 143.531844 -372.76913)
		(stroke
			(width 0.06477)
			(type default)
		)
		(layer "F.Cu")
	)
	(gr_line
		(start 143.308832 -35.65906)
		(end 143.851376 -35.116008)
		(stroke
			(width 0.06477)
			(type default)
		)
		(layer "F.Cu")
	)
	(gr_line
		(start 143.326866 -404.46452)
		(end 143.056356 -404.73503)
		(stroke
			(width 0.06477)
			(type default)
		)
		(layer "F.Cu")
	)
	(gr_line
		(start 143.352266 -408.784044)
		(end 143.056356 -409.079954)
		(stroke
			(width 0.06477)
			(type default)
		)
		(layer "F.Cu")
	)
	(gr_line
		(start 143.35379 -34.887916)
		(end 143.080486 -35.16122)
		(stroke
			(width 0.06477)
			(type default)
		)
		(layer "F.Cu")
	)
	(gr_line
		(start 143.35379 -34.887916)
		(end 143.62176 -34.887916)
		(stroke
			(width 0.06477)
			(type default)
		)
		(layer "F.Cu")
	)
	(gr_line
		(start 143.40459 -387.184392)
		(end 143.428974 -387.184392)
		(stroke
			(width 0.06477)
			(type default)
		)
		(layer "F.Cu")
	)
	(gr_line
		(start 143.506444 -371.49913)
		(end 143.235934 -371.76964)
		(stroke
			(width 0.06477)
			(type default)
		)
		(layer "F.Cu")
	)
	(gr_line
		(start 143.51762 -381.827532)
		(end 144.04594 -381.827532)
		(stroke
			(width 0.0508)
			(type default)
		)
		(layer "F.Cu")
	)
	(gr_line
		(start 143.51889 -382.044702)
		(end 143.62938 -382.155192)
		(stroke
			(width 0.0508)
			(type default)
		)
		(layer "F.Cu")
	)
	(gr_line
		(start 143.531844 -373.30253)
		(end 143.182594 -373.65178)
		(stroke
			(width 0.0508)
			(type default)
		)
		(layer "F.Cu")
	)
	(gr_line
		(start 143.62176 -34.887916)
		(end 143.35379 -34.887916)
		(stroke
			(width 0.06477)
			(type default)
		)
		(layer "F.Cu")
	)
	(gr_line
		(start 143.62938 -382.155192)
		(end 143.93418 -382.155192)
		(stroke
			(width 0.0508)
			(type default)
		)
		(layer "F.Cu")
	)
	(gr_line
		(start 143.851376 -35.116008)
		(end 143.308832 -35.65906)
		(stroke
			(width 0.06477)
			(type default)
		)
		(layer "F.Cu")
	)
	(gr_line
		(start 143.93418 -382.155192)
		(end 144.04467 -382.044702)
		(stroke
			(width 0.0508)
			(type default)
		)
		(layer "F.Cu")
	)
	(gr_line
		(start 144.319244 -370.83873)
		(end 144.668494 -371.18798)
		(stroke
			(width 0.0508)
			(type default)
		)
		(layer "F.Cu")
	)
	(gr_line
		(start 144.344644 -369.03533)
		(end 144.615154 -369.30584)
		(stroke
			(width 0.06477)
			(type default)
		)
		(layer "F.Cu")
	)
	(gr_line
		(start 144.35074 -381.827532)
		(end 144.87906 -381.827532)
		(stroke
			(width 0.0508)
			(type default)
		)
		(layer "F.Cu")
	)
	(gr_line
		(start 144.35201 -382.044702)
		(end 144.4625 -382.155192)
		(stroke
			(width 0.0508)
			(type default)
		)
		(layer "F.Cu")
	)
	(gr_line
		(start 144.36344 -32.487362)
		(end 144.36344 -31.98749)
		(stroke
			(width 0.06477)
			(type default)
		)
		(layer "F.Cu")
	)
	(gr_line
		(start 144.36344 -32.487362)
		(end 144.8816 -33.005522)
		(stroke
			(width 0.06477)
			(type default)
		)
		(layer "F.Cu")
	)
	(gr_line
		(start 144.36344 -31.98749)
		(end 144.36344 -32.487362)
		(stroke
			(width 0.06477)
			(type default)
		)
		(layer "F.Cu")
	)
	(gr_line
		(start 144.4625 -382.155192)
		(end 144.7673 -382.155192)
		(stroke
			(width 0.0508)
			(type default)
		)
		(layer "F.Cu")
	)
	(gr_line
		(start 144.615154 -370.00942)
		(end 144.319244 -370.30533)
		(stroke
			(width 0.06477)
			(type default)
		)
		(layer "F.Cu")
	)
	(gr_line
		(start 144.62379 -31.18739)
		(end 144.36344 -31.18739)
		(stroke
			(width 0.06477)
			(type default)
		)
		(layer "F.Cu")
	)
	(gr_line
		(start 144.7673 -382.155192)
		(end 144.87779 -382.044702)
		(stroke
			(width 0.0508)
			(type default)
		)
		(layer "F.Cu")
	)
	(gr_line
		(start 144.8816 -33.005522)
		(end 144.36344 -32.487362)
		(stroke
			(width 0.06477)
			(type default)
		)
		(layer "F.Cu")
	)
	(gr_line
		(start 144.937734 -370.00942)
		(end 145.233644 -370.30533)
		(stroke
			(width 0.06477)
			(type default)
		)
		(layer "F.Cu")
	)
	(gr_line
		(start 144.954244 -375.942098)
		(end 145.328132 -376.315986)
		(stroke
			(width 0.0508)
			(type default)
		)
		(layer "F.Cu")
	)
	(gr_line
		(start 144.963134 -378.53239)
		(end 145.07972 -378.81433)
		(stroke
			(width 0.0508)
			(type default)
		)
		(layer "F.Cu")
	)
	(gr_line
		(start 144.997678 -200.21169)
		(end 144.997678 -199.94372)
		(stroke
			(width 0.06477)
			(type default)
		)
		(layer "F.Cu")
	)
	(gr_line
		(start 144.997678 -199.94372)
		(end 145.270982 -199.670416)
		(stroke
			(width 0.06477)
			(type default)
		)
		(layer "F.Cu")
	)
	(gr_line
		(start 144.99844 -31.67634)
		(end 145.48739 -31.18739)
		(stroke
			(width 0.06477)
			(type default)
		)
		(layer "F.Cu")
	)
	(gr_line
		(start 144.99844 -30.81274)
		(end 144.62379 -31.18739)
		(stroke
			(width 0.06477)
			(type default)
		)
		(layer "F.Cu")
	)
	(gr_line
		(start 145.023078 -378.387864)
		(end 144.963134 -378.53239)
		(stroke
			(width 0.0508)
			(type default)
		)
		(layer "F.Cu")
	)
	(gr_line
		(start 145.07972 -378.81433)
		(end 145.2245 -378.87402)
		(stroke
			(width 0.0508)
			(type default)
		)
		(layer "F.Cu")
	)
	(gr_line
		(start 145.108422 -375.78919)
		(end 145.26514 -375.78919)
		(stroke
			(width 0.0508)
			(type default)
		)
		(layer "F.Cu")
	)
	(gr_line
		(start 145.125694 -387.531102)
		(end 145.729452 -387.531102)
		(stroke
			(width 0.0508)
			(type default)
		)
		(layer "F.Cu")
	)
	(gr_line
		(start 145.126964 -387.748272)
		(end 145.209768 -387.831076)
		(stroke
			(width 0.0508)
			(type default)
		)
		(layer "F.Cu")
	)
	(gr_line
		(start 145.20545 -33.006792)
		(end 145.20545 -32.963358)
		(stroke
			(width 0.06477)
			(type default)
		)
		(layer "F.Cu")
	)
	(gr_line
		(start 145.20545 -32.963358)
		(end 145.20545 -33.006792)
		(stroke
			(width 0.06477)
			(type default)
		)
		(layer "F.Cu")
	)
	(gr_line
		(start 145.20545 -32.963358)
		(end 145.63344 -32.535368)
		(stroke
			(width 0.06477)
			(type default)
		)
		(layer "F.Cu")
	)
	(gr_line
		(start 145.208244 -369.03533)
		(end 144.937734 -369.30584)
		(stroke
			(width 0.06477)
			(type default)
		)
		(layer "F.Cu")
	)
	(gr_line
		(start 145.223484 -378.30379)
		(end 145.425668 -378.792232)
		(stroke
			(width 0.0508)
			(type default)
		)
		(layer "F.Cu")
	)
	(gr_line
		(start 145.233644 -370.83873)
		(end 144.884394 -371.18798)
		(stroke
			(width 0.0508)
			(type default)
		)
		(layer "F.Cu")
	)
	(gr_line
		(start 145.26514 -375.78919)
		(end 145.48104 -376.00509)
		(stroke
			(width 0.0508)
			(type default)
		)
		(layer "F.Cu")
	)
	(gr_line
		(start 145.270982 -199.670416)
		(end 145.538952 -199.670416)
		(stroke
			(width 0.06477)
			(type default)
		)
		(layer "F.Cu")
	)
	(gr_line
		(start 145.48104 -376.00509)
		(end 145.48104 -376.161808)
		(stroke
			(width 0.0508)
			(type default)
		)
		(layer "F.Cu")
	)
	(gr_line
		(start 145.48739 -31.18739)
		(end 145.63344 -31.18739)
		(stroke
			(width 0.06477)
			(type default)
		)
		(layer "F.Cu")
	)
	(gr_line
		(start 145.501106 -408.784044)
		(end 145.797016 -409.079954)
		(stroke
			(width 0.06477)
			(type default)
		)
		(layer "F.Cu")
	)
	(gr_line
		(start 145.50771 -379.62967)
		(end 145.677128 -379.883162)
		(stroke
			(width 0.0508)
			(type default)
		)
		(layer "F.Cu")
	)
	(gr_line
		(start 145.526506 -404.46452)
		(end 145.797016 -404.73503)
		(stroke
			(width 0.06477)
			(type default)
		)
		(layer "F.Cu")
	)
	(gr_line
		(start 145.53819 -379.476)
		(end 145.50771 -379.62967)
		(stroke
			(width 0.0508)
			(type default)
		)
		(layer "F.Cu")
	)
	(gr_line
		(start 145.63344 -32.535368)
		(end 145.20545 -32.963358)
		(stroke
			(width 0.06477)
			(type default)
		)
		(layer "F.Cu")
	)
	(gr_line
		(start 145.63344 -32.535368)
		(end 145.63344 -31.98749)
		(stroke
			(width 0.06477)
			(type default)
		)
		(layer "F.Cu")
	)
	(gr_line
		(start 145.63344 -31.98749)
		(end 145.63344 -32.535368)
		(stroke
			(width 0.06477)
			(type default)
		)
		(layer "F.Cu")
	)
	(gr_line
		(start 145.666968 -372.921022)
		(end 146.040856 -373.294656)
		(stroke
			(width 0.0508)
			(type default)
		)
		(layer "F.Cu")
	)
	(gr_line
		(start 145.677128 -379.883162)
		(end 145.830798 -379.913896)
		(stroke
			(width 0.0508)
			(type default)
		)
		(layer "F.Cu")
	)
	(gr_line
		(start 145.718022 -379.354588)
		(end 145.718276 -379.354588)
		(stroke
			(width 0.0508)
			(type default)
		)
		(layer "F.Cu")
	)
	(gr_line
		(start 145.718276 -379.354588)
		(end 146.0119 -379.794008)
		(stroke
			(width 0.0508)
			(type default)
		)
		(layer "F.Cu")
	)
	(gr_line
		(start 145.768568 -199.898508)
		(end 145.226024 -200.441306)
		(stroke
			(width 0.06477)
			(type default)
		)
		(layer "F.Cu")
	)
	(gr_line
		(start 145.797016 -412.299658)
		(end 145.526506 -412.570168)
		(stroke
			(width 0.06477)
			(type default)
		)
		(layer "F.Cu")
	)
	(gr_line
		(start 145.797016 -407.954734)
		(end 145.501106 -408.250644)
		(stroke
			(width 0.06477)
			(type default)
		)
		(layer "F.Cu")
	)
	(gr_line
		(start 145.813272 -199.396096)
		(end 145.813272 -199.128126)
		(stroke
			(width 0.06477)
			(type default)
		)
		(layer "F.Cu")
	)
	(gr_line
		(start 145.813272 -199.128126)
		(end 146.086576 -198.854822)
		(stroke
			(width 0.06477)
			(type default)
		)
		(layer "F.Cu")
	)
	(gr_line
		(start 145.8214 -372.768114)
		(end 145.977864 -372.768114)
		(stroke
			(width 0.0508)
			(type default)
		)
		(layer "F.Cu")
	)
	(gr_line
		(start 145.977864 -372.768114)
		(end 146.193764 -372.984014)
		(stroke
			(width 0.0508)
			(type default)
		)
		(layer "F.Cu")
	)
	(gr_line
		(start 146.0119 -379.794008)
		(end 146.0119 -379.794262)
		(stroke
			(width 0.0508)
			(type default)
		)
		(layer "F.Cu")
	)
	(gr_line
		(start 146.040856 -373.294656)
		(end 146.040856 -373.29491)
		(stroke
			(width 0.0508)
			(type default)
		)
		(layer "F.Cu")
	)
	(gr_line
		(start 146.086576 -198.854822)
		(end 146.354546 -198.854822)
		(stroke
			(width 0.06477)
			(type default)
		)
		(layer "F.Cu")
	)
	(gr_line
		(start 146.119596 -412.299658)
		(end 146.390106 -412.570168)
		(stroke
			(width 0.06477)
			(type default)
		)
		(layer "F.Cu")
	)
	(gr_line
		(start 146.119596 -407.954734)
		(end 146.415506 -408.250644)
		(stroke
			(width 0.06477)
			(type default)
		)
		(layer "F.Cu")
	)
	(gr_line
		(start 146.193764 -372.984014)
		(end 146.193764 -373.140478)
		(stroke
			(width 0.0508)
			(type default)
		)
		(layer "F.Cu")
	)
	(gr_line
		(start 146.206972 -210.437984)
		(end 146.206972 -210.051904)
		(stroke
			(width 0.06477)
			(type default)
		)
		(layer "F.Cu")
	)
	(gr_line
		(start 146.206972 -210.051904)
		(end 146.396202 -209.862674)
		(stroke
			(width 0.06477)
			(type default)
		)
		(layer "F.Cu")
	)
	(gr_line
		(start 146.206972 -209.284824)
		(end 146.206972 -208.898744)
		(stroke
			(width 0.06477)
			(type default)
		)
		(layer "F.Cu")
	)
	(gr_line
		(start 146.206972 -208.898744)
		(end 146.396202 -208.709514)
		(stroke
			(width 0.06477)
			(type default)
		)
		(layer "F.Cu")
	)
	(gr_line
		(start 146.390106 -404.46452)
		(end 146.119596 -404.73503)
		(stroke
			(width 0.06477)
			(type default)
		)
		(layer "F.Cu")
	)
	(gr_line
		(start 146.396202 -210.627214)
		(end 146.206972 -210.437984)
		(stroke
			(width 0.06477)
			(type default)
		)
		(layer "F.Cu")
	)
	(gr_line
		(start 146.396202 -209.474054)
		(end 146.206972 -209.284824)
		(stroke
			(width 0.06477)
			(type default)
		)
		(layer "F.Cu")
	)
	(gr_line
		(start 146.415506 -408.784044)
		(end 146.119596 -409.079954)
		(stroke
			(width 0.06477)
			(type default)
		)
		(layer "F.Cu")
	)
	(gr_line
		(start 146.4437 -383.50571)
		(end 146.534886 -383.596896)
		(stroke
			(width 0.0508)
			(type default)
		)
		(layer "F.Cu")
	)
	(gr_line
		(start 146.4437 -383.2352)
		(end 146.4437 -383.50571)
		(stroke
			(width 0.0508)
			(type default)
		)
		(layer "F.Cu")
	)
	(gr_line
		(start 146.534886 -383.596896)
		(end 146.669252 -383.596896)
		(stroke
			(width 0.0508)
			(type default)
		)
		(layer "F.Cu")
	)
	(gr_line
		(start 146.584416 -199.082914)
		(end 146.041364 -199.625712)
		(stroke
			(width 0.06477)
			(type default)
		)
		(layer "F.Cu")
	)
	(gr_line
		(start 146.628866 -198.580502)
		(end 146.628866 -198.312532)
		(stroke
			(width 0.06477)
			(type default)
		)
		(layer "F.Cu")
	)
	(gr_line
		(start 146.628866 -198.312532)
		(end 146.90217 -198.039228)
		(stroke
			(width 0.06477)
			(type default)
		)
		(layer "F.Cu")
	)
	(gr_line
		(start 146.669252 -383.596896)
		(end 146.745706 -383.520442)
		(stroke
			(width 0.0508)
			(type default)
		)
		(layer "F.Cu")
	)
	(gr_line
		(start 146.720052 -210.628484)
		(end 146.720052 -209.861404)
		(stroke
			(width 0.06477)
			(type default)
		)
		(layer "F.Cu")
	)
	(gr_line
		(start 146.720052 -209.475324)
		(end 146.720052 -208.708244)
		(stroke
			(width 0.06477)
			(type default)
		)
		(layer "F.Cu")
	)
	(gr_line
		(start 146.735038 -382.943862)
		(end 146.4437 -383.2352)
		(stroke
			(width 0.0508)
			(type default)
		)
		(layer "F.Cu")
	)
	(gr_line
		(start 146.745706 -383.520442)
		(end 146.745706 -383.402586)
		(stroke
			(width 0.0508)
			(type default)
		)
		(layer "F.Cu")
	)
	(gr_line
		(start 146.829018 -391.36447)
		(end 146.745706 -391.281158)
		(stroke
			(width 0.0508)
			(type default)
		)
		(layer "F.Cu")
	)
	(gr_line
		(start 146.89836 -388.774432)
		(end 147.41906 -388.774432)
		(stroke
			(width 0.0635)
			(type default)
		)
		(layer "F.Cu")
	)
	(gr_line
		(start 146.89836 -385.31038)
		(end 147.41906 -385.31038)
		(stroke
			(width 0.0635)
			(type default)
		)
		(layer "F.Cu")
	)
	(gr_line
		(start 146.90217 -198.039228)
		(end 147.17014 -198.039228)
		(stroke
			(width 0.06477)
			(type default)
		)
		(layer "F.Cu")
	)
	(gr_line
		(start 146.952208 -383.13741)
		(end 147.04568 -383.230882)
		(stroke
			(width 0.0508)
			(type default)
		)
		(layer "F.Cu")
	)
	(gr_line
		(start 146.952208 -382.942592)
		(end 146.952208 -383.13741)
		(stroke
			(width 0.0508)
			(type default)
		)
		(layer "F.Cu")
	)
	(gr_line
		(start 147.04568 -383.230882)
		(end 147.04568 -383.92227)
		(stroke
			(width 0.0508)
			(type default)
		)
		(layer "F.Cu")
	)
	(gr_line
		(start 147.046188 -391.36574)
		(end 147.046188 -390.761982)
		(stroke
			(width 0.0508)
			(type default)
		)
		(layer "F.Cu")
	)
	(gr_line
		(start 147.046188 -390.761982)
		(end 147.04568 -390.761474)
		(stroke
			(width 0.0508)
			(type default)
		)
		(layer "F.Cu")
	)
	(gr_line
		(start 147.09775 -190.95466)
		(end 147.1422 -190.91021)
		(stroke
			(width 0.06477)
			(type default)
		)
		(layer "F.Cu")
	)
	(gr_line
		(start 147.1168 -191.77381)
		(end 147.09775 -191.75476)
		(stroke
			(width 0.06477)
			(type default)
		)
		(layer "F.Cu")
	)
	(gr_line
		(start 147.29841 -389.467344)
		(end 147.81911 -389.467344)
		(stroke
			(width 0.0635)
			(type default)
		)
		(layer "F.Cu")
	)
	(gr_line
		(start 147.29841 -386.003292)
		(end 147.81911 -386.003292)
		(stroke
			(width 0.0635)
			(type default)
		)
		(layer "F.Cu")
	)
	(gr_line
		(start 147.305522 -392.977116)
		(end 147.30349 -392.977116)
		(stroke
			(width 0.0508)
			(type default)
		)
		(layer "F.Cu")
	)
	(gr_line
		(start 147.399756 -198.26732)
		(end 146.856958 -198.810372)
		(stroke
			(width 0.06477)
			(type default)
		)
		(layer "F.Cu")
	)
	(gr_line
		(start 147.444206 -393.292838)
		(end 147.444206 -393.1158)
		(stroke
			(width 0.0508)
			(type default)
		)
		(layer "F.Cu")
	)
	(gr_line
		(start 147.444206 -393.1158)
		(end 147.305522 -392.977116)
		(stroke
			(width 0.0508)
			(type default)
		)
		(layer "F.Cu")
	)
	(gr_line
		(start 147.444206 -392.6205)
		(end 147.30476 -392.759946)
		(stroke
			(width 0.0508)
			(type default)
		)
		(layer "F.Cu")
	)
	(gr_line
		(start 147.444206 -392.429238)
		(end 147.444206 -392.6205)
		(stroke
			(width 0.0508)
			(type default)
		)
		(layer "F.Cu")
	)
	(gr_line
		(start 147.643596 -383.50571)
		(end 147.734782 -383.596896)
		(stroke
			(width 0.0508)
			(type default)
		)
		(layer "F.Cu")
	)
	(gr_line
		(start 147.643596 -383.2352)
		(end 147.643596 -383.50571)
		(stroke
			(width 0.0508)
			(type default)
		)
		(layer "F.Cu")
	)
	(gr_line
		(start 147.722844 -375.76633)
		(end 148.072094 -376.11558)
		(stroke
			(width 0.0508)
			(type default)
		)
		(layer "F.Cu")
	)
	(gr_line
		(start 147.734782 -383.596896)
		(end 147.869148 -383.596896)
		(stroke
			(width 0.0508)
			(type default)
		)
		(layer "F.Cu")
	)
	(gr_line
		(start 147.748244 -373.96293)
		(end 148.018754 -374.23344)
		(stroke
			(width 0.06477)
			(type default)
		)
		(layer "F.Cu")
	)
	(gr_line
		(start 147.869148 -383.596896)
		(end 147.945602 -383.520442)
		(stroke
			(width 0.0508)
			(type default)
		)
		(layer "F.Cu")
	)
	(gr_line
		(start 147.934934 -382.943862)
		(end 147.643596 -383.2352)
		(stroke
			(width 0.0508)
			(type default)
		)
		(layer "F.Cu")
	)
	(gr_line
		(start 147.945602 -383.520442)
		(end 147.945602 -383.402586)
		(stroke
			(width 0.0508)
			(type default)
		)
		(layer "F.Cu")
	)
	(gr_line
		(start 148.018754 -374.93702)
		(end 147.722844 -375.23293)
		(stroke
			(width 0.06477)
			(type default)
		)
		(layer "F.Cu")
	)
	(gr_line
		(start 148.028914 -391.36447)
		(end 147.945602 -391.281158)
		(stroke
			(width 0.0508)
			(type default)
		)
		(layer "F.Cu")
	)
	(gr_line
		(start 148.09089 -190.9318)
		(end 148.11375 -190.95466)
		(stroke
			(width 0.06477)
			(type default)
		)
		(layer "F.Cu")
	)
	(gr_line
		(start 148.098256 -388.774432)
		(end 148.618956 -388.774432)
		(stroke
			(width 0.0635)
			(type default)
		)
		(layer "F.Cu")
	)
	(gr_line
		(start 148.098256 -385.31038)
		(end 148.618956 -385.31038)
		(stroke
			(width 0.0635)
			(type default)
		)
		(layer "F.Cu")
	)
	(gr_line
		(start 148.152104 -383.13741)
		(end 148.245576 -383.230882)
		(stroke
			(width 0.0508)
			(type default)
		)
		(layer "F.Cu")
	)
	(gr_line
		(start 148.152104 -382.942592)
		(end 148.152104 -383.13741)
		(stroke
			(width 0.0508)
			(type default)
		)
		(layer "F.Cu")
	)
	(gr_line
		(start 148.245576 -383.230882)
		(end 148.245576 -383.92227)
		(stroke
			(width 0.0508)
			(type default)
		)
		(layer "F.Cu")
	)
	(gr_line
		(start 148.246084 -391.36574)
		(end 148.246084 -390.761982)
		(stroke
			(width 0.0508)
			(type default)
		)
		(layer "F.Cu")
	)
	(gr_line
		(start 148.246084 -390.761982)
		(end 148.245576 -390.761474)
		(stroke
			(width 0.0508)
			(type default)
		)
		(layer "F.Cu")
	)
	(gr_line
		(start 148.341334 -374.93702)
		(end 148.637244 -375.23293)
		(stroke
			(width 0.06477)
			(type default)
		)
		(layer "F.Cu")
	)
	(gr_line
		(start 148.498306 -389.467344)
		(end 149.019006 -389.467344)
		(stroke
			(width 0.0635)
			(type default)
		)
		(layer "F.Cu")
	)
	(gr_line
		(start 148.498306 -386.003292)
		(end 149.019006 -386.003292)
		(stroke
			(width 0.0635)
			(type default)
		)
		(layer "F.Cu")
	)
	(gr_line
		(start 148.505418 -392.977116)
		(end 148.503386 -392.977116)
		(stroke
			(width 0.0508)
			(type default)
		)
		(layer "F.Cu")
	)
	(gr_line
		(start 148.564346 -408.784044)
		(end 148.860256 -409.079954)
		(stroke
			(width 0.06477)
			(type default)
		)
		(layer "F.Cu")
	)
	(gr_line
		(start 148.589746 -404.46452)
		(end 148.860256 -404.73503)
		(stroke
			(width 0.06477)
			(type default)
		)
		(layer "F.Cu")
	)
	(gr_line
		(start 148.611844 -373.96293)
		(end 148.341334 -374.23344)
		(stroke
			(width 0.06477)
			(type default)
		)
		(layer "F.Cu")
	)
	(gr_line
		(start 148.637244 -375.76633)
		(end 148.287994 -376.11558)
		(stroke
			(width 0.0508)
			(type default)
		)
		(layer "F.Cu")
	)
	(gr_line
		(start 148.644102 -393.292838)
		(end 148.644102 -393.1158)
		(stroke
			(width 0.0508)
			(type default)
		)
		(layer "F.Cu")
	)
	(gr_line
		(start 148.644102 -393.1158)
		(end 148.505418 -392.977116)
		(stroke
			(width 0.0508)
			(type default)
		)
		(layer "F.Cu")
	)
	(gr_line
		(start 148.644102 -392.6205)
		(end 148.504656 -392.759946)
		(stroke
			(width 0.0508)
			(type default)
		)
		(layer "F.Cu")
	)
	(gr_line
		(start 148.644102 -392.429238)
		(end 148.644102 -392.6205)
		(stroke
			(width 0.0508)
			(type default)
		)
		(layer "F.Cu")
	)
	(gr_line
		(start 148.843746 -383.50571)
		(end 148.934932 -383.596896)
		(stroke
			(width 0.0508)
			(type default)
		)
		(layer "F.Cu")
	)
	(gr_line
		(start 148.843746 -383.2352)
		(end 148.843746 -383.50571)
		(stroke
			(width 0.0508)
			(type default)
		)
		(layer "F.Cu")
	)
	(gr_line
		(start 148.860256 -412.299658)
		(end 148.589746 -412.570168)
		(stroke
			(width 0.06477)
			(type default)
		)
		(layer "F.Cu")
	)
	(gr_line
		(start 148.860256 -407.954734)
		(end 148.564346 -408.250644)
		(stroke
			(width 0.06477)
			(type default)
		)
		(layer "F.Cu")
	)
	(gr_line
		(start 148.878798 -377.606814)
		(end 149.214332 -378.015754)
		(stroke
			(width 0.0508)
			(type default)
		)
		(layer "F.Cu")
	)
	(gr_line
		(start 148.934932 -383.596896)
		(end 149.069298 -383.596896)
		(stroke
			(width 0.0508)
			(type default)
		)
		(layer "F.Cu")
	)
	(gr_line
		(start 149.047454 -377.470162)
		(end 149.202902 -377.485402)
		(stroke
			(width 0.0508)
			(type default)
		)
		(layer "F.Cu")
	)
	(gr_line
		(start 149.069298 -383.596896)
		(end 149.145752 -383.520442)
		(stroke
			(width 0.0508)
			(type default)
		)
		(layer "F.Cu")
	)
	(gr_line
		(start 149.135084 -382.943862)
		(end 148.843746 -383.2352)
		(stroke
			(width 0.0508)
			(type default)
		)
		(layer "F.Cu")
	)
	(gr_line
		(start 149.145752 -383.520442)
		(end 149.145752 -383.402586)
		(stroke
			(width 0.0508)
			(type default)
		)
		(layer "F.Cu")
	)
	(gr_line
		(start 149.182836 -412.299658)
		(end 149.453346 -412.570168)
		(stroke
			(width 0.06477)
			(type default)
		)
		(layer "F.Cu")
	)
	(gr_line
		(start 149.182836 -407.954734)
		(end 149.478746 -408.250644)
		(stroke
			(width 0.06477)
			(type default)
		)
		(layer "F.Cu")
	)
	(gr_line
		(start 149.202902 -377.485402)
		(end 149.39645 -377.721114)
		(stroke
			(width 0.0508)
			(type default)
		)
		(layer "F.Cu")
	)
	(gr_line
		(start 149.229064 -391.36447)
		(end 149.145752 -391.281158)
		(stroke
			(width 0.0508)
			(type default)
		)
		(layer "F.Cu")
	)
	(gr_line
		(start 149.2758 -190.926466)
		(end 149.230334 -190.971932)
		(stroke
			(width 0.06477)
			(type default)
		)
		(layer "F.Cu")
	)
	(gr_line
		(start 149.298406 -388.774432)
		(end 149.819106 -388.774432)
		(stroke
			(width 0.0635)
			(type default)
		)
		(layer "F.Cu")
	)
	(gr_line
		(start 149.298406 -385.31038)
		(end 149.819106 -385.31038)
		(stroke
			(width 0.0635)
			(type default)
		)
		(layer "F.Cu")
	)
	(gr_line
		(start 149.352254 -383.13741)
		(end 149.445726 -383.230882)
		(stroke
			(width 0.0508)
			(type default)
		)
		(layer "F.Cu")
	)
	(gr_line
		(start 149.352254 -382.942592)
		(end 149.352254 -383.13741)
		(stroke
			(width 0.0508)
			(type default)
		)
		(layer "F.Cu")
	)
	(gr_line
		(start 149.39645 -377.721114)
		(end 149.381464 -377.87707)
		(stroke
			(width 0.0508)
			(type default)
		)
		(layer "F.Cu")
	)
	(gr_line
		(start 149.424644 -373.30253)
		(end 149.773894 -373.65178)
		(stroke
			(width 0.0508)
			(type default)
		)
		(layer "F.Cu")
	)
	(gr_line
		(start 149.445726 -383.230882)
		(end 149.445726 -383.92227)
		(stroke
			(width 0.0508)
			(type default)
		)
		(layer "F.Cu")
	)
	(gr_line
		(start 149.446234 -391.36574)
		(end 149.446234 -390.761982)
		(stroke
			(width 0.0508)
			(type default)
		)
		(layer "F.Cu")
	)
	(gr_line
		(start 149.446234 -390.761982)
		(end 149.445726 -390.761474)
		(stroke
			(width 0.0508)
			(type default)
		)
		(layer "F.Cu")
	)
	(gr_line
		(start 149.450044 -371.49913)
		(end 149.720554 -371.76964)
		(stroke
			(width 0.06477)
			(type default)
		)
		(layer "F.Cu")
	)
	(gr_line
		(start 149.453346 -404.46452)
		(end 149.182836 -404.73503)
		(stroke
			(width 0.06477)
			(type default)
		)
		(layer "F.Cu")
	)
	(gr_line
		(start 149.478746 -408.784044)
		(end 149.182836 -409.079954)
		(stroke
			(width 0.06477)
			(type default)
		)
		(layer "F.Cu")
	)
	(gr_line
		(start 149.698202 -389.467344)
		(end 150.218902 -389.467344)
		(stroke
			(width 0.0635)
			(type default)
		)
		(layer "F.Cu")
	)
	(gr_line
		(start 149.698202 -386.003292)
		(end 150.218902 -386.003292)
		(stroke
			(width 0.0635)
			(type default)
		)
		(layer "F.Cu")
	)
	(gr_line
		(start 149.705568 -392.977116)
		(end 149.703536 -392.977116)
		(stroke
			(width 0.0508)
			(type default)
		)
		(layer "F.Cu")
	)
	(gr_line
		(start 149.720554 -372.47322)
		(end 149.424644 -372.76913)
		(stroke
			(width 0.06477)
			(type default)
		)
		(layer "F.Cu")
	)
	(gr_line
		(start 149.773894 -374.529096)
		(end 149.773894 -375.057416)
		(stroke
			(width 0.0508)
			(type default)
		)
		(layer "F.Cu")
	)
	(gr_line
		(start 149.844252 -393.292838)
		(end 149.844252 -393.1158)
		(stroke
			(width 0.0508)
			(type default)
		)
		(layer "F.Cu")
	)
	(gr_line
		(start 149.844252 -393.1158)
		(end 149.705568 -392.977116)
		(stroke
			(width 0.0508)
			(type default)
		)
		(layer "F.Cu")
	)
	(gr_line
		(start 149.844252 -392.6205)
		(end 149.704806 -392.759946)
		(stroke
			(width 0.0508)
			(type default)
		)
		(layer "F.Cu")
	)
	(gr_line
		(start 149.844252 -392.429238)
		(end 149.844252 -392.6205)
		(stroke
			(width 0.0508)
			(type default)
		)
		(layer "F.Cu")
	)
	(gr_line
		(start 149.991064 -374.530366)
		(end 150.101554 -374.640856)
		(stroke
			(width 0.0508)
			(type default)
		)
		(layer "F.Cu")
	)
	(gr_line
		(start 150.043134 -372.47322)
		(end 150.339044 -372.76913)
		(stroke
			(width 0.06477)
			(type default)
		)
		(layer "F.Cu")
	)
	(gr_line
		(start 150.043642 -383.50571)
		(end 150.134828 -383.596896)
		(stroke
			(width 0.0508)
			(type default)
		)
		(layer "F.Cu")
	)
	(gr_line
		(start 150.043642 -383.2352)
		(end 150.043642 -383.50571)
		(stroke
			(width 0.0508)
			(type default)
		)
		(layer "F.Cu")
	)
	(gr_line
		(start 150.101554 -374.945656)
		(end 149.991064 -375.056146)
		(stroke
			(width 0.0508)
			(type default)
		)
		(layer "F.Cu")
	)
	(gr_line
		(start 150.101554 -374.640856)
		(end 150.101554 -374.945656)
		(stroke
			(width 0.0508)
			(type default)
		)
		(layer "F.Cu")
	)
	(gr_line
		(start 150.134828 -383.596896)
		(end 150.269194 -383.596896)
		(stroke
			(width 0.0508)
			(type default)
		)
		(layer "F.Cu")
	)
	(gr_line
		(start 150.246334 -190.971932)
		(end 150.206202 -190.9318)
		(stroke
			(width 0.06477)
			(type default)
		)
		(layer "F.Cu")
	)
	(gr_line
		(start 150.269194 -383.596896)
		(end 150.345648 -383.520442)
		(stroke
			(width 0.0508)
			(type default)
		)
		(layer "F.Cu")
	)
	(gr_line
		(start 150.313644 -371.49913)
		(end 150.043134 -371.76964)
		(stroke
			(width 0.06477)
			(type default)
		)
		(layer "F.Cu")
	)
	(gr_line
		(start 150.33498 -382.943862)
		(end 150.043642 -383.2352)
		(stroke
			(width 0.0508)
			(type default)
		)
		(layer "F.Cu")
	)
	(gr_line
		(start 150.339044 -373.30253)
		(end 149.989794 -373.65178)
		(stroke
			(width 0.0508)
			(type default)
		)
		(layer "F.Cu")
	)
	(gr_line
		(start 150.345648 -383.520442)
		(end 150.345648 -383.402586)
		(stroke
			(width 0.0508)
			(type default)
		)
		(layer "F.Cu")
	)
	(gr_line
		(start 150.42896 -391.36447)
		(end 150.345648 -391.281158)
		(stroke
			(width 0.0508)
			(type default)
		)
		(layer "F.Cu")
	)
	(gr_line
		(start 150.498302 -388.774432)
		(end 151.019002 -388.774432)
		(stroke
			(width 0.0635)
			(type default)
		)
		(layer "F.Cu")
	)
	(gr_line
		(start 150.498302 -385.31038)
		(end 151.019002 -385.31038)
		(stroke
			(width 0.0635)
			(type default)
		)
		(layer "F.Cu")
	)
	(gr_line
		(start 150.55215 -383.13741)
		(end 150.645622 -383.230882)
		(stroke
			(width 0.0508)
			(type default)
		)
		(layer "F.Cu")
	)
	(gr_line
		(start 150.55215 -382.942592)
		(end 150.55215 -383.13741)
		(stroke
			(width 0.0508)
			(type default)
		)
		(layer "F.Cu")
	)
	(gr_line
		(start 150.645622 -383.230882)
		(end 150.645622 -383.92227)
		(stroke
			(width 0.0508)
			(type default)
		)
		(layer "F.Cu")
	)
	(gr_line
		(start 150.64613 -391.36574)
		(end 150.64613 -390.761982)
		(stroke
			(width 0.0508)
			(type default)
		)
		(layer "F.Cu")
	)
	(gr_line
		(start 150.64613 -390.761982)
		(end 150.645622 -390.761474)
		(stroke
			(width 0.0508)
			(type default)
		)
		(layer "F.Cu")
	)
	(gr_line
		(start 150.898352 -389.467344)
		(end 151.419052 -389.467344)
		(stroke
			(width 0.0635)
			(type default)
		)
		(layer "F.Cu")
	)
	(gr_line
		(start 150.898352 -386.003292)
		(end 151.419052 -386.003292)
		(stroke
			(width 0.0635)
			(type default)
		)
		(layer "F.Cu")
	)
	(gr_line
		(start 150.905464 -392.977116)
		(end 150.903432 -392.977116)
		(stroke
			(width 0.0508)
			(type default)
		)
		(layer "F.Cu")
	)
	(gr_line
		(start 151.044148 -393.292838)
		(end 151.044148 -393.1158)
		(stroke
			(width 0.0508)
			(type default)
		)
		(layer "F.Cu")
	)
	(gr_line
		(start 151.044148 -393.1158)
		(end 150.905464 -392.977116)
		(stroke
			(width 0.0508)
			(type default)
		)
		(layer "F.Cu")
	)
	(gr_line
		(start 151.044148 -392.6205)
		(end 150.904702 -392.759946)
		(stroke
			(width 0.0508)
			(type default)
		)
		(layer "F.Cu")
	)
	(gr_line
		(start 151.044148 -392.429238)
		(end 151.044148 -392.6205)
		(stroke
			(width 0.0508)
			(type default)
		)
		(layer "F.Cu")
	)
	(gr_line
		(start 151.126444 -370.83873)
		(end 151.475694 -371.18798)
		(stroke
			(width 0.0508)
			(type default)
		)
		(layer "F.Cu")
	)
	(gr_line
		(start 151.151844 -369.03533)
		(end 151.422354 -369.30584)
		(stroke
			(width 0.06477)
			(type default)
		)
		(layer "F.Cu")
	)
	(gr_line
		(start 151.243792 -383.50571)
		(end 151.334978 -383.596896)
		(stroke
			(width 0.0508)
			(type default)
		)
		(layer "F.Cu")
	)
	(gr_line
		(start 151.243792 -383.2352)
		(end 151.243792 -383.50571)
		(stroke
			(width 0.0508)
			(type default)
		)
		(layer "F.Cu")
	)
	(gr_line
		(start 151.254206 -190.95466)
		(end 151.3078 -190.901066)
		(stroke
			(width 0.06477)
			(type default)
		)
		(layer "F.Cu")
	)
	(gr_line
		(start 151.269446 -191.77)
		(end 151.254206 -191.75476)
		(stroke
			(width 0.06477)
			(type default)
		)
		(layer "F.Cu")
	)
	(gr_line
		(start 151.334978 -383.596896)
		(end 151.469344 -383.596896)
		(stroke
			(width 0.0508)
			(type default)
		)
		(layer "F.Cu")
	)
	(gr_line
		(start 151.422354 -370.00942)
		(end 151.126444 -370.30533)
		(stroke
			(width 0.06477)
			(type default)
		)
		(layer "F.Cu")
	)
	(gr_line
		(start 151.469344 -383.596896)
		(end 151.545798 -383.520442)
		(stroke
			(width 0.0508)
			(type default)
		)
		(layer "F.Cu")
	)
	(gr_line
		(start 151.53513 -382.943862)
		(end 151.243792 -383.2352)
		(stroke
			(width 0.0508)
			(type default)
		)
		(layer "F.Cu")
	)
	(gr_line
		(start 151.545798 -383.520442)
		(end 151.545798 -383.402586)
		(stroke
			(width 0.0508)
			(type default)
		)
		(layer "F.Cu")
	)
	(gr_line
		(start 151.627586 -408.784044)
		(end 151.923496 -409.079954)
		(stroke
			(width 0.06477)
			(type default)
		)
		(layer "F.Cu")
	)
	(gr_line
		(start 151.62911 -391.36447)
		(end 151.545798 -391.281158)
		(stroke
			(width 0.0508)
			(type default)
		)
		(layer "F.Cu")
	)
	(gr_line
		(start 151.652986 -404.46452)
		(end 151.923496 -404.73503)
		(stroke
			(width 0.06477)
			(type default)
		)
		(layer "F.Cu")
	)
	(gr_line
		(start 151.698198 -388.774432)
		(end 152.218898 -388.774432)
		(stroke
			(width 0.0635)
			(type default)
		)
		(layer "F.Cu")
	)
	(gr_line
		(start 151.698198 -385.31038)
		(end 152.218898 -385.31038)
		(stroke
			(width 0.0635)
			(type default)
		)
		(layer "F.Cu")
	)
	(gr_line
		(start 151.744934 -370.00942)
		(end 152.040844 -370.30533)
		(stroke
			(width 0.06477)
			(type default)
		)
		(layer "F.Cu")
	)
	(gr_line
		(start 151.7523 -383.13741)
		(end 151.845772 -383.230882)
		(stroke
			(width 0.0508)
			(type default)
		)
		(layer "F.Cu")
	)
	(gr_line
		(start 151.7523 -382.942592)
		(end 151.7523 -383.13741)
		(stroke
			(width 0.0508)
			(type default)
		)
		(layer "F.Cu")
	)
	(gr_arc
		(start 151.7523 -381.5715)
		(mid 151.7523 -381.571881)
		(end 151.7523 -381.572262)
		(stroke
			(width 0.0508)
			(type default)
		)
		(layer "F.Cu")
	)
	(gr_line
		(start 151.845772 -383.230882)
		(end 151.845772 -383.92227)
		(stroke
			(width 0.0508)
			(type default)
		)
		(layer "F.Cu")
	)
	(gr_line
		(start 151.84628 -391.36574)
		(end 151.84628 -390.761982)
		(stroke
			(width 0.0508)
			(type default)
		)
		(layer "F.Cu")
	)
	(gr_line
		(start 151.84628 -390.761982)
		(end 151.845772 -390.761474)
		(stroke
			(width 0.0508)
			(type default)
		)
		(layer "F.Cu")
	)
	(gr_line
		(start 151.923496 -412.299658)
		(end 151.652986 -412.570168)
		(stroke
			(width 0.06477)
			(type default)
		)
		(layer "F.Cu")
	)
	(gr_line
		(start 151.923496 -407.954734)
		(end 151.627586 -408.250644)
		(stroke
			(width 0.06477)
			(type default)
		)
		(layer "F.Cu")
	)
	(gr_line
		(start 152.015444 -369.03533)
		(end 151.744934 -369.30584)
		(stroke
			(width 0.06477)
			(type default)
		)
		(layer "F.Cu")
	)
	(gr_line
		(start 152.040844 -370.83873)
		(end 151.691594 -371.18798)
		(stroke
			(width 0.0508)
			(type default)
		)
		(layer "F.Cu")
	)
	(gr_line
		(start 152.098248 -389.467344)
		(end 152.618948 -389.467344)
		(stroke
			(width 0.0635)
			(type default)
		)
		(layer "F.Cu")
	)
	(gr_line
		(start 152.098248 -386.003292)
		(end 152.618948 -386.003292)
		(stroke
			(width 0.0635)
			(type default)
		)
		(layer "F.Cu")
	)
	(gr_line
		(start 152.105614 -392.977116)
		(end 152.103582 -392.977116)
		(stroke
			(width 0.0508)
			(type default)
		)
		(layer "F.Cu")
	)
	(gr_line
		(start 152.244298 -393.292838)
		(end 152.244298 -393.1158)
		(stroke
			(width 0.0508)
			(type default)
		)
		(layer "F.Cu")
	)
	(gr_line
		(start 152.244298 -393.1158)
		(end 152.105614 -392.977116)
		(stroke
			(width 0.0508)
			(type default)
		)
		(layer "F.Cu")
	)
	(gr_line
		(start 152.244298 -392.6205)
		(end 152.104852 -392.759946)
		(stroke
			(width 0.0508)
			(type default)
		)
		(layer "F.Cu")
	)
	(gr_line
		(start 152.244298 -392.429238)
		(end 152.244298 -392.6205)
		(stroke
			(width 0.0508)
			(type default)
		)
		(layer "F.Cu")
	)
	(gr_line
		(start 152.246076 -412.299658)
		(end 152.516586 -412.570168)
		(stroke
			(width 0.06477)
			(type default)
		)
		(layer "F.Cu")
	)
	(gr_line
		(start 152.246076 -407.954734)
		(end 152.541986 -408.250644)
		(stroke
			(width 0.06477)
			(type default)
		)
		(layer "F.Cu")
	)
	(gr_line
		(start 152.247346 -190.9318)
		(end 152.270206 -190.95466)
		(stroke
			(width 0.06477)
			(type default)
		)
		(layer "F.Cu")
	)
	(gr_line
		(start 152.270206 -191.75476)
		(end 152.254966 -191.77)
		(stroke
			(width 0.06477)
			(type default)
		)
		(layer "F.Cu")
	)
	(gr_line
		(start 152.443688 -383.50571)
		(end 152.534874 -383.596896)
		(stroke
			(width 0.0508)
			(type default)
		)
		(layer "F.Cu")
	)
	(gr_line
		(start 152.443688 -383.2352)
		(end 152.443688 -383.50571)
		(stroke
			(width 0.0508)
			(type default)
		)
		(layer "F.Cu")
	)
	(gr_line
		(start 152.516586 -404.46452)
		(end 152.246076 -404.73503)
		(stroke
			(width 0.06477)
			(type default)
		)
		(layer "F.Cu")
	)
	(gr_line
		(start 152.534874 -383.596896)
		(end 152.66924 -383.596896)
		(stroke
			(width 0.0508)
			(type default)
		)
		(layer "F.Cu")
	)
	(gr_line
		(start 152.541986 -408.784044)
		(end 152.246076 -409.079954)
		(stroke
			(width 0.06477)
			(type default)
		)
		(layer "F.Cu")
	)
	(gr_line
		(start 152.66924 -383.596896)
		(end 152.745694 -383.520442)
		(stroke
			(width 0.0508)
			(type default)
		)
		(layer "F.Cu")
	)
	(gr_line
		(start 152.735026 -382.943862)
		(end 152.443688 -383.2352)
		(stroke
			(width 0.0508)
			(type default)
		)
		(layer "F.Cu")
	)
	(gr_line
		(start 152.745694 -383.520442)
		(end 152.745694 -383.402586)
		(stroke
			(width 0.0508)
			(type default)
		)
		(layer "F.Cu")
	)
	(gr_line
		(start 152.829006 -391.36447)
		(end 152.745694 -391.281158)
		(stroke
			(width 0.0508)
			(type default)
		)
		(layer "F.Cu")
	)
	(gr_line
		(start 152.898348 -388.774432)
		(end 153.419048 -388.774432)
		(stroke
			(width 0.0635)
			(type default)
		)
		(layer "F.Cu")
	)
	(gr_line
		(start 152.898348 -385.31038)
		(end 153.419048 -385.31038)
		(stroke
			(width 0.0635)
			(type default)
		)
		(layer "F.Cu")
	)
	(gr_line
		(start 152.952196 -383.13741)
		(end 153.045668 -383.230882)
		(stroke
			(width 0.0508)
			(type default)
		)
		(layer "F.Cu")
	)
	(gr_line
		(start 152.952196 -382.942592)
		(end 152.952196 -383.13741)
		(stroke
			(width 0.0508)
			(type default)
		)
		(layer "F.Cu")
	)
	(gr_line
		(start 153.045668 -383.230882)
		(end 153.045668 -383.92227)
		(stroke
			(width 0.0508)
			(type default)
		)
		(layer "F.Cu")
	)
	(gr_line
		(start 153.046176 -391.36574)
		(end 153.046176 -390.761982)
		(stroke
			(width 0.0508)
			(type default)
		)
		(layer "F.Cu")
	)
	(gr_line
		(start 153.046176 -390.761982)
		(end 153.045668 -390.761474)
		(stroke
			(width 0.0508)
			(type default)
		)
		(layer "F.Cu")
	)
	(gr_line
		(start 153.19502 -374.849136)
		(end 153.19502 -375.377456)
		(stroke
			(width 0.0508)
			(type default)
		)
		(layer "F.Cu")
	)
	(gr_line
		(start 153.277824 -190.958216)
		(end 153.624534 -190.611506)
		(stroke
			(width 0.06477)
			(type default)
		)
		(layer "F.Cu")
	)
	(gr_line
		(start 153.298398 -389.467344)
		(end 153.819098 -389.467344)
		(stroke
			(width 0.0635)
			(type default)
		)
		(layer "F.Cu")
	)
	(gr_line
		(start 153.298398 -386.003292)
		(end 153.819098 -386.003292)
		(stroke
			(width 0.0635)
			(type default)
		)
		(layer "F.Cu")
	)
	(gr_line
		(start 153.30551 -392.977116)
		(end 153.303478 -392.977116)
		(stroke
			(width 0.0508)
			(type default)
		)
		(layer "F.Cu")
	)
	(gr_line
		(start 153.41219 -374.850406)
		(end 153.52268 -374.960896)
		(stroke
			(width 0.0508)
			(type default)
		)
		(layer "F.Cu")
	)
	(gr_line
		(start 153.444194 -393.292838)
		(end 153.444194 -393.1158)
		(stroke
			(width 0.0508)
			(type default)
		)
		(layer "F.Cu")
	)
	(gr_line
		(start 153.444194 -393.1158)
		(end 153.30551 -392.977116)
		(stroke
			(width 0.0508)
			(type default)
		)
		(layer "F.Cu")
	)
	(gr_line
		(start 153.444194 -392.6205)
		(end 153.304748 -392.759946)
		(stroke
			(width 0.0508)
			(type default)
		)
		(layer "F.Cu")
	)
	(gr_line
		(start 153.444194 -392.429238)
		(end 153.444194 -392.6205)
		(stroke
			(width 0.0508)
			(type default)
		)
		(layer "F.Cu")
	)
	(gr_line
		(start 153.52268 -375.265696)
		(end 153.41219 -375.376186)
		(stroke
			(width 0.0508)
			(type default)
		)
		(layer "F.Cu")
	)
	(gr_line
		(start 153.52268 -374.960896)
		(end 153.52268 -375.265696)
		(stroke
			(width 0.0508)
			(type default)
		)
		(layer "F.Cu")
	)
	(gr_line
		(start 153.624534 -192.105026)
		(end 153.277824 -191.758316)
		(stroke
			(width 0.06477)
			(type default)
		)
		(layer "F.Cu")
	)
	(gr_line
		(start 153.643584 -383.50571)
		(end 153.73477 -383.596896)
		(stroke
			(width 0.0508)
			(type default)
		)
		(layer "F.Cu")
	)
	(gr_line
		(start 153.643584 -383.2352)
		(end 153.643584 -383.50571)
		(stroke
			(width 0.0508)
			(type default)
		)
		(layer "F.Cu")
	)
	(gr_line
		(start 153.73477 -383.596896)
		(end 153.869136 -383.596896)
		(stroke
			(width 0.0508)
			(type default)
		)
		(layer "F.Cu")
	)
	(gr_line
		(start 153.869136 -383.596896)
		(end 153.94559 -383.520442)
		(stroke
			(width 0.0508)
			(type default)
		)
		(layer "F.Cu")
	)
	(gr_line
		(start 153.934922 -382.943862)
		(end 153.643584 -383.2352)
		(stroke
			(width 0.0508)
			(type default)
		)
		(layer "F.Cu")
	)
	(gr_line
		(start 153.94559 -383.520442)
		(end 153.94559 -383.402586)
		(stroke
			(width 0.0508)
			(type default)
		)
		(layer "F.Cu")
	)
	(gr_line
		(start 153.947114 -192.105026)
		(end 154.293824 -191.758316)
		(stroke
			(width 0.06477)
			(type default)
		)
		(layer "F.Cu")
	)
	(gr_line
		(start 154.029156 -391.364724)
		(end 153.94559 -391.281158)
		(stroke
			(width 0.0508)
			(type default)
		)
		(layer "F.Cu")
	)
	(gr_line
		(start 154.098244 -388.774432)
		(end 154.618944 -388.774432)
		(stroke
			(width 0.0635)
			(type default)
		)
		(layer "F.Cu")
	)
	(gr_line
		(start 154.098244 -385.31038)
		(end 154.618944 -385.31038)
		(stroke
			(width 0.0635)
			(type default)
		)
		(layer "F.Cu")
	)
	(gr_line
		(start 154.152092 -383.13741)
		(end 154.245818 -383.231136)
		(stroke
			(width 0.0508)
			(type default)
		)
		(layer "F.Cu")
	)
	(gr_line
		(start 154.152092 -382.942592)
		(end 154.152092 -383.13741)
		(stroke
			(width 0.0508)
			(type default)
		)
		(layer "F.Cu")
	)
	(gr_line
		(start 154.245818 -383.231136)
		(end 154.245818 -383.92227)
		(stroke
			(width 0.0508)
			(type default)
		)
		(layer "F.Cu")
	)
	(gr_line
		(start 154.246326 -391.365486)
		(end 154.246072 -391.36574)
		(stroke
			(width 0.0508)
			(type default)
		)
		(layer "F.Cu")
	)
	(gr_line
		(start 154.246326 -391.365486)
		(end 154.246326 -390.761982)
		(stroke
			(width 0.0508)
			(type default)
		)
		(layer "F.Cu")
	)
	(gr_line
		(start 154.246326 -390.761982)
		(end 154.245818 -390.761474)
		(stroke
			(width 0.0508)
			(type default)
		)
		(layer "F.Cu")
	)
	(gr_line
		(start 154.293824 -190.958216)
		(end 153.947114 -190.611506)
		(stroke
			(width 0.06477)
			(type default)
		)
		(layer "F.Cu")
	)
	(gr_line
		(start 154.498294 -389.467344)
		(end 155.018994 -389.467344)
		(stroke
			(width 0.0635)
			(type default)
		)
		(layer "F.Cu")
	)
	(gr_line
		(start 154.498294 -386.003292)
		(end 155.018994 -386.003292)
		(stroke
			(width 0.0635)
			(type default)
		)
		(layer "F.Cu")
	)
	(gr_line
		(start 154.505406 -392.977116)
		(end 154.503628 -392.977116)
		(stroke
			(width 0.0508)
			(type default)
		)
		(layer "F.Cu")
	)
	(gr_line
		(start 154.530044 -375.76633)
		(end 154.831796 -376.068082)
		(stroke
			(width 0.0508)
			(type default)
		)
		(layer "F.Cu")
	)
	(gr_line
		(start 154.555444 -373.96293)
		(end 154.825954 -374.23344)
		(stroke
			(width 0.06477)
			(type default)
		)
		(layer "F.Cu")
	)
	(gr_line
		(start 154.644344 -393.292838)
		(end 154.644344 -393.116054)
		(stroke
			(width 0.0508)
			(type default)
		)
		(layer "F.Cu")
	)
	(gr_line
		(start 154.644344 -393.116054)
		(end 154.505406 -392.977116)
		(stroke
			(width 0.0508)
			(type default)
		)
		(layer "F.Cu")
	)
	(gr_line
		(start 154.644344 -392.6205)
		(end 154.504898 -392.759946)
		(stroke
			(width 0.0508)
			(type default)
		)
		(layer "F.Cu")
	)
	(gr_line
		(start 154.644344 -392.429238)
		(end 154.644344 -392.6205)
		(stroke
			(width 0.0508)
			(type default)
		)
		(layer "F.Cu")
	)
	(gr_line
		(start 154.690826 -408.784044)
		(end 154.986736 -409.079954)
		(stroke
			(width 0.06477)
			(type default)
		)
		(layer "F.Cu")
	)
	(gr_line
		(start 154.716226 -404.46452)
		(end 154.986736 -404.73503)
		(stroke
			(width 0.06477)
			(type default)
		)
		(layer "F.Cu")
	)
	(gr_line
		(start 154.825954 -374.93702)
		(end 154.530044 -375.23293)
		(stroke
			(width 0.06477)
			(type default)
		)
		(layer "F.Cu")
	)
	(gr_line
		(start 154.843734 -383.50571)
		(end 154.93492 -383.596896)
		(stroke
			(width 0.0508)
			(type default)
		)
		(layer "F.Cu")
	)
	(gr_line
		(start 154.843734 -383.2352)
		(end 154.843734 -383.50571)
		(stroke
			(width 0.0508)
			(type default)
		)
		(layer "F.Cu")
	)
	(gr_line
		(start 154.87142 -175.653192)
		(end 155.413964 -175.110648)
		(stroke
			(width 0.06477)
			(type default)
		)
		(layer "F.Cu")
	)
	(gr_arc
		(start 154.878278 -376.165872)
		(mid 154.8634 -376.113003)
		(end 154.831796 -376.068082)
		(stroke
			(width 0.0508)
			(type default)
		)
		(layer "F.Cu")
	)
	(gr_line
		(start 154.879294 -377.07443)
		(end 154.879294 -377.60275)
		(stroke
			(width 0.0508)
			(type default)
		)
		(layer "F.Cu")
	)
	(gr_line
		(start 154.93492 -383.596896)
		(end 155.069286 -383.596896)
		(stroke
			(width 0.0508)
			(type default)
		)
		(layer "F.Cu")
	)
	(gr_line
		(start 154.986736 -412.299658)
		(end 154.716226 -412.570168)
		(stroke
			(width 0.06477)
			(type default)
		)
		(layer "F.Cu")
	)
	(gr_line
		(start 154.986736 -407.954734)
		(end 154.690826 -408.250644)
		(stroke
			(width 0.06477)
			(type default)
		)
		(layer "F.Cu")
	)
	(gr_line
		(start 155.069286 -383.596896)
		(end 155.14574 -383.520442)
		(stroke
			(width 0.0508)
			(type default)
		)
		(layer "F.Cu")
	)
	(gr_line
		(start 155.096464 -377.0757)
		(end 155.206954 -377.18619)
		(stroke
			(width 0.0508)
			(type default)
		)
		(layer "F.Cu")
	)
	(gr_line
		(start 155.10129 -175.881538)
		(end 155.369006 -175.881538)
		(stroke
			(width 0.06477)
			(type default)
		)
		(layer "F.Cu")
	)
	(gr_line
		(start 155.135072 -382.943862)
		(end 154.843734 -383.2352)
		(stroke
			(width 0.0508)
			(type default)
		)
		(layer "F.Cu")
	)
	(gr_arc
		(start 155.142438 -376.068336)
		(mid 155.110839 -376.112982)
		(end 155.095956 -376.165618)
		(stroke
			(width 0.0508)
			(type default)
		)
		(layer "F.Cu")
	)
	(gr_line
		(start 155.14574 -383.520442)
		(end 155.14574 -383.402586)
		(stroke
			(width 0.0508)
			(type default)
		)
		(layer "F.Cu")
	)
	(gr_line
		(start 155.148534 -374.93702)
		(end 155.444444 -375.23293)
		(stroke
			(width 0.06477)
			(type default)
		)
		(layer "F.Cu")
	)
	(gr_line
		(start 155.206954 -377.49099)
		(end 155.096464 -377.60148)
		(stroke
			(width 0.0508)
			(type default)
		)
		(layer "F.Cu")
	)
	(gr_line
		(start 155.206954 -377.18619)
		(end 155.206954 -377.49099)
		(stroke
			(width 0.0508)
			(type default)
		)
		(layer "F.Cu")
	)
	(gr_line
		(start 155.229052 -391.36447)
		(end 155.14574 -391.281158)
		(stroke
			(width 0.0508)
			(type default)
		)
		(layer "F.Cu")
	)
	(gr_line
		(start 155.298394 -388.774432)
		(end 155.819094 -388.774432)
		(stroke
			(width 0.0635)
			(type default)
		)
		(layer "F.Cu")
	)
	(gr_line
		(start 155.298394 -385.31038)
		(end 155.819094 -385.31038)
		(stroke
			(width 0.0635)
			(type default)
		)
		(layer "F.Cu")
	)
	(gr_line
		(start 155.306522 -190.961264)
		(end 155.3718 -190.895986)
		(stroke
			(width 0.06477)
			(type default)
		)
		(layer "F.Cu")
	)
	(gr_line
		(start 155.309316 -412.299658)
		(end 155.579826 -412.570168)
		(stroke
			(width 0.06477)
			(type default)
		)
		(layer "F.Cu")
	)
	(gr_line
		(start 155.309316 -407.954734)
		(end 155.605226 -408.250644)
		(stroke
			(width 0.06477)
			(type default)
		)
		(layer "F.Cu")
	)
	(gr_line
		(start 155.3464 -191.801242)
		(end 155.306522 -191.761364)
		(stroke
			(width 0.06477)
			(type default)
		)
		(layer "F.Cu")
	)
	(gr_line
		(start 155.352242 -383.13741)
		(end 155.445714 -383.230882)
		(stroke
			(width 0.0508)
			(type default)
		)
		(layer "F.Cu")
	)
	(gr_line
		(start 155.352242 -382.94183)
		(end 155.352242 -383.13741)
		(stroke
			(width 0.0508)
			(type default)
		)
		(layer "F.Cu")
	)
	(gr_line
		(start 155.369006 -175.881538)
		(end 155.64231 -175.608234)
		(stroke
			(width 0.06477)
			(type default)
		)
		(layer "F.Cu")
	)
	(gr_line
		(start 155.419044 -373.96293)
		(end 155.148534 -374.23344)
		(stroke
			(width 0.06477)
			(type default)
		)
		(layer "F.Cu")
	)
	(gr_line
		(start 155.444444 -375.76633)
		(end 155.142438 -376.068336)
		(stroke
			(width 0.0508)
			(type default)
		)
		(layer "F.Cu")
	)
	(gr_line
		(start 155.445714 -383.230882)
		(end 155.445714 -383.92227)
		(stroke
			(width 0.0508)
			(type default)
		)
		(layer "F.Cu")
	)
	(gr_line
		(start 155.446222 -391.36574)
		(end 155.446222 -390.761982)
		(stroke
			(width 0.0508)
			(type default)
		)
		(layer "F.Cu")
	)
	(gr_line
		(start 155.446222 -390.761982)
		(end 155.445714 -390.761474)
		(stroke
			(width 0.0508)
			(type default)
		)
		(layer "F.Cu")
	)
	(gr_line
		(start 155.523438 -192.720976)
		(end 155.591256 -192.5574)
		(stroke
			(width 0.06477)
			(type default)
		)
		(layer "F.Cu")
	)
	(gr_line
		(start 155.579826 -404.46452)
		(end 155.309316 -404.73503)
		(stroke
			(width 0.06477)
			(type default)
		)
		(layer "F.Cu")
	)
	(gr_line
		(start 155.605226 -408.784044)
		(end 155.309316 -409.079954)
		(stroke
			(width 0.06477)
			(type default)
		)
		(layer "F.Cu")
	)
	(gr_line
		(start 155.64231 -175.608234)
		(end 155.64231 -175.340518)
		(stroke
			(width 0.06477)
			(type default)
		)
		(layer "F.Cu")
	)
	(gr_line
		(start 155.68676 -174.837852)
		(end 156.229812 -174.295054)
		(stroke
			(width 0.06477)
			(type default)
		)
		(layer "F.Cu")
	)
	(gr_line
		(start 155.69819 -389.467344)
		(end 156.21889 -389.467344)
		(stroke
			(width 0.0635)
			(type default)
		)
		(layer "F.Cu")
	)
	(gr_line
		(start 155.69819 -386.003292)
		(end 156.21889 -386.003292)
		(stroke
			(width 0.0635)
			(type default)
		)
		(layer "F.Cu")
	)
	(gr_line
		(start 155.705556 -392.977116)
		(end 155.703524 -392.977116)
		(stroke
			(width 0.0508)
			(type default)
		)
		(layer "F.Cu")
	)
	(gr_line
		(start 155.82138 -192.844674)
		(end 155.82138 -192.84442)
		(stroke
			(width 0.06477)
			(type default)
		)
		(layer "F.Cu")
	)
	(gr_line
		(start 155.82138 -192.84442)
		(end 155.889198 -192.680844)
		(stroke
			(width 0.06477)
			(type default)
		)
		(layer "F.Cu")
	)
	(gr_line
		(start 155.84424 -393.292838)
		(end 155.84424 -393.1158)
		(stroke
			(width 0.0508)
			(type default)
		)
		(layer "F.Cu")
	)
	(gr_line
		(start 155.84424 -393.1158)
		(end 155.705556 -392.977116)
		(stroke
			(width 0.0508)
			(type default)
		)
		(layer "F.Cu")
	)
	(gr_line
		(start 155.84424 -392.6205)
		(end 155.704794 -392.759946)
		(stroke
			(width 0.0508)
			(type default)
		)
		(layer "F.Cu")
	)
	(gr_line
		(start 155.84424 -392.429238)
		(end 155.84424 -392.6205)
		(stroke
			(width 0.0508)
			(type default)
		)
		(layer "F.Cu")
	)
	(gr_line
		(start 155.91663 -175.066198)
		(end 156.1846 -175.066198)
		(stroke
			(width 0.06477)
			(type default)
		)
		(layer "F.Cu")
	)
	(gr_line
		(start 156.04363 -383.50571)
		(end 156.134816 -383.596896)
		(stroke
			(width 0.0508)
			(type default)
		)
		(layer "F.Cu")
	)
	(gr_line
		(start 156.04363 -383.2352)
		(end 156.04363 -383.50571)
		(stroke
			(width 0.0508)
			(type default)
		)
		(layer "F.Cu")
	)
	(gr_line
		(start 156.134816 -383.596896)
		(end 156.269182 -383.596896)
		(stroke
			(width 0.0508)
			(type default)
		)
		(layer "F.Cu")
	)
	(gr_line
		(start 156.1846 -175.066198)
		(end 156.457904 -174.792894)
		(stroke
			(width 0.06477)
			(type default)
		)
		(layer "F.Cu")
	)
	(gr_line
		(start 156.231844 -373.30253)
		(end 156.533596 -373.604282)
		(stroke
			(width 0.0508)
			(type default)
		)
		(layer "F.Cu")
	)
	(gr_line
		(start 156.257244 -371.49913)
		(end 156.527754 -371.76964)
		(stroke
			(width 0.06477)
			(type default)
		)
		(layer "F.Cu")
	)
	(gr_line
		(start 156.269182 -383.596896)
		(end 156.345636 -383.520442)
		(stroke
			(width 0.0508)
			(type default)
		)
		(layer "F.Cu")
	)
	(gr_line
		(start 156.334968 -382.943862)
		(end 156.04363 -383.2352)
		(stroke
			(width 0.0508)
			(type default)
		)
		(layer "F.Cu")
	)
	(gr_line
		(start 156.345636 -383.520442)
		(end 156.345636 -383.402586)
		(stroke
			(width 0.0508)
			(type default)
		)
		(layer "F.Cu")
	)
	(gr_line
		(start 156.428948 -391.36447)
		(end 156.345636 -391.281158)
		(stroke
			(width 0.0508)
			(type default)
		)
		(layer "F.Cu")
	)
	(gr_line
		(start 156.457904 -174.792894)
		(end 156.457904 -174.524924)
		(stroke
			(width 0.06477)
			(type default)
		)
		(layer "F.Cu")
	)
	(gr_line
		(start 156.49829 -388.774432)
		(end 157.01899 -388.774432)
		(stroke
			(width 0.0635)
			(type default)
		)
		(layer "F.Cu")
	)
	(gr_line
		(start 156.49829 -385.31038)
		(end 157.01899 -385.31038)
		(stroke
			(width 0.0635)
			(type default)
		)
		(layer "F.Cu")
	)
	(gr_line
		(start 156.502354 -174.022258)
		(end 157.045152 -173.47946)
		(stroke
			(width 0.06477)
			(type default)
		)
		(layer "F.Cu")
	)
	(gr_line
		(start 156.527754 -372.47322)
		(end 156.231844 -372.76913)
		(stroke
			(width 0.06477)
			(type default)
		)
		(layer "F.Cu")
	)
	(gr_line
		(start 156.552138 -383.13741)
		(end 156.64561 -383.230882)
		(stroke
			(width 0.0508)
			(type default)
		)
		(layer "F.Cu")
	)
	(gr_line
		(start 156.552138 -382.942592)
		(end 156.552138 -383.13741)
		(stroke
			(width 0.0508)
			(type default)
		)
		(layer "F.Cu")
	)
	(gr_arc
		(start 156.580078 -373.702072)
		(mid 156.5652 -373.649203)
		(end 156.533596 -373.604282)
		(stroke
			(width 0.0508)
			(type default)
		)
		(layer "F.Cu")
	)
	(gr_line
		(start 156.581094 -374.84304)
		(end 156.581094 -375.37136)
		(stroke
			(width 0.0508)
			(type default)
		)
		(layer "F.Cu")
	)
	(gr_line
		(start 156.64561 -383.230882)
		(end 156.64561 -383.92227)
		(stroke
			(width 0.0508)
			(type default)
		)
		(layer "F.Cu")
	)
	(gr_line
		(start 156.646118 -391.36574)
		(end 156.646118 -390.761982)
		(stroke
			(width 0.0508)
			(type default)
		)
		(layer "F.Cu")
	)
	(gr_line
		(start 156.646118 -390.761982)
		(end 156.64561 -390.761474)
		(stroke
			(width 0.0508)
			(type default)
		)
		(layer "F.Cu")
	)
	(gr_line
		(start 156.732224 -174.250604)
		(end 157.000194 -174.250604)
		(stroke
			(width 0.06477)
			(type default)
		)
		(layer "F.Cu")
	)
	(gr_line
		(start 156.798264 -374.84431)
		(end 156.908754 -374.9548)
		(stroke
			(width 0.0508)
			(type default)
		)
		(layer "F.Cu")
	)
	(gr_arc
		(start 156.844492 -373.604282)
		(mid 156.812855 -373.649183)
		(end 156.79801 -373.702072)
		(stroke
			(width 0.0508)
			(type default)
		)
		(layer "F.Cu")
	)
	(gr_line
		(start 156.850334 -372.47322)
		(end 157.146244 -372.76913)
		(stroke
			(width 0.06477)
			(type default)
		)
		(layer "F.Cu")
	)
	(gr_line
		(start 156.89834 -389.467344)
		(end 157.41904 -389.467344)
		(stroke
			(width 0.0635)
			(type default)
		)
		(layer "F.Cu")
	)
	(gr_line
		(start 156.89834 -386.003292)
		(end 157.41904 -386.003292)
		(stroke
			(width 0.0635)
			(type default)
		)
		(layer "F.Cu")
	)
	(gr_line
		(start 156.905452 -392.977116)
		(end 156.90342 -392.977116)
		(stroke
			(width 0.0508)
			(type default)
		)
		(layer "F.Cu")
	)
	(gr_line
		(start 156.908754 -375.2596)
		(end 156.798264 -375.37009)
		(stroke
			(width 0.0508)
			(type default)
		)
		(layer "F.Cu")
	)
	(gr_line
		(start 156.908754 -374.9548)
		(end 156.908754 -375.2596)
		(stroke
			(width 0.0508)
			(type default)
		)
		(layer "F.Cu")
	)
	(gr_line
		(start 157.000194 -174.250604)
		(end 157.273498 -173.9773)
		(stroke
			(width 0.06477)
			(type default)
		)
		(layer "F.Cu")
	)
	(gr_line
		(start 157.04439 -393.292838)
		(end 157.04439 -393.116054)
		(stroke
			(width 0.0508)
			(type default)
		)
		(layer "F.Cu")
	)
	(gr_line
		(start 157.04439 -393.116054)
		(end 156.905452 -392.977116)
		(stroke
			(width 0.0508)
			(type default)
		)
		(layer "F.Cu")
	)
	(gr_line
		(start 157.04439 -392.620246)
		(end 156.90469 -392.759946)
		(stroke
			(width 0.0508)
			(type default)
		)
		(layer "F.Cu")
	)
	(gr_line
		(start 157.04439 -392.429238)
		(end 157.04439 -392.620246)
		(stroke
			(width 0.0508)
			(type default)
		)
		(layer "F.Cu")
	)
	(gr_line
		(start 157.120844 -371.49913)
		(end 156.850334 -371.76964)
		(stroke
			(width 0.06477)
			(type default)
		)
		(layer "F.Cu")
	)
	(gr_line
		(start 157.146244 -373.30253)
		(end 156.844492 -373.604282)
		(stroke
			(width 0.0508)
			(type default)
		)
		(layer "F.Cu")
	)
	(gr_line
		(start 157.24378 -383.50571)
		(end 157.334966 -383.596896)
		(stroke
			(width 0.0508)
			(type default)
		)
		(layer "F.Cu")
	)
	(gr_line
		(start 157.24378 -383.2352)
		(end 157.24378 -383.50571)
		(stroke
			(width 0.0508)
			(type default)
		)
		(layer "F.Cu")
	)
	(gr_line
		(start 157.273498 -173.9773)
		(end 157.273498 -173.70933)
		(stroke
			(width 0.06477)
			(type default)
		)
		(layer "F.Cu")
	)
	(gr_line
		(start 157.334966 -383.596896)
		(end 157.469332 -383.596896)
		(stroke
			(width 0.0508)
			(type default)
		)
		(layer "F.Cu")
	)
	(gr_line
		(start 157.469332 -383.596896)
		(end 157.545786 -383.520442)
		(stroke
			(width 0.0508)
			(type default)
		)
		(layer "F.Cu")
	)
	(gr_line
		(start 157.535118 -382.943862)
		(end 157.24378 -383.2352)
		(stroke
			(width 0.0508)
			(type default)
		)
		(layer "F.Cu")
	)
	(gr_line
		(start 157.545786 -383.520442)
		(end 157.545786 -383.402586)
		(stroke
			(width 0.0508)
			(type default)
		)
		(layer "F.Cu")
	)
	(gr_line
		(start 157.629098 -391.36447)
		(end 157.545786 -391.281158)
		(stroke
			(width 0.0508)
			(type default)
		)
		(layer "F.Cu")
	)
	(gr_line
		(start 157.698186 -388.774432)
		(end 158.218886 -388.774432)
		(stroke
			(width 0.0635)
			(type default)
		)
		(layer "F.Cu")
	)
	(gr_line
		(start 157.698186 -385.31038)
		(end 158.218886 -385.31038)
		(stroke
			(width 0.0635)
			(type default)
		)
		(layer "F.Cu")
	)
	(gr_line
		(start 157.752288 -383.13741)
		(end 157.84576 -383.230882)
		(stroke
			(width 0.0508)
			(type default)
		)
		(layer "F.Cu")
	)
	(gr_line
		(start 157.752288 -382.942592)
		(end 157.752288 -383.13741)
		(stroke
			(width 0.0508)
			(type default)
		)
		(layer "F.Cu")
	)
	(gr_line
		(start 157.754066 -408.784044)
		(end 158.049976 -409.079954)
		(stroke
			(width 0.06477)
			(type default)
		)
		(layer "F.Cu")
	)
	(gr_line
		(start 157.779466 -404.46452)
		(end 158.049976 -404.73503)
		(stroke
			(width 0.06477)
			(type default)
		)
		(layer "F.Cu")
	)
	(gr_line
		(start 157.84576 -383.230882)
		(end 157.84576 -383.92227)
		(stroke
			(width 0.0508)
			(type default)
		)
		(layer "F.Cu")
	)
	(gr_line
		(start 157.846268 -391.36574)
		(end 157.846268 -390.761982)
		(stroke
			(width 0.0508)
			(type default)
		)
		(layer "F.Cu")
	)
	(gr_line
		(start 157.846268 -390.761982)
		(end 157.84576 -390.761474)
		(stroke
			(width 0.0508)
			(type default)
		)
		(layer "F.Cu")
	)
	(gr_line
		(start 157.933644 -370.83873)
		(end 158.282894 -371.18798)
		(stroke
			(width 0.0508)
			(type default)
		)
		(layer "F.Cu")
	)
	(gr_line
		(start 157.959044 -369.03533)
		(end 158.229554 -369.30584)
		(stroke
			(width 0.06477)
			(type default)
		)
		(layer "F.Cu")
	)
	(gr_line
		(start 158.049976 -412.299658)
		(end 157.779466 -412.570168)
		(stroke
			(width 0.06477)
			(type default)
		)
		(layer "F.Cu")
	)
	(gr_line
		(start 158.049976 -407.954734)
		(end 157.754066 -408.250644)
		(stroke
			(width 0.06477)
			(type default)
		)
		(layer "F.Cu")
	)
	(gr_line
		(start 158.098236 -389.467344)
		(end 158.618936 -389.467344)
		(stroke
			(width 0.0635)
			(type default)
		)
		(layer "F.Cu")
	)
	(gr_line
		(start 158.098236 -386.003292)
		(end 158.618936 -386.003292)
		(stroke
			(width 0.0635)
			(type default)
		)
		(layer "F.Cu")
	)
	(gr_line
		(start 158.105602 -392.977116)
		(end 158.10357 -392.977116)
		(stroke
			(width 0.0508)
			(type default)
		)
		(layer "F.Cu")
	)
	(gr_line
		(start 158.229554 -370.00942)
		(end 157.933644 -370.30533)
		(stroke
			(width 0.06477)
			(type default)
		)
		(layer "F.Cu")
	)
	(gr_line
		(start 158.244286 -393.292838)
		(end 158.244286 -393.1158)
		(stroke
			(width 0.0508)
			(type default)
		)
		(layer "F.Cu")
	)
	(gr_line
		(start 158.244286 -393.1158)
		(end 158.105602 -392.977116)
		(stroke
			(width 0.0508)
			(type default)
		)
		(layer "F.Cu")
	)
	(gr_line
		(start 158.244286 -392.6205)
		(end 158.10484 -392.759946)
		(stroke
			(width 0.0508)
			(type default)
		)
		(layer "F.Cu")
	)
	(gr_line
		(start 158.244286 -392.429238)
		(end 158.244286 -392.6205)
		(stroke
			(width 0.0508)
			(type default)
		)
		(layer "F.Cu")
	)
	(gr_line
		(start 158.372556 -412.299658)
		(end 158.643066 -412.570168)
		(stroke
			(width 0.06477)
			(type default)
		)
		(layer "F.Cu")
	)
	(gr_line
		(start 158.372556 -407.954734)
		(end 158.668466 -408.250644)
		(stroke
			(width 0.06477)
			(type default)
		)
		(layer "F.Cu")
	)
	(gr_line
		(start 158.443676 -383.50571)
		(end 158.534862 -383.596896)
		(stroke
			(width 0.0508)
			(type default)
		)
		(layer "F.Cu")
	)
	(gr_line
		(start 158.443676 -383.2352)
		(end 158.443676 -383.50571)
		(stroke
			(width 0.0508)
			(type default)
		)
		(layer "F.Cu")
	)
	(gr_line
		(start 158.534862 -383.596896)
		(end 158.669228 -383.596896)
		(stroke
			(width 0.0508)
			(type default)
		)
		(layer "F.Cu")
	)
	(gr_line
		(start 158.552134 -370.00942)
		(end 158.848044 -370.30533)
		(stroke
			(width 0.06477)
			(type default)
		)
		(layer "F.Cu")
	)
	(gr_line
		(start 158.643066 -404.46452)
		(end 158.372556 -404.73503)
		(stroke
			(width 0.06477)
			(type default)
		)
		(layer "F.Cu")
	)
	(gr_line
		(start 158.668466 -408.784044)
		(end 158.372556 -409.079954)
		(stroke
			(width 0.06477)
			(type default)
		)
		(layer "F.Cu")
	)
	(gr_line
		(start 158.669228 -383.596896)
		(end 158.745682 -383.520442)
		(stroke
			(width 0.0508)
			(type default)
		)
		(layer "F.Cu")
	)
	(gr_line
		(start 158.735014 -382.943862)
		(end 158.443676 -383.2352)
		(stroke
			(width 0.0508)
			(type default)
		)
		(layer "F.Cu")
	)
	(gr_line
		(start 158.745682 -383.520442)
		(end 158.745682 -383.402586)
		(stroke
			(width 0.0508)
			(type default)
		)
		(layer "F.Cu")
	)
	(gr_line
		(start 158.822644 -369.03533)
		(end 158.552134 -369.30584)
		(stroke
			(width 0.06477)
			(type default)
		)
		(layer "F.Cu")
	)
	(gr_line
		(start 158.828486 -391.363962)
		(end 158.745682 -391.281158)
		(stroke
			(width 0.0508)
			(type default)
		)
		(layer "F.Cu")
	)
	(gr_line
		(start 158.848044 -370.83873)
		(end 158.498794 -371.18798)
		(stroke
			(width 0.0508)
			(type default)
		)
		(layer "F.Cu")
	)
	(gr_line
		(start 158.898336 -388.774432)
		(end 159.419036 -388.774432)
		(stroke
			(width 0.0635)
			(type default)
		)
		(layer "F.Cu")
	)
	(gr_line
		(start 158.898336 -385.31038)
		(end 159.419036 -385.31038)
		(stroke
			(width 0.0635)
			(type default)
		)
		(layer "F.Cu")
	)
	(gr_line
		(start 158.952184 -383.13741)
		(end 159.045656 -383.230882)
		(stroke
			(width 0.0508)
			(type default)
		)
		(layer "F.Cu")
	)
	(gr_line
		(start 158.952184 -382.942592)
		(end 158.952184 -383.13741)
		(stroke
			(width 0.0508)
			(type default)
		)
		(layer "F.Cu")
	)
	(gr_line
		(start 158.966154 -376.553984)
		(end 158.809436 -376.553984)
		(stroke
			(width 0.0508)
			(type default)
		)
		(layer "F.Cu")
	)
	(gr_line
		(start 159.015684 -378.48286)
		(end 159.01543 -378.48286)
		(stroke
			(width 0.0508)
			(type default)
		)
		(layer "F.Cu")
	)
	(gr_line
		(start 159.029146 -376.027188)
		(end 158.655258 -376.401076)
		(stroke
			(width 0.0508)
			(type default)
		)
		(layer "F.Cu")
	)
	(gr_line
		(start 159.045656 -391.365232)
		(end 159.045656 -390.761474)
		(stroke
			(width 0.0508)
			(type default)
		)
		(layer "F.Cu")
	)
	(gr_line
		(start 159.045656 -383.230882)
		(end 159.045656 -383.92227)
		(stroke
			(width 0.0508)
			(type default)
		)
		(layer "F.Cu")
	)
	(gr_line
		(start 159.182054 -376.338084)
		(end 158.966154 -376.553984)
		(stroke
			(width 0.0508)
			(type default)
		)
		(layer "F.Cu")
	)
	(gr_line
		(start 159.182054 -376.181366)
		(end 159.182054 -376.338084)
		(stroke
			(width 0.0508)
			(type default)
		)
		(layer "F.Cu")
	)
	(gr_line
		(start 159.298386 -389.467344)
		(end 159.819086 -389.467344)
		(stroke
			(width 0.0635)
			(type default)
		)
		(layer "F.Cu")
	)
	(gr_line
		(start 159.298386 -386.003292)
		(end 159.819086 -386.003292)
		(stroke
			(width 0.0635)
			(type default)
		)
		(layer "F.Cu")
	)
	(gr_line
		(start 159.305498 -392.977116)
		(end 159.303466 -392.977116)
		(stroke
			(width 0.0508)
			(type default)
		)
		(layer "F.Cu")
	)
	(gr_line
		(start 159.326326 -378.635768)
		(end 159.169862 -378.635768)
		(stroke
			(width 0.0508)
			(type default)
		)
		(layer "F.Cu")
	)
	(gr_line
		(start 159.389064 -378.10948)
		(end 159.015684 -378.48286)
		(stroke
			(width 0.0508)
			(type default)
		)
		(layer "F.Cu")
	)
	(gr_line
		(start 159.444436 -393.292838)
		(end 159.444436 -393.116054)
		(stroke
			(width 0.0508)
			(type default)
		)
		(layer "F.Cu")
	)
	(gr_line
		(start 159.444436 -393.116054)
		(end 159.305498 -392.977116)
		(stroke
			(width 0.0508)
			(type default)
		)
		(layer "F.Cu")
	)
	(gr_line
		(start 159.444436 -392.620246)
		(end 159.304736 -392.759946)
		(stroke
			(width 0.0508)
			(type default)
		)
		(layer "F.Cu")
	)
	(gr_line
		(start 159.444436 -392.429238)
		(end 159.444436 -392.620246)
		(stroke
			(width 0.0508)
			(type default)
		)
		(layer "F.Cu")
	)
	(gr_line
		(start 159.541972 -378.420122)
		(end 159.326326 -378.635768)
		(stroke
			(width 0.0508)
			(type default)
		)
		(layer "F.Cu")
	)
	(gr_line
		(start 159.541972 -378.263658)
		(end 159.541972 -378.420122)
		(stroke
			(width 0.0508)
			(type default)
		)
		(layer "F.Cu")
	)
	(gr_line
		(start 159.643572 -383.50571)
		(end 159.734758 -383.596896)
		(stroke
			(width 0.0508)
			(type default)
		)
		(layer "F.Cu")
	)
	(gr_line
		(start 159.643572 -383.2352)
		(end 159.643572 -383.50571)
		(stroke
			(width 0.0508)
			(type default)
		)
		(layer "F.Cu")
	)
	(gr_line
		(start 159.734758 -383.596896)
		(end 159.869124 -383.596896)
		(stroke
			(width 0.0508)
			(type default)
		)
		(layer "F.Cu")
	)
	(gr_line
		(start 159.869124 -383.596896)
		(end 159.945578 -383.520442)
		(stroke
			(width 0.0508)
			(type default)
		)
		(layer "F.Cu")
	)
	(gr_line
		(start 159.93491 -382.943862)
		(end 159.643572 -383.2352)
		(stroke
			(width 0.0508)
			(type default)
		)
		(layer "F.Cu")
	)
	(gr_line
		(start 159.945578 -383.520442)
		(end 159.945578 -383.402586)
		(stroke
			(width 0.0508)
			(type default)
		)
		(layer "F.Cu")
	)
	(gr_line
		(start 160.02889 -391.36447)
		(end 159.945578 -391.281158)
		(stroke
			(width 0.0508)
			(type default)
		)
		(layer "F.Cu")
	)
	(gr_line
		(start 160.098232 -388.774432)
		(end 160.618932 -388.774432)
		(stroke
			(width 0.0635)
			(type default)
		)
		(layer "F.Cu")
	)
	(gr_line
		(start 160.098232 -385.31038)
		(end 160.618932 -385.31038)
		(stroke
			(width 0.0635)
			(type default)
		)
		(layer "F.Cu")
	)
	(gr_line
		(start 160.15208 -383.13741)
		(end 160.245806 -383.231136)
		(stroke
			(width 0.0508)
			(type default)
		)
		(layer "F.Cu")
	)
	(gr_line
		(start 160.15208 -382.942592)
		(end 160.15208 -383.13741)
		(stroke
			(width 0.0508)
			(type default)
		)
		(layer "F.Cu")
	)
	(gr_line
		(start 160.245806 -383.231136)
		(end 160.245806 -383.92227)
		(stroke
			(width 0.0508)
			(type default)
		)
		(layer "F.Cu")
	)
	(gr_line
		(start 160.24606 -391.36574)
		(end 160.24606 -390.761728)
		(stroke
			(width 0.0508)
			(type default)
		)
		(layer "F.Cu")
	)
	(gr_line
		(start 160.24606 -390.761728)
		(end 160.245806 -390.761474)
		(stroke
			(width 0.0508)
			(type default)
		)
		(layer "F.Cu")
	)
	(gr_line
		(start 160.498282 -389.467344)
		(end 161.018982 -389.467344)
		(stroke
			(width 0.0635)
			(type default)
		)
		(layer "F.Cu")
	)
	(gr_line
		(start 160.498282 -386.003292)
		(end 161.018982 -386.003292)
		(stroke
			(width 0.0635)
			(type default)
		)
		(layer "F.Cu")
	)
	(gr_line
		(start 160.505394 -392.977116)
		(end 160.503362 -392.977116)
		(stroke
			(width 0.0508)
			(type default)
		)
		(layer "F.Cu")
	)
	(gr_line
		(start 160.644332 -393.292838)
		(end 160.644332 -393.116054)
		(stroke
			(width 0.0508)
			(type default)
		)
		(layer "F.Cu")
	)
	(gr_line
		(start 160.644332 -393.116054)
		(end 160.505394 -392.977116)
		(stroke
			(width 0.0508)
			(type default)
		)
		(layer "F.Cu")
	)
	(gr_line
		(start 160.644332 -392.620246)
		(end 160.504632 -392.759946)
		(stroke
			(width 0.0508)
			(type default)
		)
		(layer "F.Cu")
	)
	(gr_line
		(start 160.644332 -392.429238)
		(end 160.644332 -392.620246)
		(stroke
			(width 0.0508)
			(type default)
		)
		(layer "F.Cu")
	)
	(gr_line
		(start 160.817306 -408.784044)
		(end 161.113216 -409.079954)
		(stroke
			(width 0.06477)
			(type default)
		)
		(layer "F.Cu")
	)
	(gr_line
		(start 160.842706 -404.46452)
		(end 161.113216 -404.73503)
		(stroke
			(width 0.06477)
			(type default)
		)
		(layer "F.Cu")
	)
	(gr_line
		(start 160.843722 -383.50571)
		(end 160.934908 -383.596896)
		(stroke
			(width 0.0508)
			(type default)
		)
		(layer "F.Cu")
	)
	(gr_line
		(start 160.843722 -383.2352)
		(end 160.843722 -383.50571)
		(stroke
			(width 0.0508)
			(type default)
		)
		(layer "F.Cu")
	)
	(gr_line
		(start 160.934908 -383.596896)
		(end 161.069274 -383.596896)
		(stroke
			(width 0.0508)
			(type default)
		)
		(layer "F.Cu")
	)
	(gr_line
		(start 161.069274 -383.596896)
		(end 161.145728 -383.520442)
		(stroke
			(width 0.0508)
			(type default)
		)
		(layer "F.Cu")
	)
	(gr_line
		(start 161.113216 -412.299658)
		(end 160.842706 -412.570168)
		(stroke
			(width 0.06477)
			(type default)
		)
		(layer "F.Cu")
	)
	(gr_line
		(start 161.113216 -407.954734)
		(end 160.817306 -408.250644)
		(stroke
			(width 0.06477)
			(type default)
		)
		(layer "F.Cu")
	)
	(gr_line
		(start 161.13506 -382.943862)
		(end 160.843722 -383.2352)
		(stroke
			(width 0.0508)
			(type default)
		)
		(layer "F.Cu")
	)
	(gr_line
		(start 161.145728 -383.520442)
		(end 161.145728 -383.402586)
		(stroke
			(width 0.0508)
			(type default)
		)
		(layer "F.Cu")
	)
	(gr_line
		(start 161.22904 -391.36447)
		(end 161.145728 -391.281158)
		(stroke
			(width 0.0508)
			(type default)
		)
		(layer "F.Cu")
	)
	(gr_line
		(start 161.237676 -149.988016)
		(end 161.571686 -150.322026)
		(stroke
			(width 0.06477)
			(type default)
		)
		(layer "F.Cu")
	)
	(gr_line
		(start 161.298382 -388.774432)
		(end 161.819082 -388.774432)
		(stroke
			(width 0.0635)
			(type default)
		)
		(layer "F.Cu")
	)
	(gr_line
		(start 161.298382 -385.31038)
		(end 161.819082 -385.31038)
		(stroke
			(width 0.0635)
			(type default)
		)
		(layer "F.Cu")
	)
	(gr_line
		(start 161.337244 -375.76633)
		(end 161.685478 -376.114564)
		(stroke
			(width 0.0508)
			(type default)
		)
		(layer "F.Cu")
	)
	(gr_line
		(start 161.35223 -383.13741)
		(end 161.445702 -383.230882)
		(stroke
			(width 0.0508)
			(type default)
		)
		(layer "F.Cu")
	)
	(gr_line
		(start 161.35223 -382.942592)
		(end 161.35223 -383.13741)
		(stroke
			(width 0.0508)
			(type default)
		)
		(layer "F.Cu")
	)
	(gr_line
		(start 161.362644 -373.96293)
		(end 161.633154 -374.23344)
		(stroke
			(width 0.06477)
			(type default)
		)
		(layer "F.Cu")
	)
	(gr_line
		(start 161.435796 -412.299658)
		(end 161.706306 -412.570168)
		(stroke
			(width 0.06477)
			(type default)
		)
		(layer "F.Cu")
	)
	(gr_line
		(start 161.435796 -407.954734)
		(end 161.731706 -408.250644)
		(stroke
			(width 0.06477)
			(type default)
		)
		(layer "F.Cu")
	)
	(gr_line
		(start 161.445702 -383.230882)
		(end 161.445702 -383.92227)
		(stroke
			(width 0.0508)
			(type default)
		)
		(layer "F.Cu")
	)
	(gr_line
		(start 161.44621 -391.36574)
		(end 161.44621 -390.761982)
		(stroke
			(width 0.0508)
			(type default)
		)
		(layer "F.Cu")
	)
	(gr_line
		(start 161.44621 -390.761982)
		(end 161.445702 -390.761474)
		(stroke
			(width 0.0508)
			(type default)
		)
		(layer "F.Cu")
	)
	(gr_line
		(start 161.584132 -20.668488)
		(end 161.584132 -19.906488)
		(stroke
			(width 0.06477)
			(type default)
		)
		(layer "F.Cu")
	)
	(gr_line
		(start 161.584132 -19.520408)
		(end 161.584132 -18.758408)
		(stroke
			(width 0.06477)
			(type default)
		)
		(layer "F.Cu")
	)
	(gr_line
		(start 161.584132 -15.719552)
		(end 161.584132 -14.957552)
		(stroke
			(width 0.06477)
			(type default)
		)
		(layer "F.Cu")
	)
	(gr_line
		(start 161.633154 -374.93702)
		(end 161.337244 -375.23293)
		(stroke
			(width 0.06477)
			(type default)
		)
		(layer "F.Cu")
	)
	(gr_line
		(start 161.685478 -376.114564)
		(end 161.685478 -376.116596)
		(stroke
			(width 0.0508)
			(type default)
		)
		(layer "F.Cu")
	)
	(gr_line
		(start 161.698178 -389.467344)
		(end 162.218878 -389.467344)
		(stroke
			(width 0.0635)
			(type default)
		)
		(layer "F.Cu")
	)
	(gr_line
		(start 161.698178 -386.003292)
		(end 162.218878 -386.003292)
		(stroke
			(width 0.0635)
			(type default)
		)
		(layer "F.Cu")
	)
	(gr_line
		(start 161.702242 -392.977116)
		(end 161.678874 -392.977116)
		(stroke
			(width 0.0508)
			(type default)
		)
		(layer "F.Cu")
	)
	(gr_line
		(start 161.704528 -170.901106)
		(end 161.434018 -170.630596)
		(stroke
			(width 0.06477)
			(type default)
		)
		(layer "F.Cu")
	)
	(gr_line
		(start 161.706306 -404.46452)
		(end 161.435796 -404.73503)
		(stroke
			(width 0.06477)
			(type default)
		)
		(layer "F.Cu")
	)
	(gr_line
		(start 161.731706 -408.784044)
		(end 161.435796 -409.079954)
		(stroke
			(width 0.06477)
			(type default)
		)
		(layer "F.Cu")
	)
	(gr_line
		(start 161.844228 -393.292838)
		(end 161.844228 -393.119102)
		(stroke
			(width 0.0508)
			(type default)
		)
		(layer "F.Cu")
	)
	(gr_line
		(start 161.844228 -393.119102)
		(end 161.702242 -392.977116)
		(stroke
			(width 0.0508)
			(type default)
		)
		(layer "F.Cu")
	)
	(gr_line
		(start 161.844228 -392.595862)
		(end 161.680144 -392.759946)
		(stroke
			(width 0.0508)
			(type default)
		)
		(layer "F.Cu")
	)
	(gr_line
		(start 161.844228 -392.429238)
		(end 161.844228 -392.595862)
		(stroke
			(width 0.0508)
			(type default)
		)
		(layer "F.Cu")
	)
	(gr_line
		(start 161.88436 -22.852634)
		(end 161.75228 -22.10181)
		(stroke
			(width 0.06477)
			(type default)
		)
		(layer "F.Cu")
	)
	(gr_line
		(start 161.894266 -150.322026)
		(end 162.228276 -149.988016)
		(stroke
			(width 0.06477)
			(type default)
		)
		(layer "F.Cu")
	)
	(gr_line
		(start 161.907982 -20.667218)
		(end 162.094672 -20.480528)
		(stroke
			(width 0.06477)
			(type default)
		)
		(layer "F.Cu")
	)
	(gr_line
		(start 161.907982 -19.519138)
		(end 162.094672 -19.332448)
		(stroke
			(width 0.06477)
			(type default)
		)
		(layer "F.Cu")
	)
	(gr_line
		(start 161.907982 -15.718282)
		(end 162.094672 -15.531592)
		(stroke
			(width 0.06477)
			(type default)
		)
		(layer "F.Cu")
	)
	(gr_line
		(start 161.911538 -361.12577)
		(end 161.911284 -361.12577)
		(stroke
			(width 0.06477)
			(type default)
		)
		(layer "F.Cu")
	)
	(gr_line
		(start 161.955734 -374.93702)
		(end 162.251644 -375.23293)
		(stroke
			(width 0.06477)
			(type default)
		)
		(layer "F.Cu")
	)
	(gr_line
		(start 162.027108 -170.901106)
		(end 162.297618 -170.630596)
		(stroke
			(width 0.06477)
			(type default)
		)
		(layer "F.Cu")
	)
	(gr_line
		(start 162.043618 -383.50571)
		(end 162.134804 -383.596896)
		(stroke
			(width 0.0508)
			(type default)
		)
		(layer "F.Cu")
	)
	(gr_line
		(start 162.043618 -383.2352)
		(end 162.043618 -383.50571)
		(stroke
			(width 0.0508)
			(type default)
		)
		(layer "F.Cu")
	)
	(gr_line
		(start 162.070034 -22.045676)
		(end 162.06978 -22.04593)
		(stroke
			(width 0.06477)
			(type default)
		)
		(layer "F.Cu")
	)
	(gr_line
		(start 162.08375 -23.983442)
		(end 161.951416 -23.232618)
		(stroke
			(width 0.06477)
			(type default)
		)
		(layer "F.Cu")
	)
	(gr_line
		(start 162.094672 -20.480528)
		(end 162.094672 -20.094448)
		(stroke
			(width 0.06477)
			(type default)
		)
		(layer "F.Cu")
	)
	(gr_line
		(start 162.094672 -20.094448)
		(end 161.907982 -19.907758)
		(stroke
			(width 0.06477)
			(type default)
		)
		(layer "F.Cu")
	)
	(gr_line
		(start 162.094672 -19.332448)
		(end 162.094672 -18.946368)
		(stroke
			(width 0.06477)
			(type default)
		)
		(layer "F.Cu")
	)
	(gr_line
		(start 162.094672 -18.946368)
		(end 161.907982 -18.759678)
		(stroke
			(width 0.06477)
			(type default)
		)
		(layer "F.Cu")
	)
	(gr_line
		(start 162.094672 -15.531592)
		(end 162.094672 -15.145512)
		(stroke
			(width 0.06477)
			(type default)
		)
		(layer "F.Cu")
	)
	(gr_line
		(start 162.094672 -15.145512)
		(end 161.907982 -14.958822)
		(stroke
			(width 0.06477)
			(type default)
		)
		(layer "F.Cu")
	)
	(gr_line
		(start 162.134804 -383.596896)
		(end 162.26917 -383.596896)
		(stroke
			(width 0.0508)
			(type default)
		)
		(layer "F.Cu")
	)
	(gr_line
		(start 162.20313 -22.795484)
		(end 162.354768 -22.578822)
		(stroke
			(width 0.06477)
			(type default)
		)
		(layer "F.Cu")
	)
	(gr_line
		(start 162.226244 -373.96293)
		(end 161.955734 -374.23344)
		(stroke
			(width 0.06477)
			(type default)
		)
		(layer "F.Cu")
	)
	(gr_line
		(start 162.251644 -375.76633)
		(end 161.902648 -376.115326)
		(stroke
			(width 0.0508)
			(type default)
		)
		(layer "F.Cu")
	)
	(gr_line
		(start 162.26917 -383.596896)
		(end 162.345624 -383.520442)
		(stroke
			(width 0.0508)
			(type default)
		)
		(layer "F.Cu")
	)
	(gr_line
		(start 162.287966 -22.19833)
		(end 162.071558 -22.0472)
		(stroke
			(width 0.06477)
			(type default)
		)
		(layer "F.Cu")
	)
	(gr_line
		(start 162.334956 -382.943862)
		(end 162.043618 -383.2352)
		(stroke
			(width 0.0508)
			(type default)
		)
		(layer "F.Cu")
	)
	(gr_line
		(start 162.345624 -383.520442)
		(end 162.345624 -383.402586)
		(stroke
			(width 0.0508)
			(type default)
		)
		(layer "F.Cu")
	)
	(gr_line
		(start 162.354768 -22.578822)
		(end 162.287966 -22.19833)
		(stroke
			(width 0.06477)
			(type default)
		)
		(layer "F.Cu")
	)
	(gr_line
		(start 162.40252 -23.926546)
		(end 162.554158 -23.70963)
		(stroke
			(width 0.06477)
			(type default)
		)
		(layer "F.Cu")
	)
	(gr_line
		(start 162.428936 -391.36447)
		(end 162.345624 -391.281158)
		(stroke
			(width 0.0508)
			(type default)
		)
		(layer "F.Cu")
	)
	(gr_line
		(start 162.487102 -23.329138)
		(end 162.270694 -23.177754)
		(stroke
			(width 0.06477)
			(type default)
		)
		(layer "F.Cu")
	)
	(gr_line
		(start 162.498278 -388.774432)
		(end 163.018978 -388.774432)
		(stroke
			(width 0.0635)
			(type default)
		)
		(layer "F.Cu")
	)
	(gr_line
		(start 162.498278 -385.31038)
		(end 163.018978 -385.31038)
		(stroke
			(width 0.0635)
			(type default)
		)
		(layer "F.Cu")
	)
	(gr_line
		(start 162.552126 -383.13741)
		(end 162.645598 -383.230882)
		(stroke
			(width 0.0508)
			(type default)
		)
		(layer "F.Cu")
	)
	(gr_line
		(start 162.552126 -382.942592)
		(end 162.552126 -383.13741)
		(stroke
			(width 0.0508)
			(type default)
		)
		(layer "F.Cu")
	)
	(gr_line
		(start 162.554158 -23.70963)
		(end 162.487102 -23.329138)
		(stroke
			(width 0.06477)
			(type default)
		)
		(layer "F.Cu")
	)
	(gr_line
		(start 162.645598 -383.230882)
		(end 162.645598 -383.92227)
		(stroke
			(width 0.0508)
			(type default)
		)
		(layer "F.Cu")
	)
	(gr_line
		(start 162.646106 -391.36574)
		(end 162.646106 -390.761982)
		(stroke
			(width 0.0508)
			(type default)
		)
		(layer "F.Cu")
	)
	(gr_line
		(start 162.646106 -390.761982)
		(end 162.645598 -390.761474)
		(stroke
			(width 0.0508)
			(type default)
		)
		(layer "F.Cu")
	)
	(gr_line
		(start 162.898328 -389.467344)
		(end 163.419028 -389.467344)
		(stroke
			(width 0.0635)
			(type default)
		)
		(layer "F.Cu")
	)
	(gr_line
		(start 162.898328 -386.003292)
		(end 163.419028 -386.003292)
		(stroke
			(width 0.0635)
			(type default)
		)
		(layer "F.Cu")
	)
	(gr_line
		(start 162.90544 -392.977116)
		(end 162.903408 -392.977116)
		(stroke
			(width 0.0508)
			(type default)
		)
		(layer "F.Cu")
	)
	(gr_line
		(start 162.94735 -25.555194)
		(end 162.51047 -24.930608)
		(stroke
			(width 0.06477)
			(type default)
		)
		(layer "F.Cu")
	)
	(gr_line
		(start 163.036758 -24.79167)
		(end 162.776408 -24.745696)
		(stroke
			(width 0.06477)
			(type default)
		)
		(layer "F.Cu")
	)
	(gr_line
		(start 163.039044 -373.30253)
		(end 163.388294 -373.65178)
		(stroke
			(width 0.0508)
			(type default)
		)
		(layer "F.Cu")
	)
	(gr_line
		(start 163.044124 -393.292838)
		(end 163.044124 -393.1158)
		(stroke
			(width 0.0508)
			(type default)
		)
		(layer "F.Cu")
	)
	(gr_line
		(start 163.044124 -393.1158)
		(end 162.90544 -392.977116)
		(stroke
			(width 0.0508)
			(type default)
		)
		(layer "F.Cu")
	)
	(gr_line
		(start 163.044124 -392.6205)
		(end 162.904678 -392.759946)
		(stroke
			(width 0.0508)
			(type default)
		)
		(layer "F.Cu")
	)
	(gr_line
		(start 163.044124 -392.429238)
		(end 163.044124 -392.6205)
		(stroke
			(width 0.0508)
			(type default)
		)
		(layer "F.Cu")
	)
	(gr_line
		(start 163.064444 -371.49913)
		(end 163.334954 -371.76964)
		(stroke
			(width 0.06477)
			(type default)
		)
		(layer "F.Cu")
	)
	(gr_line
		(start 163.212272 -25.368758)
		(end 163.258246 -25.108154)
		(stroke
			(width 0.06477)
			(type default)
		)
		(layer "F.Cu")
	)
	(gr_line
		(start 163.258246 -25.108154)
		(end 163.036758 -24.79167)
		(stroke
			(width 0.06477)
			(type default)
		)
		(layer "F.Cu")
	)
	(gr_line
		(start 163.334954 -372.47322)
		(end 163.039044 -372.76913)
		(stroke
			(width 0.06477)
			(type default)
		)
		(layer "F.Cu")
	)
	(gr_line
		(start 163.388294 -375.021856)
		(end 163.388294 -375.550176)
		(stroke
			(width 0.0508)
			(type default)
		)
		(layer "F.Cu")
	)
	(gr_line
		(start 163.605464 -375.023126)
		(end 163.715954 -375.133616)
		(stroke
			(width 0.0508)
			(type default)
		)
		(layer "F.Cu")
	)
	(gr_line
		(start 163.629086 -391.36447)
		(end 163.545774 -391.281158)
		(stroke
			(width 0.0508)
			(type default)
		)
		(layer "F.Cu")
	)
	(gr_line
		(start 163.629086 -383.319274)
		(end 163.545774 -383.402586)
		(stroke
			(width 0.0508)
			(type default)
		)
		(layer "F.Cu")
	)
	(gr_line
		(start 163.657534 -372.47322)
		(end 163.953444 -372.76913)
		(stroke
			(width 0.06477)
			(type default)
		)
		(layer "F.Cu")
	)
	(gr_line
		(start 163.698428 -388.774432)
		(end 164.219128 -388.774432)
		(stroke
			(width 0.0635)
			(type default)
		)
		(layer "F.Cu")
	)
	(gr_line
		(start 163.698428 -385.31038)
		(end 164.219128 -385.31038)
		(stroke
			(width 0.0635)
			(type default)
		)
		(layer "F.Cu")
	)
	(gr_line
		(start 163.715954 -375.438416)
		(end 163.605464 -375.548906)
		(stroke
			(width 0.0508)
			(type default)
		)
		(layer "F.Cu")
	)
	(gr_line
		(start 163.715954 -375.133616)
		(end 163.715954 -375.438416)
		(stroke
			(width 0.0508)
			(type default)
		)
		(layer "F.Cu")
	)
	(gr_line
		(start 163.728908 -146.167094)
		(end 163.394898 -145.833084)
		(stroke
			(width 0.06477)
			(type default)
		)
		(layer "F.Cu")
	)
	(gr_line
		(start 163.75253 -381.689102)
		(end 163.752276 -381.688848)
		(stroke
			(width 0.0508)
			(type default)
		)
		(layer "F.Cu")
	)
	(gr_line
		(start 163.846256 -391.36574)
		(end 163.846256 -390.761982)
		(stroke
			(width 0.0508)
			(type default)
		)
		(layer "F.Cu")
	)
	(gr_line
		(start 163.846256 -390.761982)
		(end 163.845748 -390.761474)
		(stroke
			(width 0.0508)
			(type default)
		)
		(layer "F.Cu")
	)
	(gr_line
		(start 163.846256 -383.921762)
		(end 163.845748 -383.92227)
		(stroke
			(width 0.0508)
			(type default)
		)
		(layer "F.Cu")
	)
	(gr_line
		(start 163.846256 -383.318004)
		(end 163.846256 -383.921762)
		(stroke
			(width 0.0508)
			(type default)
		)
		(layer "F.Cu")
	)
	(gr_line
		(start 163.928044 -371.49913)
		(end 163.657534 -371.76964)
		(stroke
			(width 0.06477)
			(type default)
		)
		(layer "F.Cu")
	)
	(gr_line
		(start 163.953444 -373.30253)
		(end 163.604194 -373.65178)
		(stroke
			(width 0.0508)
			(type default)
		)
		(layer "F.Cu")
	)
	(gr_line
		(start 164.087556 -392.977116)
		(end 164.076888 -392.977116)
		(stroke
			(width 0.0508)
			(type default)
		)
		(layer "F.Cu")
	)
	(gr_line
		(start 164.098224 -389.467344)
		(end 164.618924 -389.467344)
		(stroke
			(width 0.0635)
			(type default)
		)
		(layer "F.Cu")
	)
	(gr_line
		(start 164.098224 -386.003292)
		(end 164.618924 -386.003292)
		(stroke
			(width 0.0635)
			(type default)
		)
		(layer "F.Cu")
	)
	(gr_line
		(start 164.244274 -393.292838)
		(end 164.244274 -393.133834)
		(stroke
			(width 0.0508)
			(type default)
		)
		(layer "F.Cu")
	)
	(gr_line
		(start 164.244274 -393.133834)
		(end 164.087556 -392.977116)
		(stroke
			(width 0.0508)
			(type default)
		)
		(layer "F.Cu")
	)
	(gr_line
		(start 164.244274 -392.59383)
		(end 164.078158 -392.759946)
		(stroke
			(width 0.0508)
			(type default)
		)
		(layer "F.Cu")
	)
	(gr_line
		(start 164.244274 -392.429238)
		(end 164.244274 -392.59383)
		(stroke
			(width 0.0508)
			(type default)
		)
		(layer "F.Cu")
	)
	(gr_line
		(start 164.385498 -145.833084)
		(end 164.051488 -146.167094)
		(stroke
			(width 0.06477)
			(type default)
		)
		(layer "F.Cu")
	)
	(gr_line
		(start 164.508942 -150.274274)
		(end 164.174932 -149.940264)
		(stroke
			(width 0.06477)
			(type default)
		)
		(layer "F.Cu")
	)
	(gr_line
		(start 164.740844 -370.83873)
		(end 165.090094 -371.18798)
		(stroke
			(width 0.0508)
			(type default)
		)
		(layer "F.Cu")
	)
	(gr_line
		(start 164.766244 -369.03533)
		(end 165.036754 -369.30584)
		(stroke
			(width 0.06477)
			(type default)
		)
		(layer "F.Cu")
	)
	(gr_line
		(start 164.828982 -391.36447)
		(end 164.74567 -391.281158)
		(stroke
			(width 0.0508)
			(type default)
		)
		(layer "F.Cu")
	)
	(gr_line
		(start 164.828982 -383.319274)
		(end 164.74567 -383.402586)
		(stroke
			(width 0.0508)
			(type default)
		)
		(layer "F.Cu")
	)
	(gr_line
		(start 164.898324 -388.774432)
		(end 165.419024 -388.774432)
		(stroke
			(width 0.0635)
			(type default)
		)
		(layer "F.Cu")
	)
	(gr_line
		(start 164.898324 -385.31038)
		(end 165.419024 -385.31038)
		(stroke
			(width 0.0635)
			(type default)
		)
		(layer "F.Cu")
	)
	(gr_line
		(start 165.036754 -370.00942)
		(end 164.740844 -370.30533)
		(stroke
			(width 0.06477)
			(type default)
		)
		(layer "F.Cu")
	)
	(gr_line
		(start 165.046152 -391.36574)
		(end 165.046152 -390.761982)
		(stroke
			(width 0.0508)
			(type default)
		)
		(layer "F.Cu")
	)
	(gr_line
		(start 165.046152 -390.761982)
		(end 165.045644 -390.761474)
		(stroke
			(width 0.0508)
			(type default)
		)
		(layer "F.Cu")
	)
	(gr_line
		(start 165.046152 -383.921762)
		(end 165.045644 -383.92227)
		(stroke
			(width 0.0508)
			(type default)
		)
		(layer "F.Cu")
	)
	(gr_line
		(start 165.046152 -383.318004)
		(end 165.046152 -383.921762)
		(stroke
			(width 0.0508)
			(type default)
		)
		(layer "F.Cu")
	)
	(gr_line
		(start 165.165532 -149.940264)
		(end 164.831522 -150.274274)
		(stroke
			(width 0.06477)
			(type default)
		)
		(layer "F.Cu")
	)
	(gr_line
		(start 165.288976 -392.977116)
		(end 165.28288 -392.977116)
		(stroke
			(width 0.0508)
			(type default)
		)
		(layer "F.Cu")
	)
	(gr_line
		(start 165.298374 -389.467344)
		(end 165.819074 -389.467344)
		(stroke
			(width 0.0635)
			(type default)
		)
		(layer "F.Cu")
	)
	(gr_line
		(start 165.298374 -386.003292)
		(end 165.819074 -386.003292)
		(stroke
			(width 0.0635)
			(type default)
		)
		(layer "F.Cu")
	)
	(gr_line
		(start 165.359334 -370.00942)
		(end 165.655244 -370.30533)
		(stroke
			(width 0.06477)
			(type default)
		)
		(layer "F.Cu")
	)
	(gr_line
		(start 165.44417 -393.292838)
		(end 165.44417 -393.13231)
		(stroke
			(width 0.0508)
			(type default)
		)
		(layer "F.Cu")
	)
	(gr_line
		(start 165.44417 -393.13231)
		(end 165.288976 -392.977116)
		(stroke
			(width 0.0508)
			(type default)
		)
		(layer "F.Cu")
	)
	(gr_line
		(start 165.44417 -392.599926)
		(end 165.28415 -392.759946)
		(stroke
			(width 0.0508)
			(type default)
		)
		(layer "F.Cu")
	)
	(gr_line
		(start 165.44417 -392.429238)
		(end 165.44417 -392.599926)
		(stroke
			(width 0.0508)
			(type default)
		)
		(layer "F.Cu")
	)
	(gr_line
		(start 165.629844 -369.03533)
		(end 165.359334 -369.30584)
		(stroke
			(width 0.06477)
			(type default)
		)
		(layer "F.Cu")
	)
	(gr_line
		(start 165.655244 -370.83873)
		(end 165.305994 -371.18798)
		(stroke
			(width 0.0508)
			(type default)
		)
		(layer "F.Cu")
	)
	(gr_line
		(start 165.845236 -362.125768)
		(end 166.115746 -362.396278)
		(stroke
			(width 0.06477)
			(type default)
		)
		(layer "F.Cu")
	)
	(gr_line
		(start 165.845236 -361.803188)
		(end 166.115746 -361.532678)
		(stroke
			(width 0.06477)
			(type default)
		)
		(layer "F.Cu")
	)
	(gr_line
		(start 166.27348 -373.078502)
		(end 166.647368 -373.45239)
		(stroke
			(width 0.0508)
			(type default)
		)
		(layer "F.Cu")
	)
	(gr_line
		(start 166.427912 -372.925594)
		(end 166.584376 -372.925594)
		(stroke
			(width 0.0508)
			(type default)
		)
		(layer "F.Cu")
	)
	(gr_line
		(start 166.584376 -372.925594)
		(end 166.800276 -373.141494)
		(stroke
			(width 0.0508)
			(type default)
		)
		(layer "F.Cu")
	)
	(gr_line
		(start 166.800276 -373.141494)
		(end 166.800276 -373.297958)
		(stroke
			(width 0.0508)
			(type default)
		)
		(layer "F.Cu")
	)
	(gr_line
		(start 166.867078 -13.025628)
		(end 166.867078 -13.599922)
		(stroke
			(width 0.06477)
			(type default)
		)
		(layer "F.Cu")
	)
	(gr_line
		(start 167.005762 -12.886944)
		(end 166.867078 -13.025628)
		(stroke
			(width 0.06477)
			(type default)
		)
		(layer "F.Cu")
	)
	(gr_line
		(start 167.328342 -12.886944)
		(end 167.467026 -13.025628)
		(stroke
			(width 0.06477)
			(type default)
		)
		(layer "F.Cu")
	)
	(gr_line
		(start 167.467026 -13.025628)
		(end 167.467026 -13.599922)
		(stroke
			(width 0.06477)
			(type default)
		)
		(layer "F.Cu")
	)
	(gr_line
		(start 167.874442 -379.708918)
		(end 167.763952 -379.819408)
		(stroke
			(width 0.0508)
			(type default)
		)
		(layer "F.Cu")
	)
	(gr_line
		(start 168.144444 -370.83873)
		(end 168.493694 -371.18798)
		(stroke
			(width 0.0508)
			(type default)
		)
		(layer "F.Cu")
	)
	(gr_line
		(start 168.169844 -369.03533)
		(end 168.440354 -369.30584)
		(stroke
			(width 0.06477)
			(type default)
		)
		(layer "F.Cu")
	)
	(gr_line
		(start 168.179242 -379.708918)
		(end 167.874442 -379.708918)
		(stroke
			(width 0.0508)
			(type default)
		)
		(layer "F.Cu")
	)
	(gr_line
		(start 168.289732 -379.819408)
		(end 168.179242 -379.708918)
		(stroke
			(width 0.0508)
			(type default)
		)
		(layer "F.Cu")
	)
	(gr_line
		(start 168.291002 -380.036578)
		(end 167.762682 -380.036578)
		(stroke
			(width 0.0508)
			(type default)
		)
		(layer "F.Cu")
	)
	(gr_line
		(start 168.440354 -370.00942)
		(end 168.144444 -370.30533)
		(stroke
			(width 0.06477)
			(type default)
		)
		(layer "F.Cu")
	)
	(gr_line
		(start 168.709594 -371.527832)
		(end 168.709848 -371.527578)
		(stroke
			(width 0.0508)
			(type default)
		)
		(layer "F.Cu")
	)
	(gr_line
		(start 168.756838 -376.71883)
		(end 168.666922 -376.71883)
		(stroke
			(width 0.0508)
			(type default)
		)
		(layer "F.Cu")
	)
	(gr_line
		(start 168.762934 -370.00942)
		(end 169.058844 -370.30533)
		(stroke
			(width 0.06477)
			(type default)
		)
		(layer "F.Cu")
	)
	(gr_line
		(start 168.896538 -376.776742)
		(end 168.756838 -376.71883)
		(stroke
			(width 0.0508)
			(type default)
		)
		(layer "F.Cu")
	)
	(gr_line
		(start 169.033444 -369.03533)
		(end 168.762934 -369.30584)
		(stroke
			(width 0.06477)
			(type default)
		)
		(layer "F.Cu")
	)
	(gr_line
		(start 169.058844 -370.83873)
		(end 168.709594 -371.18798)
		(stroke
			(width 0.0508)
			(type default)
		)
		(layer "F.Cu")
	)
	(gr_line
		(start 169.102024 -380.385828)
		(end 168.752774 -380.036578)
		(stroke
			(width 0.0508)
			(type default)
		)
		(layer "F.Cu")
	)
	(gr_line
		(start 169.102024 -379.471428)
		(end 168.752774 -379.820678)
		(stroke
			(width 0.0508)
			(type default)
		)
		(layer "F.Cu")
	)
	(gr_line
		(start 169.102024 -376.982228)
		(end 168.896538 -376.776742)
		(stroke
			(width 0.0508)
			(type default)
		)
		(layer "F.Cu")
	)
	(gr_line
		(start 169.102024 -376.067828)
		(end 168.668192 -376.50166)
		(stroke
			(width 0.0508)
			(type default)
		)
		(layer "F.Cu")
	)
	(gr_line
		(start 169.424096 -372.904258)
		(end 169.797984 -373.278146)
		(stroke
			(width 0.0508)
			(type default)
		)
		(layer "F.Cu")
	)
	(gr_line
		(start 169.578274 -372.75135)
		(end 169.734992 -372.75135)
		(stroke
			(width 0.0508)
			(type default)
		)
		(layer "F.Cu")
	)
	(gr_line
		(start 169.734992 -372.75135)
		(end 169.950892 -372.96725)
		(stroke
			(width 0.0508)
			(type default)
		)
		(layer "F.Cu")
	)
	(gr_line
		(start 169.931334 -380.089918)
		(end 169.635424 -380.385828)
		(stroke
			(width 0.06477)
			(type default)
		)
		(layer "F.Cu")
	)
	(gr_line
		(start 169.931334 -379.767338)
		(end 169.635424 -379.471428)
		(stroke
			(width 0.06477)
			(type default)
		)
		(layer "F.Cu")
	)
	(gr_line
		(start 169.931334 -376.686318)
		(end 169.635424 -376.982228)
		(stroke
			(width 0.06477)
			(type default)
		)
		(layer "F.Cu")
	)
	(gr_line
		(start 169.931334 -376.363738)
		(end 169.635424 -376.067828)
		(stroke
			(width 0.06477)
			(type default)
		)
		(layer "F.Cu")
	)
	(gr_line
		(start 169.950892 -372.96725)
		(end 169.950892 -373.123968)
		(stroke
			(width 0.0508)
			(type default)
		)
		(layer "F.Cu")
	)
	(gr_line
		(start 170.46702 -13.599922)
		(end 170.46702 -13.016484)
		(stroke
			(width 0.06477)
			(type default)
		)
		(layer "F.Cu")
	)
	(gr_line
		(start 170.46702 -13.016484)
		(end 170.604434 -12.87907)
		(stroke
			(width 0.06477)
			(type default)
		)
		(layer "F.Cu")
	)
	(gr_line
		(start 170.605704 -11.056874)
		(end 170.605704 -11.055858)
		(stroke
			(width 0.06477)
			(type default)
		)
		(layer "F.Cu")
	)
	(gr_line
		(start 170.605704 -11.055858)
		(end 170.335702 -10.785856)
		(stroke
			(width 0.06477)
			(type default)
		)
		(layer "F.Cu")
	)
	(gr_line
		(start 170.905424 -380.360428)
		(end 170.634914 -380.089918)
		(stroke
			(width 0.06477)
			(type default)
		)
		(layer "F.Cu")
	)
	(gr_line
		(start 170.905424 -379.496828)
		(end 170.634914 -379.767338)
		(stroke
			(width 0.06477)
			(type default)
		)
		(layer "F.Cu")
	)
	(gr_line
		(start 170.905424 -376.956828)
		(end 170.634914 -376.686318)
		(stroke
			(width 0.06477)
			(type default)
		)
		(layer "F.Cu")
	)
	(gr_line
		(start 170.905424 -376.093228)
		(end 170.634914 -376.363738)
		(stroke
			(width 0.06477)
			(type default)
		)
		(layer "F.Cu")
	)
	(gr_line
		(start 170.928284 -12.925552)
		(end 171.066968 -13.064236)
		(stroke
			(width 0.06477)
			(type default)
		)
		(layer "F.Cu")
	)
	(gr_line
		(start 170.928284 -12.8778)
		(end 170.928284 -12.925552)
		(stroke
			(width 0.06477)
			(type default)
		)
		(layer "F.Cu")
	)
	(gr_line
		(start 171.066968 -13.064236)
		(end 171.066968 -13.599922)
		(stroke
			(width 0.06477)
			(type default)
		)
		(layer "F.Cu")
	)
	(gr_line
		(start 171.199302 -10.785856)
		(end 170.9293 -11.055858)
		(stroke
			(width 0.06477)
			(type default)
		)
		(layer "F.Cu")
	)
	(gr_line
		(start 175.854614 -369.868958)
		(end 175.584104 -369.598448)
		(stroke
			(width 0.06477)
			(type default)
		)
		(layer "F.Cu")
	)
	(gr_line
		(start 176.177194 -369.868958)
		(end 176.447704 -369.598448)
		(stroke
			(width 0.06477)
			(type default)
		)
		(layer "F.Cu")
	)
	(gr_line
		(start 177.108358 -55.299864)
		(end 177.786538 -55.299864)
		(stroke
			(width 0.06477)
			(type default)
		)
		(layer "F.Cu")
	)
	(gr_line
		(start 177.108358 -54.799992)
		(end 177.796698 -54.799992)
		(stroke
			(width 0.06477)
			(type default)
		)
		(layer "F.Cu")
	)
	(gr_line
		(start 177.108358 -52.29987)
		(end 177.786538 -52.29987)
		(stroke
			(width 0.06477)
			(type default)
		)
		(layer "F.Cu")
	)
	(gr_line
		(start 177.108358 -51.799998)
		(end 177.796698 -51.799998)
		(stroke
			(width 0.06477)
			(type default)
		)
		(layer "F.Cu")
	)
	(gr_line
		(start 177.108358 -49.299876)
		(end 177.786538 -49.299876)
		(stroke
			(width 0.06477)
			(type default)
		)
		(layer "F.Cu")
	)
	(gr_line
		(start 177.108358 -48.800004)
		(end 177.796698 -48.800004)
		(stroke
			(width 0.06477)
			(type default)
		)
		(layer "F.Cu")
	)
	(gr_line
		(start 177.108358 -46.299882)
		(end 177.786538 -46.299882)
		(stroke
			(width 0.06477)
			(type default)
		)
		(layer "F.Cu")
	)
	(gr_line
		(start 177.108358 -45.80001)
		(end 177.796698 -45.80001)
		(stroke
			(width 0.06477)
			(type default)
		)
		(layer "F.Cu")
	)
	(gr_line
		(start 177.786538 -55.299864)
		(end 177.875184 -55.211218)
		(stroke
			(width 0.06477)
			(type default)
		)
		(layer "F.Cu")
	)
	(gr_line
		(start 177.786538 -52.29987)
		(end 177.875184 -52.211224)
		(stroke
			(width 0.06477)
			(type default)
		)
		(layer "F.Cu")
	)
	(gr_line
		(start 177.786538 -49.299876)
		(end 177.875184 -49.21123)
		(stroke
			(width 0.06477)
			(type default)
		)
		(layer "F.Cu")
	)
	(gr_line
		(start 177.786538 -46.299882)
		(end 177.875184 -46.211236)
		(stroke
			(width 0.06477)
			(type default)
		)
		(layer "F.Cu")
	)
	(gr_line
		(start 177.786538 -43.299888)
		(end 177.108358 -43.299888)
		(stroke
			(width 0.06477)
			(type default)
		)
		(layer "F.Cu")
	)
	(gr_line
		(start 177.7873 -53.799994)
		(end 177.108358 -53.799994)
		(stroke
			(width 0.06477)
			(type default)
		)
		(layer "F.Cu")
	)
	(gr_line
		(start 177.7873 -50.8)
		(end 177.108358 -50.8)
		(stroke
			(width 0.06477)
			(type default)
		)
		(layer "F.Cu")
	)
	(gr_line
		(start 177.7873 -47.800006)
		(end 177.108358 -47.800006)
		(stroke
			(width 0.06477)
			(type default)
		)
		(layer "F.Cu")
	)
	(gr_line
		(start 177.7873 -44.800012)
		(end 177.108358 -44.800012)
		(stroke
			(width 0.06477)
			(type default)
		)
		(layer "F.Cu")
	)
	(gr_line
		(start 177.794666 -53.299868)
		(end 177.108358 -53.299868)
		(stroke
			(width 0.06477)
			(type default)
		)
		(layer "F.Cu")
	)
	(gr_line
		(start 177.794666 -50.299874)
		(end 177.108358 -50.299874)
		(stroke
			(width 0.06477)
			(type default)
		)
		(layer "F.Cu")
	)
	(gr_line
		(start 177.794666 -47.29988)
		(end 177.108358 -47.29988)
		(stroke
			(width 0.06477)
			(type default)
		)
		(layer "F.Cu")
	)
	(gr_line
		(start 177.794666 -44.299886)
		(end 177.108358 -44.299886)
		(stroke
			(width 0.06477)
			(type default)
		)
		(layer "F.Cu")
	)
	(gr_line
		(start 177.796698 -54.799992)
		(end 177.884074 -54.887368)
		(stroke
			(width 0.06477)
			(type default)
		)
		(layer "F.Cu")
	)
	(gr_line
		(start 177.796698 -51.799998)
		(end 177.884074 -51.887374)
		(stroke
			(width 0.06477)
			(type default)
		)
		(layer "F.Cu")
	)
	(gr_line
		(start 177.796698 -48.800004)
		(end 177.884074 -48.88738)
		(stroke
			(width 0.06477)
			(type default)
		)
		(layer "F.Cu")
	)
	(gr_line
		(start 177.796698 -45.80001)
		(end 177.884074 -45.887386)
		(stroke
			(width 0.06477)
			(type default)
		)
		(layer "F.Cu")
	)
	(gr_line
		(start 177.796698 -42.800016)
		(end 177.108358 -42.800016)
		(stroke
			(width 0.06477)
			(type default)
		)
		(layer "F.Cu")
	)
	(gr_line
		(start 177.875184 -55.211218)
		(end 177.885344 -55.211218)
		(stroke
			(width 0.06477)
			(type default)
		)
		(layer "F.Cu")
	)
	(gr_line
		(start 177.875184 -52.211224)
		(end 177.885344 -52.211224)
		(stroke
			(width 0.06477)
			(type default)
		)
		(layer "F.Cu")
	)
	(gr_line
		(start 177.875184 -49.21123)
		(end 177.885344 -49.21123)
		(stroke
			(width 0.06477)
			(type default)
		)
		(layer "F.Cu")
	)
	(gr_line
		(start 177.875184 -46.211236)
		(end 177.885344 -46.211236)
		(stroke
			(width 0.06477)
			(type default)
		)
		(layer "F.Cu")
	)
	(gr_line
		(start 177.875184 -43.211242)
		(end 177.786538 -43.299888)
		(stroke
			(width 0.06477)
			(type default)
		)
		(layer "F.Cu")
	)
	(gr_line
		(start 177.8762 -53.711094)
		(end 177.7873 -53.799994)
		(stroke
			(width 0.06477)
			(type default)
		)
		(layer "F.Cu")
	)
	(gr_line
		(start 177.8762 -50.7111)
		(end 177.7873 -50.8)
		(stroke
			(width 0.06477)
			(type default)
		)
		(layer "F.Cu")
	)
	(gr_line
		(start 177.8762 -47.711106)
		(end 177.7873 -47.800006)
		(stroke
			(width 0.06477)
			(type default)
		)
		(layer "F.Cu")
	)
	(gr_line
		(start 177.8762 -44.711112)
		(end 177.7873 -44.800012)
		(stroke
			(width 0.06477)
			(type default)
		)
		(layer "F.Cu")
	)
	(gr_line
		(start 177.882042 -53.387244)
		(end 177.794666 -53.299868)
		(stroke
			(width 0.06477)
			(type default)
		)
		(layer "F.Cu")
	)
	(gr_line
		(start 177.882042 -50.38725)
		(end 177.794666 -50.299874)
		(stroke
			(width 0.06477)
			(type default)
		)
		(layer "F.Cu")
	)
	(gr_line
		(start 177.882042 -47.387256)
		(end 177.794666 -47.29988)
		(stroke
			(width 0.06477)
			(type default)
		)
		(layer "F.Cu")
	)
	(gr_line
		(start 177.882042 -44.387262)
		(end 177.794666 -44.299886)
		(stroke
			(width 0.06477)
			(type default)
		)
		(layer "F.Cu")
	)
	(gr_line
		(start 177.883312 -53.711094)
		(end 177.8762 -53.711094)
		(stroke
			(width 0.06477)
			(type default)
		)
		(layer "F.Cu")
	)
	(gr_line
		(start 177.883312 -50.7111)
		(end 177.8762 -50.7111)
		(stroke
			(width 0.06477)
			(type default)
		)
		(layer "F.Cu")
	)
	(gr_line
		(start 177.883312 -47.711106)
		(end 177.8762 -47.711106)
		(stroke
			(width 0.06477)
			(type default)
		)
		(layer "F.Cu")
	)
	(gr_line
		(start 177.883312 -44.711112)
		(end 177.8762 -44.711112)
		(stroke
			(width 0.06477)
			(type default)
		)
		(layer "F.Cu")
	)
	(gr_line
		(start 177.884074 -42.887392)
		(end 177.796698 -42.800016)
		(stroke
			(width 0.06477)
			(type default)
		)
		(layer "F.Cu")
	)
	(gr_line
		(start 177.885344 -43.211242)
		(end 177.875184 -43.211242)
		(stroke
			(width 0.06477)
			(type default)
		)
		(layer "F.Cu")
	)
	(gr_line
		(start 178.741324 -55.211218)
		(end 179.011834 -55.481728)
		(stroke
			(width 0.06477)
			(type default)
		)
		(layer "F.Cu")
	)
	(gr_line
		(start 178.741324 -54.888638)
		(end 179.011834 -54.618128)
		(stroke
			(width 0.06477)
			(type default)
		)
		(layer "F.Cu")
	)
	(gr_line
		(start 178.741324 -52.211224)
		(end 179.011834 -52.481734)
		(stroke
			(width 0.06477)
			(type default)
		)
		(layer "F.Cu")
	)
	(gr_line
		(start 178.741324 -51.888644)
		(end 179.011834 -51.618134)
		(stroke
			(width 0.06477)
			(type default)
		)
		(layer "F.Cu")
	)
	(gr_line
		(start 178.741324 -49.21123)
		(end 179.011834 -49.48174)
		(stroke
			(width 0.06477)
			(type default)
		)
		(layer "F.Cu")
	)
	(gr_line
		(start 178.741324 -48.88865)
		(end 179.011834 -48.61814)
		(stroke
			(width 0.06477)
			(type default)
		)
		(layer "F.Cu")
	)
	(gr_line
		(start 178.741324 -46.211236)
		(end 179.011834 -46.481746)
		(stroke
			(width 0.06477)
			(type default)
		)
		(layer "F.Cu")
	)
	(gr_line
		(start 178.741324 -45.888656)
		(end 179.011834 -45.618146)
		(stroke
			(width 0.06477)
			(type default)
		)
		(layer "F.Cu")
	)
	(gr_line
		(start 179.011834 -43.481752)
		(end 178.741324 -43.211242)
		(stroke
			(width 0.06477)
			(type default)
		)
		(layer "F.Cu")
	)
	(gr_line
		(start 179.011834 -42.618152)
		(end 178.741324 -42.888662)
		(stroke
			(width 0.06477)
			(type default)
		)
		(layer "F.Cu")
	)
	(gr_line
		(start 179.967382 -44.711112)
		(end 179.964334 -44.711112)
		(stroke
			(width 0.06477)
			(type default)
		)
		(layer "F.Cu")
	)
	(gr_line
		(start 179.992528 -53.711094)
		(end 179.939188 -53.711094)
		(stroke
			(width 0.06477)
			(type default)
		)
		(layer "F.Cu")
	)
	(gr_line
		(start 179.99837 -50.7111)
		(end 179.939188 -50.7111)
		(stroke
			(width 0.06477)
			(type default)
		)
		(layer "F.Cu")
	)
	(gr_line
		(start 180.01234 -47.388526)
		(end 179.919376 -47.388526)
		(stroke
			(width 0.06477)
			(type default)
		)
		(layer "F.Cu")
	)
	(gr_line
		(start 180.261768 -53.980334)
		(end 179.992528 -53.711094)
		(stroke
			(width 0.06477)
			(type default)
		)
		(layer "F.Cu")
	)
	(gr_line
		(start 180.261768 -53.065934)
		(end 179.940458 -53.387244)
		(stroke
			(width 0.06477)
			(type default)
		)
		(layer "F.Cu")
	)
	(gr_line
		(start 180.261768 -50.974498)
		(end 179.99837 -50.7111)
		(stroke
			(width 0.06477)
			(type default)
		)
		(layer "F.Cu")
	)
	(gr_line
		(start 180.261768 -50.06594)
		(end 179.940458 -50.38725)
		(stroke
			(width 0.06477)
			(type default)
		)
		(layer "F.Cu")
	)
	(gr_line
		(start 180.261768 -50.060098)
		(end 180.261768 -50.06594)
		(stroke
			(width 0.06477)
			(type default)
		)
		(layer "F.Cu")
	)
	(gr_line
		(start 180.261768 -48.053498)
		(end 179.920646 -47.712376)
		(stroke
			(width 0.06477)
			(type default)
		)
		(layer "F.Cu")
	)
	(gr_line
		(start 180.261768 -47.139098)
		(end 180.01234 -47.388526)
		(stroke
			(width 0.06477)
			(type default)
		)
		(layer "F.Cu")
	)
	(gr_line
		(start 180.261768 -45.005498)
		(end 179.967382 -44.711112)
		(stroke
			(width 0.06477)
			(type default)
		)
		(layer "F.Cu")
	)
	(gr_line
		(start 180.261768 -44.091098)
		(end 179.965604 -44.387262)
		(stroke
			(width 0.06477)
			(type default)
		)
		(layer "F.Cu")
	)
	(gr_line
		(start 181.084982 -53.355748)
		(end 180.795168 -53.065934)
		(stroke
			(width 0.06477)
			(type default)
		)
		(layer "F.Cu")
	)
	(gr_line
		(start 181.084982 -50.349912)
		(end 180.795168 -50.060098)
		(stroke
			(width 0.06477)
			(type default)
		)
		(layer "F.Cu")
	)
	(gr_line
		(start 181.084982 -47.428912)
		(end 180.795168 -47.139098)
		(stroke
			(width 0.06477)
			(type default)
		)
		(layer "F.Cu")
	)
	(gr_line
		(start 181.084982 -44.380912)
		(end 180.795168 -44.091098)
		(stroke
			(width 0.06477)
			(type default)
		)
		(layer "F.Cu")
	)
	(gr_line
		(start 181.095904 -53.679598)
		(end 180.795168 -53.980334)
		(stroke
			(width 0.06477)
			(type default)
		)
		(layer "F.Cu")
	)
	(gr_line
		(start 181.095904 -50.673762)
		(end 180.795168 -50.974498)
		(stroke
			(width 0.06477)
			(type default)
		)
		(layer "F.Cu")
	)
	(gr_line
		(start 181.095904 -47.752762)
		(end 180.795168 -48.053498)
		(stroke
			(width 0.06477)
			(type default)
		)
		(layer "F.Cu")
	)
	(gr_line
		(start 181.095904 -44.704762)
		(end 180.795168 -45.005498)
		(stroke
			(width 0.06477)
			(type default)
		)
		(layer "F.Cu")
	)
	(gr_line
		(start 181.097174 -53.355748)
		(end 181.084982 -53.355748)
		(stroke
			(width 0.06477)
			(type default)
		)
		(layer "F.Cu")
	)
	(gr_line
		(start 181.097174 -50.349912)
		(end 181.084982 -50.349912)
		(stroke
			(width 0.06477)
			(type default)
		)
		(layer "F.Cu")
	)
	(gr_line
		(start 181.097174 -47.428912)
		(end 181.084982 -47.428912)
		(stroke
			(width 0.06477)
			(type default)
		)
		(layer "F.Cu")
	)
	(gr_line
		(start 181.097174 -44.380912)
		(end 181.084982 -44.380912)
		(stroke
			(width 0.06477)
			(type default)
		)
		(layer "F.Cu")
	)
	(gr_line
		(start 181.777132 -53.355748)
		(end 181.76494 -53.355748)
		(stroke
			(width 0.06477)
			(type default)
		)
		(layer "F.Cu")
	)
	(gr_line
		(start 181.777132 -50.349912)
		(end 181.76494 -50.349912)
		(stroke
			(width 0.06477)
			(type default)
		)
		(layer "F.Cu")
	)
	(gr_line
		(start 181.777132 -47.428912)
		(end 181.76494 -47.428912)
		(stroke
			(width 0.06477)
			(type default)
		)
		(layer "F.Cu")
	)
	(gr_line
		(start 181.777132 -44.380912)
		(end 181.76494 -44.380912)
		(stroke
			(width 0.06477)
			(type default)
		)
		(layer "F.Cu")
	)
	(gr_line
		(start 182.041546 -53.954934)
		(end 181.76621 -53.679598)
		(stroke
			(width 0.06477)
			(type default)
		)
		(layer "F.Cu")
	)
	(gr_line
		(start 182.041546 -53.091334)
		(end 181.777132 -53.355748)
		(stroke
			(width 0.06477)
			(type default)
		)
		(layer "F.Cu")
	)
	(gr_line
		(start 182.041546 -50.949098)
		(end 181.76621 -50.673762)
		(stroke
			(width 0.06477)
			(type default)
		)
		(layer "F.Cu")
	)
	(gr_line
		(start 182.041546 -50.085498)
		(end 181.777132 -50.349912)
		(stroke
			(width 0.06477)
			(type default)
		)
		(layer "F.Cu")
	)
	(gr_line
		(start 182.041546 -48.028098)
		(end 181.76621 -47.752762)
		(stroke
			(width 0.06477)
			(type default)
		)
		(layer "F.Cu")
	)
	(gr_line
		(start 182.041546 -47.164498)
		(end 181.777132 -47.428912)
		(stroke
			(width 0.06477)
			(type default)
		)
		(layer "F.Cu")
	)
	(gr_line
		(start 182.041546 -44.980098)
		(end 181.76621 -44.704762)
		(stroke
			(width 0.06477)
			(type default)
		)
		(layer "F.Cu")
	)
	(gr_line
		(start 182.041546 -44.116498)
		(end 181.777132 -44.380912)
		(stroke
			(width 0.06477)
			(type default)
		)
		(layer "F.Cu")
	)
	(gr_line
		(start 185.037222 5.813298)
		(end 184.38495 5.631434)
		(stroke
			(width 0.06477)
			(type default)
		)
		(layer "F.Cu")
	)
	(gr_line
		(start 185.037222 6.31317)
		(end 184.38495 6.495034)
		(stroke
			(width 0.06477)
			(type default)
		)
		(layer "F.Cu")
	)
	(gr_line
		(start 207.090264 -352.15195)
		(end 206.831184 -352.41103)
		(stroke
			(width 0.06477)
			(type default)
		)
		(layer "F.Cu")
	)
	(gr_line
		(start 207.111854 -351.8281)
		(end 206.831184 -351.54743)
		(stroke
			(width 0.06477)
			(type default)
		)
		(layer "F.Cu")
	)
	(gr_line
		(start 207.113124 -352.15195)
		(end 207.090264 -352.15195)
		(stroke
			(width 0.06477)
			(type default)
		)
		(layer "F.Cu")
	)
	(gr_line
		(start 209.468466 -350.100138)
		(end 209.468466 -350.368108)
		(stroke
			(width 0.06477)
			(type default)
		)
		(layer "F.Cu")
	)
	(gr_line
		(start 209.743548 -349.825056)
		(end 209.468466 -350.100138)
		(stroke
			(width 0.06477)
			(type default)
		)
		(layer "F.Cu")
	)
	(gr_line
		(start 210.011518 -349.825056)
		(end 209.743548 -349.825056)
		(stroke
			(width 0.06477)
			(type default)
		)
		(layer "F.Cu")
	)
	(gr_line
		(start 210.097116 -348.971362)
		(end 210.286346 -349.160592)
		(stroke
			(width 0.06477)
			(type default)
		)
		(layer "F.Cu")
	)
	(gr_line
		(start 210.097116 -348.582742)
		(end 210.097116 -348.971362)
		(stroke
			(width 0.06477)
			(type default)
		)
		(layer "F.Cu")
	)
	(gr_line
		(start 210.097116 -347.813122)
		(end 210.286346 -348.002352)
		(stroke
			(width 0.06477)
			(type default)
		)
		(layer "F.Cu")
	)
	(gr_line
		(start 210.097116 -347.424502)
		(end 210.097116 -347.813122)
		(stroke
			(width 0.06477)
			(type default)
		)
		(layer "F.Cu")
	)
	(gr_line
		(start 210.097116 -346.654882)
		(end 210.286346 -346.844112)
		(stroke
			(width 0.06477)
			(type default)
		)
		(layer "F.Cu")
	)
	(gr_line
		(start 210.097116 -346.266262)
		(end 210.097116 -346.654882)
		(stroke
			(width 0.06477)
			(type default)
		)
		(layer "F.Cu")
	)
	(gr_line
		(start 210.241388 -350.053148)
		(end 209.696812 -350.597724)
		(stroke
			(width 0.06477)
			(type default)
		)
		(layer "F.Cu")
	)
	(gr_line
		(start 210.286346 -348.393512)
		(end 210.097116 -348.582742)
		(stroke
			(width 0.06477)
			(type default)
		)
		(layer "F.Cu")
	)
	(gr_line
		(start 210.286346 -347.235272)
		(end 210.097116 -347.424502)
		(stroke
			(width 0.06477)
			(type default)
		)
		(layer "F.Cu")
	)
	(gr_line
		(start 210.286346 -346.077032)
		(end 210.097116 -346.266262)
		(stroke
			(width 0.06477)
			(type default)
		)
		(layer "F.Cu")
	)
	(gr_line
		(start 210.535012 -179.485798)
		(end 210.810094 -179.76088)
		(stroke
			(width 0.06477)
			(type default)
		)
		(layer "F.Cu")
	)
	(gr_line
		(start 210.535012 -179.21732)
		(end 210.535012 -179.485798)
		(stroke
			(width 0.06477)
			(type default)
		)
		(layer "F.Cu")
	)
	(gr_line
		(start 210.610196 -348.392242)
		(end 210.610196 -349.161862)
		(stroke
			(width 0.06477)
			(type default)
		)
		(layer "F.Cu")
	)
	(gr_line
		(start 210.610196 -347.234002)
		(end 210.610196 -348.003622)
		(stroke
			(width 0.06477)
			(type default)
		)
		(layer "F.Cu")
	)
	(gr_line
		(start 210.610196 -346.075762)
		(end 210.610196 -346.845382)
		(stroke
			(width 0.06477)
			(type default)
		)
		(layer "F.Cu")
	)
	(gr_line
		(start 210.763612 -178.987704)
		(end 211.308188 -179.53228)
		(stroke
			(width 0.06477)
			(type default)
		)
		(layer "F.Cu")
	)
	(gr_line
		(start 210.810094 -179.76088)
		(end 211.078572 -179.76088)
		(stroke
			(width 0.06477)
			(type default)
		)
		(layer "F.Cu")
	)
	(gr_line
		(start 211.354162 -180.304694)
		(end 211.629244 -180.579776)
		(stroke
			(width 0.06477)
			(type default)
		)
		(layer "F.Cu")
	)
	(gr_line
		(start 211.354162 -180.03647)
		(end 211.354162 -180.304694)
		(stroke
			(width 0.06477)
			(type default)
		)
		(layer "F.Cu")
	)
	(gr_line
		(start 211.582762 -179.806854)
		(end 212.127338 -180.35143)
		(stroke
			(width 0.06477)
			(type default)
		)
		(layer "F.Cu")
	)
	(gr_line
		(start 211.629244 -180.579776)
		(end 211.897468 -180.579776)
		(stroke
			(width 0.06477)
			(type default)
		)
		(layer "F.Cu")
	)
	(gr_line
		(start 213.43112 0.25273)
		(end 213.297008 0.25273)
		(stroke
			(width 0.06477)
			(type default)
		)
		(layer "F.Cu")
	)
	(gr_line
		(start 213.432136 -0.247142)
		(end 213.297008 -0.247142)
		(stroke
			(width 0.06477)
			(type default)
		)
		(layer "F.Cu")
	)
	(gr_line
		(start 213.519766 -0.159512)
		(end 213.432136 -0.247142)
		(stroke
			(width 0.06477)
			(type default)
		)
		(layer "F.Cu")
	)
	(gr_line
		(start 213.519766 0.164084)
		(end 213.43112 0.25273)
		(stroke
			(width 0.06477)
			(type default)
		)
		(layer "F.Cu")
	)
	(gr_line
		(start 213.520782 0.164084)
		(end 213.519766 0.164084)
		(stroke
			(width 0.06477)
			(type default)
		)
		(layer "F.Cu")
	)
	(gr_line
		(start 213.94928 -5.509006)
		(end 213.297008 -5.327142)
		(stroke
			(width 0.06477)
			(type default)
		)
		(layer "F.Cu")
	)
	(gr_line
		(start 213.94928 -4.645406)
		(end 213.297008 -4.82727)
		(stroke
			(width 0.06477)
			(type default)
		)
		(layer "F.Cu")
	)
	(gr_line
		(start 213.94928 4.650994)
		(end 213.297008 4.832858)
		(stroke
			(width 0.06477)
			(type default)
		)
		(layer "F.Cu")
	)
	(gr_line
		(start 213.94928 5.514594)
		(end 213.297008 5.33273)
		(stroke
			(width 0.06477)
			(type default)
		)
		(layer "F.Cu")
	)
	(gr_line
		(start 214.799418 -205.459584)
		(end 214.988648 -205.648814)
		(stroke
			(width 0.06477)
			(type default)
		)
		(layer "F.Cu")
	)
	(gr_line
		(start 214.799418 -205.070964)
		(end 214.799418 -205.459584)
		(stroke
			(width 0.06477)
			(type default)
		)
		(layer "F.Cu")
	)
	(gr_line
		(start 214.799418 -204.301344)
		(end 214.988648 -204.490574)
		(stroke
			(width 0.06477)
			(type default)
		)
		(layer "F.Cu")
	)
	(gr_line
		(start 214.799418 -203.912724)
		(end 214.799418 -204.301344)
		(stroke
			(width 0.06477)
			(type default)
		)
		(layer "F.Cu")
	)
	(gr_line
		(start 214.988648 -204.881734)
		(end 214.799418 -205.070964)
		(stroke
			(width 0.06477)
			(type default)
		)
		(layer "F.Cu")
	)
	(gr_line
		(start 214.988648 -203.723494)
		(end 214.799418 -203.912724)
		(stroke
			(width 0.06477)
			(type default)
		)
		(layer "F.Cu")
	)
	(gr_line
		(start 215.312498 -204.880464)
		(end 215.312498 -205.650084)
		(stroke
			(width 0.06477)
			(type default)
		)
		(layer "F.Cu")
	)
	(gr_line
		(start 215.312498 -203.722224)
		(end 215.312498 -204.491844)
		(stroke
			(width 0.06477)
			(type default)
		)
		(layer "F.Cu")
	)
	(gr_line
		(start 218.679268 -84.037932)
		(end 218.949778 -83.767422)
		(stroke
			(width 0.06477)
			(type default)
		)
		(layer "F.Cu")
	)
	(gr_line
		(start 219.542868 -84.037932)
		(end 219.272358 -83.767422)
		(stroke
			(width 0.06477)
			(type default)
		)
		(layer "F.Cu")
	)
	(gr_line
		(start 229.903528 -64.08293)
		(end 229.903528 -64.85001)
		(stroke
			(width 0.06477)
			(type default)
		)
		(layer "F.Cu")
	)
	(gr_line
		(start 229.903528 -62.92977)
		(end 229.903528 -63.69685)
		(stroke
			(width 0.06477)
			(type default)
		)
		(layer "F.Cu")
	)
	(gr_line
		(start 229.903528 -60.395358)
		(end 229.903528 -61.162438)
		(stroke
			(width 0.06477)
			(type default)
		)
		(layer "F.Cu")
	)
	(gr_line
		(start 229.903528 -59.242198)
		(end 229.903528 -60.009278)
		(stroke
			(width 0.06477)
			(type default)
		)
		(layer "F.Cu")
	)
	(gr_line
		(start 230.227378 -64.0842)
		(end 230.416608 -64.27343)
		(stroke
			(width 0.06477)
			(type default)
		)
		(layer "F.Cu")
	)
	(gr_line
		(start 230.227378 -62.93104)
		(end 230.416608 -63.12027)
		(stroke
			(width 0.06477)
			(type default)
		)
		(layer "F.Cu")
	)
	(gr_line
		(start 230.227378 -60.396628)
		(end 230.416608 -60.585858)
		(stroke
			(width 0.06477)
			(type default)
		)
		(layer "F.Cu")
	)
	(gr_line
		(start 230.227378 -59.243468)
		(end 230.416608 -59.432698)
		(stroke
			(width 0.06477)
			(type default)
		)
		(layer "F.Cu")
	)
	(gr_line
		(start 230.416608 -64.65951)
		(end 230.227378 -64.84874)
		(stroke
			(width 0.06477)
			(type default)
		)
		(layer "F.Cu")
	)
	(gr_line
		(start 230.416608 -64.27343)
		(end 230.416608 -64.65951)
		(stroke
			(width 0.06477)
			(type default)
		)
		(layer "F.Cu")
	)
	(gr_line
		(start 230.416608 -63.50635)
		(end 230.227378 -63.69558)
		(stroke
			(width 0.06477)
			(type default)
		)
		(layer "F.Cu")
	)
	(gr_line
		(start 230.416608 -63.12027)
		(end 230.416608 -63.50635)
		(stroke
			(width 0.06477)
			(type default)
		)
		(layer "F.Cu")
	)
	(gr_line
		(start 230.416608 -60.971938)
		(end 230.227378 -61.161168)
		(stroke
			(width 0.06477)
			(type default)
		)
		(layer "F.Cu")
	)
	(gr_line
		(start 230.416608 -60.585858)
		(end 230.416608 -60.971938)
		(stroke
			(width 0.06477)
			(type default)
		)
		(layer "F.Cu")
	)
	(gr_line
		(start 230.416608 -59.818778)
		(end 230.227378 -60.008008)
		(stroke
			(width 0.06477)
			(type default)
		)
		(layer "F.Cu")
	)
	(gr_line
		(start 230.416608 -59.432698)
		(end 230.416608 -59.818778)
		(stroke
			(width 0.06477)
			(type default)
		)
		(layer "F.Cu")
	)
	(gr_line
		(start 231.360726 -52.30368)
		(end 231.357678 -52.30368)
		(stroke
			(width 0.06477)
			(type default)
		)
		(layer "F.Cu")
	)
	(gr_line
		(start 231.385618 -54.103778)
		(end 231.371902 -54.103778)
		(stroke
			(width 0.06477)
			(type default)
		)
		(layer "F.Cu")
	)
	(gr_line
		(start 231.394762 -58.0263)
		(end 231.388666 -58.0263)
		(stroke
			(width 0.06477)
			(type default)
		)
		(layer "F.Cu")
	)
	(gr_line
		(start 231.402382 -56.226202)
		(end 231.365806 -56.226202)
		(stroke
			(width 0.06477)
			(type default)
		)
		(layer "F.Cu")
	)
	(gr_line
		(start 231.496362 -52.764944)
		(end 231.358948 -52.62753)
		(stroke
			(width 0.06477)
			(type default)
		)
		(layer "F.Cu")
	)
	(gr_line
		(start 231.49941 -52.164996)
		(end 231.360726 -52.30368)
		(stroke
			(width 0.06477)
			(type default)
		)
		(layer "F.Cu")
	)
	(gr_line
		(start 231.50449 -55.764938)
		(end 231.367076 -55.902352)
		(stroke
			(width 0.06477)
			(type default)
		)
		(layer "F.Cu")
	)
	(gr_line
		(start 231.510586 -54.565042)
		(end 231.373172 -54.427628)
		(stroke
			(width 0.06477)
			(type default)
		)
		(layer "F.Cu")
	)
	(gr_line
		(start 231.524302 -53.965094)
		(end 231.385618 -54.103778)
		(stroke
			(width 0.06477)
			(type default)
		)
		(layer "F.Cu")
	)
	(gr_line
		(start 231.52735 -57.565036)
		(end 231.389936 -57.70245)
		(stroke
			(width 0.06477)
			(type default)
		)
		(layer "F.Cu")
	)
	(gr_line
		(start 231.533446 -58.164984)
		(end 231.394762 -58.0263)
		(stroke
			(width 0.06477)
			(type default)
		)
		(layer "F.Cu")
	)
	(gr_line
		(start 231.541066 -56.364886)
		(end 231.402382 -56.226202)
		(stroke
			(width 0.06477)
			(type default)
		)
		(layer "F.Cu")
	)
	(gr_line
		(start 232.000044 -58.164984)
		(end 231.533446 -58.164984)
		(stroke
			(width 0.06477)
			(type default)
		)
		(layer "F.Cu")
	)
	(gr_line
		(start 232.000044 -57.565036)
		(end 231.52735 -57.565036)
		(stroke
			(width 0.06477)
			(type default)
		)
		(layer "F.Cu")
	)
	(gr_line
		(start 232.000044 -56.364886)
		(end 231.541066 -56.364886)
		(stroke
			(width 0.06477)
			(type default)
		)
		(layer "F.Cu")
	)
	(gr_line
		(start 232.000044 -55.764938)
		(end 231.50449 -55.764938)
		(stroke
			(width 0.06477)
			(type default)
		)
		(layer "F.Cu")
	)
	(gr_line
		(start 232.000044 -54.565042)
		(end 231.510586 -54.565042)
		(stroke
			(width 0.06477)
			(type default)
		)
		(layer "F.Cu")
	)
	(gr_line
		(start 232.000044 -53.965094)
		(end 231.524302 -53.965094)
		(stroke
			(width 0.06477)
			(type default)
		)
		(layer "F.Cu")
	)
	(gr_line
		(start 232.000044 -52.764944)
		(end 231.496362 -52.764944)
		(stroke
			(width 0.06477)
			(type default)
		)
		(layer "F.Cu")
	)
	(gr_line
		(start 232.000044 -52.164996)
		(end 231.49941 -52.164996)
		(stroke
			(width 0.06477)
			(type default)
		)
		(layer "F.Cu")
	)
	(gr_line
		(start 235.23702 -116.764816)
		(end 235.23702 -116.764562)
		(stroke
			(width 0.06477)
			(type default)
		)
		(layer "F.Cu")
	)
	(gr_line
		(start 235.737908 2.118614)
		(end 235.737908 2.118868)
		(stroke
			(width 0.06477)
			(type default)
		)
		(layer "F.Cu")
	)
	(gr_line
		(start 237.046008 -52.164996)
		(end 236.599984 -52.164996)
		(stroke
			(width 0.06477)
			(type default)
		)
		(layer "F.Cu")
	)
	(gr_line
		(start 237.049056 -53.965094)
		(end 236.599984 -53.965094)
		(stroke
			(width 0.06477)
			(type default)
		)
		(layer "F.Cu")
	)
	(gr_line
		(start 237.057184 -55.764938)
		(end 236.599984 -55.764938)
		(stroke
			(width 0.06477)
			(type default)
		)
		(layer "F.Cu")
	)
	(gr_line
		(start 237.071408 -52.764944)
		(end 236.599984 -52.764944)
		(stroke
			(width 0.06477)
			(type default)
		)
		(layer "F.Cu")
	)
	(gr_line
		(start 237.073948 -54.565042)
		(end 236.599984 -54.565042)
		(stroke
			(width 0.06477)
			(type default)
		)
		(layer "F.Cu")
	)
	(gr_line
		(start 237.079536 -58.164984)
		(end 236.599984 -58.164984)
		(stroke
			(width 0.06477)
			(type default)
		)
		(layer "F.Cu")
	)
	(gr_line
		(start 237.082584 -57.565036)
		(end 236.599984 -57.565036)
		(stroke
			(width 0.06477)
			(type default)
		)
		(layer "F.Cu")
	)
	(gr_line
		(start 237.09376 -56.364886)
		(end 236.599984 -56.364886)
		(stroke
			(width 0.06477)
			(type default)
		)
		(layer "F.Cu")
	)
	(gr_line
		(start 237.115604 -50.964846)
		(end 236.599984 -50.964846)
		(stroke
			(width 0.06477)
			(type default)
		)
		(layer "F.Cu")
	)
	(gr_line
		(start 237.119668 -50.364898)
		(end 236.599984 -50.364898)
		(stroke
			(width 0.06477)
			(type default)
		)
		(layer "F.Cu")
	)
	(gr_line
		(start 237.184692 -52.30368)
		(end 237.046008 -52.164996)
		(stroke
			(width 0.06477)
			(type default)
		)
		(layer "F.Cu")
	)
	(gr_line
		(start 237.18774 -54.103778)
		(end 237.049056 -53.965094)
		(stroke
			(width 0.06477)
			(type default)
		)
		(layer "F.Cu")
	)
	(gr_line
		(start 237.195868 -55.903622)
		(end 237.057184 -55.764938)
		(stroke
			(width 0.06477)
			(type default)
		)
		(layer "F.Cu")
	)
	(gr_line
		(start 237.208822 -52.62753)
		(end 237.071408 -52.764944)
		(stroke
			(width 0.06477)
			(type default)
		)
		(layer "F.Cu")
	)
	(gr_line
		(start 237.210092 -52.30368)
		(end 237.184692 -52.30368)
		(stroke
			(width 0.06477)
			(type default)
		)
		(layer "F.Cu")
	)
	(gr_line
		(start 237.211362 -54.427628)
		(end 237.073948 -54.565042)
		(stroke
			(width 0.06477)
			(type default)
		)
		(layer "F.Cu")
	)
	(gr_line
		(start 237.212632 -54.103778)
		(end 237.18774 -54.103778)
		(stroke
			(width 0.06477)
			(type default)
		)
		(layer "F.Cu")
	)
	(gr_line
		(start 237.21822 -58.0263)
		(end 237.079536 -58.164984)
		(stroke
			(width 0.06477)
			(type default)
		)
		(layer "F.Cu")
	)
	(gr_line
		(start 237.219998 -57.70245)
		(end 237.082584 -57.565036)
		(stroke
			(width 0.06477)
			(type default)
		)
		(layer "F.Cu")
	)
	(gr_line
		(start 237.221268 -58.0263)
		(end 237.21822 -58.0263)
		(stroke
			(width 0.06477)
			(type default)
		)
		(layer "F.Cu")
	)
	(gr_line
		(start 237.231174 -56.227472)
		(end 237.09376 -56.364886)
		(stroke
			(width 0.06477)
			(type default)
		)
		(layer "F.Cu")
	)
	(gr_line
		(start 237.232444 -55.903622)
		(end 237.195868 -55.903622)
		(stroke
			(width 0.06477)
			(type default)
		)
		(layer "F.Cu")
	)
	(gr_line
		(start 237.254796 -50.825654)
		(end 237.115604 -50.964846)
		(stroke
			(width 0.06477)
			(type default)
		)
		(layer "F.Cu")
	)
	(gr_line
		(start 237.256574 -50.501804)
		(end 237.119668 -50.364898)
		(stroke
			(width 0.06477)
			(type default)
		)
		(layer "F.Cu")
	)
	(gr_line
		(start 237.257844 -50.825654)
		(end 237.254796 -50.825654)
		(stroke
			(width 0.06477)
			(type default)
		)
		(layer "F.Cu")
	)
	(gr_line
		(start 238.595154 -57.70372)
		(end 238.584994 -57.70372)
		(stroke
			(width 0.06477)
			(type default)
		)
		(layer "F.Cu")
	)
	(gr_line
		(start 238.595154 -52.30368)
		(end 238.584994 -52.30368)
		(stroke
			(width 0.06477)
			(type default)
		)
		(layer "F.Cu")
	)
	(gr_line
		(start 238.604044 -54.103778)
		(end 238.576104 -54.103778)
		(stroke
			(width 0.06477)
			(type default)
		)
		(layer "F.Cu")
	)
	(gr_line
		(start 238.885984 -58.32729)
		(end 238.586264 -58.02757)
		(stroke
			(width 0.06477)
			(type default)
		)
		(layer "F.Cu")
	)
	(gr_line
		(start 238.885984 -57.41289)
		(end 238.595154 -57.70372)
		(stroke
			(width 0.06477)
			(type default)
		)
		(layer "F.Cu")
	)
	(gr_line
		(start 238.885984 -54.736238)
		(end 238.577374 -54.427628)
		(stroke
			(width 0.06477)
			(type default)
		)
		(layer "F.Cu")
	)
	(gr_line
		(start 238.885984 -53.821838)
		(end 238.604044 -54.103778)
		(stroke
			(width 0.06477)
			(type default)
		)
		(layer "F.Cu")
	)
	(gr_line
		(start 238.885984 -52.92725)
		(end 238.586264 -52.62753)
		(stroke
			(width 0.06477)
			(type default)
		)
		(layer "F.Cu")
	)
	(gr_line
		(start 238.885984 -52.01285)
		(end 238.595154 -52.30368)
		(stroke
			(width 0.06477)
			(type default)
		)
		(layer "F.Cu")
	)
	(gr_line
		(start 239.248696 -50.85842)
		(end 239.059466 -50.66919)
		(stroke
			(width 0.06477)
			(type default)
		)
		(layer "F.Cu")
	)
	(gr_line
		(start 239.634776 -50.85842)
		(end 239.248696 -50.85842)
		(stroke
			(width 0.06477)
			(type default)
		)
		(layer "F.Cu")
	)
	(gr_line
		(start 239.715294 -58.03138)
		(end 239.419384 -58.32729)
		(stroke
			(width 0.06477)
			(type default)
		)
		(layer "F.Cu")
	)
	(gr_line
		(start 239.715294 -57.7088)
		(end 239.419384 -57.41289)
		(stroke
			(width 0.06477)
			(type default)
		)
		(layer "F.Cu")
	)
	(gr_line
		(start 239.715294 -54.440328)
		(end 239.419384 -54.736238)
		(stroke
			(width 0.06477)
			(type default)
		)
		(layer "F.Cu")
	)
	(gr_line
		(start 239.715294 -54.117748)
		(end 239.419384 -53.821838)
		(stroke
			(width 0.06477)
			(type default)
		)
		(layer "F.Cu")
	)
	(gr_line
		(start 239.715294 -52.63134)
		(end 239.419384 -52.92725)
		(stroke
			(width 0.06477)
			(type default)
		)
		(layer "F.Cu")
	)
	(gr_line
		(start 239.715294 -52.30876)
		(end 239.419384 -52.01285)
		(stroke
			(width 0.06477)
			(type default)
		)
		(layer "F.Cu")
	)
	(gr_line
		(start 239.824006 -50.66919)
		(end 239.634776 -50.85842)
		(stroke
			(width 0.06477)
			(type default)
		)
		(layer "F.Cu")
	)
	(gr_line
		(start 239.825276 -50.34534)
		(end 239.058196 -50.34534)
		(stroke
			(width 0.06477)
			(type default)
		)
		(layer "F.Cu")
	)
	(gr_line
		(start 240.296954 -55.903622)
		(end 240.286794 -55.903622)
		(stroke
			(width 0.06477)
			(type default)
		)
		(layer "F.Cu")
	)
	(gr_line
		(start 240.400078 -54.628288)
		(end 240.213388 -54.441598)
		(stroke
			(width 0.06477)
			(type default)
		)
		(layer "F.Cu")
	)
	(gr_line
		(start 240.587784 -56.527192)
		(end 240.288064 -56.227472)
		(stroke
			(width 0.06477)
			(type default)
		)
		(layer "F.Cu")
	)
	(gr_line
		(start 240.587784 -55.612792)
		(end 240.296954 -55.903622)
		(stroke
			(width 0.06477)
			(type default)
		)
		(layer "F.Cu")
	)
	(gr_line
		(start 240.786158 -54.628288)
		(end 240.400078 -54.628288)
		(stroke
			(width 0.06477)
			(type default)
		)
		(layer "F.Cu")
	)
	(gr_line
		(start 240.972848 -54.441598)
		(end 240.786158 -54.628288)
		(stroke
			(width 0.06477)
			(type default)
		)
		(layer "F.Cu")
	)
	(gr_line
		(start 240.974118 -54.117748)
		(end 240.212118 -54.117748)
		(stroke
			(width 0.06477)
			(type default)
		)
		(layer "F.Cu")
	)
	(gr_line
		(start 241.069876 -51.21021)
		(end 241.069876 -50.94224)
		(stroke
			(width 0.06477)
			(type default)
		)
		(layer "F.Cu")
	)
	(gr_line
		(start 241.34318 -51.483514)
		(end 241.069876 -51.21021)
		(stroke
			(width 0.06477)
			(type default)
		)
		(layer "F.Cu")
	)
	(gr_line
		(start 241.417094 -56.231282)
		(end 241.121184 -56.527192)
		(stroke
			(width 0.06477)
			(type default)
		)
		(layer "F.Cu")
	)
	(gr_line
		(start 241.417094 -55.908702)
		(end 241.121184 -55.612792)
		(stroke
			(width 0.06477)
			(type default)
		)
		(layer "F.Cu")
	)
	(gr_line
		(start 241.570002 -53.473604)
		(end 241.570002 -53.205634)
		(stroke
			(width 0.06477)
			(type default)
		)
		(layer "F.Cu")
	)
	(gr_line
		(start 241.61115 -51.483514)
		(end 241.34318 -51.483514)
		(stroke
			(width 0.06477)
			(type default)
		)
		(layer "F.Cu")
	)
	(gr_line
		(start 241.62004 -54.984396)
		(end 241.62004 -54.716426)
		(stroke
			(width 0.06477)
			(type default)
		)
		(layer "F.Cu")
	)
	(gr_line
		(start 241.779552 -56.963056)
		(end 241.880644 -56.718708)
		(stroke
			(width 0.06477)
			(type default)
		)
		(layer "F.Cu")
	)
	(gr_line
		(start 241.798348 -52.975764)
		(end 241.798348 -52.976018)
		(stroke
			(width 0.06477)
			(type default)
		)
		(layer "F.Cu")
	)
	(gr_line
		(start 241.840766 -51.255168)
		(end 241.297968 -50.712624)
		(stroke
			(width 0.06477)
			(type default)
		)
		(layer "F.Cu")
	)
	(gr_line
		(start 241.843306 -53.746908)
		(end 241.570002 -53.473604)
		(stroke
			(width 0.06477)
			(type default)
		)
		(layer "F.Cu")
	)
	(gr_line
		(start 241.88547 -52.025804)
		(end 241.88547 -51.757834)
		(stroke
			(width 0.06477)
			(type default)
		)
		(layer "F.Cu")
	)
	(gr_line
		(start 241.895122 -55.259478)
		(end 241.62004 -54.984396)
		(stroke
			(width 0.06477)
			(type default)
		)
		(layer "F.Cu")
	)
	(gr_line
		(start 241.927126 -57.319926)
		(end 241.779552 -56.963056)
		(stroke
			(width 0.06477)
			(type default)
		)
		(layer "F.Cu")
	)
	(gr_line
		(start 242.111276 -53.746908)
		(end 241.843306 -53.746908)
		(stroke
			(width 0.06477)
			(type default)
		)
		(layer "F.Cu")
	)
	(gr_line
		(start 242.158774 -52.299108)
		(end 241.88547 -52.025804)
		(stroke
			(width 0.06477)
			(type default)
		)
		(layer "F.Cu")
	)
	(gr_line
		(start 242.163092 -55.259478)
		(end 241.895122 -55.259478)
		(stroke
			(width 0.06477)
			(type default)
		)
		(layer "F.Cu")
	)
	(gr_line
		(start 242.171474 -57.420764)
		(end 241.927126 -57.319926)
		(stroke
			(width 0.06477)
			(type default)
		)
		(layer "F.Cu")
	)
	(gr_line
		(start 242.341146 -53.518816)
		(end 241.798348 -52.976018)
		(stroke
			(width 0.06477)
			(type default)
		)
		(layer "F.Cu")
	)
	(gr_line
		(start 242.385596 -54.288944)
		(end 242.385596 -54.021228)
		(stroke
			(width 0.06477)
			(type default)
		)
		(layer "F.Cu")
	)
	(gr_line
		(start 242.392962 -55.031132)
		(end 241.848132 -54.486556)
		(stroke
			(width 0.06477)
			(type default)
		)
		(layer "F.Cu")
	)
	(gr_line
		(start 242.426744 -52.299108)
		(end 242.158774 -52.299108)
		(stroke
			(width 0.06477)
			(type default)
		)
		(layer "F.Cu")
	)
	(gr_line
		(start 242.455954 -62.067948)
		(end 242.455954 -61.681868)
		(stroke
			(width 0.06477)
			(type default)
		)
		(layer "F.Cu")
	)
	(gr_line
		(start 242.455954 -61.681868)
		(end 242.645184 -61.492638)
		(stroke
			(width 0.06477)
			(type default)
		)
		(layer "F.Cu")
	)
	(gr_line
		(start 242.455954 -60.914788)
		(end 242.455954 -60.528708)
		(stroke
			(width 0.06477)
			(type default)
		)
		(layer "F.Cu")
	)
	(gr_line
		(start 242.455954 -60.528708)
		(end 242.645184 -60.339478)
		(stroke
			(width 0.06477)
			(type default)
		)
		(layer "F.Cu")
	)
	(gr_line
		(start 242.455954 -59.761628)
		(end 242.455954 -59.375548)
		(stroke
			(width 0.06477)
			(type default)
		)
		(layer "F.Cu")
	)
	(gr_line
		(start 242.455954 -59.375548)
		(end 242.645184 -59.186318)
		(stroke
			(width 0.06477)
			(type default)
		)
		(layer "F.Cu")
	)
	(gr_line
		(start 242.47094 -57.298082)
		(end 242.179348 -56.593994)
		(stroke
			(width 0.06477)
			(type default)
		)
		(layer "F.Cu")
	)
	(gr_line
		(start 242.645184 -62.257178)
		(end 242.455954 -62.067948)
		(stroke
			(width 0.06477)
			(type default)
		)
		(layer "F.Cu")
	)
	(gr_line
		(start 242.645184 -61.104018)
		(end 242.455954 -60.914788)
		(stroke
			(width 0.06477)
			(type default)
		)
		(layer "F.Cu")
	)
	(gr_line
		(start 242.645184 -59.950858)
		(end 242.455954 -59.761628)
		(stroke
			(width 0.06477)
			(type default)
		)
		(layer "F.Cu")
	)
	(gr_line
		(start 242.65636 -52.071016)
		(end 242.113816 -51.527964)
		(stroke
			(width 0.06477)
			(type default)
		)
		(layer "F.Cu")
	)
	(gr_line
		(start 242.6589 -54.562248)
		(end 242.385596 -54.288944)
		(stroke
			(width 0.06477)
			(type default)
		)
		(layer "F.Cu")
	)
	(gr_line
		(start 242.701064 -52.841398)
		(end 242.701064 -52.573428)
		(stroke
			(width 0.06477)
			(type default)
		)
		(layer "F.Cu")
	)
	(gr_line
		(start 242.897914 -57.004712)
		(end 242.999006 -56.760618)
		(stroke
			(width 0.06477)
			(type default)
		)
		(layer "F.Cu")
	)
	(gr_line
		(start 242.926616 -54.562248)
		(end 242.6589 -54.562248)
		(stroke
			(width 0.06477)
			(type default)
		)
		(layer "F.Cu")
	)
	(gr_line
		(start 242.969034 -62.258448)
		(end 242.969034 -61.491368)
		(stroke
			(width 0.06477)
			(type default)
		)
		(layer "F.Cu")
	)
	(gr_line
		(start 242.969034 -61.105288)
		(end 242.969034 -60.338208)
		(stroke
			(width 0.06477)
			(type default)
		)
		(layer "F.Cu")
	)
	(gr_line
		(start 242.969034 -59.952128)
		(end 242.969034 -59.185048)
		(stroke
			(width 0.06477)
			(type default)
		)
		(layer "F.Cu")
	)
	(gr_line
		(start 242.974368 -53.114702)
		(end 242.701064 -52.841398)
		(stroke
			(width 0.06477)
			(type default)
		)
		(layer "F.Cu")
	)
	(gr_line
		(start 243.045742 -57.361582)
		(end 242.897914 -57.004712)
		(stroke
			(width 0.06477)
			(type default)
		)
		(layer "F.Cu")
	)
	(gr_line
		(start 243.156232 -54.334156)
		(end 242.613688 -53.791612)
		(stroke
			(width 0.06477)
			(type default)
		)
		(layer "F.Cu")
	)
	(gr_line
		(start 243.242338 -53.114702)
		(end 242.974368 -53.114702)
		(stroke
			(width 0.06477)
			(type default)
		)
		(layer "F.Cu")
	)
	(gr_line
		(start 243.289836 -57.462928)
		(end 243.045742 -57.361582)
		(stroke
			(width 0.06477)
			(type default)
		)
		(layer "F.Cu")
	)
	(gr_line
		(start 243.29771 -56.63565)
		(end 243.297456 -56.635396)
		(stroke
			(width 0.06477)
			(type default)
		)
		(layer "F.Cu")
	)
	(gr_line
		(start 243.365274 -55.654702)
		(end 243.466366 -55.410354)
		(stroke
			(width 0.06477)
			(type default)
		)
		(layer "F.Cu")
	)
	(gr_line
		(start 243.44122 -59.238642)
		(end 243.44122 -58.852562)
		(stroke
			(width 0.06477)
			(type default)
		)
		(layer "F.Cu")
	)
	(gr_line
		(start 243.44122 -58.852562)
		(end 243.62791 -58.665872)
		(stroke
			(width 0.06477)
			(type default)
		)
		(layer "F.Cu")
	)
	(gr_line
		(start 243.472208 -52.88661)
		(end 242.929156 -52.343812)
		(stroke
			(width 0.06477)
			(type default)
		)
		(layer "F.Cu")
	)
	(gr_line
		(start 243.512848 -56.011572)
		(end 243.365274 -55.654702)
		(stroke
			(width 0.06477)
			(type default)
		)
		(layer "F.Cu")
	)
	(gr_line
		(start 243.589556 -57.339992)
		(end 243.29771 -56.63565)
		(stroke
			(width 0.06477)
			(type default)
		)
		(layer "F.Cu")
	)
	(gr_line
		(start 243.62791 -59.425332)
		(end 243.44122 -59.238642)
		(stroke
			(width 0.06477)
			(type default)
		)
		(layer "F.Cu")
	)
	(gr_line
		(start 243.757196 -56.112918)
		(end 243.512848 -56.011572)
		(stroke
			(width 0.06477)
			(type default)
		)
		(layer "F.Cu")
	)
	(gr_line
		(start 243.781326 2.134108)
		(end 243.781326 2.134362)
		(stroke
			(width 0.06477)
			(type default)
		)
		(layer "F.Cu")
	)
	(gr_line
		(start 243.804694 -56.71566)
		(end 243.905786 -56.471312)
		(stroke
			(width 0.06477)
			(type default)
		)
		(layer "F.Cu")
	)
	(gr_line
		(start 243.95176 -59.426602)
		(end 243.95176 -58.664602)
		(stroke
			(width 0.06477)
			(type default)
		)
		(layer "F.Cu")
	)
	(gr_line
		(start 243.952522 -57.07253)
		(end 243.804694 -56.71566)
		(stroke
			(width 0.06477)
			(type default)
		)
		(layer "F.Cu")
	)
	(gr_line
		(start 244.056916 -55.989982)
		(end 243.76507 -55.28564)
		(stroke
			(width 0.06477)
			(type default)
		)
		(layer "F.Cu")
	)
	(gr_line
		(start 244.196616 -57.173368)
		(end 243.952522 -57.07253)
		(stroke
			(width 0.06477)
			(type default)
		)
		(layer "F.Cu")
	)
	(gr_line
		(start 244.333268 -57.500266)
		(end 244.198394 -57.17413)
		(stroke
			(width 0.06477)
			(type default)
		)
		(layer "F.Cu")
	)
	(gr_line
		(start 244.496336 -57.05094)
		(end 244.204744 -56.346598)
		(stroke
			(width 0.06477)
			(type default)
		)
		(layer "F.Cu")
	)
	(gr_line
		(start 244.631464 -57.376822)
		(end 244.496336 -57.05094)
		(stroke
			(width 0.06477)
			(type default)
		)
		(layer "F.Cu")
	)
	(gr_line
		(start 245.025164 -156.111194)
		(end 245.115842 -156.873194)
		(stroke
			(width 0.06477)
			(type default)
		)
		(layer "F.Cu")
	)
	(gr_line
		(start 245.161308 -157.25648)
		(end 245.251986 -158.01848)
		(stroke
			(width 0.06477)
			(type default)
		)
		(layer "F.Cu")
	)
	(gr_line
		(start 245.297706 -158.401766)
		(end 245.388384 -159.163766)
		(stroke
			(width 0.06477)
			(type default)
		)
		(layer "F.Cu")
	)
	(gr_line
		(start 245.346728 -156.07411)
		(end 245.557294 -156.239718)
		(stroke
			(width 0.06477)
			(type default)
		)
		(layer "F.Cu")
	)
	(gr_line
		(start 245.434104 -159.547052)
		(end 245.524782 -160.309052)
		(stroke
			(width 0.06477)
			(type default)
		)
		(layer "F.Cu")
	)
	(gr_line
		(start 245.483126 -157.219396)
		(end 245.693692 -157.385004)
		(stroke
			(width 0.06477)
			(type default)
		)
		(layer "F.Cu")
	)
	(gr_line
		(start 245.557294 -156.239718)
		(end 245.603014 -156.623512)
		(stroke
			(width 0.06477)
			(type default)
		)
		(layer "F.Cu")
	)
	(gr_line
		(start 245.603014 -156.623512)
		(end 245.437152 -156.834078)
		(stroke
			(width 0.06477)
			(type default)
		)
		(layer "F.Cu")
	)
	(gr_line
		(start 245.619524 -158.364682)
		(end 245.83009 -158.53029)
		(stroke
			(width 0.06477)
			(type default)
		)
		(layer "F.Cu")
	)
	(gr_line
		(start 245.693692 -157.385004)
		(end 245.739412 -157.768798)
		(stroke
			(width 0.06477)
			(type default)
		)
		(layer "F.Cu")
	)
	(gr_line
		(start 245.739412 -157.768798)
		(end 245.57355 -157.979364)
		(stroke
			(width 0.06477)
			(type default)
		)
		(layer "F.Cu")
	)
	(gr_line
		(start 245.755668 -159.509968)
		(end 245.966488 -159.675576)
		(stroke
			(width 0.06477)
			(type default)
		)
		(layer "F.Cu")
	)
	(gr_line
		(start 245.83009 -158.53029)
		(end 245.87581 -158.914084)
		(stroke
			(width 0.06477)
			(type default)
		)
		(layer "F.Cu")
	)
	(gr_line
		(start 245.87581 -158.914084)
		(end 245.709948 -159.12465)
		(stroke
			(width 0.06477)
			(type default)
		)
		(layer "F.Cu")
	)
	(gr_line
		(start 245.966488 -159.675576)
		(end 246.012208 -160.059116)
		(stroke
			(width 0.06477)
			(type default)
		)
		(layer "F.Cu")
	)
	(gr_line
		(start 246.012208 -160.059116)
		(end 245.846346 -160.269936)
		(stroke
			(width 0.06477)
			(type default)
		)
		(layer "F.Cu")
	)
	(gr_line
		(start 246.103648 -156.19349)
		(end 246.194326 -156.95549)
		(stroke
			(width 0.06477)
			(type default)
		)
		(layer "F.Cu")
	)
	(gr_line
		(start 246.240046 -157.338776)
		(end 246.330724 -158.100776)
		(stroke
			(width 0.06477)
			(type default)
		)
		(layer "F.Cu")
	)
	(gr_line
		(start 246.37619 -158.484062)
		(end 246.467122 -159.246062)
		(stroke
			(width 0.06477)
			(type default)
		)
		(layer "F.Cu")
	)
	(gr_line
		(start 246.425212 -156.156406)
		(end 246.635778 -156.322014)
		(stroke
			(width 0.06477)
			(type default)
		)
		(layer "F.Cu")
	)
	(gr_line
		(start 246.512588 -159.629348)
		(end 246.603266 -160.391348)
		(stroke
			(width 0.06477)
			(type default)
		)
		(layer "F.Cu")
	)
	(gr_line
		(start 246.56161 -157.301692)
		(end 246.772176 -157.4673)
		(stroke
			(width 0.06477)
			(type default)
		)
		(layer "F.Cu")
	)
	(gr_line
		(start 246.635778 -156.322014)
		(end 246.681498 -156.705808)
		(stroke
			(width 0.06477)
			(type default)
		)
		(layer "F.Cu")
	)
	(gr_line
		(start 246.681498 -156.705808)
		(end 246.51589 -156.916374)
		(stroke
			(width 0.06477)
			(type default)
		)
		(layer "F.Cu")
	)
	(gr_line
		(start 246.698008 -158.446978)
		(end 246.908574 -158.612586)
		(stroke
			(width 0.06477)
			(type default)
		)
		(layer "F.Cu")
	)
	(gr_line
		(start 246.772176 -157.4673)
		(end 246.817896 -157.851094)
		(stroke
			(width 0.06477)
			(type default)
		)
		(layer "F.Cu")
	)
	(gr_line
		(start 246.817896 -157.851094)
		(end 246.652034 -158.06166)
		(stroke
			(width 0.06477)
			(type default)
		)
		(layer "F.Cu")
	)
	(gr_line
		(start 246.834406 -159.592264)
		(end 247.044972 -159.757872)
		(stroke
			(width 0.06477)
			(type default)
		)
		(layer "F.Cu")
	)
	(gr_line
		(start 246.908574 -158.612586)
		(end 246.954294 -158.99638)
		(stroke
			(width 0.06477)
			(type default)
		)
		(layer "F.Cu")
	)
	(gr_line
		(start 246.954294 -158.99638)
		(end 246.788432 -159.206946)
		(stroke
			(width 0.06477)
			(type default)
		)
		(layer "F.Cu")
	)
	(gr_line
		(start 247.044972 -159.757872)
		(end 247.090692 -160.141666)
		(stroke
			(width 0.06477)
			(type default)
		)
		(layer "F.Cu")
	)
	(gr_line
		(start 247.090692 -160.141666)
		(end 246.92483 -160.352232)
		(stroke
			(width 0.06477)
			(type default)
		)
		(layer "F.Cu")
	)
	(gr_line
		(start 247.803162 2.140712)
		(end 247.803162 2.140966)
		(stroke
			(width 0.06477)
			(type default)
		)
		(layer "F.Cu")
	)
	(gr_line
		(start 249.298968 -200.488042)
		(end 249.389138 -201.244708)
		(stroke
			(width 0.06477)
			(type default)
		)
		(layer "F.Cu")
	)
	(gr_line
		(start 249.443748 -201.70394)
		(end 249.533664 -202.46086)
		(stroke
			(width 0.06477)
			(type default)
		)
		(layer "F.Cu")
	)
	(gr_line
		(start 249.586242 -202.902312)
		(end 249.676412 -203.659232)
		(stroke
			(width 0.06477)
			(type default)
		)
		(layer "F.Cu")
	)
	(gr_line
		(start 249.619008 -200.449688)
		(end 249.619262 -200.449688)
		(stroke
			(width 0.06477)
			(type default)
		)
		(layer "F.Cu")
	)
	(gr_line
		(start 249.620786 -200.450958)
		(end 249.828304 -200.614026)
		(stroke
			(width 0.06477)
			(type default)
		)
		(layer "F.Cu")
	)
	(gr_line
		(start 249.765312 -201.666856)
		(end 249.973084 -201.830178)
		(stroke
			(width 0.06477)
			(type default)
		)
		(layer "F.Cu")
	)
	(gr_line
		(start 249.828304 -200.614026)
		(end 249.87377 -200.99782)
		(stroke
			(width 0.06477)
			(type default)
		)
		(layer "F.Cu")
	)
	(gr_line
		(start 249.87377 -200.99782)
		(end 249.710448 -201.205338)
		(stroke
			(width 0.06477)
			(type default)
		)
		(layer "F.Cu")
	)
	(gr_line
		(start 249.906536 -202.864212)
		(end 249.90679 -202.864212)
		(stroke
			(width 0.06477)
			(type default)
		)
		(layer "F.Cu")
	)
	(gr_line
		(start 249.90806 -202.865482)
		(end 250.115578 -203.028804)
		(stroke
			(width 0.06477)
			(type default)
		)
		(layer "F.Cu")
	)
	(gr_line
		(start 249.973084 -201.830178)
		(end 250.018804 -202.213718)
		(stroke
			(width 0.06477)
			(type default)
		)
		(layer "F.Cu")
	)
	(gr_line
		(start 250.018804 -202.213718)
		(end 249.855228 -202.42149)
		(stroke
			(width 0.06477)
			(type default)
		)
		(layer "F.Cu")
	)
	(gr_line
		(start 250.115578 -203.028804)
		(end 250.161298 -203.412344)
		(stroke
			(width 0.06477)
			(type default)
		)
		(layer "F.Cu")
	)
	(gr_line
		(start 250.161298 -203.412344)
		(end 249.997976 -203.620116)
		(stroke
			(width 0.06477)
			(type default)
		)
		(layer "F.Cu")
	)
	(gr_line
		(start 250.295664 -200.38187)
		(end 250.386342 -201.14387)
		(stroke
			(width 0.06477)
			(type default)
		)
		(layer "F.Cu")
	)
	(gr_line
		(start 250.431808 -201.527156)
		(end 250.52274 -202.288902)
		(stroke
			(width 0.06477)
			(type default)
		)
		(layer "F.Cu")
	)
	(gr_line
		(start 250.574048 -202.720956)
		(end 250.664726 -203.482956)
		(stroke
			(width 0.06477)
			(type default)
		)
		(layer "F.Cu")
	)
	(gr_line
		(start 250.615958 -200.34377)
		(end 250.616212 -200.34377)
		(stroke
			(width 0.06477)
			(type default)
		)
		(layer "F.Cu")
	)
	(gr_line
		(start 250.617228 -200.344786)
		(end 250.827794 -200.510394)
		(stroke
			(width 0.06477)
			(type default)
		)
		(layer "F.Cu")
	)
	(gr_line
		(start 250.753626 -201.490072)
		(end 250.964192 -201.65568)
		(stroke
			(width 0.06477)
			(type default)
		)
		(layer "F.Cu")
	)
	(gr_line
		(start 250.827794 -200.510394)
		(end 250.873514 -200.894188)
		(stroke
			(width 0.06477)
			(type default)
		)
		(layer "F.Cu")
	)
	(gr_line
		(start 250.873514 -200.894188)
		(end 250.707652 -201.104754)
		(stroke
			(width 0.06477)
			(type default)
		)
		(layer "F.Cu")
	)
	(gr_line
		(start 250.895866 -202.683872)
		(end 251.106432 -202.849734)
		(stroke
			(width 0.06477)
			(type default)
		)
		(layer "F.Cu")
	)
	(gr_line
		(start 250.964192 -201.65568)
		(end 251.009912 -202.03922)
		(stroke
			(width 0.06477)
			(type default)
		)
		(layer "F.Cu")
	)
	(gr_line
		(start 251.009912 -202.03922)
		(end 250.84405 -202.249786)
		(stroke
			(width 0.06477)
			(type default)
		)
		(layer "F.Cu")
	)
	(gr_line
		(start 251.106432 -202.849734)
		(end 251.152152 -203.233274)
		(stroke
			(width 0.06477)
			(type default)
		)
		(layer "F.Cu")
	)
	(gr_line
		(start 251.152152 -203.233274)
		(end 250.98629 -203.44384)
		(stroke
			(width 0.06477)
			(type default)
		)
		(layer "F.Cu")
	)
	(gr_line
		(start 251.358654 -209.066638)
		(end 251.6505 -209.770726)
		(stroke
			(width 0.06477)
			(type default)
		)
		(layer "F.Cu")
	)
	(gr_line
		(start 251.368052 -200.409556)
		(end 251.458984 -201.173842)
		(stroke
			(width 0.06477)
			(type default)
		)
		(layer "F.Cu")
	)
	(gr_line
		(start 251.50445 -201.557128)
		(end 251.595382 -202.319128)
		(stroke
			(width 0.06477)
			(type default)
		)
		(layer "F.Cu")
	)
	(gr_line
		(start 251.640848 -202.702414)
		(end 251.73178 -203.464668)
		(stroke
			(width 0.06477)
			(type default)
		)
		(layer "F.Cu")
	)
	(gr_line
		(start 251.658374 -208.943956)
		(end 251.902722 -209.044794)
		(stroke
			(width 0.06477)
			(type default)
		)
		(layer "F.Cu")
	)
	(gr_line
		(start 251.68987 -200.374758)
		(end 251.900436 -200.540366)
		(stroke
			(width 0.06477)
			(type default)
		)
		(layer "F.Cu")
	)
	(gr_line
		(start 251.798074 -210.127342)
		(end 252.091698 -210.836256)
		(stroke
			(width 0.06477)
			(type default)
		)
		(layer "F.Cu")
	)
	(gr_line
		(start 251.822458 2.136394)
		(end 251.822458 2.136648)
		(stroke
			(width 0.06477)
			(type default)
		)
		(layer "F.Cu")
	)
	(gr_line
		(start 251.826268 -201.520044)
		(end 252.036834 -201.685652)
		(stroke
			(width 0.06477)
			(type default)
		)
		(layer "F.Cu")
	)
	(gr_line
		(start 251.900436 -200.540366)
		(end 251.946156 -200.92416)
		(stroke
			(width 0.06477)
			(type default)
		)
		(layer "F.Cu")
	)
	(gr_line
		(start 251.902722 -209.044794)
		(end 252.050296 -209.401664)
		(stroke
			(width 0.06477)
			(type default)
		)
		(layer "F.Cu")
	)
	(gr_line
		(start 251.946156 -200.92416)
		(end 251.780294 -201.134726)
		(stroke
			(width 0.06477)
			(type default)
		)
		(layer "F.Cu")
	)
	(gr_line
		(start 251.962666 -202.66533)
		(end 252.173486 -202.831192)
		(stroke
			(width 0.06477)
			(type default)
		)
		(layer "F.Cu")
	)
	(gr_line
		(start 252.036834 -201.685652)
		(end 252.082554 -202.069446)
		(stroke
			(width 0.06477)
			(type default)
		)
		(layer "F.Cu")
	)
	(gr_line
		(start 252.050296 -209.401664)
		(end 251.949204 -209.646012)
		(stroke
			(width 0.06477)
			(type default)
		)
		(layer "F.Cu")
	)
	(gr_line
		(start 252.052074 -203.426568)
		(end 252.052328 -203.426314)
		(stroke
			(width 0.06477)
			(type default)
		)
		(layer "F.Cu")
	)
	(gr_line
		(start 252.082554 -202.069446)
		(end 251.916692 -202.280012)
		(stroke
			(width 0.06477)
			(type default)
		)
		(layer "F.Cu")
	)
	(gr_line
		(start 252.097794 -210.004406)
		(end 252.345444 -210.107022)
		(stroke
			(width 0.06477)
			(type default)
		)
		(layer "F.Cu")
	)
	(gr_line
		(start 252.173486 -202.831192)
		(end 252.219206 -203.214732)
		(stroke
			(width 0.06477)
			(type default)
		)
		(layer "F.Cu")
	)
	(gr_line
		(start 252.219206 -203.214732)
		(end 252.05309 -203.425298)
		(stroke
			(width 0.06477)
			(type default)
		)
		(layer "F.Cu")
	)
	(gr_line
		(start 252.345444 -210.107022)
		(end 252.493272 -210.463892)
		(stroke
			(width 0.06477)
			(type default)
		)
		(layer "F.Cu")
	)
	(gr_line
		(start 252.493272 -210.463892)
		(end 252.390656 -210.711542)
		(stroke
			(width 0.06477)
			(type default)
		)
		(layer "F.Cu")
	)
	(gr_line
		(start 252.509274 -200.389998)
		(end 252.600206 -201.154538)
		(stroke
			(width 0.06477)
			(type default)
		)
		(layer "F.Cu")
	)
	(gr_line
		(start 252.64618 -201.540364)
		(end 252.661928 -201.673206)
		(stroke
			(width 0.06477)
			(type default)
		)
		(layer "F.Cu")
	)
	(gr_line
		(start 252.662182 -201.67346)
		(end 252.661928 -201.673206)
		(stroke
			(width 0.06477)
			(type default)
		)
		(layer "F.Cu")
	)
	(gr_line
		(start 252.662182 -201.67346)
		(end 252.737112 -202.302364)
		(stroke
			(width 0.06477)
			(type default)
		)
		(layer "F.Cu")
	)
	(gr_line
		(start 252.782832 -202.68565)
		(end 252.87351 -203.447396)
		(stroke
			(width 0.06477)
			(type default)
		)
		(layer "F.Cu")
	)
	(gr_line
		(start 252.823726 -211.81187)
		(end 253.366524 -212.354668)
		(stroke
			(width 0.06477)
			(type default)
		)
		(layer "F.Cu")
	)
	(gr_line
		(start 252.830838 -200.352914)
		(end 253.041658 -200.518776)
		(stroke
			(width 0.06477)
			(type default)
		)
		(layer "F.Cu")
	)
	(gr_line
		(start 252.967744 -201.503026)
		(end 253.178564 -201.668888)
		(stroke
			(width 0.06477)
			(type default)
		)
		(layer "F.Cu")
	)
	(gr_line
		(start 253.041658 -200.518776)
		(end 253.087632 -200.904856)
		(stroke
			(width 0.06477)
			(type default)
		)
		(layer "F.Cu")
	)
	(gr_line
		(start 253.053342 -211.583524)
		(end 253.321566 -211.583524)
		(stroke
			(width 0.06477)
			(type default)
		)
		(layer "F.Cu")
	)
	(gr_line
		(start 253.087632 -200.904856)
		(end 252.92177 -201.115676)
		(stroke
			(width 0.06477)
			(type default)
		)
		(layer "F.Cu")
	)
	(gr_line
		(start 253.104396 -202.648566)
		(end 253.315216 -202.814174)
		(stroke
			(width 0.06477)
			(type default)
		)
		(layer "F.Cu")
	)
	(gr_line
		(start 253.178564 -201.668888)
		(end 253.224284 -202.052682)
		(stroke
			(width 0.06477)
			(type default)
		)
		(layer "F.Cu")
	)
	(gr_line
		(start 253.224284 -202.052682)
		(end 253.058676 -202.263248)
		(stroke
			(width 0.06477)
			(type default)
		)
		(layer "F.Cu")
	)
	(gr_line
		(start 253.315216 -202.814174)
		(end 253.360682 -203.197714)
		(stroke
			(width 0.06477)
			(type default)
		)
		(layer "F.Cu")
	)
	(gr_line
		(start 253.321566 -211.583524)
		(end 253.59487 -211.856828)
		(stroke
			(width 0.06477)
			(type default)
		)
		(layer "F.Cu")
	)
	(gr_line
		(start 253.360682 -203.197714)
		(end 253.19482 -203.40828)
		(stroke
			(width 0.06477)
			(type default)
		)
		(layer "F.Cu")
	)
	(gr_line
		(start 253.59487 -211.856828)
		(end 253.59487 -212.124798)
		(stroke
			(width 0.06477)
			(type default)
		)
		(layer "F.Cu")
	)
	(gr_line
		(start 253.63932 -212.627464)
		(end 254.182372 -213.170262)
		(stroke
			(width 0.06477)
			(type default)
		)
		(layer "F.Cu")
	)
	(gr_line
		(start 253.86919 -212.399118)
		(end 254.13716 -212.399118)
		(stroke
			(width 0.06477)
			(type default)
		)
		(layer "F.Cu")
	)
	(gr_line
		(start 254.13716 -212.399118)
		(end 254.410464 -212.672422)
		(stroke
			(width 0.06477)
			(type default)
		)
		(layer "F.Cu")
	)
	(gr_line
		(start 254.410464 -212.672422)
		(end 254.410464 -212.940392)
		(stroke
			(width 0.06477)
			(type default)
		)
		(layer "F.Cu")
	)
	(gr_line
		(start 255.61417 -213.170516)
		(end 255.699006 -213.170516)
		(stroke
			(width 0.06477)
			(type default)
		)
		(layer "F.Cu")
	)
	(gr_line
		(start 255.61544 -213.494366)
		(end 255.927098 -213.806024)
		(stroke
			(width 0.06477)
			(type default)
		)
		(layer "F.Cu")
	)
	(gr_line
		(start 255.620012 -207.587342)
		(end 255.693164 -207.587342)
		(stroke
			(width 0.06477)
			(type default)
		)
		(layer "F.Cu")
	)
	(gr_line
		(start 255.621282 -207.911192)
		(end 255.927098 -208.217008)
		(stroke
			(width 0.06477)
			(type default)
		)
		(layer "F.Cu")
	)
	(gr_line
		(start 255.633728 -210.395566)
		(end 255.679448 -210.395566)
		(stroke
			(width 0.06477)
			(type default)
		)
		(layer "F.Cu")
	)
	(gr_line
		(start 255.634998 -210.719416)
		(end 255.927098 -211.011516)
		(stroke
			(width 0.06477)
			(type default)
		)
		(layer "F.Cu")
	)
	(gr_line
		(start 255.639824 -204.829918)
		(end 255.673352 -204.829918)
		(stroke
			(width 0.06477)
			(type default)
		)
		(layer "F.Cu")
	)
	(gr_line
		(start 255.641094 -205.153768)
		(end 255.927098 -205.439772)
		(stroke
			(width 0.06477)
			(type default)
		)
		(layer "F.Cu")
	)
	(gr_line
		(start 255.671828 -194.041014)
		(end 255.641348 -194.041014)
		(stroke
			(width 0.06477)
			(type default)
		)
		(layer "F.Cu")
	)
	(gr_line
		(start 255.673352 -204.829918)
		(end 255.927098 -204.576172)
		(stroke
			(width 0.06477)
			(type default)
		)
		(layer "F.Cu")
	)
	(gr_line
		(start 255.679448 -210.395566)
		(end 255.927098 -210.147916)
		(stroke
			(width 0.06477)
			(type default)
		)
		(layer "F.Cu")
	)
	(gr_line
		(start 255.693164 -207.587342)
		(end 255.927098 -207.353408)
		(stroke
			(width 0.06477)
			(type default)
		)
		(layer "F.Cu")
	)
	(gr_line
		(start 255.699006 -213.170516)
		(end 255.927098 -212.942424)
		(stroke
			(width 0.06477)
			(type default)
		)
		(layer "F.Cu")
	)
	(gr_line
		(start 255.838198 2.108962)
		(end 255.838198 2.109216)
		(stroke
			(width 0.06477)
			(type default)
		)
		(layer "F.Cu")
	)
	(gr_line
		(start 255.927098 -202.662536)
		(end 256.20091 -202.388724)
		(stroke
			(width 0.06477)
			(type default)
		)
		(layer "F.Cu")
	)
	(gr_line
		(start 255.927098 -201.798936)
		(end 256.193036 -202.064874)
		(stroke
			(width 0.06477)
			(type default)
		)
		(layer "F.Cu")
	)
	(gr_line
		(start 255.927098 -199.868028)
		(end 256.197608 -199.597518)
		(stroke
			(width 0.06477)
			(type default)
		)
		(layer "F.Cu")
	)
	(gr_line
		(start 255.927098 -199.004428)
		(end 256.196338 -199.273668)
		(stroke
			(width 0.06477)
			(type default)
		)
		(layer "F.Cu")
	)
	(gr_line
		(start 255.927098 -197.07352)
		(end 256.200148 -196.80047)
		(stroke
			(width 0.06477)
			(type default)
		)
		(layer "F.Cu")
	)
	(gr_line
		(start 255.927098 -196.20992)
		(end 256.193798 -196.47662)
		(stroke
			(width 0.06477)
			(type default)
		)
		(layer "F.Cu")
	)
	(gr_line
		(start 255.927098 -194.296284)
		(end 255.671828 -194.041014)
		(stroke
			(width 0.06477)
			(type default)
		)
		(layer "F.Cu")
	)
	(gr_line
		(start 255.927098 -193.432684)
		(end 255.642618 -193.717164)
		(stroke
			(width 0.06477)
			(type default)
		)
		(layer "F.Cu")
	)
	(gr_line
		(start 256.193036 -202.064874)
		(end 256.20218 -202.064874)
		(stroke
			(width 0.06477)
			(type default)
		)
		(layer "F.Cu")
	)
	(gr_line
		(start 256.193798 -196.47662)
		(end 256.201418 -196.47662)
		(stroke
			(width 0.06477)
			(type default)
		)
		(layer "F.Cu")
	)
	(gr_line
		(start 256.196338 -199.273668)
		(end 256.198878 -199.273668)
		(stroke
			(width 0.06477)
			(type default)
		)
		(layer "F.Cu")
	)
	(gr_line
		(start 256.992374 -195.361814)
		(end 256.992374 -194.975734)
		(stroke
			(width 0.06477)
			(type default)
		)
		(layer "F.Cu")
	)
	(gr_line
		(start 256.992374 -194.975734)
		(end 257.181604 -194.786504)
		(stroke
			(width 0.06477)
			(type default)
		)
		(layer "F.Cu")
	)
	(gr_line
		(start 256.992374 -194.208654)
		(end 256.992374 -193.822574)
		(stroke
			(width 0.06477)
			(type default)
		)
		(layer "F.Cu")
	)
	(gr_line
		(start 256.992374 -193.822574)
		(end 257.181604 -193.633344)
		(stroke
			(width 0.06477)
			(type default)
		)
		(layer "F.Cu")
	)
	(gr_line
		(start 256.992374 -193.055494)
		(end 256.992374 -192.669414)
		(stroke
			(width 0.06477)
			(type default)
		)
		(layer "F.Cu")
	)
	(gr_line
		(start 256.992374 -192.669414)
		(end 257.181604 -192.480184)
		(stroke
			(width 0.06477)
			(type default)
		)
		(layer "F.Cu")
	)
	(gr_line
		(start 257.083306 -201.767694)
		(end 257.083306 -201.499724)
		(stroke
			(width 0.06477)
			(type default)
		)
		(layer "F.Cu")
	)
	(gr_line
		(start 257.083306 -201.499724)
		(end 257.35661 -201.22642)
		(stroke
			(width 0.06477)
			(type default)
		)
		(layer "F.Cu")
	)
	(gr_line
		(start 257.181604 -195.551044)
		(end 256.992374 -195.361814)
		(stroke
			(width 0.06477)
			(type default)
		)
		(layer "F.Cu")
	)
	(gr_line
		(start 257.181604 -194.397884)
		(end 256.992374 -194.208654)
		(stroke
			(width 0.06477)
			(type default)
		)
		(layer "F.Cu")
	)
	(gr_line
		(start 257.181604 -193.244724)
		(end 256.992374 -193.055494)
		(stroke
			(width 0.06477)
			(type default)
		)
		(layer "F.Cu")
	)
	(gr_line
		(start 257.311398 -201.997564)
		(end 257.854196 -201.454512)
		(stroke
			(width 0.06477)
			(type default)
		)
		(layer "F.Cu")
	)
	(gr_line
		(start 257.35661 -201.22642)
		(end 257.62458 -201.22642)
		(stroke
			(width 0.06477)
			(type default)
		)
		(layer "F.Cu")
	)
	(gr_line
		(start 257.505454 -195.552314)
		(end 257.505454 -194.785234)
		(stroke
			(width 0.06477)
			(type default)
		)
		(layer "F.Cu")
	)
	(gr_line
		(start 257.505454 -194.399154)
		(end 257.505454 -193.632074)
		(stroke
			(width 0.06477)
			(type default)
		)
		(layer "F.Cu")
	)
	(gr_line
		(start 257.505454 -193.245994)
		(end 257.505454 -192.478914)
		(stroke
			(width 0.06477)
			(type default)
		)
		(layer "F.Cu")
	)
	(gr_line
		(start 257.8989 -200.9521)
		(end 257.8989 -200.68413)
		(stroke
			(width 0.06477)
			(type default)
		)
		(layer "F.Cu")
	)
	(gr_line
		(start 257.8989 -200.68413)
		(end 258.172204 -200.410826)
		(stroke
			(width 0.06477)
			(type default)
		)
		(layer "F.Cu")
	)
	(gr_line
		(start 258.126992 -201.181716)
		(end 258.670044 -200.639172)
		(stroke
			(width 0.06477)
			(type default)
		)
		(layer "F.Cu")
	)
	(gr_line
		(start 258.172204 -200.410826)
		(end 258.440174 -200.410826)
		(stroke
			(width 0.06477)
			(type default)
		)
		(layer "F.Cu")
	)
	(gr_line
		(start 258.237228 -196.414136)
		(end 258.237228 -196.028056)
		(stroke
			(width 0.06477)
			(type default)
		)
		(layer "F.Cu")
	)
	(gr_line
		(start 258.237228 -196.028056)
		(end 258.426458 -195.838826)
		(stroke
			(width 0.06477)
			(type default)
		)
		(layer "F.Cu")
	)
	(gr_line
		(start 258.237228 -195.260976)
		(end 258.237228 -194.874896)
		(stroke
			(width 0.06477)
			(type default)
		)
		(layer "F.Cu")
	)
	(gr_line
		(start 258.237228 -194.874896)
		(end 258.426458 -194.685666)
		(stroke
			(width 0.06477)
			(type default)
		)
		(layer "F.Cu")
	)
	(gr_line
		(start 258.426458 -196.603366)
		(end 258.237228 -196.414136)
		(stroke
			(width 0.06477)
			(type default)
		)
		(layer "F.Cu")
	)
	(gr_line
		(start 258.426458 -195.450206)
		(end 258.237228 -195.260976)
		(stroke
			(width 0.06477)
			(type default)
		)
		(layer "F.Cu")
	)
	(gr_line
		(start 258.427474 -197.38721)
		(end 258.427728 -197.38721)
		(stroke
			(width 0.06477)
			(type default)
		)
		(layer "F.Cu")
	)
	(gr_line
		(start 258.750308 -196.604636)
		(end 258.750308 -195.837556)
		(stroke
			(width 0.06477)
			(type default)
		)
		(layer "F.Cu")
	)
	(gr_line
		(start 258.750308 -195.451476)
		(end 258.750308 -194.684396)
		(stroke
			(width 0.06477)
			(type default)
		)
		(layer "F.Cu")
	)
	(gr_line
		(start 259.211572 -198.873872)
		(end 259.211572 -198.487792)
		(stroke
			(width 0.06477)
			(type default)
		)
		(layer "F.Cu")
	)
	(gr_line
		(start 259.211572 -198.487792)
		(end 259.400802 -198.298562)
		(stroke
			(width 0.06477)
			(type default)
		)
		(layer "F.Cu")
	)
	(gr_line
		(start 259.400802 -199.063102)
		(end 259.211572 -198.873872)
		(stroke
			(width 0.06477)
			(type default)
		)
		(layer "F.Cu")
	)
	(gr_line
		(start 259.724652 -199.064372)
		(end 259.724652 -198.297292)
		(stroke
			(width 0.06477)
			(type default)
		)
		(layer "F.Cu")
	)
	(gr_line
		(start 260.067552 -189.058042)
		(end 260.201664 -188.825886)
		(stroke
			(width 0.06477)
			(type default)
		)
		(layer "F.Cu")
	)
	(gr_line
		(start 260.167374 -189.431422)
		(end 260.067552 -189.058042)
		(stroke
			(width 0.06477)
			(type default)
		)
		(layer "F.Cu")
	)
	(gr_line
		(start 260.202172 -188.82487)
		(end 260.202426 -188.824616)
		(stroke
			(width 0.06477)
			(type default)
		)
		(layer "F.Cu")
	)
	(gr_line
		(start 260.366002 -190.172086)
		(end 260.49986 -189.940184)
		(stroke
			(width 0.06477)
			(type default)
		)
		(layer "F.Cu")
	)
	(gr_line
		(start 260.39953 -189.56528)
		(end 260.167374 -189.431422)
		(stroke
			(width 0.06477)
			(type default)
		)
		(layer "F.Cu")
	)
	(gr_line
		(start 260.465824 -190.545466)
		(end 260.366002 -190.172086)
		(stroke
			(width 0.06477)
			(type default)
		)
		(layer "F.Cu")
	)
	(gr_line
		(start 260.475222 -194.492626)
		(end 260.816598 -194.15125)
		(stroke
			(width 0.06477)
			(type default)
		)
		(layer "F.Cu")
	)
	(gr_line
		(start 260.475222 -193.502026)
		(end 260.800596 -193.8274)
		(stroke
			(width 0.06477)
			(type default)
		)
		(layer "F.Cu")
	)
	(gr_line
		(start 260.664452 -191.28613)
		(end 260.79831 -191.054482)
		(stroke
			(width 0.06477)
			(type default)
		)
		(layer "F.Cu")
	)
	(gr_line
		(start 260.697726 -190.679324)
		(end 260.465824 -190.545466)
		(stroke
			(width 0.06477)
			(type default)
		)
		(layer "F.Cu")
	)
	(gr_line
		(start 260.712712 -189.482476)
		(end 260.514084 -188.74105)
		(stroke
			(width 0.06477)
			(type default)
		)
		(layer "F.Cu")
	)
	(gr_line
		(start 260.764274 -191.65951)
		(end 260.664452 -191.28613)
		(stroke
			(width 0.06477)
			(type default)
		)
		(layer "F.Cu")
	)
	(gr_line
		(start 260.800596 -193.8274)
		(end 260.817868 -193.8274)
		(stroke
			(width 0.06477)
			(type default)
		)
		(layer "F.Cu")
	)
	(gr_line
		(start 260.996176 -191.793114)
		(end 260.764274 -191.65951)
		(stroke
			(width 0.06477)
			(type default)
		)
		(layer "F.Cu")
	)
	(gr_line
		(start 261.010908 -190.59652)
		(end 260.812534 -189.855348)
		(stroke
			(width 0.06477)
			(type default)
		)
		(layer "F.Cu")
	)
	(gr_line
		(start 261.047484 -191.980058)
		(end 260.9977 -191.79413)
		(stroke
			(width 0.06477)
			(type default)
		)
		(layer "F.Cu")
	)
	(gr_line
		(start 261.25932 -191.524382)
		(end 261.11073 -190.969392)
		(stroke
			(width 0.06477)
			(type default)
		)
		(layer "F.Cu")
	)
	(gr_line
		(start 261.309358 -191.710818)
		(end 261.25932 -191.524382)
		(stroke
			(width 0.06477)
			(type default)
		)
		(layer "F.Cu")
	)
	(gr_line
		(start 261.359142 -191.896492)
		(end 261.309358 -191.710818)
		(stroke
			(width 0.06477)
			(type default)
		)
		(layer "F.Cu")
	)
	(gr_line
		(start 277.103332 -419.081712)
		(end 277.368254 -418.81679)
		(stroke
			(width 0.06477)
			(type default)
		)
		(layer "F.Cu")
	)
	(gr_line
		(start 277.103332 -418.218112)
		(end 277.37816 -418.49294)
		(stroke
			(width 0.06477)
			(type default)
		)
		(layer "F.Cu")
	)
	(gr_line
		(start 277.368254 -418.81679)
		(end 277.37943 -418.81679)
		(stroke
			(width 0.06477)
			(type default)
		)
		(layer "F.Cu")
	)
	(gr_line
		(start 283.172662 -418.661596)
		(end 283.174694 -418.661596)
		(stroke
			(width 0.06477)
			(type default)
		)
		(layer "F.Cu")
	)
	(gr_line
		(start 283.173932 -418.985446)
		(end 283.261562 -419.073076)
		(stroke
			(width 0.06477)
			(type default)
		)
		(layer "F.Cu")
	)
	(gr_line
		(start 283.174694 -418.661596)
		(end 283.26334 -418.57295)
		(stroke
			(width 0.06477)
			(type default)
		)
		(layer "F.Cu")
	)
	(gr_line
		(start 283.187648 -407.827226)
		(end 282.917138 -407.556716)
		(stroke
			(width 0.06477)
			(type default)
		)
		(layer "F.Cu")
	)
	(gr_line
		(start 283.261562 -419.073076)
		(end 283.506164 -419.073076)
		(stroke
			(width 0.06477)
			(type default)
		)
		(layer "F.Cu")
	)
	(gr_line
		(start 283.26334 -418.57295)
		(end 283.506164 -418.57295)
		(stroke
			(width 0.06477)
			(type default)
		)
		(layer "F.Cu")
	)
	(gr_line
		(start 283.505402 -373.686324)
		(end 283.234892 -373.956834)
		(stroke
			(width 0.06477)
			(type default)
		)
		(layer "F.Cu")
	)
	(gr_line
		(start 283.505402 -373.363744)
		(end 283.234892 -373.093234)
		(stroke
			(width 0.06477)
			(type default)
		)
		(layer "F.Cu")
	)
	(gr_line
		(start 283.510228 -407.827226)
		(end 283.780738 -407.556716)
		(stroke
			(width 0.06477)
			(type default)
		)
		(layer "F.Cu")
	)
	(gr_line
		(start 286.131 -420.940738)
		(end 286.219646 -421.029384)
		(stroke
			(width 0.06477)
			(type default)
		)
		(layer "F.Cu")
	)
	(gr_line
		(start 286.131 -420.697914)
		(end 286.131 -420.940738)
		(stroke
			(width 0.06477)
			(type default)
		)
		(layer "F.Cu")
	)
	(gr_line
		(start 286.131 -415.948114)
		(end 286.131 -415.703512)
		(stroke
			(width 0.06477)
			(type default)
		)
		(layer "F.Cu")
	)
	(gr_line
		(start 286.131 -415.703512)
		(end 286.21863 -415.615882)
		(stroke
			(width 0.06477)
			(type default)
		)
		(layer "F.Cu")
	)
	(gr_line
		(start 286.219646 -422.05656)
		(end 285.949136 -422.32707)
		(stroke
			(width 0.06477)
			(type default)
		)
		(layer "F.Cu")
	)
	(gr_line
		(start 286.219646 -421.029384)
		(end 286.219646 -421.031416)
		(stroke
			(width 0.06477)
			(type default)
		)
		(layer "F.Cu")
	)
	(gr_line
		(start 286.542226 -422.05656)
		(end 286.812736 -422.32707)
		(stroke
			(width 0.06477)
			(type default)
		)
		(layer "F.Cu")
	)
	(gr_line
		(start 286.54248 -415.616644)
		(end 286.54248 -415.614612)
		(stroke
			(width 0.06477)
			(type default)
		)
		(layer "F.Cu")
	)
	(gr_line
		(start 286.631126 -420.942516)
		(end 286.543496 -421.030146)
		(stroke
			(width 0.06477)
			(type default)
		)
		(layer "F.Cu")
	)
	(gr_line
		(start 286.631126 -420.697914)
		(end 286.631126 -420.942516)
		(stroke
			(width 0.06477)
			(type default)
		)
		(layer "F.Cu")
	)
	(gr_line
		(start 286.631126 -415.948114)
		(end 286.631126 -415.70529)
		(stroke
			(width 0.06477)
			(type default)
		)
		(layer "F.Cu")
	)
	(gr_line
		(start 286.631126 -415.70529)
		(end 286.54248 -415.616644)
		(stroke
			(width 0.06477)
			(type default)
		)
		(layer "F.Cu")
	)
	(gr_line
		(start 288.255964 -419.572948)
		(end 288.499042 -419.572948)
		(stroke
			(width 0.06477)
			(type default)
		)
		(layer "F.Cu")
	)
	(gr_line
		(start 288.255964 -419.073076)
		(end 288.500566 -419.073076)
		(stroke
			(width 0.06477)
			(type default)
		)
		(layer "F.Cu")
	)
	(gr_line
		(start 288.255964 -418.073078)
		(end 288.449766 -418.073078)
		(stroke
			(width 0.06477)
			(type default)
		)
		(layer "F.Cu")
	)
	(gr_line
		(start 288.255964 -417.572952)
		(end 288.451036 -417.572952)
		(stroke
			(width 0.06477)
			(type default)
		)
		(layer "F.Cu")
	)
	(gr_line
		(start 288.449766 -418.073078)
		(end 288.538666 -417.984178)
		(stroke
			(width 0.06477)
			(type default)
		)
		(layer "F.Cu")
	)
	(gr_line
		(start 288.451036 -417.572952)
		(end 288.538666 -417.660582)
		(stroke
			(width 0.06477)
			(type default)
		)
		(layer "F.Cu")
	)
	(gr_line
		(start 288.499042 -419.572948)
		(end 288.587434 -419.484556)
		(stroke
			(width 0.06477)
			(type default)
		)
		(layer "F.Cu")
	)
	(gr_line
		(start 288.500566 -419.073076)
		(end 288.588196 -419.160706)
		(stroke
			(width 0.06477)
			(type default)
		)
		(layer "F.Cu")
	)
	(gr_line
		(start 288.538666 -417.984178)
		(end 288.539682 -417.984178)
		(stroke
			(width 0.06477)
			(type default)
		)
		(layer "F.Cu")
	)
	(gr_line
		(start 288.587434 -419.484556)
		(end 288.589466 -419.484556)
		(stroke
			(width 0.06477)
			(type default)
		)
		(layer "F.Cu")
	)
	(gr_line
		(start 289.564826 -417.984178)
		(end 289.835336 -418.254688)
		(stroke
			(width 0.06477)
			(type default)
		)
		(layer "F.Cu")
	)
	(gr_line
		(start 289.564826 -417.661598)
		(end 289.835336 -417.391088)
		(stroke
			(width 0.06477)
			(type default)
		)
		(layer "F.Cu")
	)
	(gr_line
		(start 290.940744 -420.253922)
		(end 291.211254 -420.524432)
		(stroke
			(width 0.06477)
			(type default)
		)
		(layer "F.Cu")
	)
	(gr_line
		(start 290.940744 -419.931342)
		(end 291.211254 -419.660832)
		(stroke
			(width 0.06477)
			(type default)
		)
		(layer "F.Cu")
	)
	(gr_line
		(start 297.282616 -396.171674)
		(end 297.553126 -395.901164)
		(stroke
			(width 0.06477)
			(type default)
		)
		(layer "F.Cu")
	)
	(gr_line
		(start 297.282616 -395.308074)
		(end 297.553126 -395.578584)
		(stroke
			(width 0.06477)
			(type default)
		)
		(layer "F.Cu")
	)
	(gr_line
		(start 297.430444 -390.75106)
		(end 297.700954 -390.48055)
		(stroke
			(width 0.06477)
			(type default)
		)
		(layer "F.Cu")
	)
	(gr_line
		(start 297.430444 -389.88746)
		(end 297.700954 -390.15797)
		(stroke
			(width 0.06477)
			(type default)
		)
		(layer "F.Cu")
	)
	(gr_line
		(start 297.430444 -385.21386)
		(end 297.700954 -384.94335)
		(stroke
			(width 0.06477)
			(type default)
		)
		(layer "F.Cu")
	)
	(gr_line
		(start 297.430444 -384.35026)
		(end 297.700954 -384.62077)
		(stroke
			(width 0.06477)
			(type default)
		)
		(layer "F.Cu")
	)
	(gr_line
		(start 298.015914 -395.901164)
		(end 298.261024 -396.146274)
		(stroke
			(width 0.06477)
			(type default)
		)
		(layer "F.Cu")
	)
	(gr_line
		(start 298.015914 -395.578584)
		(end 298.261024 -395.333474)
		(stroke
			(width 0.06477)
			(type default)
		)
		(layer "F.Cu")
	)
	(gr_line
		(start 298.404534 -390.48055)
		(end 298.700444 -390.77646)
		(stroke
			(width 0.06477)
			(type default)
		)
		(layer "F.Cu")
	)
	(gr_line
		(start 298.404534 -390.15797)
		(end 298.700444 -389.86206)
		(stroke
			(width 0.06477)
			(type default)
		)
		(layer "F.Cu")
	)
	(gr_line
		(start 298.404534 -384.94335)
		(end 298.700444 -385.23926)
		(stroke
			(width 0.06477)
			(type default)
		)
		(layer "F.Cu")
	)
	(gr_line
		(start 298.404534 -384.62077)
		(end 298.700444 -384.32486)
		(stroke
			(width 0.06477)
			(type default)
		)
		(layer "F.Cu")
	)
	(gr_line
		(start 298.794424 -396.146274)
		(end 299.039026 -395.901672)
		(stroke
			(width 0.06477)
			(type default)
		)
		(layer "F.Cu")
	)
	(gr_line
		(start 298.794424 -395.333474)
		(end 299.038772 -395.577822)
		(stroke
			(width 0.06477)
			(type default)
		)
		(layer "F.Cu")
	)
	(gr_line
		(start 298.989496 -381.68453)
		(end 299.338746 -382.03378)
		(stroke
			(width 0.0508)
			(type default)
		)
		(layer "F.Cu")
	)
	(gr_line
		(start 299.014896 -379.88113)
		(end 299.285406 -380.15164)
		(stroke
			(width 0.06477)
			(type default)
		)
		(layer "F.Cu")
	)
	(gr_line
		(start 299.038772 -395.577822)
		(end 299.040296 -395.577822)
		(stroke
			(width 0.06477)
			(type default)
		)
		(layer "F.Cu")
	)
	(gr_line
		(start 299.233844 -390.77646)
		(end 299.583602 -390.426702)
		(stroke
			(width 0.0508)
			(type default)
		)
		(layer "F.Cu")
	)
	(gr_line
		(start 299.233844 -389.86206)
		(end 299.581316 -390.209532)
		(stroke
			(width 0.0508)
			(type default)
		)
		(layer "F.Cu")
	)
	(gr_line
		(start 299.233844 -385.23926)
		(end 299.603668 -384.869436)
		(stroke
			(width 0.0508)
			(type default)
		)
		(layer "F.Cu")
	)
	(gr_line
		(start 299.233844 -384.32486)
		(end 299.56125 -384.652266)
		(stroke
			(width 0.0508)
			(type default)
		)
		(layer "F.Cu")
	)
	(gr_line
		(start 299.285406 -380.85522)
		(end 298.989496 -381.15113)
		(stroke
			(width 0.06477)
			(type default)
		)
		(layer "F.Cu")
	)
	(gr_line
		(start 299.297852 -395.577822)
		(end 299.299376 -395.577822)
		(stroke
			(width 0.06477)
			(type default)
		)
		(layer "F.Cu")
	)
	(gr_line
		(start 299.299122 -395.901672)
		(end 299.543724 -396.146274)
		(stroke
			(width 0.06477)
			(type default)
		)
		(layer "F.Cu")
	)
	(gr_line
		(start 299.299376 -395.577822)
		(end 299.543724 -395.333474)
		(stroke
			(width 0.06477)
			(type default)
		)
		(layer "F.Cu")
	)
	(gr_line
		(start 299.466762 -0.158496)
		(end 299.461682 -0.158496)
		(stroke
			(width 0.06477)
			(type default)
		)
		(layer "F.Cu")
	)
	(gr_line
		(start 299.543724 -396.146274)
		(end 299.799756 -395.890242)
		(stroke
			(width 0.06477)
			(type default)
		)
		(layer "F.Cu")
	)
	(gr_line
		(start 299.543724 -395.333474)
		(end 299.776642 -395.566392)
		(stroke
			(width 0.06477)
			(type default)
		)
		(layer "F.Cu")
	)
	(gr_line
		(start 299.550328 0.25273)
		(end 299.462952 0.165354)
		(stroke
			(width 0.06477)
			(type default)
		)
		(layer "F.Cu")
	)
	(gr_line
		(start 299.555408 -0.247142)
		(end 299.466762 -0.158496)
		(stroke
			(width 0.06477)
			(type default)
		)
		(layer "F.Cu")
	)
	(gr_line
		(start 299.56125 -384.652266)
		(end 299.604938 -384.652266)
		(stroke
			(width 0.0508)
			(type default)
		)
		(layer "F.Cu")
	)
	(gr_line
		(start 299.581316 -390.209532)
		(end 299.584872 -390.209532)
		(stroke
			(width 0.0508)
			(type default)
		)
		(layer "F.Cu")
	)
	(gr_line
		(start 299.607986 -380.85522)
		(end 299.903896 -381.15113)
		(stroke
			(width 0.06477)
			(type default)
		)
		(layer "F.Cu")
	)
	(gr_line
		(start 299.712888 -5.327142)
		(end 299.060616 -5.509006)
		(stroke
			(width 0.06477)
			(type default)
		)
		(layer "F.Cu")
	)
	(gr_line
		(start 299.712888 -4.82727)
		(end 299.060616 -4.645406)
		(stroke
			(width 0.06477)
			(type default)
		)
		(layer "F.Cu")
	)
	(gr_line
		(start 299.712888 -0.247142)
		(end 299.555408 -0.247142)
		(stroke
			(width 0.06477)
			(type default)
		)
		(layer "F.Cu")
	)
	(gr_line
		(start 299.712888 0.25273)
		(end 299.550328 0.25273)
		(stroke
			(width 0.06477)
			(type default)
		)
		(layer "F.Cu")
	)
	(gr_line
		(start 299.712888 4.832858)
		(end 299.060616 4.650994)
		(stroke
			(width 0.06477)
			(type default)
		)
		(layer "F.Cu")
	)
	(gr_line
		(start 299.712888 5.33273)
		(end 299.060616 5.514594)
		(stroke
			(width 0.06477)
			(type default)
		)
		(layer "F.Cu")
	)
	(gr_line
		(start 299.776642 -395.566392)
		(end 299.801026 -395.566392)
		(stroke
			(width 0.06477)
			(type default)
		)
		(layer "F.Cu")
	)
	(gr_line
		(start 299.878496 -379.88113)
		(end 299.607986 -380.15164)
		(stroke
			(width 0.06477)
			(type default)
		)
		(layer "F.Cu")
	)
	(gr_line
		(start 299.889672 -390.209532)
		(end 300.417992 -390.209532)
		(stroke
			(width 0.0508)
			(type default)
		)
		(layer "F.Cu")
	)
	(gr_line
		(start 299.890942 -390.426702)
		(end 300.001432 -390.537192)
		(stroke
			(width 0.0508)
			(type default)
		)
		(layer "F.Cu")
	)
	(gr_line
		(start 299.903896 -381.68453)
		(end 299.554646 -382.03378)
		(stroke
			(width 0.0508)
			(type default)
		)
		(layer "F.Cu")
	)
	(gr_line
		(start 300.001432 -390.537192)
		(end 300.306232 -390.537192)
		(stroke
			(width 0.0508)
			(type default)
		)
		(layer "F.Cu")
	)
	(gr_line
		(start 300.306232 -390.537192)
		(end 300.416722 -390.426702)
		(stroke
			(width 0.0508)
			(type default)
		)
		(layer "F.Cu")
	)
	(gr_line
		(start 300.691296 -379.22073)
		(end 301.040546 -379.56998)
		(stroke
			(width 0.0508)
			(type default)
		)
		(layer "F.Cu")
	)
	(gr_line
		(start 300.716696 -377.41733)
		(end 300.987206 -377.68784)
		(stroke
			(width 0.06477)
			(type default)
		)
		(layer "F.Cu")
	)
	(gr_line
		(start 300.722792 -390.209532)
		(end 301.251112 -390.209532)
		(stroke
			(width 0.0508)
			(type default)
		)
		(layer "F.Cu")
	)
	(gr_line
		(start 300.724062 -390.426702)
		(end 300.834552 -390.537192)
		(stroke
			(width 0.0508)
			(type default)
		)
		(layer "F.Cu")
	)
	(gr_line
		(start 300.834552 -390.537192)
		(end 301.139352 -390.537192)
		(stroke
			(width 0.0508)
			(type default)
		)
		(layer "F.Cu")
	)
	(gr_line
		(start 300.987206 -378.39142)
		(end 300.691296 -378.68733)
		(stroke
			(width 0.06477)
			(type default)
		)
		(layer "F.Cu")
	)
	(gr_line
		(start 301.139352 -390.537192)
		(end 301.249842 -390.426702)
		(stroke
			(width 0.0508)
			(type default)
		)
		(layer "F.Cu")
	)
	(gr_line
		(start 301.309786 -378.39142)
		(end 301.605696 -378.68733)
		(stroke
			(width 0.06477)
			(type default)
		)
		(layer "F.Cu")
	)
	(gr_line
		(start 301.326296 -384.324098)
		(end 301.700184 -384.697986)
		(stroke
			(width 0.0508)
			(type default)
		)
		(layer "F.Cu")
	)
	(gr_line
		(start 301.335186 -386.91439)
		(end 301.451772 -387.19633)
		(stroke
			(width 0.0508)
			(type default)
		)
		(layer "F.Cu")
	)
	(gr_line
		(start 301.39513 -386.769864)
		(end 301.335186 -386.91439)
		(stroke
			(width 0.0508)
			(type default)
		)
		(layer "F.Cu")
	)
	(gr_line
		(start 301.451772 -387.19633)
		(end 301.596552 -387.25602)
		(stroke
			(width 0.0508)
			(type default)
		)
		(layer "F.Cu")
	)
	(gr_line
		(start 301.480474 -384.17119)
		(end 301.637192 -384.17119)
		(stroke
			(width 0.0508)
			(type default)
		)
		(layer "F.Cu")
	)
	(gr_line
		(start 301.497746 -395.913102)
		(end 302.101504 -395.913102)
		(stroke
			(width 0.0508)
			(type default)
		)
		(layer "F.Cu")
	)
	(gr_line
		(start 301.499016 -396.130272)
		(end 301.58182 -396.213076)
		(stroke
			(width 0.0508)
			(type default)
		)
		(layer "F.Cu")
	)
	(gr_line
		(start 301.580296 -377.41733)
		(end 301.309786 -377.68784)
		(stroke
			(width 0.06477)
			(type default)
		)
		(layer "F.Cu")
	)
	(gr_line
		(start 301.595536 -386.68579)
		(end 301.79772 -387.174232)
		(stroke
			(width 0.0508)
			(type default)
		)
		(layer "F.Cu")
	)
	(gr_line
		(start 301.605696 -379.22073)
		(end 301.256446 -379.56998)
		(stroke
			(width 0.0508)
			(type default)
		)
		(layer "F.Cu")
	)
	(gr_line
		(start 301.637192 -384.17119)
		(end 301.853092 -384.38709)
		(stroke
			(width 0.0508)
			(type default)
		)
		(layer "F.Cu")
	)
	(gr_line
		(start 301.853092 -384.38709)
		(end 301.853092 -384.543808)
		(stroke
			(width 0.0508)
			(type default)
		)
		(layer "F.Cu")
	)
	(gr_line
		(start 301.879762 -388.01167)
		(end 302.04918 -388.265162)
		(stroke
			(width 0.0508)
			(type default)
		)
		(layer "F.Cu")
	)
	(gr_line
		(start 301.910242 -387.858)
		(end 301.879762 -388.01167)
		(stroke
			(width 0.0508)
			(type default)
		)
		(layer "F.Cu")
	)
	(gr_line
		(start 302.03902 -381.303022)
		(end 302.412908 -381.676656)
		(stroke
			(width 0.0508)
			(type default)
		)
		(layer "F.Cu")
	)
	(gr_line
		(start 302.04918 -388.265162)
		(end 302.20285 -388.295896)
		(stroke
			(width 0.0508)
			(type default)
		)
		(layer "F.Cu")
	)
	(gr_line
		(start 302.090074 -387.736588)
		(end 302.090328 -387.736588)
		(stroke
			(width 0.0508)
			(type default)
		)
		(layer "F.Cu")
	)
	(gr_line
		(start 302.090328 -387.736588)
		(end 302.383952 -388.176008)
		(stroke
			(width 0.0508)
			(type default)
		)
		(layer "F.Cu")
	)
	(gr_line
		(start 302.193452 -381.150114)
		(end 302.349916 -381.150114)
		(stroke
			(width 0.0508)
			(type default)
		)
		(layer "F.Cu")
	)
	(gr_line
		(start 302.349916 -381.150114)
		(end 302.565816 -381.366014)
		(stroke
			(width 0.0508)
			(type default)
		)
		(layer "F.Cu")
	)
	(gr_line
		(start 302.383952 -388.176008)
		(end 302.383952 -388.176262)
		(stroke
			(width 0.0508)
			(type default)
		)
		(layer "F.Cu")
	)
	(gr_line
		(start 302.412908 -381.676656)
		(end 302.412908 -381.67691)
		(stroke
			(width 0.0508)
			(type default)
		)
		(layer "F.Cu")
	)
	(gr_line
		(start 302.565816 -381.366014)
		(end 302.565816 -381.522478)
		(stroke
			(width 0.0508)
			(type default)
		)
		(layer "F.Cu")
	)
	(gr_line
		(start 302.815752 -391.88771)
		(end 302.906938 -391.978896)
		(stroke
			(width 0.0508)
			(type default)
		)
		(layer "F.Cu")
	)
	(gr_line
		(start 302.815752 -391.6172)
		(end 302.815752 -391.88771)
		(stroke
			(width 0.0508)
			(type default)
		)
		(layer "F.Cu")
	)
	(gr_line
		(start 302.906938 -391.978896)
		(end 303.041304 -391.978896)
		(stroke
			(width 0.0508)
			(type default)
		)
		(layer "F.Cu")
	)
	(gr_line
		(start 303.041304 -391.978896)
		(end 303.117758 -391.902442)
		(stroke
			(width 0.0508)
			(type default)
		)
		(layer "F.Cu")
	)
	(gr_line
		(start 303.10709 -391.325862)
		(end 302.815752 -391.6172)
		(stroke
			(width 0.0508)
			(type default)
		)
		(layer "F.Cu")
	)
	(gr_line
		(start 303.117758 -391.902442)
		(end 303.117758 -391.784586)
		(stroke
			(width 0.0508)
			(type default)
		)
		(layer "F.Cu")
	)
	(gr_line
		(start 303.20107 -399.74647)
		(end 303.117758 -399.663158)
		(stroke
			(width 0.0508)
			(type default)
		)
		(layer "F.Cu")
	)
	(gr_line
		(start 303.270412 -397.156432)
		(end 303.791112 -397.156432)
		(stroke
			(width 0.0635)
			(type default)
		)
		(layer "F.Cu")
	)
	(gr_line
		(start 303.270412 -393.69238)
		(end 303.791112 -393.69238)
		(stroke
			(width 0.0635)
			(type default)
		)
		(layer "F.Cu")
	)
	(gr_line
		(start 303.32426 -391.51941)
		(end 303.417732 -391.612882)
		(stroke
			(width 0.0508)
			(type default)
		)
		(layer "F.Cu")
	)
	(gr_line
		(start 303.32426 -391.324592)
		(end 303.32426 -391.51941)
		(stroke
			(width 0.0508)
			(type default)
		)
		(layer "F.Cu")
	)
	(gr_line
		(start 303.417732 -391.612882)
		(end 303.417732 -392.30427)
		(stroke
			(width 0.0508)
			(type default)
		)
		(layer "F.Cu")
	)
	(gr_line
		(start 303.41824 -399.74774)
		(end 303.41824 -399.143982)
		(stroke
			(width 0.0508)
			(type default)
		)
		(layer "F.Cu")
	)
	(gr_line
		(start 303.41824 -399.143982)
		(end 303.417732 -399.143474)
		(stroke
			(width 0.0508)
			(type default)
		)
		(layer "F.Cu")
	)
	(gr_line
		(start 303.670462 -397.849344)
		(end 304.191162 -397.849344)
		(stroke
			(width 0.0635)
			(type default)
		)
		(layer "F.Cu")
	)
	(gr_line
		(start 303.670462 -394.385292)
		(end 304.191162 -394.385292)
		(stroke
			(width 0.0635)
			(type default)
		)
		(layer "F.Cu")
	)
	(gr_line
		(start 303.677574 -401.359116)
		(end 303.675542 -401.359116)
		(stroke
			(width 0.0508)
			(type default)
		)
		(layer "F.Cu")
	)
	(gr_line
		(start 303.768506 -417.166044)
		(end 304.064416 -417.461954)
		(stroke
			(width 0.06477)
			(type default)
		)
		(layer "F.Cu")
	)
	(gr_line
		(start 303.793906 -412.84652)
		(end 304.064416 -413.11703)
		(stroke
			(width 0.06477)
			(type default)
		)
		(layer "F.Cu")
	)
	(gr_line
		(start 303.816258 -401.674838)
		(end 303.816258 -401.4978)
		(stroke
			(width 0.0508)
			(type default)
		)
		(layer "F.Cu")
	)
	(gr_line
		(start 303.816258 -401.4978)
		(end 303.677574 -401.359116)
		(stroke
			(width 0.0508)
			(type default)
		)
		(layer "F.Cu")
	)
	(gr_line
		(start 303.816258 -401.0025)
		(end 303.676812 -401.141946)
		(stroke
			(width 0.0508)
			(type default)
		)
		(layer "F.Cu")
	)
	(gr_line
		(start 303.816258 -400.811238)
		(end 303.816258 -401.0025)
		(stroke
			(width 0.0508)
			(type default)
		)
		(layer "F.Cu")
	)
	(gr_line
		(start 304.015648 -391.88771)
		(end 304.106834 -391.978896)
		(stroke
			(width 0.0508)
			(type default)
		)
		(layer "F.Cu")
	)
	(gr_line
		(start 304.015648 -391.6172)
		(end 304.015648 -391.88771)
		(stroke
			(width 0.0508)
			(type default)
		)
		(layer "F.Cu")
	)
	(gr_line
		(start 304.064416 -420.681658)
		(end 303.793906 -420.952168)
		(stroke
			(width 0.06477)
			(type default)
		)
		(layer "F.Cu")
	)
	(gr_line
		(start 304.064416 -416.336734)
		(end 303.768506 -416.632644)
		(stroke
			(width 0.06477)
			(type default)
		)
		(layer "F.Cu")
	)
	(gr_line
		(start 304.094896 -384.14833)
		(end 304.444146 -384.49758)
		(stroke
			(width 0.0508)
			(type default)
		)
		(layer "F.Cu")
	)
	(gr_line
		(start 304.106834 -391.978896)
		(end 304.2412 -391.978896)
		(stroke
			(width 0.0508)
			(type default)
		)
		(layer "F.Cu")
	)
	(gr_line
		(start 304.120296 -382.34493)
		(end 304.390806 -382.61544)
		(stroke
			(width 0.06477)
			(type default)
		)
		(layer "F.Cu")
	)
	(gr_line
		(start 304.2412 -391.978896)
		(end 304.317654 -391.902442)
		(stroke
			(width 0.0508)
			(type default)
		)
		(layer "F.Cu")
	)
	(gr_line
		(start 304.306986 -391.325862)
		(end 304.015648 -391.6172)
		(stroke
			(width 0.0508)
			(type default)
		)
		(layer "F.Cu")
	)
	(gr_line
		(start 304.317654 -391.902442)
		(end 304.317654 -391.784586)
		(stroke
			(width 0.0508)
			(type default)
		)
		(layer "F.Cu")
	)
	(gr_line
		(start 304.386996 -420.681658)
		(end 304.657506 -420.952168)
		(stroke
			(width 0.06477)
			(type default)
		)
		(layer "F.Cu")
	)
	(gr_line
		(start 304.386996 -416.336734)
		(end 304.682906 -416.632644)
		(stroke
			(width 0.06477)
			(type default)
		)
		(layer "F.Cu")
	)
	(gr_line
		(start 304.390806 -383.31902)
		(end 304.094896 -383.61493)
		(stroke
			(width 0.06477)
			(type default)
		)
		(layer "F.Cu")
	)
	(gr_line
		(start 304.400966 -399.74647)
		(end 304.317654 -399.663158)
		(stroke
			(width 0.0508)
			(type default)
		)
		(layer "F.Cu")
	)
	(gr_line
		(start 304.470308 -397.156432)
		(end 304.991008 -397.156432)
		(stroke
			(width 0.0635)
			(type default)
		)
		(layer "F.Cu")
	)
	(gr_line
		(start 304.470308 -393.69238)
		(end 304.991008 -393.69238)
		(stroke
			(width 0.0635)
			(type default)
		)
		(layer "F.Cu")
	)
	(gr_line
		(start 304.524156 -391.51941)
		(end 304.617628 -391.612882)
		(stroke
			(width 0.0508)
			(type default)
		)
		(layer "F.Cu")
	)
	(gr_line
		(start 304.524156 -391.324592)
		(end 304.524156 -391.51941)
		(stroke
			(width 0.0508)
			(type default)
		)
		(layer "F.Cu")
	)
	(gr_line
		(start 304.617628 -391.612882)
		(end 304.617628 -392.30427)
		(stroke
			(width 0.0508)
			(type default)
		)
		(layer "F.Cu")
	)
	(gr_line
		(start 304.618136 -399.74774)
		(end 304.618136 -399.143982)
		(stroke
			(width 0.0508)
			(type default)
		)
		(layer "F.Cu")
	)
	(gr_line
		(start 304.618136 -399.143982)
		(end 304.617628 -399.143474)
		(stroke
			(width 0.0508)
			(type default)
		)
		(layer "F.Cu")
	)
	(gr_line
		(start 304.657506 -412.84652)
		(end 304.386996 -413.11703)
		(stroke
			(width 0.06477)
			(type default)
		)
		(layer "F.Cu")
	)
	(gr_line
		(start 304.682906 -417.166044)
		(end 304.386996 -417.461954)
		(stroke
			(width 0.06477)
			(type default)
		)
		(layer "F.Cu")
	)
	(gr_line
		(start 304.713386 -383.31902)
		(end 305.009296 -383.61493)
		(stroke
			(width 0.06477)
			(type default)
		)
		(layer "F.Cu")
	)
	(gr_line
		(start 304.870358 -397.849344)
		(end 305.391058 -397.849344)
		(stroke
			(width 0.0635)
			(type default)
		)
		(layer "F.Cu")
	)
	(gr_line
		(start 304.870358 -394.385292)
		(end 305.391058 -394.385292)
		(stroke
			(width 0.0635)
			(type default)
		)
		(layer "F.Cu")
	)
	(gr_line
		(start 304.87747 -401.359116)
		(end 304.875438 -401.359116)
		(stroke
			(width 0.0508)
			(type default)
		)
		(layer "F.Cu")
	)
	(gr_line
		(start 304.983896 -382.34493)
		(end 304.713386 -382.61544)
		(stroke
			(width 0.06477)
			(type default)
		)
		(layer "F.Cu")
	)
	(gr_line
		(start 305.009296 -384.14833)
		(end 304.660046 -384.49758)
		(stroke
			(width 0.0508)
			(type default)
		)
		(layer "F.Cu")
	)
	(gr_line
		(start 305.016154 -401.674838)
		(end 305.016154 -401.4978)
		(stroke
			(width 0.0508)
			(type default)
		)
		(layer "F.Cu")
	)
	(gr_line
		(start 305.016154 -401.4978)
		(end 304.87747 -401.359116)
		(stroke
			(width 0.0508)
			(type default)
		)
		(layer "F.Cu")
	)
	(gr_line
		(start 305.016154 -401.0025)
		(end 304.876708 -401.141946)
		(stroke
			(width 0.0508)
			(type default)
		)
		(layer "F.Cu")
	)
	(gr_line
		(start 305.016154 -400.811238)
		(end 305.016154 -401.0025)
		(stroke
			(width 0.0508)
			(type default)
		)
		(layer "F.Cu")
	)
	(gr_line
		(start 305.215798 -391.88771)
		(end 305.306984 -391.978896)
		(stroke
			(width 0.0508)
			(type default)
		)
		(layer "F.Cu")
	)
	(gr_line
		(start 305.215798 -391.6172)
		(end 305.215798 -391.88771)
		(stroke
			(width 0.0508)
			(type default)
		)
		(layer "F.Cu")
	)
	(gr_line
		(start 305.25085 -385.988814)
		(end 305.586384 -386.397754)
		(stroke
			(width 0.0508)
			(type default)
		)
		(layer "F.Cu")
	)
	(gr_line
		(start 305.306984 -391.978896)
		(end 305.44135 -391.978896)
		(stroke
			(width 0.0508)
			(type default)
		)
		(layer "F.Cu")
	)
	(gr_line
		(start 305.402742 -153.589736)
		(end 305.034442 -153.958036)
		(stroke
			(width 0.127)
			(type default)
		)
		(layer "F.Cu")
	)
	(gr_line
		(start 305.402742 -153.208736)
		(end 305.034442 -152.840436)
		(stroke
			(width 0.127)
			(type default)
		)
		(layer "F.Cu")
	)
	(gr_line
		(start 305.419506 -385.852162)
		(end 305.574954 -385.867402)
		(stroke
			(width 0.0508)
			(type default)
		)
		(layer "F.Cu")
	)
	(gr_line
		(start 305.44135 -391.978896)
		(end 305.517804 -391.902442)
		(stroke
			(width 0.0508)
			(type default)
		)
		(layer "F.Cu")
	)
	(gr_line
		(start 305.507136 -391.325862)
		(end 305.215798 -391.6172)
		(stroke
			(width 0.0508)
			(type default)
		)
		(layer "F.Cu")
	)
	(gr_line
		(start 305.517804 -391.902442)
		(end 305.517804 -391.784586)
		(stroke
			(width 0.0508)
			(type default)
		)
		(layer "F.Cu")
	)
	(gr_line
		(start 305.574954 -385.867402)
		(end 305.768502 -386.103114)
		(stroke
			(width 0.0508)
			(type default)
		)
		(layer "F.Cu")
	)
	(gr_line
		(start 305.601116 -399.74647)
		(end 305.517804 -399.663158)
		(stroke
			(width 0.0508)
			(type default)
		)
		(layer "F.Cu")
	)
	(gr_line
		(start 305.670458 -397.156432)
		(end 306.191158 -397.156432)
		(stroke
			(width 0.0635)
			(type default)
		)
		(layer "F.Cu")
	)
	(gr_line
		(start 305.670458 -393.69238)
		(end 306.191158 -393.69238)
		(stroke
			(width 0.0635)
			(type default)
		)
		(layer "F.Cu")
	)
	(gr_line
		(start 305.724306 -391.51941)
		(end 305.817778 -391.612882)
		(stroke
			(width 0.0508)
			(type default)
		)
		(layer "F.Cu")
	)
	(gr_line
		(start 305.724306 -391.324592)
		(end 305.724306 -391.51941)
		(stroke
			(width 0.0508)
			(type default)
		)
		(layer "F.Cu")
	)
	(gr_line
		(start 305.768502 -386.103114)
		(end 305.753516 -386.25907)
		(stroke
			(width 0.0508)
			(type default)
		)
		(layer "F.Cu")
	)
	(gr_line
		(start 305.796696 -381.68453)
		(end 306.145946 -382.03378)
		(stroke
			(width 0.0508)
			(type default)
		)
		(layer "F.Cu")
	)
	(gr_line
		(start 305.817778 -391.612882)
		(end 305.817778 -392.30427)
		(stroke
			(width 0.0508)
			(type default)
		)
		(layer "F.Cu")
	)
	(gr_line
		(start 305.818286 -399.74774)
		(end 305.818286 -399.143982)
		(stroke
			(width 0.0508)
			(type default)
		)
		(layer "F.Cu")
	)
	(gr_line
		(start 305.818286 -399.143982)
		(end 305.817778 -399.143474)
		(stroke
			(width 0.0508)
			(type default)
		)
		(layer "F.Cu")
	)
	(gr_line
		(start 305.822096 -379.88113)
		(end 306.092606 -380.15164)
		(stroke
			(width 0.06477)
			(type default)
		)
		(layer "F.Cu")
	)
	(gr_line
		(start 306.070254 -397.849344)
		(end 306.590954 -397.849344)
		(stroke
			(width 0.0635)
			(type default)
		)
		(layer "F.Cu")
	)
	(gr_line
		(start 306.070254 -394.385292)
		(end 306.590954 -394.385292)
		(stroke
			(width 0.0635)
			(type default)
		)
		(layer "F.Cu")
	)
	(gr_line
		(start 306.07762 -401.359116)
		(end 306.075588 -401.359116)
		(stroke
			(width 0.0508)
			(type default)
		)
		(layer "F.Cu")
	)
	(gr_line
		(start 306.092606 -380.85522)
		(end 305.796696 -381.15113)
		(stroke
			(width 0.06477)
			(type default)
		)
		(layer "F.Cu")
	)
	(gr_line
		(start 306.145946 -382.911096)
		(end 306.145946 -383.439416)
		(stroke
			(width 0.0508)
			(type default)
		)
		(layer "F.Cu")
	)
	(gr_line
		(start 306.216304 -401.674838)
		(end 306.216304 -401.4978)
		(stroke
			(width 0.0508)
			(type default)
		)
		(layer "F.Cu")
	)
	(gr_line
		(start 306.216304 -401.4978)
		(end 306.07762 -401.359116)
		(stroke
			(width 0.0508)
			(type default)
		)
		(layer "F.Cu")
	)
	(gr_line
		(start 306.216304 -401.0025)
		(end 306.076858 -401.141946)
		(stroke
			(width 0.0508)
			(type default)
		)
		(layer "F.Cu")
	)
	(gr_line
		(start 306.216304 -400.811238)
		(end 306.216304 -401.0025)
		(stroke
			(width 0.0508)
			(type default)
		)
		(layer "F.Cu")
	)
	(gr_line
		(start 306.363116 -382.912366)
		(end 306.473606 -383.022856)
		(stroke
			(width 0.0508)
			(type default)
		)
		(layer "F.Cu")
	)
	(gr_line
		(start 306.415186 -380.85522)
		(end 306.711096 -381.15113)
		(stroke
			(width 0.06477)
			(type default)
		)
		(layer "F.Cu")
	)
	(gr_line
		(start 306.415694 -391.88771)
		(end 306.50688 -391.978896)
		(stroke
			(width 0.0508)
			(type default)
		)
		(layer "F.Cu")
	)
	(gr_line
		(start 306.415694 -391.6172)
		(end 306.415694 -391.88771)
		(stroke
			(width 0.0508)
			(type default)
		)
		(layer "F.Cu")
	)
	(gr_line
		(start 306.473606 -383.327656)
		(end 306.363116 -383.438146)
		(stroke
			(width 0.0508)
			(type default)
		)
		(layer "F.Cu")
	)
	(gr_line
		(start 306.473606 -383.022856)
		(end 306.473606 -383.327656)
		(stroke
			(width 0.0508)
			(type default)
		)
		(layer "F.Cu")
	)
	(gr_line
		(start 306.50688 -391.978896)
		(end 306.641246 -391.978896)
		(stroke
			(width 0.0508)
			(type default)
		)
		(layer "F.Cu")
	)
	(gr_line
		(start 306.641246 -391.978896)
		(end 306.7177 -391.902442)
		(stroke
			(width 0.0508)
			(type default)
		)
		(layer "F.Cu")
	)
	(gr_line
		(start 306.685696 -379.88113)
		(end 306.415186 -380.15164)
		(stroke
			(width 0.06477)
			(type default)
		)
		(layer "F.Cu")
	)
	(gr_line
		(start 306.707032 -391.325862)
		(end 306.415694 -391.6172)
		(stroke
			(width 0.0508)
			(type default)
		)
		(layer "F.Cu")
	)
	(gr_line
		(start 306.711096 -381.68453)
		(end 306.361846 -382.03378)
		(stroke
			(width 0.0508)
			(type default)
		)
		(layer "F.Cu")
	)
	(gr_line
		(start 306.7177 -391.902442)
		(end 306.7177 -391.784586)
		(stroke
			(width 0.0508)
			(type default)
		)
		(layer "F.Cu")
	)
	(gr_line
		(start 306.801012 -399.74647)
		(end 306.7177 -399.663158)
		(stroke
			(width 0.0508)
			(type default)
		)
		(layer "F.Cu")
	)
	(gr_line
		(start 306.831746 -417.166044)
		(end 307.127656 -417.461954)
		(stroke
			(width 0.06477)
			(type default)
		)
		(layer "F.Cu")
	)
	(gr_line
		(start 306.857146 -412.84652)
		(end 307.127656 -413.11703)
		(stroke
			(width 0.06477)
			(type default)
		)
		(layer "F.Cu")
	)
	(gr_line
		(start 306.870354 -397.156432)
		(end 307.391054 -397.156432)
		(stroke
			(width 0.0635)
			(type default)
		)
		(layer "F.Cu")
	)
	(gr_line
		(start 306.870354 -393.69238)
		(end 307.391054 -393.69238)
		(stroke
			(width 0.0635)
			(type default)
		)
		(layer "F.Cu")
	)
	(gr_line
		(start 306.924202 -391.51941)
		(end 307.017674 -391.612882)
		(stroke
			(width 0.0508)
			(type default)
		)
		(layer "F.Cu")
	)
	(gr_line
		(start 306.924202 -391.324592)
		(end 306.924202 -391.51941)
		(stroke
			(width 0.0508)
			(type default)
		)
		(layer "F.Cu")
	)
	(gr_line
		(start 307.017674 -391.612882)
		(end 307.017674 -392.30427)
		(stroke
			(width 0.0508)
			(type default)
		)
		(layer "F.Cu")
	)
	(gr_line
		(start 307.018182 -399.74774)
		(end 307.018182 -399.143982)
		(stroke
			(width 0.0508)
			(type default)
		)
		(layer "F.Cu")
	)
	(gr_line
		(start 307.018182 -399.143982)
		(end 307.017674 -399.143474)
		(stroke
			(width 0.0508)
			(type default)
		)
		(layer "F.Cu")
	)
	(gr_line
		(start 307.127656 -420.681658)
		(end 306.857146 -420.952168)
		(stroke
			(width 0.06477)
			(type default)
		)
		(layer "F.Cu")
	)
	(gr_line
		(start 307.127656 -416.336734)
		(end 306.831746 -416.632644)
		(stroke
			(width 0.06477)
			(type default)
		)
		(layer "F.Cu")
	)
	(gr_line
		(start 307.270404 -397.849344)
		(end 307.791104 -397.849344)
		(stroke
			(width 0.0635)
			(type default)
		)
		(layer "F.Cu")
	)
	(gr_line
		(start 307.270404 -394.385292)
		(end 307.791104 -394.385292)
		(stroke
			(width 0.0635)
			(type default)
		)
		(layer "F.Cu")
	)
	(gr_line
		(start 307.277516 -401.359116)
		(end 307.275484 -401.359116)
		(stroke
			(width 0.0508)
			(type default)
		)
		(layer "F.Cu")
	)
	(gr_line
		(start 307.4162 -401.674838)
		(end 307.4162 -401.4978)
		(stroke
			(width 0.0508)
			(type default)
		)
		(layer "F.Cu")
	)
	(gr_line
		(start 307.4162 -401.4978)
		(end 307.277516 -401.359116)
		(stroke
			(width 0.0508)
			(type default)
		)
		(layer "F.Cu")
	)
	(gr_line
		(start 307.4162 -401.0025)
		(end 307.276754 -401.141946)
		(stroke
			(width 0.0508)
			(type default)
		)
		(layer "F.Cu")
	)
	(gr_line
		(start 307.4162 -400.811238)
		(end 307.4162 -401.0025)
		(stroke
			(width 0.0508)
			(type default)
		)
		(layer "F.Cu")
	)
	(gr_line
		(start 307.450236 -420.681658)
		(end 307.720746 -420.952168)
		(stroke
			(width 0.06477)
			(type default)
		)
		(layer "F.Cu")
	)
	(gr_line
		(start 307.450236 -416.336734)
		(end 307.746146 -416.632644)
		(stroke
			(width 0.06477)
			(type default)
		)
		(layer "F.Cu")
	)
	(gr_line
		(start 307.498496 -379.22073)
		(end 307.847746 -379.56998)
		(stroke
			(width 0.0508)
			(type default)
		)
		(layer "F.Cu")
	)
	(gr_line
		(start 307.523896 -377.41733)
		(end 307.794406 -377.68784)
		(stroke
			(width 0.06477)
			(type default)
		)
		(layer "F.Cu")
	)
	(gr_line
		(start 307.615844 -391.88771)
		(end 307.70703 -391.978896)
		(stroke
			(width 0.0508)
			(type default)
		)
		(layer "F.Cu")
	)
	(gr_line
		(start 307.615844 -391.6172)
		(end 307.615844 -391.88771)
		(stroke
			(width 0.0508)
			(type default)
		)
		(layer "F.Cu")
	)
	(gr_line
		(start 307.70703 -391.978896)
		(end 307.841396 -391.978896)
		(stroke
			(width 0.0508)
			(type default)
		)
		(layer "F.Cu")
	)
	(gr_line
		(start 307.720746 -412.84652)
		(end 307.450236 -413.11703)
		(stroke
			(width 0.06477)
			(type default)
		)
		(layer "F.Cu")
	)
	(gr_line
		(start 307.746146 -417.166044)
		(end 307.450236 -417.461954)
		(stroke
			(width 0.06477)
			(type default)
		)
		(layer "F.Cu")
	)
	(gr_line
		(start 307.794406 -378.39142)
		(end 307.498496 -378.68733)
		(stroke
			(width 0.06477)
			(type default)
		)
		(layer "F.Cu")
	)
	(gr_line
		(start 307.841396 -391.978896)
		(end 307.91785 -391.902442)
		(stroke
			(width 0.0508)
			(type default)
		)
		(layer "F.Cu")
	)
	(gr_line
		(start 307.907182 -391.325862)
		(end 307.615844 -391.6172)
		(stroke
			(width 0.0508)
			(type default)
		)
		(layer "F.Cu")
	)
	(gr_line
		(start 307.91785 -391.902442)
		(end 307.91785 -391.784586)
		(stroke
			(width 0.0508)
			(type default)
		)
		(layer "F.Cu")
	)
	(gr_line
		(start 308.001162 -399.74647)
		(end 307.91785 -399.663158)
		(stroke
			(width 0.0508)
			(type default)
		)
		(layer "F.Cu")
	)
	(gr_line
		(start 308.07025 -397.156432)
		(end 308.59095 -397.156432)
		(stroke
			(width 0.0635)
			(type default)
		)
		(layer "F.Cu")
	)
	(gr_line
		(start 308.07025 -393.69238)
		(end 308.59095 -393.69238)
		(stroke
			(width 0.0635)
			(type default)
		)
		(layer "F.Cu")
	)
	(gr_line
		(start 308.116986 -378.39142)
		(end 308.412896 -378.68733)
		(stroke
			(width 0.06477)
			(type default)
		)
		(layer "F.Cu")
	)
	(gr_line
		(start 308.124352 -391.51941)
		(end 308.217824 -391.612882)
		(stroke
			(width 0.0508)
			(type default)
		)
		(layer "F.Cu")
	)
	(gr_line
		(start 308.124352 -391.324592)
		(end 308.124352 -391.51941)
		(stroke
			(width 0.0508)
			(type default)
		)
		(layer "F.Cu")
	)
	(gr_arc
		(start 308.124352 -389.9535)
		(mid 308.124352 -389.953881)
		(end 308.124352 -389.954262)
		(stroke
			(width 0.0508)
			(type default)
		)
		(layer "F.Cu")
	)
	(gr_line
		(start 308.217824 -391.612882)
		(end 308.217824 -392.30427)
		(stroke
			(width 0.0508)
			(type default)
		)
		(layer "F.Cu")
	)
	(gr_line
		(start 308.218332 -399.74774)
		(end 308.218332 -399.143982)
		(stroke
			(width 0.0508)
			(type default)
		)
		(layer "F.Cu")
	)
	(gr_line
		(start 308.218332 -399.143982)
		(end 308.217824 -399.143474)
		(stroke
			(width 0.0508)
			(type default)
		)
		(layer "F.Cu")
	)
	(gr_line
		(start 308.387496 -377.41733)
		(end 308.116986 -377.68784)
		(stroke
			(width 0.06477)
			(type default)
		)
		(layer "F.Cu")
	)
	(gr_line
		(start 308.412896 -379.22073)
		(end 308.063646 -379.56998)
		(stroke
			(width 0.0508)
			(type default)
		)
		(layer "F.Cu")
	)
	(gr_line
		(start 308.4703 -397.849344)
		(end 308.991 -397.849344)
		(stroke
			(width 0.0635)
			(type default)
		)
		(layer "F.Cu")
	)
	(gr_line
		(start 308.4703 -394.385292)
		(end 308.991 -394.385292)
		(stroke
			(width 0.0635)
			(type default)
		)
		(layer "F.Cu")
	)
	(gr_line
		(start 308.477666 -401.359116)
		(end 308.475634 -401.359116)
		(stroke
			(width 0.0508)
			(type default)
		)
		(layer "F.Cu")
	)
	(gr_line
		(start 308.61635 -401.674838)
		(end 308.61635 -401.4978)
		(stroke
			(width 0.0508)
			(type default)
		)
		(layer "F.Cu")
	)
	(gr_line
		(start 308.61635 -401.4978)
		(end 308.477666 -401.359116)
		(stroke
			(width 0.0508)
			(type default)
		)
		(layer "F.Cu")
	)
	(gr_line
		(start 308.61635 -401.0025)
		(end 308.476904 -401.141946)
		(stroke
			(width 0.0508)
			(type default)
		)
		(layer "F.Cu")
	)
	(gr_line
		(start 308.61635 -400.811238)
		(end 308.61635 -401.0025)
		(stroke
			(width 0.0508)
			(type default)
		)
		(layer "F.Cu")
	)
	(gr_line
		(start 308.81574 -391.88771)
		(end 308.906926 -391.978896)
		(stroke
			(width 0.0508)
			(type default)
		)
		(layer "F.Cu")
	)
	(gr_line
		(start 308.81574 -391.6172)
		(end 308.81574 -391.88771)
		(stroke
			(width 0.0508)
			(type default)
		)
		(layer "F.Cu")
	)
	(gr_line
		(start 308.906926 -391.978896)
		(end 309.041292 -391.978896)
		(stroke
			(width 0.0508)
			(type default)
		)
		(layer "F.Cu")
	)
	(gr_line
		(start 309.041292 -391.978896)
		(end 309.117746 -391.902442)
		(stroke
			(width 0.0508)
			(type default)
		)
		(layer "F.Cu")
	)
	(gr_line
		(start 309.107078 -391.325862)
		(end 308.81574 -391.6172)
		(stroke
			(width 0.0508)
			(type default)
		)
		(layer "F.Cu")
	)
	(gr_line
		(start 309.117746 -391.902442)
		(end 309.117746 -391.784586)
		(stroke
			(width 0.0508)
			(type default)
		)
		(layer "F.Cu")
	)
	(gr_line
		(start 309.201058 -399.74647)
		(end 309.117746 -399.663158)
		(stroke
			(width 0.0508)
			(type default)
		)
		(layer "F.Cu")
	)
	(gr_line
		(start 309.2704 -397.156432)
		(end 309.7911 -397.156432)
		(stroke
			(width 0.0635)
			(type default)
		)
		(layer "F.Cu")
	)
	(gr_line
		(start 309.2704 -393.69238)
		(end 309.7911 -393.69238)
		(stroke
			(width 0.0635)
			(type default)
		)
		(layer "F.Cu")
	)
	(gr_line
		(start 309.324248 -391.51941)
		(end 309.41772 -391.612882)
		(stroke
			(width 0.0508)
			(type default)
		)
		(layer "F.Cu")
	)
	(gr_line
		(start 309.324248 -391.324592)
		(end 309.324248 -391.51941)
		(stroke
			(width 0.0508)
			(type default)
		)
		(layer "F.Cu")
	)
	(gr_line
		(start 309.41772 -391.612882)
		(end 309.41772 -392.30427)
		(stroke
			(width 0.0508)
			(type default)
		)
		(layer "F.Cu")
	)
	(gr_line
		(start 309.418228 -399.74774)
		(end 309.418228 -399.143982)
		(stroke
			(width 0.0508)
			(type default)
		)
		(layer "F.Cu")
	)
	(gr_line
		(start 309.418228 -399.143982)
		(end 309.41772 -399.143474)
		(stroke
			(width 0.0508)
			(type default)
		)
		(layer "F.Cu")
	)
	(gr_line
		(start 309.567072 -383.231136)
		(end 309.567072 -383.759456)
		(stroke
			(width 0.0508)
			(type default)
		)
		(layer "F.Cu")
	)
	(gr_line
		(start 309.67045 -397.849344)
		(end 310.19115 -397.849344)
		(stroke
			(width 0.0635)
			(type default)
		)
		(layer "F.Cu")
	)
	(gr_line
		(start 309.67045 -394.385292)
		(end 310.19115 -394.385292)
		(stroke
			(width 0.0635)
			(type default)
		)
		(layer "F.Cu")
	)
	(gr_line
		(start 309.677562 -401.359116)
		(end 309.67553 -401.359116)
		(stroke
			(width 0.0508)
			(type default)
		)
		(layer "F.Cu")
	)
	(gr_line
		(start 309.784242 -383.232406)
		(end 309.894732 -383.342896)
		(stroke
			(width 0.0508)
			(type default)
		)
		(layer "F.Cu")
	)
	(gr_line
		(start 309.816246 -401.674838)
		(end 309.816246 -401.4978)
		(stroke
			(width 0.0508)
			(type default)
		)
		(layer "F.Cu")
	)
	(gr_line
		(start 309.816246 -401.4978)
		(end 309.677562 -401.359116)
		(stroke
			(width 0.0508)
			(type default)
		)
		(layer "F.Cu")
	)
	(gr_line
		(start 309.816246 -401.0025)
		(end 309.6768 -401.141946)
		(stroke
			(width 0.0508)
			(type default)
		)
		(layer "F.Cu")
	)
	(gr_line
		(start 309.816246 -400.811238)
		(end 309.816246 -401.0025)
		(stroke
			(width 0.0508)
			(type default)
		)
		(layer "F.Cu")
	)
	(gr_line
		(start 309.894732 -383.647696)
		(end 309.784242 -383.758186)
		(stroke
			(width 0.0508)
			(type default)
		)
		(layer "F.Cu")
	)
	(gr_line
		(start 309.894732 -383.342896)
		(end 309.894732 -383.647696)
		(stroke
			(width 0.0508)
			(type default)
		)
		(layer "F.Cu")
	)
	(gr_line
		(start 309.894986 -417.166044)
		(end 310.190896 -417.461954)
		(stroke
			(width 0.06477)
			(type default)
		)
		(layer "F.Cu")
	)
	(gr_line
		(start 309.920386 -412.84652)
		(end 310.190896 -413.11703)
		(stroke
			(width 0.06477)
			(type default)
		)
		(layer "F.Cu")
	)
	(gr_line
		(start 310.015636 -391.88771)
		(end 310.106822 -391.978896)
		(stroke
			(width 0.0508)
			(type default)
		)
		(layer "F.Cu")
	)
	(gr_line
		(start 310.015636 -391.6172)
		(end 310.015636 -391.88771)
		(stroke
			(width 0.0508)
			(type default)
		)
		(layer "F.Cu")
	)
	(gr_line
		(start 310.106822 -391.978896)
		(end 310.241188 -391.978896)
		(stroke
			(width 0.0508)
			(type default)
		)
		(layer "F.Cu")
	)
	(gr_line
		(start 310.190896 -420.681658)
		(end 309.920386 -420.952168)
		(stroke
			(width 0.06477)
			(type default)
		)
		(layer "F.Cu")
	)
	(gr_line
		(start 310.190896 -416.336734)
		(end 309.894986 -416.632644)
		(stroke
			(width 0.06477)
			(type default)
		)
		(layer "F.Cu")
	)
	(gr_line
		(start 310.241188 -391.978896)
		(end 310.317642 -391.902442)
		(stroke
			(width 0.0508)
			(type default)
		)
		(layer "F.Cu")
	)
	(gr_line
		(start 310.306974 -391.325862)
		(end 310.015636 -391.6172)
		(stroke
			(width 0.0508)
			(type default)
		)
		(layer "F.Cu")
	)
	(gr_line
		(start 310.317642 -391.902442)
		(end 310.317642 -391.784586)
		(stroke
			(width 0.0508)
			(type default)
		)
		(layer "F.Cu")
	)
	(gr_line
		(start 310.401208 -399.746724)
		(end 310.317642 -399.663158)
		(stroke
			(width 0.0508)
			(type default)
		)
		(layer "F.Cu")
	)
	(gr_line
		(start 310.470296 -397.156432)
		(end 310.990996 -397.156432)
		(stroke
			(width 0.0635)
			(type default)
		)
		(layer "F.Cu")
	)
	(gr_line
		(start 310.470296 -393.69238)
		(end 310.990996 -393.69238)
		(stroke
			(width 0.0635)
			(type default)
		)
		(layer "F.Cu")
	)
	(gr_line
		(start 310.513476 -420.681658)
		(end 310.783986 -420.952168)
		(stroke
			(width 0.06477)
			(type default)
		)
		(layer "F.Cu")
	)
	(gr_line
		(start 310.513476 -416.336734)
		(end 310.809386 -416.632644)
		(stroke
			(width 0.06477)
			(type default)
		)
		(layer "F.Cu")
	)
	(gr_line
		(start 310.524144 -391.51941)
		(end 310.61787 -391.613136)
		(stroke
			(width 0.0508)
			(type default)
		)
		(layer "F.Cu")
	)
	(gr_line
		(start 310.524144 -391.324592)
		(end 310.524144 -391.51941)
		(stroke
			(width 0.0508)
			(type default)
		)
		(layer "F.Cu")
	)
	(gr_line
		(start 310.61787 -391.613136)
		(end 310.61787 -392.30427)
		(stroke
			(width 0.0508)
			(type default)
		)
		(layer "F.Cu")
	)
	(gr_line
		(start 310.618378 -399.747486)
		(end 310.618124 -399.74774)
		(stroke
			(width 0.0508)
			(type default)
		)
		(layer "F.Cu")
	)
	(gr_line
		(start 310.618378 -399.747486)
		(end 310.618378 -399.143982)
		(stroke
			(width 0.0508)
			(type default)
		)
		(layer "F.Cu")
	)
	(gr_line
		(start 310.618378 -399.143982)
		(end 310.61787 -399.143474)
		(stroke
			(width 0.0508)
			(type default)
		)
		(layer "F.Cu")
	)
	(gr_line
		(start 310.783986 -412.84652)
		(end 310.513476 -413.11703)
		(stroke
			(width 0.06477)
			(type default)
		)
		(layer "F.Cu")
	)
	(gr_line
		(start 310.809386 -417.166044)
		(end 310.513476 -417.461954)
		(stroke
			(width 0.06477)
			(type default)
		)
		(layer "F.Cu")
	)
	(gr_line
		(start 310.870346 -397.849344)
		(end 311.391046 -397.849344)
		(stroke
			(width 0.0635)
			(type default)
		)
		(layer "F.Cu")
	)
	(gr_line
		(start 310.870346 -394.385292)
		(end 311.391046 -394.385292)
		(stroke
			(width 0.0635)
			(type default)
		)
		(layer "F.Cu")
	)
	(gr_line
		(start 310.877458 -401.359116)
		(end 310.87568 -401.359116)
		(stroke
			(width 0.0508)
			(type default)
		)
		(layer "F.Cu")
	)
	(gr_line
		(start 310.902096 -384.14833)
		(end 311.203848 -384.450082)
		(stroke
			(width 0.0508)
			(type default)
		)
		(layer "F.Cu")
	)
	(gr_line
		(start 310.927496 -382.34493)
		(end 311.198006 -382.61544)
		(stroke
			(width 0.06477)
			(type default)
		)
		(layer "F.Cu")
	)
	(gr_line
		(start 311.016396 -401.674838)
		(end 311.016396 -401.498054)
		(stroke
			(width 0.0508)
			(type default)
		)
		(layer "F.Cu")
	)
	(gr_line
		(start 311.016396 -401.498054)
		(end 310.877458 -401.359116)
		(stroke
			(width 0.0508)
			(type default)
		)
		(layer "F.Cu")
	)
	(gr_line
		(start 311.016396 -401.0025)
		(end 310.87695 -401.141946)
		(stroke
			(width 0.0508)
			(type default)
		)
		(layer "F.Cu")
	)
	(gr_line
		(start 311.016396 -400.811238)
		(end 311.016396 -401.0025)
		(stroke
			(width 0.0508)
			(type default)
		)
		(layer "F.Cu")
	)
	(gr_line
		(start 311.198006 -383.31902)
		(end 310.902096 -383.61493)
		(stroke
			(width 0.06477)
			(type default)
		)
		(layer "F.Cu")
	)
	(gr_line
		(start 311.215786 -391.88771)
		(end 311.306972 -391.978896)
		(stroke
			(width 0.0508)
			(type default)
		)
		(layer "F.Cu")
	)
	(gr_line
		(start 311.215786 -391.6172)
		(end 311.215786 -391.88771)
		(stroke
			(width 0.0508)
			(type default)
		)
		(layer "F.Cu")
	)
	(gr_arc
		(start 311.25033 -384.547872)
		(mid 311.235455 -384.495)
		(end 311.203848 -384.450082)
		(stroke
			(width 0.0508)
			(type default)
		)
		(layer "F.Cu")
	)
	(gr_line
		(start 311.251346 -385.45643)
		(end 311.251346 -385.98475)
		(stroke
			(width 0.0508)
			(type default)
		)
		(layer "F.Cu")
	)
	(gr_line
		(start 311.306972 -391.978896)
		(end 311.441338 -391.978896)
		(stroke
			(width 0.0508)
			(type default)
		)
		(layer "F.Cu")
	)
	(gr_line
		(start 311.441338 -391.978896)
		(end 311.517792 -391.902442)
		(stroke
			(width 0.0508)
			(type default)
		)
		(layer "F.Cu")
	)
	(gr_line
		(start 311.468516 -385.4577)
		(end 311.579006 -385.56819)
		(stroke
			(width 0.0508)
			(type default)
		)
		(layer "F.Cu")
	)
	(gr_line
		(start 311.507124 -391.325862)
		(end 311.215786 -391.6172)
		(stroke
			(width 0.0508)
			(type default)
		)
		(layer "F.Cu")
	)
	(gr_arc
		(start 311.51449 -384.450336)
		(mid 311.4829 -384.494985)
		(end 311.468008 -384.547618)
		(stroke
			(width 0.0508)
			(type default)
		)
		(layer "F.Cu")
	)
	(gr_line
		(start 311.517792 -391.902442)
		(end 311.517792 -391.784586)
		(stroke
			(width 0.0508)
			(type default)
		)
		(layer "F.Cu")
	)
	(gr_line
		(start 311.520586 -383.31902)
		(end 311.816496 -383.61493)
		(stroke
			(width 0.06477)
			(type default)
		)
		(layer "F.Cu")
	)
	(gr_line
		(start 311.579006 -385.87299)
		(end 311.468516 -385.98348)
		(stroke
			(width 0.0508)
			(type default)
		)
		(layer "F.Cu")
	)
	(gr_line
		(start 311.579006 -385.56819)
		(end 311.579006 -385.87299)
		(stroke
			(width 0.0508)
			(type default)
		)
		(layer "F.Cu")
	)
	(gr_line
		(start 311.601104 -399.74647)
		(end 311.517792 -399.663158)
		(stroke
			(width 0.0508)
			(type default)
		)
		(layer "F.Cu")
	)
	(gr_line
		(start 311.670446 -397.156432)
		(end 312.191146 -397.156432)
		(stroke
			(width 0.0635)
			(type default)
		)
		(layer "F.Cu")
	)
	(gr_line
		(start 311.670446 -393.69238)
		(end 312.191146 -393.69238)
		(stroke
			(width 0.0635)
			(type default)
		)
		(layer "F.Cu")
	)
	(gr_line
		(start 311.724294 -391.51941)
		(end 311.817766 -391.612882)
		(stroke
			(width 0.0508)
			(type default)
		)
		(layer "F.Cu")
	)
	(gr_line
		(start 311.724294 -391.32383)
		(end 311.724294 -391.51941)
		(stroke
			(width 0.0508)
			(type default)
		)
		(layer "F.Cu")
	)
	(gr_line
		(start 311.791096 -382.34493)
		(end 311.520586 -382.61544)
		(stroke
			(width 0.06477)
			(type default)
		)
		(layer "F.Cu")
	)
	(gr_line
		(start 311.816496 -384.14833)
		(end 311.51449 -384.450336)
		(stroke
			(width 0.0508)
			(type default)
		)
		(layer "F.Cu")
	)
	(gr_line
		(start 311.817766 -391.612882)
		(end 311.817766 -392.30427)
		(stroke
			(width 0.0508)
			(type default)
		)
		(layer "F.Cu")
	)
	(gr_line
		(start 311.818274 -399.74774)
		(end 311.818274 -399.143982)
		(stroke
			(width 0.0508)
			(type default)
		)
		(layer "F.Cu")
	)
	(gr_line
		(start 311.818274 -399.143982)
		(end 311.817766 -399.143474)
		(stroke
			(width 0.0508)
			(type default)
		)
		(layer "F.Cu")
	)
	(gr_line
		(start 312.070242 -397.849344)
		(end 312.590942 -397.849344)
		(stroke
			(width 0.0635)
			(type default)
		)
		(layer "F.Cu")
	)
	(gr_line
		(start 312.070242 -394.385292)
		(end 312.590942 -394.385292)
		(stroke
			(width 0.0635)
			(type default)
		)
		(layer "F.Cu")
	)
	(gr_line
		(start 312.077608 -401.359116)
		(end 312.075576 -401.359116)
		(stroke
			(width 0.0508)
			(type default)
		)
		(layer "F.Cu")
	)
	(gr_line
		(start 312.216292 -401.674838)
		(end 312.216292 -401.4978)
		(stroke
			(width 0.0508)
			(type default)
		)
		(layer "F.Cu")
	)
	(gr_line
		(start 312.216292 -401.4978)
		(end 312.077608 -401.359116)
		(stroke
			(width 0.0508)
			(type default)
		)
		(layer "F.Cu")
	)
	(gr_line
		(start 312.216292 -401.0025)
		(end 312.076846 -401.141946)
		(stroke
			(width 0.0508)
			(type default)
		)
		(layer "F.Cu")
	)
	(gr_line
		(start 312.216292 -400.811238)
		(end 312.216292 -401.0025)
		(stroke
			(width 0.0508)
			(type default)
		)
		(layer "F.Cu")
	)
	(gr_line
		(start 312.415682 -391.88771)
		(end 312.506868 -391.978896)
		(stroke
			(width 0.0508)
			(type default)
		)
		(layer "F.Cu")
	)
	(gr_line
		(start 312.415682 -391.6172)
		(end 312.415682 -391.88771)
		(stroke
			(width 0.0508)
			(type default)
		)
		(layer "F.Cu")
	)
	(gr_line
		(start 312.506868 -391.978896)
		(end 312.641234 -391.978896)
		(stroke
			(width 0.0508)
			(type default)
		)
		(layer "F.Cu")
	)
	(gr_line
		(start 312.603896 -381.68453)
		(end 312.905648 -381.986282)
		(stroke
			(width 0.0508)
			(type default)
		)
		(layer "F.Cu")
	)
	(gr_line
		(start 312.629296 -379.88113)
		(end 312.899806 -380.15164)
		(stroke
			(width 0.06477)
			(type default)
		)
		(layer "F.Cu")
	)
	(gr_line
		(start 312.641234 -391.978896)
		(end 312.717688 -391.902442)
		(stroke
			(width 0.0508)
			(type default)
		)
		(layer "F.Cu")
	)
	(gr_line
		(start 312.70702 -391.325862)
		(end 312.415682 -391.6172)
		(stroke
			(width 0.0508)
			(type default)
		)
		(layer "F.Cu")
	)
	(gr_line
		(start 312.717688 -391.902442)
		(end 312.717688 -391.784586)
		(stroke
			(width 0.0508)
			(type default)
		)
		(layer "F.Cu")
	)
	(gr_line
		(start 312.801 -399.74647)
		(end 312.717688 -399.663158)
		(stroke
			(width 0.0508)
			(type default)
		)
		(layer "F.Cu")
	)
	(gr_line
		(start 312.870342 -397.156432)
		(end 313.391042 -397.156432)
		(stroke
			(width 0.0635)
			(type default)
		)
		(layer "F.Cu")
	)
	(gr_line
		(start 312.870342 -393.69238)
		(end 313.391042 -393.69238)
		(stroke
			(width 0.0635)
			(type default)
		)
		(layer "F.Cu")
	)
	(gr_line
		(start 312.899806 -380.85522)
		(end 312.603896 -381.15113)
		(stroke
			(width 0.06477)
			(type default)
		)
		(layer "F.Cu")
	)
	(gr_line
		(start 312.92419 -391.51941)
		(end 313.017662 -391.612882)
		(stroke
			(width 0.0508)
			(type default)
		)
		(layer "F.Cu")
	)
	(gr_line
		(start 312.92419 -391.324592)
		(end 312.92419 -391.51941)
		(stroke
			(width 0.0508)
			(type default)
		)
		(layer "F.Cu")
	)
	(gr_arc
		(start 312.95213 -382.084072)
		(mid 312.937255 -382.0312)
		(end 312.905648 -381.986282)
		(stroke
			(width 0.0508)
			(type default)
		)
		(layer "F.Cu")
	)
	(gr_line
		(start 312.953146 -383.22504)
		(end 312.953146 -383.75336)
		(stroke
			(width 0.0508)
			(type default)
		)
		(layer "F.Cu")
	)
	(gr_line
		(start 312.958226 -417.166044)
		(end 313.254136 -417.461954)
		(stroke
			(width 0.06477)
			(type default)
		)
		(layer "F.Cu")
	)
	(gr_line
		(start 312.983626 -412.84652)
		(end 313.254136 -413.11703)
		(stroke
			(width 0.06477)
			(type default)
		)
		(layer "F.Cu")
	)
	(gr_line
		(start 313.017662 -391.612882)
		(end 313.017662 -392.30427)
		(stroke
			(width 0.0508)
			(type default)
		)
		(layer "F.Cu")
	)
	(gr_line
		(start 313.01817 -399.74774)
		(end 313.01817 -399.143982)
		(stroke
			(width 0.0508)
			(type default)
		)
		(layer "F.Cu")
	)
	(gr_line
		(start 313.01817 -399.143982)
		(end 313.017662 -399.143474)
		(stroke
			(width 0.0508)
			(type default)
		)
		(layer "F.Cu")
	)
	(gr_line
		(start 313.170316 -383.22631)
		(end 313.280806 -383.3368)
		(stroke
			(width 0.0508)
			(type default)
		)
		(layer "F.Cu")
	)
	(gr_arc
		(start 313.216544 -381.986282)
		(mid 313.184897 -382.03118)
		(end 313.170062 -382.084072)
		(stroke
			(width 0.0508)
			(type default)
		)
		(layer "F.Cu")
	)
	(gr_line
		(start 313.222386 -380.85522)
		(end 313.518296 -381.15113)
		(stroke
			(width 0.06477)
			(type default)
		)
		(layer "F.Cu")
	)
	(gr_line
		(start 313.254136 -420.681658)
		(end 312.983626 -420.952168)
		(stroke
			(width 0.06477)
			(type default)
		)
		(layer "F.Cu")
	)
	(gr_line
		(start 313.254136 -416.336734)
		(end 312.958226 -416.632644)
		(stroke
			(width 0.06477)
			(type default)
		)
		(layer "F.Cu")
	)
	(gr_line
		(start 313.270392 -397.849344)
		(end 313.791092 -397.849344)
		(stroke
			(width 0.0635)
			(type default)
		)
		(layer "F.Cu")
	)
	(gr_line
		(start 313.270392 -394.385292)
		(end 313.791092 -394.385292)
		(stroke
			(width 0.0635)
			(type default)
		)
		(layer "F.Cu")
	)
	(gr_line
		(start 313.277504 -401.359116)
		(end 313.275472 -401.359116)
		(stroke
			(width 0.0508)
			(type default)
		)
		(layer "F.Cu")
	)
	(gr_line
		(start 313.280806 -383.6416)
		(end 313.170316 -383.75209)
		(stroke
			(width 0.0508)
			(type default)
		)
		(layer "F.Cu")
	)
	(gr_line
		(start 313.280806 -383.3368)
		(end 313.280806 -383.6416)
		(stroke
			(width 0.0508)
			(type default)
		)
		(layer "F.Cu")
	)
	(gr_line
		(start 313.416442 -401.674838)
		(end 313.416442 -401.498054)
		(stroke
			(width 0.0508)
			(type default)
		)
		(layer "F.Cu")
	)
	(gr_line
		(start 313.416442 -401.498054)
		(end 313.277504 -401.359116)
		(stroke
			(width 0.0508)
			(type default)
		)
		(layer "F.Cu")
	)
	(gr_line
		(start 313.416442 -401.002246)
		(end 313.276742 -401.141946)
		(stroke
			(width 0.0508)
			(type default)
		)
		(layer "F.Cu")
	)
	(gr_line
		(start 313.416442 -400.811238)
		(end 313.416442 -401.002246)
		(stroke
			(width 0.0508)
			(type default)
		)
		(layer "F.Cu")
	)
	(gr_line
		(start 313.492896 -379.88113)
		(end 313.222386 -380.15164)
		(stroke
			(width 0.06477)
			(type default)
		)
		(layer "F.Cu")
	)
	(gr_line
		(start 313.518296 -381.68453)
		(end 313.216544 -381.986282)
		(stroke
			(width 0.0508)
			(type default)
		)
		(layer "F.Cu")
	)
	(gr_line
		(start 313.576716 -420.681658)
		(end 313.847226 -420.952168)
		(stroke
			(width 0.06477)
			(type default)
		)
		(layer "F.Cu")
	)
	(gr_line
		(start 313.576716 -416.336734)
		(end 313.872626 -416.632644)
		(stroke
			(width 0.06477)
			(type default)
		)
		(layer "F.Cu")
	)
	(gr_line
		(start 313.615832 -391.88771)
		(end 313.707018 -391.978896)
		(stroke
			(width 0.0508)
			(type default)
		)
		(layer "F.Cu")
	)
	(gr_line
		(start 313.615832 -391.6172)
		(end 313.615832 -391.88771)
		(stroke
			(width 0.0508)
			(type default)
		)
		(layer "F.Cu")
	)
	(gr_line
		(start 313.707018 -391.978896)
		(end 313.841384 -391.978896)
		(stroke
			(width 0.0508)
			(type default)
		)
		(layer "F.Cu")
	)
	(gr_line
		(start 313.841384 -391.978896)
		(end 313.917838 -391.902442)
		(stroke
			(width 0.0508)
			(type default)
		)
		(layer "F.Cu")
	)
	(gr_line
		(start 313.847226 -412.84652)
		(end 313.576716 -413.11703)
		(stroke
			(width 0.06477)
			(type default)
		)
		(layer "F.Cu")
	)
	(gr_line
		(start 313.872626 -417.166044)
		(end 313.576716 -417.461954)
		(stroke
			(width 0.06477)
			(type default)
		)
		(layer "F.Cu")
	)
	(gr_line
		(start 313.90717 -391.325862)
		(end 313.615832 -391.6172)
		(stroke
			(width 0.0508)
			(type default)
		)
		(layer "F.Cu")
	)
	(gr_line
		(start 313.917838 -391.902442)
		(end 313.917838 -391.784586)
		(stroke
			(width 0.0508)
			(type default)
		)
		(layer "F.Cu")
	)
	(gr_line
		(start 314.00115 -399.74647)
		(end 313.917838 -399.663158)
		(stroke
			(width 0.0508)
			(type default)
		)
		(layer "F.Cu")
	)
	(gr_line
		(start 314.070238 -397.156432)
		(end 314.590938 -397.156432)
		(stroke
			(width 0.0635)
			(type default)
		)
		(layer "F.Cu")
	)
	(gr_line
		(start 314.070238 -393.69238)
		(end 314.590938 -393.69238)
		(stroke
			(width 0.0635)
			(type default)
		)
		(layer "F.Cu")
	)
	(gr_line
		(start 314.12434 -391.51941)
		(end 314.217812 -391.612882)
		(stroke
			(width 0.0508)
			(type default)
		)
		(layer "F.Cu")
	)
	(gr_line
		(start 314.12434 -391.324592)
		(end 314.12434 -391.51941)
		(stroke
			(width 0.0508)
			(type default)
		)
		(layer "F.Cu")
	)
	(gr_line
		(start 314.217812 -391.612882)
		(end 314.217812 -392.30427)
		(stroke
			(width 0.0508)
			(type default)
		)
		(layer "F.Cu")
	)
	(gr_line
		(start 314.21832 -399.74774)
		(end 314.21832 -399.143982)
		(stroke
			(width 0.0508)
			(type default)
		)
		(layer "F.Cu")
	)
	(gr_line
		(start 314.21832 -399.143982)
		(end 314.217812 -399.143474)
		(stroke
			(width 0.0508)
			(type default)
		)
		(layer "F.Cu")
	)
	(gr_line
		(start 314.305696 -379.22073)
		(end 314.654946 -379.56998)
		(stroke
			(width 0.0508)
			(type default)
		)
		(layer "F.Cu")
	)
	(gr_line
		(start 314.331096 -377.41733)
		(end 314.601606 -377.68784)
		(stroke
			(width 0.06477)
			(type default)
		)
		(layer "F.Cu")
	)
	(gr_line
		(start 314.470288 -397.849344)
		(end 314.990988 -397.849344)
		(stroke
			(width 0.0635)
			(type default)
		)
		(layer "F.Cu")
	)
	(gr_line
		(start 314.470288 -394.385292)
		(end 314.990988 -394.385292)
		(stroke
			(width 0.0635)
			(type default)
		)
		(layer "F.Cu")
	)
	(gr_line
		(start 314.477654 -401.359116)
		(end 314.475622 -401.359116)
		(stroke
			(width 0.0508)
			(type default)
		)
		(layer "F.Cu")
	)
	(gr_line
		(start 314.601606 -378.39142)
		(end 314.305696 -378.68733)
		(stroke
			(width 0.06477)
			(type default)
		)
		(layer "F.Cu")
	)
	(gr_line
		(start 314.616338 -401.674838)
		(end 314.616338 -401.4978)
		(stroke
			(width 0.0508)
			(type default)
		)
		(layer "F.Cu")
	)
	(gr_line
		(start 314.616338 -401.4978)
		(end 314.477654 -401.359116)
		(stroke
			(width 0.0508)
			(type default)
		)
		(layer "F.Cu")
	)
	(gr_line
		(start 314.616338 -401.0025)
		(end 314.476892 -401.141946)
		(stroke
			(width 0.0508)
			(type default)
		)
		(layer "F.Cu")
	)
	(gr_line
		(start 314.616338 -400.811238)
		(end 314.616338 -401.0025)
		(stroke
			(width 0.0508)
			(type default)
		)
		(layer "F.Cu")
	)
	(gr_line
		(start 314.815728 -391.88771)
		(end 314.906914 -391.978896)
		(stroke
			(width 0.0508)
			(type default)
		)
		(layer "F.Cu")
	)
	(gr_line
		(start 314.815728 -391.6172)
		(end 314.815728 -391.88771)
		(stroke
			(width 0.0508)
			(type default)
		)
		(layer "F.Cu")
	)
	(gr_line
		(start 314.906914 -391.978896)
		(end 315.04128 -391.978896)
		(stroke
			(width 0.0508)
			(type default)
		)
		(layer "F.Cu")
	)
	(gr_line
		(start 314.924186 -378.39142)
		(end 315.220096 -378.68733)
		(stroke
			(width 0.06477)
			(type default)
		)
		(layer "F.Cu")
	)
	(gr_line
		(start 315.04128 -391.978896)
		(end 315.117734 -391.902442)
		(stroke
			(width 0.0508)
			(type default)
		)
		(layer "F.Cu")
	)
	(gr_line
		(start 315.107066 -391.325862)
		(end 314.815728 -391.6172)
		(stroke
			(width 0.0508)
			(type default)
		)
		(layer "F.Cu")
	)
	(gr_line
		(start 315.117734 -391.902442)
		(end 315.117734 -391.784586)
		(stroke
			(width 0.0508)
			(type default)
		)
		(layer "F.Cu")
	)
	(gr_line
		(start 315.194696 -377.41733)
		(end 314.924186 -377.68784)
		(stroke
			(width 0.06477)
			(type default)
		)
		(layer "F.Cu")
	)
	(gr_line
		(start 315.200538 -399.745962)
		(end 315.117734 -399.663158)
		(stroke
			(width 0.0508)
			(type default)
		)
		(layer "F.Cu")
	)
	(gr_line
		(start 315.220096 -379.22073)
		(end 314.870846 -379.56998)
		(stroke
			(width 0.0508)
			(type default)
		)
		(layer "F.Cu")
	)
	(gr_line
		(start 315.270388 -397.156432)
		(end 315.791088 -397.156432)
		(stroke
			(width 0.0635)
			(type default)
		)
		(layer "F.Cu")
	)
	(gr_line
		(start 315.270388 -393.69238)
		(end 315.791088 -393.69238)
		(stroke
			(width 0.0635)
			(type default)
		)
		(layer "F.Cu")
	)
	(gr_line
		(start 315.324236 -391.51941)
		(end 315.417708 -391.612882)
		(stroke
			(width 0.0508)
			(type default)
		)
		(layer "F.Cu")
	)
	(gr_line
		(start 315.324236 -391.324592)
		(end 315.324236 -391.51941)
		(stroke
			(width 0.0508)
			(type default)
		)
		(layer "F.Cu")
	)
	(gr_line
		(start 315.338206 -384.935984)
		(end 315.181488 -384.935984)
		(stroke
			(width 0.0508)
			(type default)
		)
		(layer "F.Cu")
	)
	(gr_line
		(start 315.387736 -386.86486)
		(end 315.387482 -386.86486)
		(stroke
			(width 0.0508)
			(type default)
		)
		(layer "F.Cu")
	)
	(gr_line
		(start 315.401198 -384.409188)
		(end 315.02731 -384.783076)
		(stroke
			(width 0.0508)
			(type default)
		)
		(layer "F.Cu")
	)
	(gr_line
		(start 315.417708 -399.747232)
		(end 315.417708 -399.143474)
		(stroke
			(width 0.0508)
			(type default)
		)
		(layer "F.Cu")
	)
	(gr_line
		(start 315.417708 -391.612882)
		(end 315.417708 -392.30427)
		(stroke
			(width 0.0508)
			(type default)
		)
		(layer "F.Cu")
	)
	(gr_line
		(start 315.554106 -384.720084)
		(end 315.338206 -384.935984)
		(stroke
			(width 0.0508)
			(type default)
		)
		(layer "F.Cu")
	)
	(gr_line
		(start 315.554106 -384.563366)
		(end 315.554106 -384.720084)
		(stroke
			(width 0.0508)
			(type default)
		)
		(layer "F.Cu")
	)
	(gr_line
		(start 315.670438 -397.849344)
		(end 316.191138 -397.849344)
		(stroke
			(width 0.0635)
			(type default)
		)
		(layer "F.Cu")
	)
	(gr_line
		(start 315.670438 -394.385292)
		(end 316.191138 -394.385292)
		(stroke
			(width 0.0635)
			(type default)
		)
		(layer "F.Cu")
	)
	(gr_line
		(start 315.67755 -401.359116)
		(end 315.675518 -401.359116)
		(stroke
			(width 0.0508)
			(type default)
		)
		(layer "F.Cu")
	)
	(gr_line
		(start 315.698378 -387.017768)
		(end 315.541914 -387.017768)
		(stroke
			(width 0.0508)
			(type default)
		)
		(layer "F.Cu")
	)
	(gr_line
		(start 315.761116 -386.49148)
		(end 315.387736 -386.86486)
		(stroke
			(width 0.0508)
			(type default)
		)
		(layer "F.Cu")
	)
	(gr_line
		(start 315.816488 -401.674838)
		(end 315.816488 -401.498054)
		(stroke
			(width 0.0508)
			(type default)
		)
		(layer "F.Cu")
	)
	(gr_line
		(start 315.816488 -401.498054)
		(end 315.67755 -401.359116)
		(stroke
			(width 0.0508)
			(type default)
		)
		(layer "F.Cu")
	)
	(gr_line
		(start 315.816488 -401.002246)
		(end 315.676788 -401.141946)
		(stroke
			(width 0.0508)
			(type default)
		)
		(layer "F.Cu")
	)
	(gr_line
		(start 315.816488 -400.811238)
		(end 315.816488 -401.002246)
		(stroke
			(width 0.0508)
			(type default)
		)
		(layer "F.Cu")
	)
	(gr_line
		(start 315.914024 -386.802122)
		(end 315.698378 -387.017768)
		(stroke
			(width 0.0508)
			(type default)
		)
		(layer "F.Cu")
	)
	(gr_line
		(start 315.914024 -386.645658)
		(end 315.914024 -386.802122)
		(stroke
			(width 0.0508)
			(type default)
		)
		(layer "F.Cu")
	)
	(gr_line
		(start 315.936884 -5.327142)
		(end 315.791088 -5.327142)
		(stroke
			(width 0.06477)
			(type default)
		)
		(layer "F.Cu")
	)
	(gr_line
		(start 315.957712 -4.82727)
		(end 315.791088 -4.82727)
		(stroke
			(width 0.06477)
			(type default)
		)
		(layer "F.Cu")
	)
	(gr_line
		(start 316.015624 -391.88771)
		(end 316.10681 -391.978896)
		(stroke
			(width 0.0508)
			(type default)
		)
		(layer "F.Cu")
	)
	(gr_line
		(start 316.015624 -391.6172)
		(end 316.015624 -391.88771)
		(stroke
			(width 0.0508)
			(type default)
		)
		(layer "F.Cu")
	)
	(gr_line
		(start 316.021466 -417.166044)
		(end 316.317376 -417.461954)
		(stroke
			(width 0.06477)
			(type default)
		)
		(layer "F.Cu")
	)
	(gr_line
		(start 316.02553 -5.238496)
		(end 315.936884 -5.327142)
		(stroke
			(width 0.06477)
			(type default)
		)
		(layer "F.Cu")
	)
	(gr_line
		(start 316.045088 -4.914646)
		(end 315.957712 -4.82727)
		(stroke
			(width 0.06477)
			(type default)
		)
		(layer "F.Cu")
	)
	(gr_line
		(start 316.046358 -5.238496)
		(end 316.02553 -5.238496)
		(stroke
			(width 0.06477)
			(type default)
		)
		(layer "F.Cu")
	)
	(gr_line
		(start 316.046866 -412.84652)
		(end 316.317376 -413.11703)
		(stroke
			(width 0.06477)
			(type default)
		)
		(layer "F.Cu")
	)
	(gr_line
		(start 316.10681 -391.978896)
		(end 316.241176 -391.978896)
		(stroke
			(width 0.0508)
			(type default)
		)
		(layer "F.Cu")
	)
	(gr_line
		(start 316.241176 -391.978896)
		(end 316.31763 -391.902442)
		(stroke
			(width 0.0508)
			(type default)
		)
		(layer "F.Cu")
	)
	(gr_line
		(start 316.306962 -391.325862)
		(end 316.015624 -391.6172)
		(stroke
			(width 0.0508)
			(type default)
		)
		(layer "F.Cu")
	)
	(gr_line
		(start 316.317376 -420.681658)
		(end 316.046866 -420.952168)
		(stroke
			(width 0.06477)
			(type default)
		)
		(layer "F.Cu")
	)
	(gr_line
		(start 316.317376 -416.336734)
		(end 316.021466 -416.632644)
		(stroke
			(width 0.06477)
			(type default)
		)
		(layer "F.Cu")
	)
	(gr_line
		(start 316.31763 -391.902442)
		(end 316.31763 -391.784586)
		(stroke
			(width 0.0508)
			(type default)
		)
		(layer "F.Cu")
	)
	(gr_line
		(start 316.400942 -399.74647)
		(end 316.31763 -399.663158)
		(stroke
			(width 0.0508)
			(type default)
		)
		(layer "F.Cu")
	)
	(gr_line
		(start 316.44336 -0.429006)
		(end 315.791088 -0.247142)
		(stroke
			(width 0.06477)
			(type default)
		)
		(layer "F.Cu")
	)
	(gr_line
		(start 316.44336 0.434594)
		(end 315.791088 0.25273)
		(stroke
			(width 0.06477)
			(type default)
		)
		(layer "F.Cu")
	)
	(gr_line
		(start 316.44336 4.650994)
		(end 315.791088 4.832858)
		(stroke
			(width 0.06477)
			(type default)
		)
		(layer "F.Cu")
	)
	(gr_line
		(start 316.44336 5.514594)
		(end 315.791088 5.33273)
		(stroke
			(width 0.06477)
			(type default)
		)
		(layer "F.Cu")
	)
	(gr_line
		(start 316.470284 -397.156432)
		(end 316.990984 -397.156432)
		(stroke
			(width 0.0635)
			(type default)
		)
		(layer "F.Cu")
	)
	(gr_line
		(start 316.470284 -393.69238)
		(end 316.990984 -393.69238)
		(stroke
			(width 0.0635)
			(type default)
		)
		(layer "F.Cu")
	)
	(gr_line
		(start 316.524132 -391.51941)
		(end 316.617858 -391.613136)
		(stroke
			(width 0.0508)
			(type default)
		)
		(layer "F.Cu")
	)
	(gr_line
		(start 316.524132 -391.324592)
		(end 316.524132 -391.51941)
		(stroke
			(width 0.0508)
			(type default)
		)
		(layer "F.Cu")
	)
	(gr_line
		(start 316.617858 -391.613136)
		(end 316.617858 -392.30427)
		(stroke
			(width 0.0508)
			(type default)
		)
		(layer "F.Cu")
	)
	(gr_line
		(start 316.618112 -399.74774)
		(end 316.618112 -399.143728)
		(stroke
			(width 0.0508)
			(type default)
		)
		(layer "F.Cu")
	)
	(gr_line
		(start 316.618112 -399.143728)
		(end 316.617858 -399.143474)
		(stroke
			(width 0.0508)
			(type default)
		)
		(layer "F.Cu")
	)
	(gr_line
		(start 316.639956 -420.681658)
		(end 316.910466 -420.952168)
		(stroke
			(width 0.06477)
			(type default)
		)
		(layer "F.Cu")
	)
	(gr_line
		(start 316.639956 -416.336734)
		(end 316.935866 -416.632644)
		(stroke
			(width 0.06477)
			(type default)
		)
		(layer "F.Cu")
	)
	(gr_line
		(start 316.870334 -397.849344)
		(end 317.391034 -397.849344)
		(stroke
			(width 0.0635)
			(type default)
		)
		(layer "F.Cu")
	)
	(gr_line
		(start 316.870334 -394.385292)
		(end 317.391034 -394.385292)
		(stroke
			(width 0.0635)
			(type default)
		)
		(layer "F.Cu")
	)
	(gr_line
		(start 316.877446 -401.359116)
		(end 316.875414 -401.359116)
		(stroke
			(width 0.0508)
			(type default)
		)
		(layer "F.Cu")
	)
	(gr_line
		(start 316.910466 -412.84652)
		(end 316.639956 -413.11703)
		(stroke
			(width 0.06477)
			(type default)
		)
		(layer "F.Cu")
	)
	(gr_line
		(start 316.935866 -417.166044)
		(end 316.639956 -417.461954)
		(stroke
			(width 0.06477)
			(type default)
		)
		(layer "F.Cu")
	)
	(gr_line
		(start 317.016384 -401.674838)
		(end 317.016384 -401.498054)
		(stroke
			(width 0.0508)
			(type default)
		)
		(layer "F.Cu")
	)
	(gr_line
		(start 317.016384 -401.498054)
		(end 316.877446 -401.359116)
		(stroke
			(width 0.0508)
			(type default)
		)
		(layer "F.Cu")
	)
	(gr_line
		(start 317.016384 -401.002246)
		(end 316.876684 -401.141946)
		(stroke
			(width 0.0508)
			(type default)
		)
		(layer "F.Cu")
	)
	(gr_line
		(start 317.016384 -400.811238)
		(end 317.016384 -401.002246)
		(stroke
			(width 0.0508)
			(type default)
		)
		(layer "F.Cu")
	)
	(gr_line
		(start 317.215774 -391.88771)
		(end 317.30696 -391.978896)
		(stroke
			(width 0.0508)
			(type default)
		)
		(layer "F.Cu")
	)
	(gr_line
		(start 317.215774 -391.6172)
		(end 317.215774 -391.88771)
		(stroke
			(width 0.0508)
			(type default)
		)
		(layer "F.Cu")
	)
	(gr_line
		(start 317.30696 -391.978896)
		(end 317.441326 -391.978896)
		(stroke
			(width 0.0508)
			(type default)
		)
		(layer "F.Cu")
	)
	(gr_line
		(start 317.441326 -391.978896)
		(end 317.51778 -391.902442)
		(stroke
			(width 0.0508)
			(type default)
		)
		(layer "F.Cu")
	)
	(gr_line
		(start 317.507112 -391.325862)
		(end 317.215774 -391.6172)
		(stroke
			(width 0.0508)
			(type default)
		)
		(layer "F.Cu")
	)
	(gr_line
		(start 317.51778 -391.902442)
		(end 317.51778 -391.784586)
		(stroke
			(width 0.0508)
			(type default)
		)
		(layer "F.Cu")
	)
	(gr_line
		(start 317.601092 -399.74647)
		(end 317.51778 -399.663158)
		(stroke
			(width 0.0508)
			(type default)
		)
		(layer "F.Cu")
	)
	(gr_line
		(start 317.670434 -397.156432)
		(end 318.191134 -397.156432)
		(stroke
			(width 0.0635)
			(type default)
		)
		(layer "F.Cu")
	)
	(gr_line
		(start 317.670434 -393.69238)
		(end 318.191134 -393.69238)
		(stroke
			(width 0.0635)
			(type default)
		)
		(layer "F.Cu")
	)
	(gr_line
		(start 317.709296 -384.14833)
		(end 318.05753 -384.496564)
		(stroke
			(width 0.0508)
			(type default)
		)
		(layer "F.Cu")
	)
	(gr_line
		(start 317.724282 -391.51941)
		(end 317.817754 -391.612882)
		(stroke
			(width 0.0508)
			(type default)
		)
		(layer "F.Cu")
	)
	(gr_line
		(start 317.724282 -391.324592)
		(end 317.724282 -391.51941)
		(stroke
			(width 0.0508)
			(type default)
		)
		(layer "F.Cu")
	)
	(gr_line
		(start 317.734696 -382.34493)
		(end 318.005206 -382.61544)
		(stroke
			(width 0.06477)
			(type default)
		)
		(layer "F.Cu")
	)
	(gr_line
		(start 317.817754 -391.612882)
		(end 317.817754 -392.30427)
		(stroke
			(width 0.0508)
			(type default)
		)
		(layer "F.Cu")
	)
	(gr_line
		(start 317.818262 -399.74774)
		(end 317.818262 -399.143982)
		(stroke
			(width 0.0508)
			(type default)
		)
		(layer "F.Cu")
	)
	(gr_line
		(start 317.818262 -399.143982)
		(end 317.817754 -399.143474)
		(stroke
			(width 0.0508)
			(type default)
		)
		(layer "F.Cu")
	)
	(gr_line
		(start 318.005206 -383.31902)
		(end 317.709296 -383.61493)
		(stroke
			(width 0.06477)
			(type default)
		)
		(layer "F.Cu")
	)
	(gr_line
		(start 318.05753 -384.496564)
		(end 318.05753 -384.498596)
		(stroke
			(width 0.0508)
			(type default)
		)
		(layer "F.Cu")
	)
	(gr_line
		(start 318.07023 -397.849344)
		(end 318.59093 -397.849344)
		(stroke
			(width 0.0635)
			(type default)
		)
		(layer "F.Cu")
	)
	(gr_line
		(start 318.07023 -394.385292)
		(end 318.59093 -394.385292)
		(stroke
			(width 0.0635)
			(type default)
		)
		(layer "F.Cu")
	)
	(gr_line
		(start 318.074294 -401.359116)
		(end 318.050926 -401.359116)
		(stroke
			(width 0.0508)
			(type default)
		)
		(layer "F.Cu")
	)
	(gr_line
		(start 318.21628 -401.674838)
		(end 318.21628 -401.501102)
		(stroke
			(width 0.0508)
			(type default)
		)
		(layer "F.Cu")
	)
	(gr_line
		(start 318.21628 -401.501102)
		(end 318.074294 -401.359116)
		(stroke
			(width 0.0508)
			(type default)
		)
		(layer "F.Cu")
	)
	(gr_line
		(start 318.21628 -400.977862)
		(end 318.052196 -401.141946)
		(stroke
			(width 0.0508)
			(type default)
		)
		(layer "F.Cu")
	)
	(gr_line
		(start 318.21628 -400.811238)
		(end 318.21628 -400.977862)
		(stroke
			(width 0.0508)
			(type default)
		)
		(layer "F.Cu")
	)
	(gr_line
		(start 318.327786 -383.31902)
		(end 318.623696 -383.61493)
		(stroke
			(width 0.06477)
			(type default)
		)
		(layer "F.Cu")
	)
	(gr_line
		(start 318.41567 -391.88771)
		(end 318.506856 -391.978896)
		(stroke
			(width 0.0508)
			(type default)
		)
		(layer "F.Cu")
	)
	(gr_line
		(start 318.41567 -391.6172)
		(end 318.41567 -391.88771)
		(stroke
			(width 0.0508)
			(type default)
		)
		(layer "F.Cu")
	)
	(gr_line
		(start 318.506856 -391.978896)
		(end 318.641222 -391.978896)
		(stroke
			(width 0.0508)
			(type default)
		)
		(layer "F.Cu")
	)
	(gr_line
		(start 318.598296 -382.34493)
		(end 318.327786 -382.61544)
		(stroke
			(width 0.06477)
			(type default)
		)
		(layer "F.Cu")
	)
	(gr_line
		(start 318.623696 -384.14833)
		(end 318.2747 -384.497326)
		(stroke
			(width 0.0508)
			(type default)
		)
		(layer "F.Cu")
	)
	(gr_line
		(start 318.641222 -391.978896)
		(end 318.717676 -391.902442)
		(stroke
			(width 0.0508)
			(type default)
		)
		(layer "F.Cu")
	)
	(gr_line
		(start 318.707008 -391.325862)
		(end 318.41567 -391.6172)
		(stroke
			(width 0.0508)
			(type default)
		)
		(layer "F.Cu")
	)
	(gr_line
		(start 318.717676 -391.902442)
		(end 318.717676 -391.784586)
		(stroke
			(width 0.0508)
			(type default)
		)
		(layer "F.Cu")
	)
	(gr_line
		(start 318.800988 -399.74647)
		(end 318.717676 -399.663158)
		(stroke
			(width 0.0508)
			(type default)
		)
		(layer "F.Cu")
	)
	(gr_line
		(start 318.87033 -397.156432)
		(end 319.39103 -397.156432)
		(stroke
			(width 0.0635)
			(type default)
		)
		(layer "F.Cu")
	)
	(gr_line
		(start 318.87033 -393.69238)
		(end 319.39103 -393.69238)
		(stroke
			(width 0.0635)
			(type default)
		)
		(layer "F.Cu")
	)
	(gr_line
		(start 318.924178 -391.51941)
		(end 319.01765 -391.612882)
		(stroke
			(width 0.0508)
			(type default)
		)
		(layer "F.Cu")
	)
	(gr_line
		(start 318.924178 -391.324592)
		(end 318.924178 -391.51941)
		(stroke
			(width 0.0508)
			(type default)
		)
		(layer "F.Cu")
	)
	(gr_line
		(start 319.01765 -391.612882)
		(end 319.01765 -392.30427)
		(stroke
			(width 0.0508)
			(type default)
		)
		(layer "F.Cu")
	)
	(gr_line
		(start 319.018158 -399.74774)
		(end 319.018158 -399.143982)
		(stroke
			(width 0.0508)
			(type default)
		)
		(layer "F.Cu")
	)
	(gr_line
		(start 319.018158 -399.143982)
		(end 319.01765 -399.143474)
		(stroke
			(width 0.0508)
			(type default)
		)
		(layer "F.Cu")
	)
	(gr_line
		(start 319.084706 -417.166044)
		(end 319.380616 -417.461954)
		(stroke
			(width 0.06477)
			(type default)
		)
		(layer "F.Cu")
	)
	(gr_line
		(start 319.110106 -412.84652)
		(end 319.380616 -413.11703)
		(stroke
			(width 0.06477)
			(type default)
		)
		(layer "F.Cu")
	)
	(gr_line
		(start 319.27038 -397.849344)
		(end 319.79108 -397.849344)
		(stroke
			(width 0.0635)
			(type default)
		)
		(layer "F.Cu")
	)
	(gr_line
		(start 319.27038 -394.385292)
		(end 319.79108 -394.385292)
		(stroke
			(width 0.0635)
			(type default)
		)
		(layer "F.Cu")
	)
	(gr_line
		(start 319.277492 -401.359116)
		(end 319.27546 -401.359116)
		(stroke
			(width 0.0508)
			(type default)
		)
		(layer "F.Cu")
	)
	(gr_line
		(start 319.380616 -420.681658)
		(end 319.110106 -420.952168)
		(stroke
			(width 0.06477)
			(type default)
		)
		(layer "F.Cu")
	)
	(gr_line
		(start 319.380616 -416.336734)
		(end 319.084706 -416.632644)
		(stroke
			(width 0.06477)
			(type default)
		)
		(layer "F.Cu")
	)
	(gr_line
		(start 319.411096 -381.68453)
		(end 319.760346 -382.03378)
		(stroke
			(width 0.0508)
			(type default)
		)
		(layer "F.Cu")
	)
	(gr_line
		(start 319.416176 -401.674838)
		(end 319.416176 -401.4978)
		(stroke
			(width 0.0508)
			(type default)
		)
		(layer "F.Cu")
	)
	(gr_line
		(start 319.416176 -401.4978)
		(end 319.277492 -401.359116)
		(stroke
			(width 0.0508)
			(type default)
		)
		(layer "F.Cu")
	)
	(gr_line
		(start 319.416176 -401.0025)
		(end 319.27673 -401.141946)
		(stroke
			(width 0.0508)
			(type default)
		)
		(layer "F.Cu")
	)
	(gr_line
		(start 319.416176 -400.811238)
		(end 319.416176 -401.0025)
		(stroke
			(width 0.0508)
			(type default)
		)
		(layer "F.Cu")
	)
	(gr_line
		(start 319.436496 -379.88113)
		(end 319.707006 -380.15164)
		(stroke
			(width 0.06477)
			(type default)
		)
		(layer "F.Cu")
	)
	(gr_line
		(start 319.703196 -420.681658)
		(end 319.973706 -420.952168)
		(stroke
			(width 0.06477)
			(type default)
		)
		(layer "F.Cu")
	)
	(gr_line
		(start 319.703196 -416.336734)
		(end 319.999106 -416.632644)
		(stroke
			(width 0.06477)
			(type default)
		)
		(layer "F.Cu")
	)
	(gr_line
		(start 319.707006 -380.85522)
		(end 319.411096 -381.15113)
		(stroke
			(width 0.06477)
			(type default)
		)
		(layer "F.Cu")
	)
	(gr_line
		(start 319.760346 -383.403856)
		(end 319.760346 -383.932176)
		(stroke
			(width 0.0508)
			(type default)
		)
		(layer "F.Cu")
	)
	(gr_line
		(start 319.973706 -412.84652)
		(end 319.703196 -413.11703)
		(stroke
			(width 0.06477)
			(type default)
		)
		(layer "F.Cu")
	)
	(gr_line
		(start 319.977516 -383.405126)
		(end 320.088006 -383.515616)
		(stroke
			(width 0.0508)
			(type default)
		)
		(layer "F.Cu")
	)
	(gr_line
		(start 319.999106 -417.166044)
		(end 319.703196 -417.461954)
		(stroke
			(width 0.06477)
			(type default)
		)
		(layer "F.Cu")
	)
	(gr_line
		(start 320.001138 -399.74647)
		(end 319.917826 -399.663158)
		(stroke
			(width 0.0508)
			(type default)
		)
		(layer "F.Cu")
	)
	(gr_line
		(start 320.001138 -391.701274)
		(end 319.917826 -391.784586)
		(stroke
			(width 0.0508)
			(type default)
		)
		(layer "F.Cu")
	)
	(gr_line
		(start 320.029586 -380.85522)
		(end 320.325496 -381.15113)
		(stroke
			(width 0.06477)
			(type default)
		)
		(layer "F.Cu")
	)
	(gr_line
		(start 320.07048 -397.156432)
		(end 320.59118 -397.156432)
		(stroke
			(width 0.0635)
			(type default)
		)
		(layer "F.Cu")
	)
	(gr_line
		(start 320.07048 -393.69238)
		(end 320.59118 -393.69238)
		(stroke
			(width 0.0635)
			(type default)
		)
		(layer "F.Cu")
	)
	(gr_line
		(start 320.088006 -383.820416)
		(end 319.977516 -383.930906)
		(stroke
			(width 0.0508)
			(type default)
		)
		(layer "F.Cu")
	)
	(gr_line
		(start 320.088006 -383.515616)
		(end 320.088006 -383.820416)
		(stroke
			(width 0.0508)
			(type default)
		)
		(layer "F.Cu")
	)
	(gr_line
		(start 320.124582 -390.071102)
		(end 320.124328 -390.070848)
		(stroke
			(width 0.0508)
			(type default)
		)
		(layer "F.Cu")
	)
	(gr_line
		(start 320.218308 -399.74774)
		(end 320.218308 -399.143982)
		(stroke
			(width 0.0508)
			(type default)
		)
		(layer "F.Cu")
	)
	(gr_line
		(start 320.218308 -399.143982)
		(end 320.2178 -399.143474)
		(stroke
			(width 0.0508)
			(type default)
		)
		(layer "F.Cu")
	)
	(gr_line
		(start 320.218308 -392.303762)
		(end 320.2178 -392.30427)
		(stroke
			(width 0.0508)
			(type default)
		)
		(layer "F.Cu")
	)
	(gr_line
		(start 320.218308 -391.700004)
		(end 320.218308 -392.303762)
		(stroke
			(width 0.0508)
			(type default)
		)
		(layer "F.Cu")
	)
	(gr_line
		(start 320.300096 -379.88113)
		(end 320.029586 -380.15164)
		(stroke
			(width 0.06477)
			(type default)
		)
		(layer "F.Cu")
	)
	(gr_line
		(start 320.325496 -381.68453)
		(end 319.976246 -382.03378)
		(stroke
			(width 0.0508)
			(type default)
		)
		(layer "F.Cu")
	)
	(gr_line
		(start 320.459608 -401.359116)
		(end 320.44894 -401.359116)
		(stroke
			(width 0.0508)
			(type default)
		)
		(layer "F.Cu")
	)
	(gr_line
		(start 320.470276 -397.849344)
		(end 320.990976 -397.849344)
		(stroke
			(width 0.0635)
			(type default)
		)
		(layer "F.Cu")
	)
	(gr_line
		(start 320.470276 -394.385292)
		(end 320.990976 -394.385292)
		(stroke
			(width 0.0635)
			(type default)
		)
		(layer "F.Cu")
	)
	(gr_line
		(start 320.616326 -401.674838)
		(end 320.616326 -401.515834)
		(stroke
			(width 0.0508)
			(type default)
		)
		(layer "F.Cu")
	)
	(gr_line
		(start 320.616326 -401.515834)
		(end 320.459608 -401.359116)
		(stroke
			(width 0.0508)
			(type default)
		)
		(layer "F.Cu")
	)
	(gr_line
		(start 320.616326 -400.97583)
		(end 320.45021 -401.141946)
		(stroke
			(width 0.0508)
			(type default)
		)
		(layer "F.Cu")
	)
	(gr_line
		(start 320.616326 -400.811238)
		(end 320.616326 -400.97583)
		(stroke
			(width 0.0508)
			(type default)
		)
		(layer "F.Cu")
	)
	(gr_line
		(start 321.112896 -379.22073)
		(end 321.462146 -379.56998)
		(stroke
			(width 0.0508)
			(type default)
		)
		(layer "F.Cu")
	)
	(gr_line
		(start 321.138296 -377.41733)
		(end 321.408806 -377.68784)
		(stroke
			(width 0.06477)
			(type default)
		)
		(layer "F.Cu")
	)
	(gr_line
		(start 321.201034 -399.74647)
		(end 321.117722 -399.663158)
		(stroke
			(width 0.0508)
			(type default)
		)
		(layer "F.Cu")
	)
	(gr_line
		(start 321.201034 -391.701274)
		(end 321.117722 -391.784586)
		(stroke
			(width 0.0508)
			(type default)
		)
		(layer "F.Cu")
	)
	(gr_line
		(start 321.270376 -397.156432)
		(end 321.791076 -397.156432)
		(stroke
			(width 0.0635)
			(type default)
		)
		(layer "F.Cu")
	)
	(gr_line
		(start 321.270376 -393.69238)
		(end 321.791076 -393.69238)
		(stroke
			(width 0.0635)
			(type default)
		)
		(layer "F.Cu")
	)
	(gr_line
		(start 321.408806 -378.39142)
		(end 321.112896 -378.68733)
		(stroke
			(width 0.06477)
			(type default)
		)
		(layer "F.Cu")
	)
	(gr_line
		(start 321.418204 -399.74774)
		(end 321.418204 -399.143982)
		(stroke
			(width 0.0508)
			(type default)
		)
		(layer "F.Cu")
	)
	(gr_line
		(start 321.418204 -399.143982)
		(end 321.417696 -399.143474)
		(stroke
			(width 0.0508)
			(type default)
		)
		(layer "F.Cu")
	)
	(gr_line
		(start 321.418204 -392.303762)
		(end 321.417696 -392.30427)
		(stroke
			(width 0.0508)
			(type default)
		)
		(layer "F.Cu")
	)
	(gr_line
		(start 321.418204 -391.700004)
		(end 321.418204 -392.303762)
		(stroke
			(width 0.0508)
			(type default)
		)
		(layer "F.Cu")
	)
	(gr_line
		(start 321.661028 -401.359116)
		(end 321.654932 -401.359116)
		(stroke
			(width 0.0508)
			(type default)
		)
		(layer "F.Cu")
	)
	(gr_line
		(start 321.670426 -397.849344)
		(end 322.191126 -397.849344)
		(stroke
			(width 0.0635)
			(type default)
		)
		(layer "F.Cu")
	)
	(gr_line
		(start 321.670426 -394.385292)
		(end 322.191126 -394.385292)
		(stroke
			(width 0.0635)
			(type default)
		)
		(layer "F.Cu")
	)
	(gr_line
		(start 321.731386 -378.39142)
		(end 322.027296 -378.68733)
		(stroke
			(width 0.06477)
			(type default)
		)
		(layer "F.Cu")
	)
	(gr_line
		(start 321.816222 -401.674838)
		(end 321.816222 -401.51431)
		(stroke
			(width 0.0508)
			(type default)
		)
		(layer "F.Cu")
	)
	(gr_line
		(start 321.816222 -401.51431)
		(end 321.661028 -401.359116)
		(stroke
			(width 0.0508)
			(type default)
		)
		(layer "F.Cu")
	)
	(gr_line
		(start 321.816222 -400.981926)
		(end 321.656202 -401.141946)
		(stroke
			(width 0.0508)
			(type default)
		)
		(layer "F.Cu")
	)
	(gr_line
		(start 321.816222 -400.811238)
		(end 321.816222 -400.981926)
		(stroke
			(width 0.0508)
			(type default)
		)
		(layer "F.Cu")
	)
	(gr_line
		(start 322.001896 -377.41733)
		(end 321.731386 -377.68784)
		(stroke
			(width 0.06477)
			(type default)
		)
		(layer "F.Cu")
	)
	(gr_line
		(start 322.027296 -379.22073)
		(end 321.678046 -379.56998)
		(stroke
			(width 0.0508)
			(type default)
		)
		(layer "F.Cu")
	)
	(gr_line
		(start 322.147946 -417.166044)
		(end 322.443856 -417.461954)
		(stroke
			(width 0.06477)
			(type default)
		)
		(layer "F.Cu")
	)
	(gr_line
		(start 322.173346 -412.84652)
		(end 322.443856 -413.11703)
		(stroke
			(width 0.06477)
			(type default)
		)
		(layer "F.Cu")
	)
	(gr_line
		(start 322.443856 -420.681658)
		(end 322.173346 -420.952168)
		(stroke
			(width 0.06477)
			(type default)
		)
		(layer "F.Cu")
	)
	(gr_line
		(start 322.443856 -416.336734)
		(end 322.147946 -416.632644)
		(stroke
			(width 0.06477)
			(type default)
		)
		(layer "F.Cu")
	)
	(gr_line
		(start 322.645532 -381.460502)
		(end 323.01942 -381.83439)
		(stroke
			(width 0.0508)
			(type default)
		)
		(layer "F.Cu")
	)
	(gr_line
		(start 322.766436 -420.681658)
		(end 323.036946 -420.952168)
		(stroke
			(width 0.06477)
			(type default)
		)
		(layer "F.Cu")
	)
	(gr_line
		(start 322.766436 -416.336734)
		(end 323.062346 -416.632644)
		(stroke
			(width 0.06477)
			(type default)
		)
		(layer "F.Cu")
	)
	(gr_line
		(start 322.799964 -381.307594)
		(end 322.956428 -381.307594)
		(stroke
			(width 0.0508)
			(type default)
		)
		(layer "F.Cu")
	)
	(gr_line
		(start 322.956428 -381.307594)
		(end 323.172328 -381.523494)
		(stroke
			(width 0.0508)
			(type default)
		)
		(layer "F.Cu")
	)
	(gr_line
		(start 323.036946 -412.84652)
		(end 322.766436 -413.11703)
		(stroke
			(width 0.06477)
			(type default)
		)
		(layer "F.Cu")
	)
	(gr_line
		(start 323.062346 -417.166044)
		(end 322.766436 -417.461954)
		(stroke
			(width 0.06477)
			(type default)
		)
		(layer "F.Cu")
	)
	(gr_line
		(start 323.172328 -381.523494)
		(end 323.172328 -381.679958)
		(stroke
			(width 0.0508)
			(type default)
		)
		(layer "F.Cu")
	)
	(gr_line
		(start 324.246494 -388.090918)
		(end 324.136004 -388.201408)
		(stroke
			(width 0.0508)
			(type default)
		)
		(layer "F.Cu")
	)
	(gr_line
		(start 324.516496 -379.22073)
		(end 324.865746 -379.56998)
		(stroke
			(width 0.0508)
			(type default)
		)
		(layer "F.Cu")
	)
	(gr_line
		(start 324.541896 -377.41733)
		(end 324.812406 -377.68784)
		(stroke
			(width 0.06477)
			(type default)
		)
		(layer "F.Cu")
	)
	(gr_line
		(start 324.551294 -388.090918)
		(end 324.246494 -388.090918)
		(stroke
			(width 0.0508)
			(type default)
		)
		(layer "F.Cu")
	)
	(gr_line
		(start 324.661784 -388.201408)
		(end 324.551294 -388.090918)
		(stroke
			(width 0.0508)
			(type default)
		)
		(layer "F.Cu")
	)
	(gr_line
		(start 324.663054 -388.418578)
		(end 324.134734 -388.418578)
		(stroke
			(width 0.0508)
			(type default)
		)
		(layer "F.Cu")
	)
	(gr_line
		(start 324.812406 -378.39142)
		(end 324.516496 -378.68733)
		(stroke
			(width 0.06477)
			(type default)
		)
		(layer "F.Cu")
	)
	(gr_line
		(start 325.081646 -379.909832)
		(end 325.0819 -379.909578)
		(stroke
			(width 0.0508)
			(type default)
		)
		(layer "F.Cu")
	)
	(gr_line
		(start 325.12889 -385.10083)
		(end 325.038974 -385.10083)
		(stroke
			(width 0.0508)
			(type default)
		)
		(layer "F.Cu")
	)
	(gr_line
		(start 325.134986 -378.39142)
		(end 325.430896 -378.68733)
		(stroke
			(width 0.06477)
			(type default)
		)
		(layer "F.Cu")
	)
	(gr_line
		(start 325.211186 -417.166044)
		(end 325.507096 -417.461954)
		(stroke
			(width 0.06477)
			(type default)
		)
		(layer "F.Cu")
	)
	(gr_line
		(start 325.236586 -412.84652)
		(end 325.507096 -413.11703)
		(stroke
			(width 0.06477)
			(type default)
		)
		(layer "F.Cu")
	)
	(gr_line
		(start 325.26859 -385.158742)
		(end 325.12889 -385.10083)
		(stroke
			(width 0.0508)
			(type default)
		)
		(layer "F.Cu")
	)
	(gr_line
		(start 325.405496 -377.41733)
		(end 325.134986 -377.68784)
		(stroke
			(width 0.06477)
			(type default)
		)
		(layer "F.Cu")
	)
	(gr_line
		(start 325.430896 -379.22073)
		(end 325.081646 -379.56998)
		(stroke
			(width 0.0508)
			(type default)
		)
		(layer "F.Cu")
	)
	(gr_line
		(start 325.474076 -388.767828)
		(end 325.124826 -388.418578)
		(stroke
			(width 0.0508)
			(type default)
		)
		(layer "F.Cu")
	)
	(gr_line
		(start 325.474076 -387.853428)
		(end 325.124826 -388.202678)
		(stroke
			(width 0.0508)
			(type default)
		)
		(layer "F.Cu")
	)
	(gr_line
		(start 325.474076 -385.364228)
		(end 325.26859 -385.158742)
		(stroke
			(width 0.0508)
			(type default)
		)
		(layer "F.Cu")
	)
	(gr_line
		(start 325.474076 -384.449828)
		(end 325.040244 -384.88366)
		(stroke
			(width 0.0508)
			(type default)
		)
		(layer "F.Cu")
	)
	(gr_line
		(start 325.507096 -420.681658)
		(end 325.236586 -420.952168)
		(stroke
			(width 0.06477)
			(type default)
		)
		(layer "F.Cu")
	)
	(gr_line
		(start 325.507096 -416.336734)
		(end 325.211186 -416.632644)
		(stroke
			(width 0.06477)
			(type default)
		)
		(layer "F.Cu")
	)
	(gr_line
		(start 325.796148 -381.286258)
		(end 326.170036 -381.660146)
		(stroke
			(width 0.0508)
			(type default)
		)
		(layer "F.Cu")
	)
	(gr_line
		(start 325.829676 -420.681658)
		(end 326.100186 -420.952168)
		(stroke
			(width 0.06477)
			(type default)
		)
		(layer "F.Cu")
	)
	(gr_line
		(start 325.829676 -416.336734)
		(end 326.125586 -416.632644)
		(stroke
			(width 0.06477)
			(type default)
		)
		(layer "F.Cu")
	)
	(gr_line
		(start 325.950326 -381.13335)
		(end 326.107044 -381.13335)
		(stroke
			(width 0.0508)
			(type default)
		)
		(layer "F.Cu")
	)
	(gr_line
		(start 326.100186 -412.84652)
		(end 325.829676 -413.11703)
		(stroke
			(width 0.06477)
			(type default)
		)
		(layer "F.Cu")
	)
	(gr_line
		(start 326.107044 -381.13335)
		(end 326.322944 -381.34925)
		(stroke
			(width 0.0508)
			(type default)
		)
		(layer "F.Cu")
	)
	(gr_line
		(start 326.125586 -417.166044)
		(end 325.829676 -417.461954)
		(stroke
			(width 0.06477)
			(type default)
		)
		(layer "F.Cu")
	)
	(gr_line
		(start 326.303386 -388.471918)
		(end 326.007476 -388.767828)
		(stroke
			(width 0.06477)
			(type default)
		)
		(layer "F.Cu")
	)
	(gr_line
		(start 326.303386 -388.149338)
		(end 326.007476 -387.853428)
		(stroke
			(width 0.06477)
			(type default)
		)
		(layer "F.Cu")
	)
	(gr_line
		(start 326.303386 -385.068318)
		(end 326.007476 -385.364228)
		(stroke
			(width 0.06477)
			(type default)
		)
		(layer "F.Cu")
	)
	(gr_line
		(start 326.303386 -384.745738)
		(end 326.007476 -384.449828)
		(stroke
			(width 0.06477)
			(type default)
		)
		(layer "F.Cu")
	)
	(gr_line
		(start 326.322944 -381.34925)
		(end 326.322944 -381.505968)
		(stroke
			(width 0.0508)
			(type default)
		)
		(layer "F.Cu")
	)
	(gr_line
		(start 326.34809 -223.69018)
		(end 326.247252 -223.31045)
		(stroke
			(width 0.127)
			(type default)
		)
		(layer "F.Cu")
	)
	(gr_line
		(start 326.511666 -150.796498)
		(end 327.10501 -151.389842)
		(stroke
			(width 0.127)
			(type default)
		)
		(layer "F.Cu")
	)
	(gr_line
		(start 326.511666 -148.214334)
		(end 326.511666 -150.796498)
		(stroke
			(width 0.127)
			(type default)
		)
		(layer "F.Cu")
	)
	(gr_line
		(start 326.81799 -222.880174)
		(end 326.438514 -222.980758)
		(stroke
			(width 0.127)
			(type default)
		)
		(layer "F.Cu")
	)
	(gr_line
		(start 327.0504 -150.573232)
		(end 327.35393 -150.876762)
		(stroke
			(width 0.127)
			(type default)
		)
		(layer "F.Cu")
	)
	(gr_line
		(start 327.0504 -148.46173)
		(end 327.0504 -150.573232)
		(stroke
			(width 0.127)
			(type default)
		)
		(layer "F.Cu")
	)
	(gr_line
		(start 327.10501 -151.389842)
		(end 327.863454 -151.389842)
		(stroke
			(width 0.127)
			(type default)
		)
		(layer "F.Cu")
	)
	(gr_line
		(start 327.277476 -388.742428)
		(end 327.006966 -388.471918)
		(stroke
			(width 0.06477)
			(type default)
		)
		(layer "F.Cu")
	)
	(gr_line
		(start 327.277476 -387.878828)
		(end 327.006966 -388.149338)
		(stroke
			(width 0.06477)
			(type default)
		)
		(layer "F.Cu")
	)
	(gr_line
		(start 327.277476 -385.338828)
		(end 327.006966 -385.068318)
		(stroke
			(width 0.06477)
			(type default)
		)
		(layer "F.Cu")
	)
	(gr_line
		(start 327.277476 -384.475228)
		(end 327.006966 -384.745738)
		(stroke
			(width 0.06477)
			(type default)
		)
		(layer "F.Cu")
	)
	(gr_line
		(start 327.35393 -150.876762)
		(end 327.819258 -150.876762)
		(stroke
			(width 0.127)
			(type default)
		)
		(layer "F.Cu")
	)
	(gr_line
		(start 327.551796 -147.174204)
		(end 326.511666 -148.214334)
		(stroke
			(width 0.127)
			(type default)
		)
		(layer "F.Cu")
	)
	(gr_line
		(start 327.551796 -142.959836)
		(end 327.551796 -147.174204)
		(stroke
			(width 0.127)
			(type default)
		)
		(layer "F.Cu")
	)
	(gr_line
		(start 327.551796 -141.917928)
		(end 327.551796 -142.959836)
		(stroke
			(width 0.127)
			(type default)
		)
		(layer "F.Cu")
	)
	(gr_line
		(start 327.551796 -141.430248)
		(end 327.551796 -141.917928)
		(stroke
			(width 0.127)
			(type default)
		)
		(layer "F.Cu")
	)
	(gr_line
		(start 327.819258 -150.876762)
		(end 328.106786 -150.589234)
		(stroke
			(width 0.127)
			(type default)
		)
		(layer "F.Cu")
	)
	(gr_line
		(start 327.863454 -151.389842)
		(end 328.114914 -151.641302)
		(stroke
			(width 0.127)
			(type default)
		)
		(layer "F.Cu")
	)
	(gr_line
		(start 328.09053 -147.4216)
		(end 327.0504 -148.46173)
		(stroke
			(width 0.127)
			(type default)
		)
		(layer "F.Cu")
	)
	(gr_line
		(start 328.09053 -144.154144)
		(end 328.09053 -147.4216)
		(stroke
			(width 0.127)
			(type default)
		)
		(layer "F.Cu")
	)
	(gr_line
		(start 328.09053 -141.649704)
		(end 328.09053 -144.154144)
		(stroke
			(width 0.127)
			(type default)
		)
		(layer "F.Cu")
	)
	(gr_line
		(start 328.274426 -417.166044)
		(end 328.570336 -417.461954)
		(stroke
			(width 0.06477)
			(type default)
		)
		(layer "F.Cu")
	)
	(gr_line
		(start 328.299826 -412.84652)
		(end 328.570336 -413.11703)
		(stroke
			(width 0.06477)
			(type default)
		)
		(layer "F.Cu")
	)
	(gr_line
		(start 328.367644 -140.145008)
		(end 328.467974 -140.245338)
		(stroke
			(width 0.127)
			(type default)
		)
		(layer "F.Cu")
	)
	(gr_line
		(start 328.367644 -139.293092)
		(end 328.367644 -140.145008)
		(stroke
			(width 0.127)
			(type default)
		)
		(layer "F.Cu")
	)
	(gr_line
		(start 328.367644 -138.051794)
		(end 328.367644 -138.492992)
		(stroke
			(width 0.127)
			(type default)
		)
		(layer "F.Cu")
	)
	(gr_line
		(start 328.467974 -140.51407)
		(end 327.551796 -141.430248)
		(stroke
			(width 0.127)
			(type default)
		)
		(layer "F.Cu")
	)
	(gr_line
		(start 328.467974 -140.245338)
		(end 328.467974 -140.51407)
		(stroke
			(width 0.127)
			(type default)
		)
		(layer "F.Cu")
	)
	(gr_line
		(start 328.548492 -141.191742)
		(end 328.09053 -141.649704)
		(stroke
			(width 0.127)
			(type default)
		)
		(layer "F.Cu")
	)
	(gr_line
		(start 328.569574 -137.849864)
		(end 328.367644 -138.051794)
		(stroke
			(width 0.127)
			(type default)
		)
		(layer "F.Cu")
	)
	(gr_line
		(start 328.570336 -420.681658)
		(end 328.299826 -420.952168)
		(stroke
			(width 0.06477)
			(type default)
		)
		(layer "F.Cu")
	)
	(gr_line
		(start 328.570336 -416.336734)
		(end 328.274426 -416.632644)
		(stroke
			(width 0.06477)
			(type default)
		)
		(layer "F.Cu")
	)
	(gr_line
		(start 328.892916 -420.681658)
		(end 329.163426 -420.952168)
		(stroke
			(width 0.06477)
			(type default)
		)
		(layer "F.Cu")
	)
	(gr_line
		(start 328.892916 -416.336734)
		(end 329.188826 -416.632644)
		(stroke
			(width 0.06477)
			(type default)
		)
		(layer "F.Cu")
	)
	(gr_line
		(start 328.914252 -142.578074)
		(end 329.223624 -142.268702)
		(stroke
			(width 0.127)
			(type default)
		)
		(layer "F.Cu")
	)
	(gr_line
		(start 329.163426 -412.84652)
		(end 328.892916 -413.11703)
		(stroke
			(width 0.06477)
			(type default)
		)
		(layer "F.Cu")
	)
	(gr_line
		(start 329.188826 -417.166044)
		(end 328.892916 -417.461954)
		(stroke
			(width 0.06477)
			(type default)
		)
		(layer "F.Cu")
	)
	(gr_line
		(start 329.223624 -142.268702)
		(end 329.223624 -141.991842)
		(stroke
			(width 0.127)
			(type default)
		)
		(layer "F.Cu")
	)
	(gr_line
		(start 329.223624 -141.191742)
		(end 328.548492 -141.191742)
		(stroke
			(width 0.127)
			(type default)
		)
		(layer "F.Cu")
	)
	(gr_line
		(start 329.810364 -396.171674)
		(end 330.080874 -395.901164)
		(stroke
			(width 0.06477)
			(type default)
		)
		(layer "F.Cu")
	)
	(gr_line
		(start 329.810364 -395.308074)
		(end 330.080874 -395.578584)
		(stroke
			(width 0.06477)
			(type default)
		)
		(layer "F.Cu")
	)
	(gr_line
		(start 329.958192 -390.75106)
		(end 330.228702 -390.48055)
		(stroke
			(width 0.06477)
			(type default)
		)
		(layer "F.Cu")
	)
	(gr_line
		(start 329.958192 -389.88746)
		(end 330.228702 -390.15797)
		(stroke
			(width 0.06477)
			(type default)
		)
		(layer "F.Cu")
	)
	(gr_line
		(start 329.958192 -385.21386)
		(end 330.228702 -384.94335)
		(stroke
			(width 0.06477)
			(type default)
		)
		(layer "F.Cu")
	)
	(gr_line
		(start 329.958192 -384.35026)
		(end 330.228702 -384.62077)
		(stroke
			(width 0.06477)
			(type default)
		)
		(layer "F.Cu")
	)
	(gr_line
		(start 330.543662 -395.901164)
		(end 330.788772 -396.146274)
		(stroke
			(width 0.06477)
			(type default)
		)
		(layer "F.Cu")
	)
	(gr_line
		(start 330.543662 -395.578584)
		(end 330.788772 -395.333474)
		(stroke
			(width 0.06477)
			(type default)
		)
		(layer "F.Cu")
	)
	(gr_line
		(start 330.932282 -390.48055)
		(end 331.228192 -390.77646)
		(stroke
			(width 0.06477)
			(type default)
		)
		(layer "F.Cu")
	)
	(gr_line
		(start 330.932282 -390.15797)
		(end 331.228192 -389.86206)
		(stroke
			(width 0.06477)
			(type default)
		)
		(layer "F.Cu")
	)
	(gr_line
		(start 330.932282 -384.94335)
		(end 331.228192 -385.23926)
		(stroke
			(width 0.06477)
			(type default)
		)
		(layer "F.Cu")
	)
	(gr_line
		(start 330.932282 -384.62077)
		(end 331.228192 -384.32486)
		(stroke
			(width 0.06477)
			(type default)
		)
		(layer "F.Cu")
	)
	(gr_line
		(start 331.322172 -396.146274)
		(end 331.566774 -395.901672)
		(stroke
			(width 0.06477)
			(type default)
		)
		(layer "F.Cu")
	)
	(gr_line
		(start 331.322172 -395.333474)
		(end 331.56652 -395.577822)
		(stroke
			(width 0.06477)
			(type default)
		)
		(layer "F.Cu")
	)
	(gr_line
		(start 331.337666 -417.166044)
		(end 331.633576 -417.461954)
		(stroke
			(width 0.06477)
			(type default)
		)
		(layer "F.Cu")
	)
	(gr_line
		(start 331.363066 -412.84652)
		(end 331.633576 -413.11703)
		(stroke
			(width 0.06477)
			(type default)
		)
		(layer "F.Cu")
	)
	(gr_line
		(start 331.517244 -381.68453)
		(end 331.866494 -382.03378)
		(stroke
			(width 0.0508)
			(type default)
		)
		(layer "F.Cu")
	)
	(gr_line
		(start 331.542644 -379.88113)
		(end 331.813154 -380.15164)
		(stroke
			(width 0.06477)
			(type default)
		)
		(layer "F.Cu")
	)
	(gr_line
		(start 331.56652 -395.577822)
		(end 331.568044 -395.577822)
		(stroke
			(width 0.06477)
			(type default)
		)
		(layer "F.Cu")
	)
	(gr_line
		(start 331.633576 -420.681658)
		(end 331.363066 -420.952168)
		(stroke
			(width 0.06477)
			(type default)
		)
		(layer "F.Cu")
	)
	(gr_line
		(start 331.633576 -416.336734)
		(end 331.337666 -416.632644)
		(stroke
			(width 0.06477)
			(type default)
		)
		(layer "F.Cu")
	)
	(gr_line
		(start 331.761592 -390.77646)
		(end 332.11135 -390.426702)
		(stroke
			(width 0.0508)
			(type default)
		)
		(layer "F.Cu")
	)
	(gr_line
		(start 331.761592 -389.86206)
		(end 332.109064 -390.209532)
		(stroke
			(width 0.0508)
			(type default)
		)
		(layer "F.Cu")
	)
	(gr_line
		(start 331.761592 -385.23926)
		(end 332.131416 -384.869436)
		(stroke
			(width 0.0508)
			(type default)
		)
		(layer "F.Cu")
	)
	(gr_line
		(start 331.761592 -384.32486)
		(end 332.088998 -384.652266)
		(stroke
			(width 0.0508)
			(type default)
		)
		(layer "F.Cu")
	)
	(gr_line
		(start 331.813154 -380.85522)
		(end 331.517244 -381.15113)
		(stroke
			(width 0.06477)
			(type default)
		)
		(layer "F.Cu")
	)
	(gr_line
		(start 331.8256 -395.577822)
		(end 331.827124 -395.577822)
		(stroke
			(width 0.06477)
			(type default)
		)
		(layer "F.Cu")
	)
	(gr_line
		(start 331.82687 -395.901672)
		(end 332.071472 -396.146274)
		(stroke
			(width 0.06477)
			(type default)
		)
		(layer "F.Cu")
	)
	(gr_line
		(start 331.827124 -395.577822)
		(end 332.071472 -395.333474)
		(stroke
			(width 0.06477)
			(type default)
		)
		(layer "F.Cu")
	)
	(gr_line
		(start 331.956156 -420.681658)
		(end 332.226666 -420.952168)
		(stroke
			(width 0.06477)
			(type default)
		)
		(layer "F.Cu")
	)
	(gr_line
		(start 331.956156 -416.336734)
		(end 332.252066 -416.632644)
		(stroke
			(width 0.06477)
			(type default)
		)
		(layer "F.Cu")
	)
	(gr_line
		(start 332.071472 -396.146274)
		(end 332.327504 -395.890242)
		(stroke
			(width 0.06477)
			(type default)
		)
		(layer "F.Cu")
	)
	(gr_line
		(start 332.071472 -395.333474)
		(end 332.30439 -395.566392)
		(stroke
			(width 0.06477)
			(type default)
		)
		(layer "F.Cu")
	)
	(gr_line
		(start 332.088998 -384.652266)
		(end 332.132686 -384.652266)
		(stroke
			(width 0.0508)
			(type default)
		)
		(layer "F.Cu")
	)
	(gr_line
		(start 332.109064 -390.209532)
		(end 332.11262 -390.209532)
		(stroke
			(width 0.0508)
			(type default)
		)
		(layer "F.Cu")
	)
	(gr_line
		(start 332.135734 -380.85522)
		(end 332.431644 -381.15113)
		(stroke
			(width 0.06477)
			(type default)
		)
		(layer "F.Cu")
	)
	(gr_line
		(start 332.226666 -412.84652)
		(end 331.956156 -413.11703)
		(stroke
			(width 0.06477)
			(type default)
		)
		(layer "F.Cu")
	)
	(gr_line
		(start 332.252066 -417.166044)
		(end 331.956156 -417.461954)
		(stroke
			(width 0.06477)
			(type default)
		)
		(layer "F.Cu")
	)
	(gr_line
		(start 332.30439 -395.566392)
		(end 332.328774 -395.566392)
		(stroke
			(width 0.06477)
			(type default)
		)
		(layer "F.Cu")
	)
	(gr_line
		(start 332.406244 -379.88113)
		(end 332.135734 -380.15164)
		(stroke
			(width 0.06477)
			(type default)
		)
		(layer "F.Cu")
	)
	(gr_line
		(start 332.41742 -390.209532)
		(end 332.94574 -390.209532)
		(stroke
			(width 0.0508)
			(type default)
		)
		(layer "F.Cu")
	)
	(gr_line
		(start 332.41869 -390.426702)
		(end 332.52918 -390.537192)
		(stroke
			(width 0.0508)
			(type default)
		)
		(layer "F.Cu")
	)
	(gr_line
		(start 332.431644 -381.68453)
		(end 332.082394 -382.03378)
		(stroke
			(width 0.0508)
			(type default)
		)
		(layer "F.Cu")
	)
	(gr_line
		(start 332.52918 -390.537192)
		(end 332.83398 -390.537192)
		(stroke
			(width 0.0508)
			(type default)
		)
		(layer "F.Cu")
	)
	(gr_line
		(start 332.83398 -390.537192)
		(end 332.94447 -390.426702)
		(stroke
			(width 0.0508)
			(type default)
		)
		(layer "F.Cu")
	)
	(gr_line
		(start 333.219044 -379.22073)
		(end 333.568294 -379.56998)
		(stroke
			(width 0.0508)
			(type default)
		)
		(layer "F.Cu")
	)
	(gr_line
		(start 333.244444 -377.41733)
		(end 333.514954 -377.68784)
		(stroke
			(width 0.06477)
			(type default)
		)
		(layer "F.Cu")
	)
	(gr_line
		(start 333.25054 -390.209532)
		(end 333.77886 -390.209532)
		(stroke
			(width 0.0508)
			(type default)
		)
		(layer "F.Cu")
	)
	(gr_line
		(start 333.25181 -390.426702)
		(end 333.3623 -390.537192)
		(stroke
			(width 0.0508)
			(type default)
		)
		(layer "F.Cu")
	)
	(gr_line
		(start 333.3623 -390.537192)
		(end 333.6671 -390.537192)
		(stroke
			(width 0.0508)
			(type default)
		)
		(layer "F.Cu")
	)
	(gr_line
		(start 333.514954 -378.39142)
		(end 333.219044 -378.68733)
		(stroke
			(width 0.06477)
			(type default)
		)
		(layer "F.Cu")
	)
	(gr_line
		(start 333.6671 -390.537192)
		(end 333.77759 -390.426702)
		(stroke
			(width 0.0508)
			(type default)
		)
		(layer "F.Cu")
	)
	(gr_line
		(start 333.837534 -378.39142)
		(end 334.133444 -378.68733)
		(stroke
			(width 0.06477)
			(type default)
		)
		(layer "F.Cu")
	)
	(gr_line
		(start 333.854044 -384.324098)
		(end 334.227932 -384.697986)
		(stroke
			(width 0.0508)
			(type default)
		)
		(layer "F.Cu")
	)
	(gr_line
		(start 333.862934 -386.91439)
		(end 333.97952 -387.19633)
		(stroke
			(width 0.0508)
			(type default)
		)
		(layer "F.Cu")
	)
	(gr_line
		(start 333.922878 -386.769864)
		(end 333.862934 -386.91439)
		(stroke
			(width 0.0508)
			(type default)
		)
		(layer "F.Cu")
	)
	(gr_line
		(start 333.97952 -387.19633)
		(end 334.1243 -387.25602)
		(stroke
			(width 0.0508)
			(type default)
		)
		(layer "F.Cu")
	)
	(gr_line
		(start 334.008222 -384.17119)
		(end 334.16494 -384.17119)
		(stroke
			(width 0.0508)
			(type default)
		)
		(layer "F.Cu")
	)
	(gr_line
		(start 334.025494 -395.913102)
		(end 334.629252 -395.913102)
		(stroke
			(width 0.0508)
			(type default)
		)
		(layer "F.Cu")
	)
	(gr_line
		(start 334.026764 -396.130272)
		(end 334.109568 -396.213076)
		(stroke
			(width 0.0508)
			(type default)
		)
		(layer "F.Cu")
	)
	(gr_line
		(start 334.108044 -377.41733)
		(end 333.837534 -377.68784)
		(stroke
			(width 0.06477)
			(type default)
		)
		(layer "F.Cu")
	)
	(gr_line
		(start 334.123284 -386.68579)
		(end 334.325468 -387.174232)
		(stroke
			(width 0.0508)
			(type default)
		)
		(layer "F.Cu")
	)
	(gr_line
		(start 334.133444 -379.22073)
		(end 333.784194 -379.56998)
		(stroke
			(width 0.0508)
			(type default)
		)
		(layer "F.Cu")
	)
	(gr_line
		(start 334.16494 -384.17119)
		(end 334.38084 -384.38709)
		(stroke
			(width 0.0508)
			(type default)
		)
		(layer "F.Cu")
	)
	(gr_line
		(start 334.38084 -384.38709)
		(end 334.38084 -384.543808)
		(stroke
			(width 0.0508)
			(type default)
		)
		(layer "F.Cu")
	)
	(gr_line
		(start 334.400906 -417.166044)
		(end 334.696816 -417.461954)
		(stroke
			(width 0.06477)
			(type default)
		)
		(layer "F.Cu")
	)
	(gr_line
		(start 334.40751 -388.01167)
		(end 334.576928 -388.265162)
		(stroke
			(width 0.0508)
			(type default)
		)
		(layer "F.Cu")
	)
	(gr_line
		(start 334.426306 -412.84652)
		(end 334.696816 -413.11703)
		(stroke
			(width 0.06477)
			(type default)
		)
		(layer "F.Cu")
	)
	(gr_line
		(start 334.43799 -387.858)
		(end 334.40751 -388.01167)
		(stroke
			(width 0.0508)
			(type default)
		)
		(layer "F.Cu")
	)
	(gr_line
		(start 334.566768 -381.303022)
		(end 334.940656 -381.676656)
		(stroke
			(width 0.0508)
			(type default)
		)
		(layer "F.Cu")
	)
	(gr_line
		(start 334.576928 -388.265162)
		(end 334.730598 -388.295896)
		(stroke
			(width 0.0508)
			(type default)
		)
		(layer "F.Cu")
	)
	(gr_line
		(start 334.617822 -387.736588)
		(end 334.618076 -387.736588)
		(stroke
			(width 0.0508)
			(type default)
		)
		(layer "F.Cu")
	)
	(gr_line
		(start 334.618076 -387.736588)
		(end 334.9117 -388.176008)
		(stroke
			(width 0.0508)
			(type default)
		)
		(layer "F.Cu")
	)
	(gr_line
		(start 334.696816 -420.681658)
		(end 334.426306 -420.952168)
		(stroke
			(width 0.06477)
			(type default)
		)
		(layer "F.Cu")
	)
	(gr_line
		(start 334.696816 -416.336734)
		(end 334.400906 -416.632644)
		(stroke
			(width 0.06477)
			(type default)
		)
		(layer "F.Cu")
	)
	(gr_line
		(start 334.7212 -381.150114)
		(end 334.877664 -381.150114)
		(stroke
			(width 0.0508)
			(type default)
		)
		(layer "F.Cu")
	)
	(gr_line
		(start 334.877664 -381.150114)
		(end 335.093564 -381.366014)
		(stroke
			(width 0.0508)
			(type default)
		)
		(layer "F.Cu")
	)
	(gr_line
		(start 334.9117 -388.176008)
		(end 334.9117 -388.176262)
		(stroke
			(width 0.0508)
			(type default)
		)
		(layer "F.Cu")
	)
	(gr_line
		(start 334.940656 -381.676656)
		(end 334.940656 -381.67691)
		(stroke
			(width 0.0508)
			(type default)
		)
		(layer "F.Cu")
	)
	(gr_line
		(start 335.019396 -420.681658)
		(end 335.289906 -420.952168)
		(stroke
			(width 0.06477)
			(type default)
		)
		(layer "F.Cu")
	)
	(gr_line
		(start 335.019396 -416.336734)
		(end 335.315306 -416.632644)
		(stroke
			(width 0.06477)
			(type default)
		)
		(layer "F.Cu")
	)
	(gr_line
		(start 335.093564 -381.366014)
		(end 335.093564 -381.522478)
		(stroke
			(width 0.0508)
			(type default)
		)
		(layer "F.Cu")
	)
	(gr_line
		(start 335.289906 -412.84652)
		(end 335.019396 -413.11703)
		(stroke
			(width 0.06477)
			(type default)
		)
		(layer "F.Cu")
	)
	(gr_line
		(start 335.315306 -417.166044)
		(end 335.019396 -417.461954)
		(stroke
			(width 0.06477)
			(type default)
		)
		(layer "F.Cu")
	)
	(gr_line
		(start 335.3435 -391.88771)
		(end 335.434686 -391.978896)
		(stroke
			(width 0.0508)
			(type default)
		)
		(layer "F.Cu")
	)
	(gr_line
		(start 335.3435 -391.6172)
		(end 335.3435 -391.88771)
		(stroke
			(width 0.0508)
			(type default)
		)
		(layer "F.Cu")
	)
	(gr_line
		(start 335.434686 -391.978896)
		(end 335.569052 -391.978896)
		(stroke
			(width 0.0508)
			(type default)
		)
		(layer "F.Cu")
	)
	(gr_line
		(start 335.569052 -391.978896)
		(end 335.645506 -391.902442)
		(stroke
			(width 0.0508)
			(type default)
		)
		(layer "F.Cu")
	)
	(gr_line
		(start 335.634838 -391.325862)
		(end 335.3435 -391.6172)
		(stroke
			(width 0.0508)
			(type default)
		)
		(layer "F.Cu")
	)
	(gr_line
		(start 335.645506 -391.902442)
		(end 335.645506 -391.784586)
		(stroke
			(width 0.0508)
			(type default)
		)
		(layer "F.Cu")
	)
	(gr_line
		(start 335.728818 -399.74647)
		(end 335.645506 -399.663158)
		(stroke
			(width 0.0508)
			(type default)
		)
		(layer "F.Cu")
	)
	(gr_line
		(start 335.79816 -397.156432)
		(end 336.31886 -397.156432)
		(stroke
			(width 0.0635)
			(type default)
		)
		(layer "F.Cu")
	)
	(gr_line
		(start 335.79816 -393.69238)
		(end 336.31886 -393.69238)
		(stroke
			(width 0.0635)
			(type default)
		)
		(layer "F.Cu")
	)
	(gr_line
		(start 335.852008 -391.51941)
		(end 335.94548 -391.612882)
		(stroke
			(width 0.0508)
			(type default)
		)
		(layer "F.Cu")
	)
	(gr_line
		(start 335.852008 -391.324592)
		(end 335.852008 -391.51941)
		(stroke
			(width 0.0508)
			(type default)
		)
		(layer "F.Cu")
	)
	(gr_line
		(start 335.94548 -391.612882)
		(end 335.94548 -392.30427)
		(stroke
			(width 0.0508)
			(type default)
		)
		(layer "F.Cu")
	)
	(gr_line
		(start 335.945988 -399.74774)
		(end 335.945988 -399.143982)
		(stroke
			(width 0.0508)
			(type default)
		)
		(layer "F.Cu")
	)
	(gr_line
		(start 335.945988 -399.143982)
		(end 335.94548 -399.143474)
		(stroke
			(width 0.0508)
			(type default)
		)
		(layer "F.Cu")
	)
	(gr_line
		(start 336.19821 -397.849344)
		(end 336.71891 -397.849344)
		(stroke
			(width 0.0635)
			(type default)
		)
		(layer "F.Cu")
	)
	(gr_line
		(start 336.19821 -394.385292)
		(end 336.71891 -394.385292)
		(stroke
			(width 0.0635)
			(type default)
		)
		(layer "F.Cu")
	)
	(gr_line
		(start 336.205322 -401.359116)
		(end 336.20329 -401.359116)
		(stroke
			(width 0.0508)
			(type default)
		)
		(layer "F.Cu")
	)
	(gr_line
		(start 336.344006 -401.674838)
		(end 336.344006 -401.4978)
		(stroke
			(width 0.0508)
			(type default)
		)
		(layer "F.Cu")
	)
	(gr_line
		(start 336.344006 -401.4978)
		(end 336.205322 -401.359116)
		(stroke
			(width 0.0508)
			(type default)
		)
		(layer "F.Cu")
	)
	(gr_line
		(start 336.344006 -401.0025)
		(end 336.20456 -401.141946)
		(stroke
			(width 0.0508)
			(type default)
		)
		(layer "F.Cu")
	)
	(gr_line
		(start 336.344006 -400.811238)
		(end 336.344006 -401.0025)
		(stroke
			(width 0.0508)
			(type default)
		)
		(layer "F.Cu")
	)
	(gr_line
		(start 336.543396 -391.88771)
		(end 336.634582 -391.978896)
		(stroke
			(width 0.0508)
			(type default)
		)
		(layer "F.Cu")
	)
	(gr_line
		(start 336.543396 -391.6172)
		(end 336.543396 -391.88771)
		(stroke
			(width 0.0508)
			(type default)
		)
		(layer "F.Cu")
	)
	(gr_line
		(start 336.622644 -384.14833)
		(end 336.971894 -384.49758)
		(stroke
			(width 0.0508)
			(type default)
		)
		(layer "F.Cu")
	)
	(gr_line
		(start 336.634582 -391.978896)
		(end 336.768948 -391.978896)
		(stroke
			(width 0.0508)
			(type default)
		)
		(layer "F.Cu")
	)
	(gr_line
		(start 336.648044 -382.34493)
		(end 336.918554 -382.61544)
		(stroke
			(width 0.06477)
			(type default)
		)
		(layer "F.Cu")
	)
	(gr_line
		(start 336.768948 -391.978896)
		(end 336.845402 -391.902442)
		(stroke
			(width 0.0508)
			(type default)
		)
		(layer "F.Cu")
	)
	(gr_line
		(start 336.834734 -391.325862)
		(end 336.543396 -391.6172)
		(stroke
			(width 0.0508)
			(type default)
		)
		(layer "F.Cu")
	)
	(gr_line
		(start 336.845402 -391.902442)
		(end 336.845402 -391.784586)
		(stroke
			(width 0.0508)
			(type default)
		)
		(layer "F.Cu")
	)
	(gr_line
		(start 336.918554 -383.31902)
		(end 336.622644 -383.61493)
		(stroke
			(width 0.06477)
			(type default)
		)
		(layer "F.Cu")
	)
	(gr_line
		(start 336.928714 -399.74647)
		(end 336.845402 -399.663158)
		(stroke
			(width 0.0508)
			(type default)
		)
		(layer "F.Cu")
	)
	(gr_line
		(start 336.998056 -397.156432)
		(end 337.518756 -397.156432)
		(stroke
			(width 0.0635)
			(type default)
		)
		(layer "F.Cu")
	)
	(gr_line
		(start 336.998056 -393.69238)
		(end 337.518756 -393.69238)
		(stroke
			(width 0.0635)
			(type default)
		)
		(layer "F.Cu")
	)
	(gr_line
		(start 337.051904 -391.51941)
		(end 337.145376 -391.612882)
		(stroke
			(width 0.0508)
			(type default)
		)
		(layer "F.Cu")
	)
	(gr_line
		(start 337.051904 -391.324592)
		(end 337.051904 -391.51941)
		(stroke
			(width 0.0508)
			(type default)
		)
		(layer "F.Cu")
	)
	(gr_line
		(start 337.145376 -391.612882)
		(end 337.145376 -392.30427)
		(stroke
			(width 0.0508)
			(type default)
		)
		(layer "F.Cu")
	)
	(gr_line
		(start 337.145884 -399.74774)
		(end 337.145884 -399.143982)
		(stroke
			(width 0.0508)
			(type default)
		)
		(layer "F.Cu")
	)
	(gr_line
		(start 337.145884 -399.143982)
		(end 337.145376 -399.143474)
		(stroke
			(width 0.0508)
			(type default)
		)
		(layer "F.Cu")
	)
	(gr_line
		(start 337.241134 -383.31902)
		(end 337.537044 -383.61493)
		(stroke
			(width 0.06477)
			(type default)
		)
		(layer "F.Cu")
	)
	(gr_line
		(start 337.398106 -397.849344)
		(end 337.918806 -397.849344)
		(stroke
			(width 0.0635)
			(type default)
		)
		(layer "F.Cu")
	)
	(gr_line
		(start 337.398106 -394.385292)
		(end 337.918806 -394.385292)
		(stroke
			(width 0.0635)
			(type default)
		)
		(layer "F.Cu")
	)
	(gr_line
		(start 337.405218 -401.359116)
		(end 337.403186 -401.359116)
		(stroke
			(width 0.0508)
			(type default)
		)
		(layer "F.Cu")
	)
	(gr_line
		(start 337.464146 -417.166044)
		(end 337.760056 -417.461954)
		(stroke
			(width 0.06477)
			(type default)
		)
		(layer "F.Cu")
	)
	(gr_line
		(start 337.489546 -412.84652)
		(end 337.760056 -413.11703)
		(stroke
			(width 0.06477)
			(type default)
		)
		(layer "F.Cu")
	)
	(gr_line
		(start 337.511644 -382.34493)
		(end 337.241134 -382.61544)
		(stroke
			(width 0.06477)
			(type default)
		)
		(layer "F.Cu")
	)
	(gr_line
		(start 337.537044 -384.14833)
		(end 337.187794 -384.49758)
		(stroke
			(width 0.0508)
			(type default)
		)
		(layer "F.Cu")
	)
	(gr_line
		(start 337.543902 -401.674838)
		(end 337.543902 -401.4978)
		(stroke
			(width 0.0508)
			(type default)
		)
		(layer "F.Cu")
	)
	(gr_line
		(start 337.543902 -401.4978)
		(end 337.405218 -401.359116)
		(stroke
			(width 0.0508)
			(type default)
		)
		(layer "F.Cu")
	)
	(gr_line
		(start 337.543902 -401.0025)
		(end 337.404456 -401.141946)
		(stroke
			(width 0.0508)
			(type default)
		)
		(layer "F.Cu")
	)
	(gr_line
		(start 337.543902 -400.811238)
		(end 337.543902 -401.0025)
		(stroke
			(width 0.0508)
			(type default)
		)
		(layer "F.Cu")
	)
	(gr_line
		(start 337.743546 -391.88771)
		(end 337.834732 -391.978896)
		(stroke
			(width 0.0508)
			(type default)
		)
		(layer "F.Cu")
	)
	(gr_line
		(start 337.743546 -391.6172)
		(end 337.743546 -391.88771)
		(stroke
			(width 0.0508)
			(type default)
		)
		(layer "F.Cu")
	)
	(gr_line
		(start 337.760056 -420.681658)
		(end 337.489546 -420.952168)
		(stroke
			(width 0.06477)
			(type default)
		)
		(layer "F.Cu")
	)
	(gr_line
		(start 337.760056 -416.336734)
		(end 337.464146 -416.632644)
		(stroke
			(width 0.06477)
			(type default)
		)
		(layer "F.Cu")
	)
	(gr_line
		(start 337.778598 -385.988814)
		(end 338.114132 -386.397754)
		(stroke
			(width 0.0508)
			(type default)
		)
		(layer "F.Cu")
	)
	(gr_line
		(start 337.834732 -391.978896)
		(end 337.969098 -391.978896)
		(stroke
			(width 0.0508)
			(type default)
		)
		(layer "F.Cu")
	)
	(gr_line
		(start 337.947254 -385.852162)
		(end 338.102702 -385.867402)
		(stroke
			(width 0.0508)
			(type default)
		)
		(layer "F.Cu")
	)
	(gr_line
		(start 337.969098 -391.978896)
		(end 338.045552 -391.902442)
		(stroke
			(width 0.0508)
			(type default)
		)
		(layer "F.Cu")
	)
	(gr_line
		(start 338.034884 -391.325862)
		(end 337.743546 -391.6172)
		(stroke
			(width 0.0508)
			(type default)
		)
		(layer "F.Cu")
	)
	(gr_line
		(start 338.045552 -391.902442)
		(end 338.045552 -391.784586)
		(stroke
			(width 0.0508)
			(type default)
		)
		(layer "F.Cu")
	)
	(gr_line
		(start 338.082636 -420.681658)
		(end 338.353146 -420.952168)
		(stroke
			(width 0.06477)
			(type default)
		)
		(layer "F.Cu")
	)
	(gr_line
		(start 338.082636 -416.336734)
		(end 338.378546 -416.632644)
		(stroke
			(width 0.06477)
			(type default)
		)
		(layer "F.Cu")
	)
	(gr_line
		(start 338.102702 -385.867402)
		(end 338.29625 -386.103114)
		(stroke
			(width 0.0508)
			(type default)
		)
		(layer "F.Cu")
	)
	(gr_line
		(start 338.128864 -399.74647)
		(end 338.045552 -399.663158)
		(stroke
			(width 0.0508)
			(type default)
		)
		(layer "F.Cu")
	)
	(gr_line
		(start 338.198206 -397.156432)
		(end 338.718906 -397.156432)
		(stroke
			(width 0.0635)
			(type default)
		)
		(layer "F.Cu")
	)
	(gr_line
		(start 338.198206 -393.69238)
		(end 338.718906 -393.69238)
		(stroke
			(width 0.0635)
			(type default)
		)
		(layer "F.Cu")
	)
	(gr_line
		(start 338.252054 -391.51941)
		(end 338.345526 -391.612882)
		(stroke
			(width 0.0508)
			(type default)
		)
		(layer "F.Cu")
	)
	(gr_line
		(start 338.252054 -391.324592)
		(end 338.252054 -391.51941)
		(stroke
			(width 0.0508)
			(type default)
		)
		(layer "F.Cu")
	)
	(gr_line
		(start 338.29625 -386.103114)
		(end 338.281264 -386.25907)
		(stroke
			(width 0.0508)
			(type default)
		)
		(layer "F.Cu")
	)
	(gr_line
		(start 338.324444 -381.68453)
		(end 338.673694 -382.03378)
		(stroke
			(width 0.0508)
			(type default)
		)
		(layer "F.Cu")
	)
	(gr_line
		(start 338.345526 -391.612882)
		(end 338.345526 -392.30427)
		(stroke
			(width 0.0508)
			(type default)
		)
		(layer "F.Cu")
	)
	(gr_line
		(start 338.346034 -399.74774)
		(end 338.346034 -399.143982)
		(stroke
			(width 0.0508)
			(type default)
		)
		(layer "F.Cu")
	)
	(gr_line
		(start 338.346034 -399.143982)
		(end 338.345526 -399.143474)
		(stroke
			(width 0.0508)
			(type default)
		)
		(layer "F.Cu")
	)
	(gr_line
		(start 338.349844 -379.88113)
		(end 338.620354 -380.15164)
		(stroke
			(width 0.06477)
			(type default)
		)
		(layer "F.Cu")
	)
	(gr_line
		(start 338.353146 -412.84652)
		(end 338.082636 -413.11703)
		(stroke
			(width 0.06477)
			(type default)
		)
		(layer "F.Cu")
	)
	(gr_line
		(start 338.378546 -417.166044)
		(end 338.082636 -417.461954)
		(stroke
			(width 0.06477)
			(type default)
		)
		(layer "F.Cu")
	)
	(gr_line
		(start 338.598002 -397.849344)
		(end 339.118702 -397.849344)
		(stroke
			(width 0.0635)
			(type default)
		)
		(layer "F.Cu")
	)
	(gr_line
		(start 338.598002 -394.385292)
		(end 339.118702 -394.385292)
		(stroke
			(width 0.0635)
			(type default)
		)
		(layer "F.Cu")
	)
	(gr_line
		(start 338.605368 -401.359116)
		(end 338.603336 -401.359116)
		(stroke
			(width 0.0508)
			(type default)
		)
		(layer "F.Cu")
	)
	(gr_line
		(start 338.620354 -380.85522)
		(end 338.324444 -381.15113)
		(stroke
			(width 0.06477)
			(type default)
		)
		(layer "F.Cu")
	)
	(gr_line
		(start 338.673694 -382.911096)
		(end 338.673694 -383.439416)
		(stroke
			(width 0.0508)
			(type default)
		)
		(layer "F.Cu")
	)
	(gr_line
		(start 338.744052 -401.674838)
		(end 338.744052 -401.4978)
		(stroke
			(width 0.0508)
			(type default)
		)
		(layer "F.Cu")
	)
	(gr_line
		(start 338.744052 -401.4978)
		(end 338.605368 -401.359116)
		(stroke
			(width 0.0508)
			(type default)
		)
		(layer "F.Cu")
	)
	(gr_line
		(start 338.744052 -401.0025)
		(end 338.604606 -401.141946)
		(stroke
			(width 0.0508)
			(type default)
		)
		(layer "F.Cu")
	)
	(gr_line
		(start 338.744052 -400.811238)
		(end 338.744052 -401.0025)
		(stroke
			(width 0.0508)
			(type default)
		)
		(layer "F.Cu")
	)
	(gr_line
		(start 338.871052 -295.145968)
		(end 339.337904 -294.88003)
		(stroke
			(width 0.06477)
			(type default)
		)
		(layer "F.Cu")
	)
	(gr_line
		(start 338.880958 -217.867992)
		(end 338.534248 -217.521282)
		(stroke
			(width 0.06477)
			(type default)
		)
		(layer "F.Cu")
	)
	(gr_line
		(start 338.890864 -382.912366)
		(end 339.001354 -383.022856)
		(stroke
			(width 0.0508)
			(type default)
		)
		(layer "F.Cu")
	)
	(gr_line
		(start 338.942934 -380.85522)
		(end 339.238844 -381.15113)
		(stroke
			(width 0.06477)
			(type default)
		)
		(layer "F.Cu")
	)
	(gr_line
		(start 338.943442 -391.88771)
		(end 339.034628 -391.978896)
		(stroke
			(width 0.0508)
			(type default)
		)
		(layer "F.Cu")
	)
	(gr_line
		(start 338.943442 -391.6172)
		(end 338.943442 -391.88771)
		(stroke
			(width 0.0508)
			(type default)
		)
		(layer "F.Cu")
	)
	(gr_line
		(start 339.001354 -383.327656)
		(end 338.890864 -383.438146)
		(stroke
			(width 0.0508)
			(type default)
		)
		(layer "F.Cu")
	)
	(gr_line
		(start 339.001354 -383.022856)
		(end 339.001354 -383.327656)
		(stroke
			(width 0.0508)
			(type default)
		)
		(layer "F.Cu")
	)
	(gr_line
		(start 339.034628 -391.978896)
		(end 339.168994 -391.978896)
		(stroke
			(width 0.0508)
			(type default)
		)
		(layer "F.Cu")
	)
	(gr_line
		(start 339.168994 -391.978896)
		(end 339.245448 -391.902442)
		(stroke
			(width 0.0508)
			(type default)
		)
		(layer "F.Cu")
	)
	(gr_line
		(start 339.213444 -379.88113)
		(end 338.942934 -380.15164)
		(stroke
			(width 0.06477)
			(type default)
		)
		(layer "F.Cu")
	)
	(gr_line
		(start 339.23478 -391.325862)
		(end 338.943442 -391.6172)
		(stroke
			(width 0.0508)
			(type default)
		)
		(layer "F.Cu")
	)
	(gr_line
		(start 339.238844 -381.68453)
		(end 338.889594 -382.03378)
		(stroke
			(width 0.0508)
			(type default)
		)
		(layer "F.Cu")
	)
	(gr_line
		(start 339.245448 -391.902442)
		(end 339.245448 -391.784586)
		(stroke
			(width 0.0508)
			(type default)
		)
		(layer "F.Cu")
	)
	(gr_line
		(start 339.32876 -399.74647)
		(end 339.245448 -399.663158)
		(stroke
			(width 0.0508)
			(type default)
		)
		(layer "F.Cu")
	)
	(gr_line
		(start 339.398102 -397.156432)
		(end 339.918802 -397.156432)
		(stroke
			(width 0.0635)
			(type default)
		)
		(layer "F.Cu")
	)
	(gr_line
		(start 339.398102 -393.69238)
		(end 339.918802 -393.69238)
		(stroke
			(width 0.0635)
			(type default)
		)
		(layer "F.Cu")
	)
	(gr_line
		(start 339.45195 -391.51941)
		(end 339.545422 -391.612882)
		(stroke
			(width 0.0508)
			(type default)
		)
		(layer "F.Cu")
	)
	(gr_line
		(start 339.45195 -391.324592)
		(end 339.45195 -391.51941)
		(stroke
			(width 0.0508)
			(type default)
		)
		(layer "F.Cu")
	)
	(gr_line
		(start 339.545422 -391.612882)
		(end 339.545422 -392.30427)
		(stroke
			(width 0.0508)
			(type default)
		)
		(layer "F.Cu")
	)
	(gr_line
		(start 339.54593 -399.74774)
		(end 339.54593 -399.143982)
		(stroke
			(width 0.0508)
			(type default)
		)
		(layer "F.Cu")
	)
	(gr_line
		(start 339.54593 -399.143982)
		(end 339.545422 -399.143474)
		(stroke
			(width 0.0508)
			(type default)
		)
		(layer "F.Cu")
	)
	(gr_line
		(start 339.550248 -217.521282)
		(end 339.203538 -217.867992)
		(stroke
			(width 0.06477)
			(type default)
		)
		(layer "F.Cu")
	)
	(gr_line
		(start 339.798152 -397.849344)
		(end 340.318852 -397.849344)
		(stroke
			(width 0.0635)
			(type default)
		)
		(layer "F.Cu")
	)
	(gr_line
		(start 339.798152 -394.385292)
		(end 340.318852 -394.385292)
		(stroke
			(width 0.0635)
			(type default)
		)
		(layer "F.Cu")
	)
	(gr_line
		(start 339.805264 -401.359116)
		(end 339.803232 -401.359116)
		(stroke
			(width 0.0508)
			(type default)
		)
		(layer "F.Cu")
	)
	(gr_line
		(start 339.808058 -295.690036)
		(end 339.341206 -295.955974)
		(stroke
			(width 0.06477)
			(type default)
		)
		(layer "F.Cu")
	)
	(gr_line
		(start 339.943948 -401.674838)
		(end 339.943948 -401.4978)
		(stroke
			(width 0.0508)
			(type default)
		)
		(layer "F.Cu")
	)
	(gr_line
		(start 339.943948 -401.4978)
		(end 339.805264 -401.359116)
		(stroke
			(width 0.0508)
			(type default)
		)
		(layer "F.Cu")
	)
	(gr_line
		(start 339.943948 -401.0025)
		(end 339.804502 -401.141946)
		(stroke
			(width 0.0508)
			(type default)
		)
		(layer "F.Cu")
	)
	(gr_line
		(start 339.943948 -400.811238)
		(end 339.943948 -401.0025)
		(stroke
			(width 0.0508)
			(type default)
		)
		(layer "F.Cu")
	)
	(gr_line
		(start 340.026244 -379.22073)
		(end 340.375494 -379.56998)
		(stroke
			(width 0.0508)
			(type default)
		)
		(layer "F.Cu")
	)
	(gr_line
		(start 340.051644 -377.41733)
		(end 340.322154 -377.68784)
		(stroke
			(width 0.06477)
			(type default)
		)
		(layer "F.Cu")
	)
	(gr_line
		(start 340.143592 -391.88771)
		(end 340.234778 -391.978896)
		(stroke
			(width 0.0508)
			(type default)
		)
		(layer "F.Cu")
	)
	(gr_line
		(start 340.143592 -391.6172)
		(end 340.143592 -391.88771)
		(stroke
			(width 0.0508)
			(type default)
		)
		(layer "F.Cu")
	)
	(gr_line
		(start 340.234778 -391.978896)
		(end 340.369144 -391.978896)
		(stroke
			(width 0.0508)
			(type default)
		)
		(layer "F.Cu")
	)
	(gr_line
		(start 340.322154 -378.39142)
		(end 340.026244 -378.68733)
		(stroke
			(width 0.06477)
			(type default)
		)
		(layer "F.Cu")
	)
	(gr_line
		(start 340.369144 -391.978896)
		(end 340.445598 -391.902442)
		(stroke
			(width 0.0508)
			(type default)
		)
		(layer "F.Cu")
	)
	(gr_line
		(start 340.43493 -391.325862)
		(end 340.143592 -391.6172)
		(stroke
			(width 0.0508)
			(type default)
		)
		(layer "F.Cu")
	)
	(gr_line
		(start 340.445598 -391.902442)
		(end 340.445598 -391.784586)
		(stroke
			(width 0.0508)
			(type default)
		)
		(layer "F.Cu")
	)
	(gr_line
		(start 340.527386 -417.166044)
		(end 340.823296 -417.461954)
		(stroke
			(width 0.06477)
			(type default)
		)
		(layer "F.Cu")
	)
	(gr_line
		(start 340.52891 -399.74647)
		(end 340.445598 -399.663158)
		(stroke
			(width 0.0508)
			(type default)
		)
		(layer "F.Cu")
	)
	(gr_line
		(start 340.552786 -412.84652)
		(end 340.823296 -413.11703)
		(stroke
			(width 0.06477)
			(type default)
		)
		(layer "F.Cu")
	)
	(gr_line
		(start 340.597998 -397.156432)
		(end 341.118698 -397.156432)
		(stroke
			(width 0.0635)
			(type default)
		)
		(layer "F.Cu")
	)
	(gr_line
		(start 340.597998 -393.69238)
		(end 341.118698 -393.69238)
		(stroke
			(width 0.0635)
			(type default)
		)
		(layer "F.Cu")
	)
	(gr_line
		(start 340.644734 -378.39142)
		(end 340.940644 -378.68733)
		(stroke
			(width 0.06477)
			(type default)
		)
		(layer "F.Cu")
	)
	(gr_line
		(start 340.6521 -391.51941)
		(end 340.745572 -391.612882)
		(stroke
			(width 0.0508)
			(type default)
		)
		(layer "F.Cu")
	)
	(gr_line
		(start 340.6521 -391.324592)
		(end 340.6521 -391.51941)
		(stroke
			(width 0.0508)
			(type default)
		)
		(layer "F.Cu")
	)
	(gr_arc
		(start 340.6521 -389.9535)
		(mid 340.6521 -389.953881)
		(end 340.6521 -389.954262)
		(stroke
			(width 0.0508)
			(type default)
		)
		(layer "F.Cu")
	)
	(gr_line
		(start 340.745572 -391.612882)
		(end 340.745572 -392.30427)
		(stroke
			(width 0.0508)
			(type default)
		)
		(layer "F.Cu")
	)
	(gr_line
		(start 340.74608 -399.74774)
		(end 340.74608 -399.143982)
		(stroke
			(width 0.0508)
			(type default)
		)
		(layer "F.Cu")
	)
	(gr_line
		(start 340.74608 -399.143982)
		(end 340.745572 -399.143474)
		(stroke
			(width 0.0508)
			(type default)
		)
		(layer "F.Cu")
	)
	(gr_line
		(start 340.823296 -420.681658)
		(end 340.552786 -420.952168)
		(stroke
			(width 0.06477)
			(type default)
		)
		(layer "F.Cu")
	)
	(gr_line
		(start 340.823296 -416.336734)
		(end 340.527386 -416.632644)
		(stroke
			(width 0.06477)
			(type default)
		)
		(layer "F.Cu")
	)
	(gr_line
		(start 340.915244 -377.41733)
		(end 340.644734 -377.68784)
		(stroke
			(width 0.06477)
			(type default)
		)
		(layer "F.Cu")
	)
	(gr_line
		(start 340.924642 -299.823124)
		(end 340.600792 -300.146974)
		(stroke
			(width 0.06477)
			(type default)
		)
		(layer "F.Cu")
	)
	(gr_line
		(start 340.940644 -379.22073)
		(end 340.591394 -379.56998)
		(stroke
			(width 0.0508)
			(type default)
		)
		(layer "F.Cu")
	)
	(gr_line
		(start 340.969092 -299.499274)
		(end 340.600792 -299.130974)
		(stroke
			(width 0.06477)
			(type default)
		)
		(layer "F.Cu")
	)
	(gr_line
		(start 340.970362 -299.823124)
		(end 340.924642 -299.823124)
		(stroke
			(width 0.06477)
			(type default)
		)
		(layer "F.Cu")
	)
	(gr_line
		(start 340.998048 -397.849344)
		(end 341.518748 -397.849344)
		(stroke
			(width 0.0635)
			(type default)
		)
		(layer "F.Cu")
	)
	(gr_line
		(start 340.998048 -394.385292)
		(end 341.518748 -394.385292)
		(stroke
			(width 0.0635)
			(type default)
		)
		(layer "F.Cu")
	)
	(gr_line
		(start 341.005414 -401.359116)
		(end 341.003382 -401.359116)
		(stroke
			(width 0.0508)
			(type default)
		)
		(layer "F.Cu")
	)
	(gr_line
		(start 341.144098 -401.674838)
		(end 341.144098 -401.4978)
		(stroke
			(width 0.0508)
			(type default)
		)
		(layer "F.Cu")
	)
	(gr_line
		(start 341.144098 -401.4978)
		(end 341.005414 -401.359116)
		(stroke
			(width 0.0508)
			(type default)
		)
		(layer "F.Cu")
	)
	(gr_line
		(start 341.144098 -401.0025)
		(end 341.004652 -401.141946)
		(stroke
			(width 0.0508)
			(type default)
		)
		(layer "F.Cu")
	)
	(gr_line
		(start 341.144098 -400.811238)
		(end 341.144098 -401.0025)
		(stroke
			(width 0.0508)
			(type default)
		)
		(layer "F.Cu")
	)
	(gr_line
		(start 341.145876 -420.681658)
		(end 341.416386 -420.952168)
		(stroke
			(width 0.06477)
			(type default)
		)
		(layer "F.Cu")
	)
	(gr_line
		(start 341.145876 -416.336734)
		(end 341.441786 -416.632644)
		(stroke
			(width 0.06477)
			(type default)
		)
		(layer "F.Cu")
	)
	(gr_line
		(start 341.343488 -391.88771)
		(end 341.434674 -391.978896)
		(stroke
			(width 0.0508)
			(type default)
		)
		(layer "F.Cu")
	)
	(gr_line
		(start 341.343488 -391.6172)
		(end 341.343488 -391.88771)
		(stroke
			(width 0.0508)
			(type default)
		)
		(layer "F.Cu")
	)
	(gr_line
		(start 341.416386 -412.84652)
		(end 341.145876 -413.11703)
		(stroke
			(width 0.06477)
			(type default)
		)
		(layer "F.Cu")
	)
	(gr_line
		(start 341.434674 -391.978896)
		(end 341.56904 -391.978896)
		(stroke
			(width 0.0508)
			(type default)
		)
		(layer "F.Cu")
	)
	(gr_line
		(start 341.441786 -417.166044)
		(end 341.145876 -417.461954)
		(stroke
			(width 0.06477)
			(type default)
		)
		(layer "F.Cu")
	)
	(gr_line
		(start 341.56904 -391.978896)
		(end 341.645494 -391.902442)
		(stroke
			(width 0.0508)
			(type default)
		)
		(layer "F.Cu")
	)
	(gr_line
		(start 341.634826 -391.325862)
		(end 341.343488 -391.6172)
		(stroke
			(width 0.0508)
			(type default)
		)
		(layer "F.Cu")
	)
	(gr_line
		(start 341.645494 -391.902442)
		(end 341.645494 -391.784586)
		(stroke
			(width 0.0508)
			(type default)
		)
		(layer "F.Cu")
	)
	(gr_line
		(start 341.728806 -399.74647)
		(end 341.645494 -399.663158)
		(stroke
			(width 0.0508)
			(type default)
		)
		(layer "F.Cu")
	)
	(gr_line
		(start 341.798148 -397.156432)
		(end 342.318848 -397.156432)
		(stroke
			(width 0.0635)
			(type default)
		)
		(layer "F.Cu")
	)
	(gr_line
		(start 341.798148 -393.69238)
		(end 342.318848 -393.69238)
		(stroke
			(width 0.0635)
			(type default)
		)
		(layer "F.Cu")
	)
	(gr_line
		(start 341.851996 -391.51941)
		(end 341.945468 -391.612882)
		(stroke
			(width 0.0508)
			(type default)
		)
		(layer "F.Cu")
	)
	(gr_line
		(start 341.851996 -391.324592)
		(end 341.851996 -391.51941)
		(stroke
			(width 0.0508)
			(type default)
		)
		(layer "F.Cu")
	)
	(gr_line
		(start 341.945468 -391.612882)
		(end 341.945468 -392.30427)
		(stroke
			(width 0.0508)
			(type default)
		)
		(layer "F.Cu")
	)
	(gr_line
		(start 341.945976 -399.74774)
		(end 341.945976 -399.143982)
		(stroke
			(width 0.0508)
			(type default)
		)
		(layer "F.Cu")
	)
	(gr_line
		(start 341.945976 -399.143982)
		(end 341.945468 -399.143474)
		(stroke
			(width 0.0508)
			(type default)
		)
		(layer "F.Cu")
	)
	(gr_line
		(start 342.09482 -383.231136)
		(end 342.09482 -383.759456)
		(stroke
			(width 0.0508)
			(type default)
		)
		(layer "F.Cu")
	)
	(gr_line
		(start 342.198198 -397.849344)
		(end 342.718898 -397.849344)
		(stroke
			(width 0.0635)
			(type default)
		)
		(layer "F.Cu")
	)
	(gr_line
		(start 342.198198 -394.385292)
		(end 342.718898 -394.385292)
		(stroke
			(width 0.0635)
			(type default)
		)
		(layer "F.Cu")
	)
	(gr_line
		(start 342.20531 -401.359116)
		(end 342.203278 -401.359116)
		(stroke
			(width 0.0508)
			(type default)
		)
		(layer "F.Cu")
	)
	(gr_line
		(start 342.31199 -383.232406)
		(end 342.42248 -383.342896)
		(stroke
			(width 0.0508)
			(type default)
		)
		(layer "F.Cu")
	)
	(gr_line
		(start 342.343994 -401.674838)
		(end 342.343994 -401.4978)
		(stroke
			(width 0.0508)
			(type default)
		)
		(layer "F.Cu")
	)
	(gr_line
		(start 342.343994 -401.4978)
		(end 342.20531 -401.359116)
		(stroke
			(width 0.0508)
			(type default)
		)
		(layer "F.Cu")
	)
	(gr_line
		(start 342.343994 -401.0025)
		(end 342.204548 -401.141946)
		(stroke
			(width 0.0508)
			(type default)
		)
		(layer "F.Cu")
	)
	(gr_line
		(start 342.343994 -400.811238)
		(end 342.343994 -401.0025)
		(stroke
			(width 0.0508)
			(type default)
		)
		(layer "F.Cu")
	)
	(gr_line
		(start 342.42248 -383.647696)
		(end 342.31199 -383.758186)
		(stroke
			(width 0.0508)
			(type default)
		)
		(layer "F.Cu")
	)
	(gr_line
		(start 342.42248 -383.342896)
		(end 342.42248 -383.647696)
		(stroke
			(width 0.0508)
			(type default)
		)
		(layer "F.Cu")
	)
	(gr_line
		(start 342.543384 -391.88771)
		(end 342.63457 -391.978896)
		(stroke
			(width 0.0508)
			(type default)
		)
		(layer "F.Cu")
	)
	(gr_line
		(start 342.543384 -391.6172)
		(end 342.543384 -391.88771)
		(stroke
			(width 0.0508)
			(type default)
		)
		(layer "F.Cu")
	)
	(gr_line
		(start 342.63457 -391.978896)
		(end 342.768936 -391.978896)
		(stroke
			(width 0.0508)
			(type default)
		)
		(layer "F.Cu")
	)
	(gr_line
		(start 342.768936 -391.978896)
		(end 342.84539 -391.902442)
		(stroke
			(width 0.0508)
			(type default)
		)
		(layer "F.Cu")
	)
	(gr_line
		(start 342.834722 -391.325862)
		(end 342.543384 -391.6172)
		(stroke
			(width 0.0508)
			(type default)
		)
		(layer "F.Cu")
	)
	(gr_line
		(start 342.84539 -391.902442)
		(end 342.84539 -391.784586)
		(stroke
			(width 0.0508)
			(type default)
		)
		(layer "F.Cu")
	)
	(gr_line
		(start 342.928956 -399.746724)
		(end 342.84539 -399.663158)
		(stroke
			(width 0.0508)
			(type default)
		)
		(layer "F.Cu")
	)
	(gr_line
		(start 342.998044 -397.156432)
		(end 343.518744 -397.156432)
		(stroke
			(width 0.0635)
			(type default)
		)
		(layer "F.Cu")
	)
	(gr_line
		(start 342.998044 -393.69238)
		(end 343.518744 -393.69238)
		(stroke
			(width 0.0635)
			(type default)
		)
		(layer "F.Cu")
	)
	(gr_line
		(start 343.051892 -391.51941)
		(end 343.145618 -391.613136)
		(stroke
			(width 0.0508)
			(type default)
		)
		(layer "F.Cu")
	)
	(gr_line
		(start 343.051892 -391.324592)
		(end 343.051892 -391.51941)
		(stroke
			(width 0.0508)
			(type default)
		)
		(layer "F.Cu")
	)
	(gr_line
		(start 343.118694 -371.952012)
		(end 342.929464 -372.141242)
		(stroke
			(width 0.06477)
			(type default)
		)
		(layer "F.Cu")
	)
	(gr_line
		(start 343.145618 -391.613136)
		(end 343.145618 -392.30427)
		(stroke
			(width 0.0508)
			(type default)
		)
		(layer "F.Cu")
	)
	(gr_line
		(start 343.146126 -399.747486)
		(end 343.145872 -399.74774)
		(stroke
			(width 0.0508)
			(type default)
		)
		(layer "F.Cu")
	)
	(gr_line
		(start 343.146126 -399.747486)
		(end 343.146126 -399.143982)
		(stroke
			(width 0.0508)
			(type default)
		)
		(layer "F.Cu")
	)
	(gr_line
		(start 343.146126 -399.143982)
		(end 343.145618 -399.143474)
		(stroke
			(width 0.0508)
			(type default)
		)
		(layer "F.Cu")
	)
	(gr_line
		(start 343.398094 -397.849344)
		(end 343.918794 -397.849344)
		(stroke
			(width 0.0635)
			(type default)
		)
		(layer "F.Cu")
	)
	(gr_line
		(start 343.398094 -394.385292)
		(end 343.918794 -394.385292)
		(stroke
			(width 0.0635)
			(type default)
		)
		(layer "F.Cu")
	)
	(gr_line
		(start 343.405206 -401.359116)
		(end 343.403428 -401.359116)
		(stroke
			(width 0.0508)
			(type default)
		)
		(layer "F.Cu")
	)
	(gr_line
		(start 343.429844 -384.14833)
		(end 343.731596 -384.450082)
		(stroke
			(width 0.0508)
			(type default)
		)
		(layer "F.Cu")
	)
	(gr_line
		(start 343.455244 -382.34493)
		(end 343.725754 -382.61544)
		(stroke
			(width 0.06477)
			(type default)
		)
		(layer "F.Cu")
	)
	(gr_line
		(start 343.507314 -371.952012)
		(end 343.118694 -371.952012)
		(stroke
			(width 0.06477)
			(type default)
		)
		(layer "F.Cu")
	)
	(gr_line
		(start 343.544144 -401.674838)
		(end 343.544144 -401.498054)
		(stroke
			(width 0.0508)
			(type default)
		)
		(layer "F.Cu")
	)
	(gr_line
		(start 343.544144 -401.498054)
		(end 343.405206 -401.359116)
		(stroke
			(width 0.0508)
			(type default)
		)
		(layer "F.Cu")
	)
	(gr_line
		(start 343.544144 -401.0025)
		(end 343.404698 -401.141946)
		(stroke
			(width 0.0508)
			(type default)
		)
		(layer "F.Cu")
	)
	(gr_line
		(start 343.544144 -400.811238)
		(end 343.544144 -401.0025)
		(stroke
			(width 0.0508)
			(type default)
		)
		(layer "F.Cu")
	)
	(gr_line
		(start 343.590626 -417.166044)
		(end 343.886536 -417.461954)
		(stroke
			(width 0.06477)
			(type default)
		)
		(layer "F.Cu")
	)
	(gr_line
		(start 343.616026 -412.84652)
		(end 343.886536 -413.11703)
		(stroke
			(width 0.06477)
			(type default)
		)
		(layer "F.Cu")
	)
	(gr_line
		(start 343.696544 -372.141242)
		(end 343.507314 -371.952012)
		(stroke
			(width 0.06477)
			(type default)
		)
		(layer "F.Cu")
	)
	(gr_line
		(start 343.697814 -372.465092)
		(end 342.928194 -372.465092)
		(stroke
			(width 0.06477)
			(type default)
		)
		(layer "F.Cu")
	)
	(gr_line
		(start 343.725754 -383.31902)
		(end 343.429844 -383.61493)
		(stroke
			(width 0.06477)
			(type default)
		)
		(layer "F.Cu")
	)
	(gr_line
		(start 343.743534 -391.88771)
		(end 343.83472 -391.978896)
		(stroke
			(width 0.0508)
			(type default)
		)
		(layer "F.Cu")
	)
	(gr_line
		(start 343.743534 -391.6172)
		(end 343.743534 -391.88771)
		(stroke
			(width 0.0508)
			(type default)
		)
		(layer "F.Cu")
	)
	(gr_arc
		(start 343.778078 -384.547872)
		(mid 343.7632 -384.495003)
		(end 343.731596 -384.450082)
		(stroke
			(width 0.0508)
			(type default)
		)
		(layer "F.Cu")
	)
	(gr_line
		(start 343.779094 -385.45643)
		(end 343.779094 -385.98475)
		(stroke
			(width 0.0508)
			(type default)
		)
		(layer "F.Cu")
	)
	(gr_line
		(start 343.83472 -391.978896)
		(end 343.969086 -391.978896)
		(stroke
			(width 0.0508)
			(type default)
		)
		(layer "F.Cu")
	)
	(gr_line
		(start 343.886536 -420.681658)
		(end 343.616026 -420.952168)
		(stroke
			(width 0.06477)
			(type default)
		)
		(layer "F.Cu")
	)
	(gr_line
		(start 343.886536 -416.336734)
		(end 343.590626 -416.632644)
		(stroke
			(width 0.06477)
			(type default)
		)
		(layer "F.Cu")
	)
	(gr_line
		(start 343.969086 -391.978896)
		(end 344.04554 -391.902442)
		(stroke
			(width 0.0508)
			(type default)
		)
		(layer "F.Cu")
	)
	(gr_line
		(start 343.996264 -385.4577)
		(end 344.106754 -385.56819)
		(stroke
			(width 0.0508)
			(type default)
		)
		(layer "F.Cu")
	)
	(gr_line
		(start 344.034872 -391.325862)
		(end 343.743534 -391.6172)
		(stroke
			(width 0.0508)
			(type default)
		)
		(layer "F.Cu")
	)
	(gr_arc
		(start 344.042238 -384.450336)
		(mid 344.010639 -384.494982)
		(end 343.995756 -384.547618)
		(stroke
			(width 0.0508)
			(type default)
		)
		(layer "F.Cu")
	)
	(gr_line
		(start 344.04554 -391.902442)
		(end 344.04554 -391.784586)
		(stroke
			(width 0.0508)
			(type default)
		)
		(layer "F.Cu")
	)
	(gr_line
		(start 344.048334 -383.31902)
		(end 344.344244 -383.61493)
		(stroke
			(width 0.06477)
			(type default)
		)
		(layer "F.Cu")
	)
	(gr_line
		(start 344.106754 -385.87299)
		(end 343.996264 -385.98348)
		(stroke
			(width 0.0508)
			(type default)
		)
		(layer "F.Cu")
	)
	(gr_line
		(start 344.106754 -385.56819)
		(end 344.106754 -385.87299)
		(stroke
			(width 0.0508)
			(type default)
		)
		(layer "F.Cu")
	)
	(gr_line
		(start 344.128852 -399.74647)
		(end 344.04554 -399.663158)
		(stroke
			(width 0.0508)
			(type default)
		)
		(layer "F.Cu")
	)
	(gr_line
		(start 344.198194 -397.156432)
		(end 344.718894 -397.156432)
		(stroke
			(width 0.0635)
			(type default)
		)
		(layer "F.Cu")
	)
	(gr_line
		(start 344.198194 -393.69238)
		(end 344.718894 -393.69238)
		(stroke
			(width 0.0635)
			(type default)
		)
		(layer "F.Cu")
	)
	(gr_line
		(start 344.209116 -420.681658)
		(end 344.479626 -420.952168)
		(stroke
			(width 0.06477)
			(type default)
		)
		(layer "F.Cu")
	)
	(gr_line
		(start 344.209116 -416.336734)
		(end 344.505026 -416.632644)
		(stroke
			(width 0.06477)
			(type default)
		)
		(layer "F.Cu")
	)
	(gr_line
		(start 344.252042 -391.51941)
		(end 344.345514 -391.612882)
		(stroke
			(width 0.0508)
			(type default)
		)
		(layer "F.Cu")
	)
	(gr_line
		(start 344.252042 -391.32383)
		(end 344.252042 -391.51941)
		(stroke
			(width 0.0508)
			(type default)
		)
		(layer "F.Cu")
	)
	(gr_line
		(start 344.276934 -371.952012)
		(end 344.087704 -372.141242)
		(stroke
			(width 0.06477)
			(type default)
		)
		(layer "F.Cu")
	)
	(gr_line
		(start 344.318844 -382.34493)
		(end 344.048334 -382.61544)
		(stroke
			(width 0.06477)
			(type default)
		)
		(layer "F.Cu")
	)
	(gr_line
		(start 344.344244 -384.14833)
		(end 344.042238 -384.450336)
		(stroke
			(width 0.0508)
			(type default)
		)
		(layer "F.Cu")
	)
	(gr_line
		(start 344.345514 -391.612882)
		(end 344.345514 -392.30427)
		(stroke
			(width 0.0508)
			(type default)
		)
		(layer "F.Cu")
	)
	(gr_line
		(start 344.346022 -399.74774)
		(end 344.346022 -399.143982)
		(stroke
			(width 0.0508)
			(type default)
		)
		(layer "F.Cu")
	)
	(gr_line
		(start 344.346022 -399.143982)
		(end 344.345514 -399.143474)
		(stroke
			(width 0.0508)
			(type default)
		)
		(layer "F.Cu")
	)
	(gr_line
		(start 344.479626 -412.84652)
		(end 344.209116 -413.11703)
		(stroke
			(width 0.06477)
			(type default)
		)
		(layer "F.Cu")
	)
	(gr_line
		(start 344.505026 -417.166044)
		(end 344.209116 -417.461954)
		(stroke
			(width 0.06477)
			(type default)
		)
		(layer "F.Cu")
	)
	(gr_line
		(start 344.59799 -397.849344)
		(end 345.11869 -397.849344)
		(stroke
			(width 0.0635)
			(type default)
		)
		(layer "F.Cu")
	)
	(gr_line
		(start 344.59799 -394.385292)
		(end 345.11869 -394.385292)
		(stroke
			(width 0.0635)
			(type default)
		)
		(layer "F.Cu")
	)
	(gr_line
		(start 344.605356 -401.359116)
		(end 344.603324 -401.359116)
		(stroke
			(width 0.0508)
			(type default)
		)
		(layer "F.Cu")
	)
	(gr_line
		(start 344.665554 -371.952012)
		(end 344.276934 -371.952012)
		(stroke
			(width 0.06477)
			(type default)
		)
		(layer "F.Cu")
	)
	(gr_line
		(start 344.74404 -401.674838)
		(end 344.74404 -401.4978)
		(stroke
			(width 0.0508)
			(type default)
		)
		(layer "F.Cu")
	)
	(gr_line
		(start 344.74404 -401.4978)
		(end 344.605356 -401.359116)
		(stroke
			(width 0.0508)
			(type default)
		)
		(layer "F.Cu")
	)
	(gr_line
		(start 344.74404 -401.0025)
		(end 344.604594 -401.141946)
		(stroke
			(width 0.0508)
			(type default)
		)
		(layer "F.Cu")
	)
	(gr_line
		(start 344.74404 -400.811238)
		(end 344.74404 -401.0025)
		(stroke
			(width 0.0508)
			(type default)
		)
		(layer "F.Cu")
	)
	(gr_line
		(start 344.854784 -372.141242)
		(end 344.665554 -371.952012)
		(stroke
			(width 0.06477)
			(type default)
		)
		(layer "F.Cu")
	)
	(gr_line
		(start 344.856054 -372.465092)
		(end 344.086434 -372.465092)
		(stroke
			(width 0.06477)
			(type default)
		)
		(layer "F.Cu")
	)
	(gr_line
		(start 344.94343 -391.88771)
		(end 345.034616 -391.978896)
		(stroke
			(width 0.0508)
			(type default)
		)
		(layer "F.Cu")
	)
	(gr_line
		(start 344.94343 -391.6172)
		(end 344.94343 -391.88771)
		(stroke
			(width 0.0508)
			(type default)
		)
		(layer "F.Cu")
	)
	(gr_line
		(start 344.981022 -294.335962)
		(end 345.447874 -294.070024)
		(stroke
			(width 0.06477)
			(type default)
		)
		(layer "F.Cu")
	)
	(gr_line
		(start 345.034616 -391.978896)
		(end 345.168982 -391.978896)
		(stroke
			(width 0.0508)
			(type default)
		)
		(layer "F.Cu")
	)
	(gr_line
		(start 345.131644 -381.68453)
		(end 345.433396 -381.986282)
		(stroke
			(width 0.0508)
			(type default)
		)
		(layer "F.Cu")
	)
	(gr_line
		(start 345.157044 -379.88113)
		(end 345.427554 -380.15164)
		(stroke
			(width 0.06477)
			(type default)
		)
		(layer "F.Cu")
	)
	(gr_line
		(start 345.168982 -391.978896)
		(end 345.245436 -391.902442)
		(stroke
			(width 0.0508)
			(type default)
		)
		(layer "F.Cu")
	)
	(gr_line
		(start 345.234768 -391.325862)
		(end 344.94343 -391.6172)
		(stroke
			(width 0.0508)
			(type default)
		)
		(layer "F.Cu")
	)
	(gr_line
		(start 345.245436 -391.902442)
		(end 345.245436 -391.784586)
		(stroke
			(width 0.0508)
			(type default)
		)
		(layer "F.Cu")
	)
	(gr_line
		(start 345.328748 -399.74647)
		(end 345.245436 -399.663158)
		(stroke
			(width 0.0508)
			(type default)
		)
		(layer "F.Cu")
	)
	(gr_line
		(start 345.39809 -397.156432)
		(end 345.91879 -397.156432)
		(stroke
			(width 0.0635)
			(type default)
		)
		(layer "F.Cu")
	)
	(gr_line
		(start 345.39809 -393.69238)
		(end 345.91879 -393.69238)
		(stroke
			(width 0.0635)
			(type default)
		)
		(layer "F.Cu")
	)
	(gr_line
		(start 345.427554 -380.85522)
		(end 345.131644 -381.15113)
		(stroke
			(width 0.06477)
			(type default)
		)
		(layer "F.Cu")
	)
	(gr_line
		(start 345.435174 -371.952012)
		(end 345.245944 -372.141242)
		(stroke
			(width 0.06477)
			(type default)
		)
		(layer "F.Cu")
	)
	(gr_line
		(start 345.447874 -295.690036)
		(end 345.756738 -295.9989)
		(stroke
			(width 0.06477)
			(type default)
		)
		(layer "F.Cu")
	)
	(gr_line
		(start 345.451938 -391.51941)
		(end 345.54541 -391.612882)
		(stroke
			(width 0.0508)
			(type default)
		)
		(layer "F.Cu")
	)
	(gr_line
		(start 345.451938 -391.324592)
		(end 345.451938 -391.51941)
		(stroke
			(width 0.0508)
			(type default)
		)
		(layer "F.Cu")
	)
	(gr_arc
		(start 345.479878 -382.084072)
		(mid 345.465 -382.031203)
		(end 345.433396 -381.986282)
		(stroke
			(width 0.0508)
			(type default)
		)
		(layer "F.Cu")
	)
	(gr_line
		(start 345.480894 -383.22504)
		(end 345.480894 -383.75336)
		(stroke
			(width 0.0508)
			(type default)
		)
		(layer "F.Cu")
	)
	(gr_line
		(start 345.54541 -391.612882)
		(end 345.54541 -392.30427)
		(stroke
			(width 0.0508)
			(type default)
		)
		(layer "F.Cu")
	)
	(gr_line
		(start 345.545918 -399.74774)
		(end 345.545918 -399.143982)
		(stroke
			(width 0.0508)
			(type default)
		)
		(layer "F.Cu")
	)
	(gr_line
		(start 345.545918 -399.143982)
		(end 345.54541 -399.143474)
		(stroke
			(width 0.0508)
			(type default)
		)
		(layer "F.Cu")
	)
	(gr_line
		(start 345.698064 -383.22631)
		(end 345.808554 -383.3368)
		(stroke
			(width 0.0508)
			(type default)
		)
		(layer "F.Cu")
	)
	(gr_arc
		(start 345.744292 -381.986282)
		(mid 345.712655 -382.031183)
		(end 345.69781 -382.084072)
		(stroke
			(width 0.0508)
			(type default)
		)
		(layer "F.Cu")
	)
	(gr_line
		(start 345.750134 -380.85522)
		(end 346.046044 -381.15113)
		(stroke
			(width 0.06477)
			(type default)
		)
		(layer "F.Cu")
	)
	(gr_line
		(start 345.79814 -397.849344)
		(end 346.31884 -397.849344)
		(stroke
			(width 0.0635)
			(type default)
		)
		(layer "F.Cu")
	)
	(gr_line
		(start 345.79814 -394.385292)
		(end 346.31884 -394.385292)
		(stroke
			(width 0.0635)
			(type default)
		)
		(layer "F.Cu")
	)
	(gr_line
		(start 345.805252 -401.359116)
		(end 345.80322 -401.359116)
		(stroke
			(width 0.0508)
			(type default)
		)
		(layer "F.Cu")
	)
	(gr_line
		(start 345.808554 -383.6416)
		(end 345.698064 -383.75209)
		(stroke
			(width 0.0508)
			(type default)
		)
		(layer "F.Cu")
	)
	(gr_line
		(start 345.808554 -383.3368)
		(end 345.808554 -383.6416)
		(stroke
			(width 0.0508)
			(type default)
		)
		(layer "F.Cu")
	)
	(gr_line
		(start 345.823794 -371.952012)
		(end 345.435174 -371.952012)
		(stroke
			(width 0.06477)
			(type default)
		)
		(layer "F.Cu")
	)
	(gr_line
		(start 345.921076 -294.335962)
		(end 346.387928 -294.070024)
		(stroke
			(width 0.06477)
			(type default)
		)
		(layer "F.Cu")
	)
	(gr_line
		(start 345.921076 -278.136096)
		(end 346.387928 -277.870158)
		(stroke
			(width 0.06477)
			(type default)
		)
		(layer "F.Cu")
	)
	(gr_line
		(start 345.921076 -276.516084)
		(end 346.387928 -276.250146)
		(stroke
			(width 0.06477)
			(type default)
		)
		(layer "F.Cu")
	)
	(gr_line
		(start 345.921076 -274.896072)
		(end 346.387928 -274.630134)
		(stroke
			(width 0.06477)
			(type default)
		)
		(layer "F.Cu")
	)
	(gr_line
		(start 345.921076 -273.27606)
		(end 346.387928 -273.010122)
		(stroke
			(width 0.06477)
			(type default)
		)
		(layer "F.Cu")
	)
	(gr_line
		(start 345.921076 -271.656048)
		(end 346.387928 -271.39011)
		(stroke
			(width 0.06477)
			(type default)
		)
		(layer "F.Cu")
	)
	(gr_line
		(start 345.921076 -270.036036)
		(end 346.387928 -269.770098)
		(stroke
			(width 0.06477)
			(type default)
		)
		(layer "F.Cu")
	)
	(gr_line
		(start 345.94419 -401.674838)
		(end 345.94419 -401.498054)
		(stroke
			(width 0.0508)
			(type default)
		)
		(layer "F.Cu")
	)
	(gr_line
		(start 345.94419 -401.498054)
		(end 345.805252 -401.359116)
		(stroke
			(width 0.0508)
			(type default)
		)
		(layer "F.Cu")
	)
	(gr_line
		(start 345.94419 -401.002246)
		(end 345.80449 -401.141946)
		(stroke
			(width 0.0508)
			(type default)
		)
		(layer "F.Cu")
	)
	(gr_line
		(start 345.94419 -400.811238)
		(end 345.94419 -401.002246)
		(stroke
			(width 0.0508)
			(type default)
		)
		(layer "F.Cu")
	)
	(gr_line
		(start 346.013024 -372.141242)
		(end 345.823794 -371.952012)
		(stroke
			(width 0.06477)
			(type default)
		)
		(layer "F.Cu")
	)
	(gr_line
		(start 346.014294 -372.465092)
		(end 345.244674 -372.465092)
		(stroke
			(width 0.06477)
			(type default)
		)
		(layer "F.Cu")
	)
	(gr_line
		(start 346.020644 -379.88113)
		(end 345.750134 -380.15164)
		(stroke
			(width 0.06477)
			(type default)
		)
		(layer "F.Cu")
	)
	(gr_line
		(start 346.046044 -381.68453)
		(end 345.744292 -381.986282)
		(stroke
			(width 0.0508)
			(type default)
		)
		(layer "F.Cu")
	)
	(gr_line
		(start 346.14358 -391.88771)
		(end 346.234766 -391.978896)
		(stroke
			(width 0.0508)
			(type default)
		)
		(layer "F.Cu")
	)
	(gr_line
		(start 346.14358 -391.6172)
		(end 346.14358 -391.88771)
		(stroke
			(width 0.0508)
			(type default)
		)
		(layer "F.Cu")
	)
	(gr_line
		(start 346.234766 -391.978896)
		(end 346.369132 -391.978896)
		(stroke
			(width 0.0508)
			(type default)
		)
		(layer "F.Cu")
	)
	(gr_line
		(start 346.369132 -391.978896)
		(end 346.445586 -391.902442)
		(stroke
			(width 0.0508)
			(type default)
		)
		(layer "F.Cu")
	)
	(gr_line
		(start 346.387928 -295.690036)
		(end 346.079318 -295.998646)
		(stroke
			(width 0.06477)
			(type default)
		)
		(layer "F.Cu")
	)
	(gr_line
		(start 346.387928 -292.450012)
		(end 345.921076 -292.71595)
		(stroke
			(width 0.06477)
			(type default)
		)
		(layer "F.Cu")
	)
	(gr_line
		(start 346.387928 -290.83)
		(end 345.921076 -291.095938)
		(stroke
			(width 0.06477)
			(type default)
		)
		(layer "F.Cu")
	)
	(gr_line
		(start 346.387928 -289.209988)
		(end 345.921076 -289.475926)
		(stroke
			(width 0.06477)
			(type default)
		)
		(layer "F.Cu")
	)
	(gr_line
		(start 346.387928 -287.59023)
		(end 345.921076 -287.856168)
		(stroke
			(width 0.06477)
			(type default)
		)
		(layer "F.Cu")
	)
	(gr_line
		(start 346.387928 -285.970218)
		(end 345.921076 -286.236156)
		(stroke
			(width 0.06477)
			(type default)
		)
		(layer "F.Cu")
	)
	(gr_line
		(start 346.387928 -284.350206)
		(end 345.921076 -284.616144)
		(stroke
			(width 0.06477)
			(type default)
		)
		(layer "F.Cu")
	)
	(gr_line
		(start 346.387928 -282.730194)
		(end 345.921076 -282.996132)
		(stroke
			(width 0.06477)
			(type default)
		)
		(layer "F.Cu")
	)
	(gr_line
		(start 346.387928 -281.110182)
		(end 345.921076 -281.37612)
		(stroke
			(width 0.06477)
			(type default)
		)
		(layer "F.Cu")
	)
	(gr_line
		(start 346.434918 -391.325862)
		(end 346.14358 -391.6172)
		(stroke
			(width 0.0508)
			(type default)
		)
		(layer "F.Cu")
	)
	(gr_line
		(start 346.445586 -391.902442)
		(end 346.445586 -391.784586)
		(stroke
			(width 0.0508)
			(type default)
		)
		(layer "F.Cu")
	)
	(gr_line
		(start 346.528898 -399.74647)
		(end 346.445586 -399.663158)
		(stroke
			(width 0.0508)
			(type default)
		)
		(layer "F.Cu")
	)
	(gr_line
		(start 346.597986 -397.156432)
		(end 347.118686 -397.156432)
		(stroke
			(width 0.0635)
			(type default)
		)
		(layer "F.Cu")
	)
	(gr_line
		(start 346.597986 -393.69238)
		(end 347.118686 -393.69238)
		(stroke
			(width 0.0635)
			(type default)
		)
		(layer "F.Cu")
	)
	(gr_line
		(start 346.652088 -391.51941)
		(end 346.74556 -391.612882)
		(stroke
			(width 0.0508)
			(type default)
		)
		(layer "F.Cu")
	)
	(gr_line
		(start 346.652088 -391.324592)
		(end 346.652088 -391.51941)
		(stroke
			(width 0.0508)
			(type default)
		)
		(layer "F.Cu")
	)
	(gr_line
		(start 346.653866 -417.166044)
		(end 346.949776 -417.461954)
		(stroke
			(width 0.06477)
			(type default)
		)
		(layer "F.Cu")
	)
	(gr_line
		(start 346.679266 -412.84652)
		(end 346.949776 -413.11703)
		(stroke
			(width 0.06477)
			(type default)
		)
		(layer "F.Cu")
	)
	(gr_line
		(start 346.74556 -391.612882)
		(end 346.74556 -392.30427)
		(stroke
			(width 0.0508)
			(type default)
		)
		(layer "F.Cu")
	)
	(gr_line
		(start 346.746068 -399.74774)
		(end 346.746068 -399.143982)
		(stroke
			(width 0.0508)
			(type default)
		)
		(layer "F.Cu")
	)
	(gr_line
		(start 346.746068 -399.143982)
		(end 346.74556 -399.143474)
		(stroke
			(width 0.0508)
			(type default)
		)
		(layer "F.Cu")
	)
	(gr_line
		(start 346.833444 -379.22073)
		(end 347.182694 -379.56998)
		(stroke
			(width 0.0508)
			(type default)
		)
		(layer "F.Cu")
	)
	(gr_line
		(start 346.858844 -377.41733)
		(end 347.129354 -377.68784)
		(stroke
			(width 0.06477)
			(type default)
		)
		(layer "F.Cu")
	)
	(gr_line
		(start 346.86113 -278.136096)
		(end 347.327982 -277.870158)
		(stroke
			(width 0.06477)
			(type default)
		)
		(layer "F.Cu")
	)
	(gr_line
		(start 346.86113 -276.516084)
		(end 347.327982 -276.250146)
		(stroke
			(width 0.06477)
			(type default)
		)
		(layer "F.Cu")
	)
	(gr_line
		(start 346.86113 -274.896072)
		(end 347.327982 -274.630134)
		(stroke
			(width 0.06477)
			(type default)
		)
		(layer "F.Cu")
	)
	(gr_line
		(start 346.86113 -273.27606)
		(end 347.327982 -273.010122)
		(stroke
			(width 0.06477)
			(type default)
		)
		(layer "F.Cu")
	)
	(gr_line
		(start 346.86113 -271.656048)
		(end 347.327982 -271.39011)
		(stroke
			(width 0.06477)
			(type default)
		)
		(layer "F.Cu")
	)
	(gr_line
		(start 346.86113 -270.036036)
		(end 347.327982 -269.770098)
		(stroke
			(width 0.06477)
			(type default)
		)
		(layer "F.Cu")
	)
	(gr_line
		(start 346.949776 -420.681658)
		(end 346.679266 -420.952168)
		(stroke
			(width 0.06477)
			(type default)
		)
		(layer "F.Cu")
	)
	(gr_line
		(start 346.949776 -416.336734)
		(end 346.653866 -416.632644)
		(stroke
			(width 0.06477)
			(type default)
		)
		(layer "F.Cu")
	)
	(gr_line
		(start 346.998036 -397.849344)
		(end 347.518736 -397.849344)
		(stroke
			(width 0.0635)
			(type default)
		)
		(layer "F.Cu")
	)
	(gr_line
		(start 346.998036 -394.385292)
		(end 347.518736 -394.385292)
		(stroke
			(width 0.0635)
			(type default)
		)
		(layer "F.Cu")
	)
	(gr_line
		(start 347.005402 -401.359116)
		(end 347.00337 -401.359116)
		(stroke
			(width 0.0508)
			(type default)
		)
		(layer "F.Cu")
	)
	(gr_line
		(start 347.129354 -378.39142)
		(end 346.833444 -378.68733)
		(stroke
			(width 0.06477)
			(type default)
		)
		(layer "F.Cu")
	)
	(gr_line
		(start 347.144086 -401.674838)
		(end 347.144086 -401.4978)
		(stroke
			(width 0.0508)
			(type default)
		)
		(layer "F.Cu")
	)
	(gr_line
		(start 347.144086 -401.4978)
		(end 347.005402 -401.359116)
		(stroke
			(width 0.0508)
			(type default)
		)
		(layer "F.Cu")
	)
	(gr_line
		(start 347.144086 -401.0025)
		(end 347.00464 -401.141946)
		(stroke
			(width 0.0508)
			(type default)
		)
		(layer "F.Cu")
	)
	(gr_line
		(start 347.144086 -400.811238)
		(end 347.144086 -401.0025)
		(stroke
			(width 0.0508)
			(type default)
		)
		(layer "F.Cu")
	)
	(gr_line
		(start 347.272356 -420.681658)
		(end 347.542866 -420.952168)
		(stroke
			(width 0.06477)
			(type default)
		)
		(layer "F.Cu")
	)
	(gr_line
		(start 347.272356 -416.336734)
		(end 347.568266 -416.632644)
		(stroke
			(width 0.06477)
			(type default)
		)
		(layer "F.Cu")
	)
	(gr_line
		(start 347.327982 -292.450012)
		(end 346.86113 -292.71595)
		(stroke
			(width 0.06477)
			(type default)
		)
		(layer "F.Cu")
	)
	(gr_line
		(start 347.327982 -290.83)
		(end 346.86113 -291.095938)
		(stroke
			(width 0.06477)
			(type default)
		)
		(layer "F.Cu")
	)
	(gr_line
		(start 347.327982 -289.209988)
		(end 346.86113 -289.475926)
		(stroke
			(width 0.06477)
			(type default)
		)
		(layer "F.Cu")
	)
	(gr_line
		(start 347.327982 -287.59023)
		(end 346.86113 -287.856168)
		(stroke
			(width 0.06477)
			(type default)
		)
		(layer "F.Cu")
	)
	(gr_line
		(start 347.327982 -285.970218)
		(end 346.86113 -286.236156)
		(stroke
			(width 0.06477)
			(type default)
		)
		(layer "F.Cu")
	)
	(gr_line
		(start 347.327982 -284.350206)
		(end 346.86113 -284.616144)
		(stroke
			(width 0.06477)
			(type default)
		)
		(layer "F.Cu")
	)
	(gr_line
		(start 347.327982 -282.730194)
		(end 346.86113 -282.996132)
		(stroke
			(width 0.06477)
			(type default)
		)
		(layer "F.Cu")
	)
	(gr_line
		(start 347.327982 -281.110182)
		(end 346.86113 -281.37612)
		(stroke
			(width 0.06477)
			(type default)
		)
		(layer "F.Cu")
	)
	(gr_line
		(start 347.343476 -391.88771)
		(end 347.434662 -391.978896)
		(stroke
			(width 0.0508)
			(type default)
		)
		(layer "F.Cu")
	)
	(gr_line
		(start 347.343476 -391.6172)
		(end 347.343476 -391.88771)
		(stroke
			(width 0.0508)
			(type default)
		)
		(layer "F.Cu")
	)
	(gr_line
		(start 347.434662 -391.978896)
		(end 347.569028 -391.978896)
		(stroke
			(width 0.0508)
			(type default)
		)
		(layer "F.Cu")
	)
	(gr_line
		(start 347.451934 -378.39142)
		(end 347.747844 -378.68733)
		(stroke
			(width 0.06477)
			(type default)
		)
		(layer "F.Cu")
	)
	(gr_line
		(start 347.542866 -412.84652)
		(end 347.272356 -413.11703)
		(stroke
			(width 0.06477)
			(type default)
		)
		(layer "F.Cu")
	)
	(gr_line
		(start 347.568266 -417.166044)
		(end 347.272356 -417.461954)
		(stroke
			(width 0.06477)
			(type default)
		)
		(layer "F.Cu")
	)
	(gr_line
		(start 347.569028 -391.978896)
		(end 347.645482 -391.902442)
		(stroke
			(width 0.0508)
			(type default)
		)
		(layer "F.Cu")
	)
	(gr_line
		(start 347.634814 -391.325862)
		(end 347.343476 -391.6172)
		(stroke
			(width 0.0508)
			(type default)
		)
		(layer "F.Cu")
	)
	(gr_line
		(start 347.645482 -391.902442)
		(end 347.645482 -391.784586)
		(stroke
			(width 0.0508)
			(type default)
		)
		(layer "F.Cu")
	)
	(gr_line
		(start 347.722444 -377.41733)
		(end 347.451934 -377.68784)
		(stroke
			(width 0.06477)
			(type default)
		)
		(layer "F.Cu")
	)
	(gr_line
		(start 347.728286 -399.745962)
		(end 347.645482 -399.663158)
		(stroke
			(width 0.0508)
			(type default)
		)
		(layer "F.Cu")
	)
	(gr_line
		(start 347.747844 -379.22073)
		(end 347.398594 -379.56998)
		(stroke
			(width 0.0508)
			(type default)
		)
		(layer "F.Cu")
	)
	(gr_line
		(start 347.798136 -397.156432)
		(end 348.318836 -397.156432)
		(stroke
			(width 0.0635)
			(type default)
		)
		(layer "F.Cu")
	)
	(gr_line
		(start 347.798136 -393.69238)
		(end 348.318836 -393.69238)
		(stroke
			(width 0.0635)
			(type default)
		)
		(layer "F.Cu")
	)
	(gr_line
		(start 347.801184 -294.335962)
		(end 348.268036 -294.070024)
		(stroke
			(width 0.06477)
			(type default)
		)
		(layer "F.Cu")
	)
	(gr_line
		(start 347.851984 -391.51941)
		(end 347.945456 -391.612882)
		(stroke
			(width 0.0508)
			(type default)
		)
		(layer "F.Cu")
	)
	(gr_line
		(start 347.851984 -391.324592)
		(end 347.851984 -391.51941)
		(stroke
			(width 0.0508)
			(type default)
		)
		(layer "F.Cu")
	)
	(gr_line
		(start 347.865954 -384.935984)
		(end 347.709236 -384.935984)
		(stroke
			(width 0.0508)
			(type default)
		)
		(layer "F.Cu")
	)
	(gr_line
		(start 347.915484 -386.86486)
		(end 347.91523 -386.86486)
		(stroke
			(width 0.0508)
			(type default)
		)
		(layer "F.Cu")
	)
	(gr_line
		(start 347.928946 -384.409188)
		(end 347.555058 -384.783076)
		(stroke
			(width 0.0508)
			(type default)
		)
		(layer "F.Cu")
	)
	(gr_line
		(start 347.945456 -399.747232)
		(end 347.945456 -399.143474)
		(stroke
			(width 0.0508)
			(type default)
		)
		(layer "F.Cu")
	)
	(gr_line
		(start 347.945456 -391.612882)
		(end 347.945456 -392.30427)
		(stroke
			(width 0.0508)
			(type default)
		)
		(layer "F.Cu")
	)
	(gr_line
		(start 347.968062 -223.69018)
		(end 347.50121 -223.424242)
		(stroke
			(width 0.06477)
			(type default)
		)
		(layer "F.Cu")
	)
	(gr_line
		(start 348.081854 -384.720084)
		(end 347.865954 -384.935984)
		(stroke
			(width 0.0508)
			(type default)
		)
		(layer "F.Cu")
	)
	(gr_line
		(start 348.081854 -384.563366)
		(end 348.081854 -384.720084)
		(stroke
			(width 0.0508)
			(type default)
		)
		(layer "F.Cu")
	)
	(gr_line
		(start 348.198186 -397.849344)
		(end 348.718886 -397.849344)
		(stroke
			(width 0.0635)
			(type default)
		)
		(layer "F.Cu")
	)
	(gr_line
		(start 348.198186 -394.385292)
		(end 348.718886 -394.385292)
		(stroke
			(width 0.0635)
			(type default)
		)
		(layer "F.Cu")
	)
	(gr_line
		(start 348.205298 -401.359116)
		(end 348.203266 -401.359116)
		(stroke
			(width 0.0508)
			(type default)
		)
		(layer "F.Cu")
	)
	(gr_line
		(start 348.226126 -387.017768)
		(end 348.069662 -387.017768)
		(stroke
			(width 0.0508)
			(type default)
		)
		(layer "F.Cu")
	)
	(gr_line
		(start 348.288864 -386.49148)
		(end 347.915484 -386.86486)
		(stroke
			(width 0.0508)
			(type default)
		)
		(layer "F.Cu")
	)
	(gr_line
		(start 348.344236 -401.674838)
		(end 348.344236 -401.498054)
		(stroke
			(width 0.0508)
			(type default)
		)
		(layer "F.Cu")
	)
	(gr_line
		(start 348.344236 -401.498054)
		(end 348.205298 -401.359116)
		(stroke
			(width 0.0508)
			(type default)
		)
		(layer "F.Cu")
	)
	(gr_line
		(start 348.344236 -401.002246)
		(end 348.204536 -401.141946)
		(stroke
			(width 0.0508)
			(type default)
		)
		(layer "F.Cu")
	)
	(gr_line
		(start 348.344236 -400.811238)
		(end 348.344236 -401.002246)
		(stroke
			(width 0.0508)
			(type default)
		)
		(layer "F.Cu")
	)
	(gr_line
		(start 348.44101 -225.044254)
		(end 348.907862 -225.310192)
		(stroke
			(width 0.06477)
			(type default)
		)
		(layer "F.Cu")
	)
	(gr_line
		(start 348.441772 -386.802122)
		(end 348.226126 -387.017768)
		(stroke
			(width 0.0508)
			(type default)
		)
		(layer "F.Cu")
	)
	(gr_line
		(start 348.441772 -386.645658)
		(end 348.441772 -386.802122)
		(stroke
			(width 0.0508)
			(type default)
		)
		(layer "F.Cu")
	)
	(gr_line
		(start 348.543372 -391.88771)
		(end 348.634558 -391.978896)
		(stroke
			(width 0.0508)
			(type default)
		)
		(layer "F.Cu")
	)
	(gr_line
		(start 348.543372 -391.6172)
		(end 348.543372 -391.88771)
		(stroke
			(width 0.0508)
			(type default)
		)
		(layer "F.Cu")
	)
	(gr_line
		(start 348.634558 -391.978896)
		(end 348.768924 -391.978896)
		(stroke
			(width 0.0508)
			(type default)
		)
		(layer "F.Cu")
	)
	(gr_line
		(start 348.741238 -294.335962)
		(end 349.20809 -294.070024)
		(stroke
			(width 0.06477)
			(type default)
		)
		(layer "F.Cu")
	)
	(gr_line
		(start 348.741238 -278.136096)
		(end 349.20809 -277.870158)
		(stroke
			(width 0.06477)
			(type default)
		)
		(layer "F.Cu")
	)
	(gr_line
		(start 348.741238 -276.516084)
		(end 349.20809 -276.250146)
		(stroke
			(width 0.06477)
			(type default)
		)
		(layer "F.Cu")
	)
	(gr_line
		(start 348.741238 -274.896072)
		(end 349.20809 -274.630134)
		(stroke
			(width 0.06477)
			(type default)
		)
		(layer "F.Cu")
	)
	(gr_line
		(start 348.741238 -273.27606)
		(end 349.20809 -273.010122)
		(stroke
			(width 0.06477)
			(type default)
		)
		(layer "F.Cu")
	)
	(gr_line
		(start 348.741238 -271.656048)
		(end 349.20809 -271.39011)
		(stroke
			(width 0.06477)
			(type default)
		)
		(layer "F.Cu")
	)
	(gr_line
		(start 348.741238 -270.036036)
		(end 349.20809 -269.770098)
		(stroke
			(width 0.06477)
			(type default)
		)
		(layer "F.Cu")
	)
	(gr_line
		(start 348.768924 -391.978896)
		(end 348.845378 -391.902442)
		(stroke
			(width 0.0508)
			(type default)
		)
		(layer "F.Cu")
	)
	(gr_line
		(start 348.83471 -391.325862)
		(end 348.543372 -391.6172)
		(stroke
			(width 0.0508)
			(type default)
		)
		(layer "F.Cu")
	)
	(gr_line
		(start 348.845378 -391.902442)
		(end 348.845378 -391.784586)
		(stroke
			(width 0.0508)
			(type default)
		)
		(layer "F.Cu")
	)
	(gr_line
		(start 348.907862 -223.69018)
		(end 348.44101 -223.424242)
		(stroke
			(width 0.06477)
			(type default)
		)
		(layer "F.Cu")
	)
	(gr_line
		(start 348.92869 -399.74647)
		(end 348.845378 -399.663158)
		(stroke
			(width 0.0508)
			(type default)
		)
		(layer "F.Cu")
	)
	(gr_line
		(start 348.998032 -397.156432)
		(end 349.518732 -397.156432)
		(stroke
			(width 0.0635)
			(type default)
		)
		(layer "F.Cu")
	)
	(gr_line
		(start 348.998032 -393.69238)
		(end 349.518732 -393.69238)
		(stroke
			(width 0.0635)
			(type default)
		)
		(layer "F.Cu")
	)
	(gr_line
		(start 349.05188 -391.51941)
		(end 349.145606 -391.613136)
		(stroke
			(width 0.0508)
			(type default)
		)
		(layer "F.Cu")
	)
	(gr_line
		(start 349.05188 -391.324592)
		(end 349.05188 -391.51941)
		(stroke
			(width 0.0508)
			(type default)
		)
		(layer "F.Cu")
	)
	(gr_line
		(start 349.145606 -391.613136)
		(end 349.145606 -392.30427)
		(stroke
			(width 0.0508)
			(type default)
		)
		(layer "F.Cu")
	)
	(gr_line
		(start 349.14586 -399.74774)
		(end 349.14586 -399.143728)
		(stroke
			(width 0.0508)
			(type default)
		)
		(layer "F.Cu")
	)
	(gr_line
		(start 349.14586 -399.143728)
		(end 349.145606 -399.143474)
		(stroke
			(width 0.0508)
			(type default)
		)
		(layer "F.Cu")
	)
	(gr_line
		(start 349.20809 -292.450012)
		(end 348.741238 -292.71595)
		(stroke
			(width 0.06477)
			(type default)
		)
		(layer "F.Cu")
	)
	(gr_line
		(start 349.20809 -290.83)
		(end 348.741238 -291.095938)
		(stroke
			(width 0.06477)
			(type default)
		)
		(layer "F.Cu")
	)
	(gr_line
		(start 349.20809 -289.209988)
		(end 348.741238 -289.475926)
		(stroke
			(width 0.06477)
			(type default)
		)
		(layer "F.Cu")
	)
	(gr_line
		(start 349.20809 -287.59023)
		(end 348.741238 -287.856168)
		(stroke
			(width 0.06477)
			(type default)
		)
		(layer "F.Cu")
	)
	(gr_line
		(start 349.20809 -285.970218)
		(end 348.741238 -286.236156)
		(stroke
			(width 0.06477)
			(type default)
		)
		(layer "F.Cu")
	)
	(gr_line
		(start 349.20809 -284.350206)
		(end 348.741238 -284.616144)
		(stroke
			(width 0.06477)
			(type default)
		)
		(layer "F.Cu")
	)
	(gr_line
		(start 349.20809 -282.730194)
		(end 348.741238 -282.996132)
		(stroke
			(width 0.06477)
			(type default)
		)
		(layer "F.Cu")
	)
	(gr_line
		(start 349.20809 -281.110182)
		(end 348.741238 -281.37612)
		(stroke
			(width 0.06477)
			(type default)
		)
		(layer "F.Cu")
	)
	(gr_line
		(start 349.381064 -225.044254)
		(end 349.847916 -225.310192)
		(stroke
			(width 0.06477)
			(type default)
		)
		(layer "F.Cu")
	)
	(gr_line
		(start 349.398082 -397.849344)
		(end 349.918782 -397.849344)
		(stroke
			(width 0.0635)
			(type default)
		)
		(layer "F.Cu")
	)
	(gr_line
		(start 349.398082 -394.385292)
		(end 349.918782 -394.385292)
		(stroke
			(width 0.0635)
			(type default)
		)
		(layer "F.Cu")
	)
	(gr_line
		(start 349.405194 -401.359116)
		(end 349.403162 -401.359116)
		(stroke
			(width 0.0508)
			(type default)
		)
		(layer "F.Cu")
	)
	(gr_line
		(start 349.544132 -401.674838)
		(end 349.544132 -401.498054)
		(stroke
			(width 0.0508)
			(type default)
		)
		(layer "F.Cu")
	)
	(gr_line
		(start 349.544132 -401.498054)
		(end 349.405194 -401.359116)
		(stroke
			(width 0.0508)
			(type default)
		)
		(layer "F.Cu")
	)
	(gr_line
		(start 349.544132 -401.002246)
		(end 349.404432 -401.141946)
		(stroke
			(width 0.0508)
			(type default)
		)
		(layer "F.Cu")
	)
	(gr_line
		(start 349.544132 -400.811238)
		(end 349.544132 -401.002246)
		(stroke
			(width 0.0508)
			(type default)
		)
		(layer "F.Cu")
	)
	(gr_line
		(start 349.681038 -278.136096)
		(end 350.14789 -277.870158)
		(stroke
			(width 0.06477)
			(type default)
		)
		(layer "F.Cu")
	)
	(gr_line
		(start 349.681038 -276.516084)
		(end 350.14789 -276.250146)
		(stroke
			(width 0.06477)
			(type default)
		)
		(layer "F.Cu")
	)
	(gr_line
		(start 349.681038 -274.896072)
		(end 350.14789 -274.630134)
		(stroke
			(width 0.06477)
			(type default)
		)
		(layer "F.Cu")
	)
	(gr_line
		(start 349.681038 -273.27606)
		(end 350.14789 -273.010122)
		(stroke
			(width 0.06477)
			(type default)
		)
		(layer "F.Cu")
	)
	(gr_line
		(start 349.681038 -271.656048)
		(end 350.14789 -271.39011)
		(stroke
			(width 0.06477)
			(type default)
		)
		(layer "F.Cu")
	)
	(gr_line
		(start 349.681038 -270.036036)
		(end 350.14789 -269.770098)
		(stroke
			(width 0.06477)
			(type default)
		)
		(layer "F.Cu")
	)
	(gr_line
		(start 349.717106 -417.166044)
		(end 350.013016 -417.461954)
		(stroke
			(width 0.06477)
			(type default)
		)
		(layer "F.Cu")
	)
	(gr_line
		(start 349.742506 -412.84652)
		(end 350.013016 -413.11703)
		(stroke
			(width 0.06477)
			(type default)
		)
		(layer "F.Cu")
	)
	(gr_line
		(start 349.743522 -391.88771)
		(end 349.834708 -391.978896)
		(stroke
			(width 0.0508)
			(type default)
		)
		(layer "F.Cu")
	)
	(gr_line
		(start 349.743522 -391.6172)
		(end 349.743522 -391.88771)
		(stroke
			(width 0.0508)
			(type default)
		)
		(layer "F.Cu")
	)
	(gr_line
		(start 349.834708 -391.978896)
		(end 349.969074 -391.978896)
		(stroke
			(width 0.0508)
			(type default)
		)
		(layer "F.Cu")
	)
	(gr_line
		(start 349.969074 -391.978896)
		(end 350.045528 -391.902442)
		(stroke
			(width 0.0508)
			(type default)
		)
		(layer "F.Cu")
	)
	(gr_line
		(start 350.013016 -420.681658)
		(end 349.742506 -420.952168)
		(stroke
			(width 0.06477)
			(type default)
		)
		(layer "F.Cu")
	)
	(gr_line
		(start 350.013016 -416.336734)
		(end 349.717106 -416.632644)
		(stroke
			(width 0.06477)
			(type default)
		)
		(layer "F.Cu")
	)
	(gr_line
		(start 350.03486 -391.325862)
		(end 349.743522 -391.6172)
		(stroke
			(width 0.0508)
			(type default)
		)
		(layer "F.Cu")
	)
	(gr_line
		(start 350.045528 -391.902442)
		(end 350.045528 -391.784586)
		(stroke
			(width 0.0508)
			(type default)
		)
		(layer "F.Cu")
	)
	(gr_line
		(start 350.12884 -399.74647)
		(end 350.045528 -399.663158)
		(stroke
			(width 0.0508)
			(type default)
		)
		(layer "F.Cu")
	)
	(gr_line
		(start 350.14789 -292.450012)
		(end 349.681038 -292.71595)
		(stroke
			(width 0.06477)
			(type default)
		)
		(layer "F.Cu")
	)
	(gr_line
		(start 350.14789 -290.83)
		(end 349.681038 -291.095938)
		(stroke
			(width 0.06477)
			(type default)
		)
		(layer "F.Cu")
	)
	(gr_line
		(start 350.14789 -289.209988)
		(end 349.681038 -289.475926)
		(stroke
			(width 0.06477)
			(type default)
		)
		(layer "F.Cu")
	)
	(gr_line
		(start 350.14789 -287.59023)
		(end 349.681038 -287.856168)
		(stroke
			(width 0.06477)
			(type default)
		)
		(layer "F.Cu")
	)
	(gr_line
		(start 350.14789 -285.970218)
		(end 349.681038 -286.236156)
		(stroke
			(width 0.06477)
			(type default)
		)
		(layer "F.Cu")
	)
	(gr_line
		(start 350.14789 -284.350206)
		(end 349.681038 -284.616144)
		(stroke
			(width 0.06477)
			(type default)
		)
		(layer "F.Cu")
	)
	(gr_line
		(start 350.14789 -282.730194)
		(end 349.681038 -282.996132)
		(stroke
			(width 0.06477)
			(type default)
		)
		(layer "F.Cu")
	)
	(gr_line
		(start 350.14789 -281.110182)
		(end 349.681038 -281.37612)
		(stroke
			(width 0.06477)
			(type default)
		)
		(layer "F.Cu")
	)
	(gr_line
		(start 350.198182 -397.156432)
		(end 350.718882 -397.156432)
		(stroke
			(width 0.0635)
			(type default)
		)
		(layer "F.Cu")
	)
	(gr_line
		(start 350.198182 -393.69238)
		(end 350.718882 -393.69238)
		(stroke
			(width 0.0635)
			(type default)
		)
		(layer "F.Cu")
	)
	(gr_line
		(start 350.237044 -384.14833)
		(end 350.585278 -384.496564)
		(stroke
			(width 0.0508)
			(type default)
		)
		(layer "F.Cu")
	)
	(gr_line
		(start 350.25203 -391.51941)
		(end 350.345502 -391.612882)
		(stroke
			(width 0.0508)
			(type default)
		)
		(layer "F.Cu")
	)
	(gr_line
		(start 350.25203 -391.324592)
		(end 350.25203 -391.51941)
		(stroke
			(width 0.0508)
			(type default)
		)
		(layer "F.Cu")
	)
	(gr_line
		(start 350.262444 -382.34493)
		(end 350.532954 -382.61544)
		(stroke
			(width 0.06477)
			(type default)
		)
		(layer "F.Cu")
	)
	(gr_line
		(start 350.335596 -420.681658)
		(end 350.606106 -420.952168)
		(stroke
			(width 0.06477)
			(type default)
		)
		(layer "F.Cu")
	)
	(gr_line
		(start 350.335596 -416.336734)
		(end 350.631506 -416.632644)
		(stroke
			(width 0.06477)
			(type default)
		)
		(layer "F.Cu")
	)
	(gr_line
		(start 350.345502 -391.612882)
		(end 350.345502 -392.30427)
		(stroke
			(width 0.0508)
			(type default)
		)
		(layer "F.Cu")
	)
	(gr_line
		(start 350.34601 -399.74774)
		(end 350.34601 -399.143982)
		(stroke
			(width 0.0508)
			(type default)
		)
		(layer "F.Cu")
	)
	(gr_line
		(start 350.34601 -399.143982)
		(end 350.345502 -399.143474)
		(stroke
			(width 0.0508)
			(type default)
		)
		(layer "F.Cu")
	)
	(gr_line
		(start 350.532954 -383.31902)
		(end 350.237044 -383.61493)
		(stroke
			(width 0.06477)
			(type default)
		)
		(layer "F.Cu")
	)
	(gr_line
		(start 350.585278 -384.496564)
		(end 350.585278 -384.498596)
		(stroke
			(width 0.0508)
			(type default)
		)
		(layer "F.Cu")
	)
	(gr_line
		(start 350.597978 -397.849344)
		(end 351.118678 -397.849344)
		(stroke
			(width 0.0635)
			(type default)
		)
		(layer "F.Cu")
	)
	(gr_line
		(start 350.597978 -394.385292)
		(end 351.118678 -394.385292)
		(stroke
			(width 0.0635)
			(type default)
		)
		(layer "F.Cu")
	)
	(gr_line
		(start 350.602042 -401.359116)
		(end 350.578674 -401.359116)
		(stroke
			(width 0.0508)
			(type default)
		)
		(layer "F.Cu")
	)
	(gr_line
		(start 350.606106 -412.84652)
		(end 350.335596 -413.11703)
		(stroke
			(width 0.06477)
			(type default)
		)
		(layer "F.Cu")
	)
	(gr_line
		(start 350.621092 -294.335962)
		(end 351.087944 -294.070024)
		(stroke
			(width 0.06477)
			(type default)
		)
		(layer "F.Cu")
	)
	(gr_line
		(start 350.631506 -417.166044)
		(end 350.335596 -417.461954)
		(stroke
			(width 0.06477)
			(type default)
		)
		(layer "F.Cu")
	)
	(gr_line
		(start 350.744028 -401.674838)
		(end 350.744028 -401.501102)
		(stroke
			(width 0.0508)
			(type default)
		)
		(layer "F.Cu")
	)
	(gr_line
		(start 350.744028 -401.501102)
		(end 350.602042 -401.359116)
		(stroke
			(width 0.0508)
			(type default)
		)
		(layer "F.Cu")
	)
	(gr_line
		(start 350.744028 -400.977862)
		(end 350.579944 -401.141946)
		(stroke
			(width 0.0508)
			(type default)
		)
		(layer "F.Cu")
	)
	(gr_line
		(start 350.744028 -400.811238)
		(end 350.744028 -400.977862)
		(stroke
			(width 0.0508)
			(type default)
		)
		(layer "F.Cu")
	)
	(gr_line
		(start 350.855534 -383.31902)
		(end 351.151444 -383.61493)
		(stroke
			(width 0.06477)
			(type default)
		)
		(layer "F.Cu")
	)
	(gr_line
		(start 350.943418 -391.88771)
		(end 351.034604 -391.978896)
		(stroke
			(width 0.0508)
			(type default)
		)
		(layer "F.Cu")
	)
	(gr_line
		(start 350.943418 -391.6172)
		(end 350.943418 -391.88771)
		(stroke
			(width 0.0508)
			(type default)
		)
		(layer "F.Cu")
	)
	(gr_line
		(start 351.034604 -391.978896)
		(end 351.16897 -391.978896)
		(stroke
			(width 0.0508)
			(type default)
		)
		(layer "F.Cu")
	)
	(gr_line
		(start 351.126044 -382.34493)
		(end 350.855534 -382.61544)
		(stroke
			(width 0.06477)
			(type default)
		)
		(layer "F.Cu")
	)
	(gr_line
		(start 351.151444 -384.14833)
		(end 350.802448 -384.497326)
		(stroke
			(width 0.0508)
			(type default)
		)
		(layer "F.Cu")
	)
	(gr_line
		(start 351.16897 -391.978896)
		(end 351.245424 -391.902442)
		(stroke
			(width 0.0508)
			(type default)
		)
		(layer "F.Cu")
	)
	(gr_line
		(start 351.234756 -391.325862)
		(end 350.943418 -391.6172)
		(stroke
			(width 0.0508)
			(type default)
		)
		(layer "F.Cu")
	)
	(gr_line
		(start 351.245424 -391.902442)
		(end 351.245424 -391.784586)
		(stroke
			(width 0.0508)
			(type default)
		)
		(layer "F.Cu")
	)
	(gr_line
		(start 351.328736 -399.74647)
		(end 351.245424 -399.663158)
		(stroke
			(width 0.0508)
			(type default)
		)
		(layer "F.Cu")
	)
	(gr_line
		(start 351.398078 -397.156432)
		(end 351.918778 -397.156432)
		(stroke
			(width 0.0635)
			(type default)
		)
		(layer "F.Cu")
	)
	(gr_line
		(start 351.398078 -393.69238)
		(end 351.918778 -393.69238)
		(stroke
			(width 0.0635)
			(type default)
		)
		(layer "F.Cu")
	)
	(gr_line
		(start 351.451926 -391.51941)
		(end 351.545398 -391.612882)
		(stroke
			(width 0.0508)
			(type default)
		)
		(layer "F.Cu")
	)
	(gr_line
		(start 351.451926 -391.324592)
		(end 351.451926 -391.51941)
		(stroke
			(width 0.0508)
			(type default)
		)
		(layer "F.Cu")
	)
	(gr_line
		(start 351.545398 -391.612882)
		(end 351.545398 -392.30427)
		(stroke
			(width 0.0508)
			(type default)
		)
		(layer "F.Cu")
	)
	(gr_line
		(start 351.545906 -399.74774)
		(end 351.545906 -399.143982)
		(stroke
			(width 0.0508)
			(type default)
		)
		(layer "F.Cu")
	)
	(gr_line
		(start 351.545906 -399.143982)
		(end 351.545398 -399.143474)
		(stroke
			(width 0.0508)
			(type default)
		)
		(layer "F.Cu")
	)
	(gr_line
		(start 351.561146 -294.335962)
		(end 352.027998 -294.070024)
		(stroke
			(width 0.06477)
			(type default)
		)
		(layer "F.Cu")
	)
	(gr_line
		(start 351.561146 -278.136096)
		(end 352.027998 -277.870158)
		(stroke
			(width 0.06477)
			(type default)
		)
		(layer "F.Cu")
	)
	(gr_line
		(start 351.561146 -276.516084)
		(end 352.027998 -276.250146)
		(stroke
			(width 0.06477)
			(type default)
		)
		(layer "F.Cu")
	)
	(gr_line
		(start 351.561146 -274.896072)
		(end 352.027998 -274.630134)
		(stroke
			(width 0.06477)
			(type default)
		)
		(layer "F.Cu")
	)
	(gr_line
		(start 351.561146 -273.27606)
		(end 352.027998 -273.010122)
		(stroke
			(width 0.06477)
			(type default)
		)
		(layer "F.Cu")
	)
	(gr_line
		(start 351.561146 -271.656048)
		(end 352.027998 -271.39011)
		(stroke
			(width 0.06477)
			(type default)
		)
		(layer "F.Cu")
	)
	(gr_line
		(start 351.561146 -270.036036)
		(end 352.027998 -269.770098)
		(stroke
			(width 0.06477)
			(type default)
		)
		(layer "F.Cu")
	)
	(gr_line
		(start 351.623122 -369.660678)
		(end 351.623122 -369.928648)
		(stroke
			(width 0.06477)
			(type default)
		)
		(layer "F.Cu")
	)
	(gr_line
		(start 351.798128 -397.849344)
		(end 352.318828 -397.849344)
		(stroke
			(width 0.0635)
			(type default)
		)
		(layer "F.Cu")
	)
	(gr_line
		(start 351.798128 -394.385292)
		(end 352.318828 -394.385292)
		(stroke
			(width 0.0635)
			(type default)
		)
		(layer "F.Cu")
	)
	(gr_line
		(start 351.80524 -401.359116)
		(end 351.803208 -401.359116)
		(stroke
			(width 0.0508)
			(type default)
		)
		(layer "F.Cu")
	)
	(gr_line
		(start 351.898204 -369.385596)
		(end 351.623122 -369.660678)
		(stroke
			(width 0.06477)
			(type default)
		)
		(layer "F.Cu")
	)
	(gr_line
		(start 351.938844 -381.68453)
		(end 352.288094 -382.03378)
		(stroke
			(width 0.0508)
			(type default)
		)
		(layer "F.Cu")
	)
	(gr_line
		(start 351.943924 -401.674838)
		(end 351.943924 -401.4978)
		(stroke
			(width 0.0508)
			(type default)
		)
		(layer "F.Cu")
	)
	(gr_line
		(start 351.943924 -401.4978)
		(end 351.80524 -401.359116)
		(stroke
			(width 0.0508)
			(type default)
		)
		(layer "F.Cu")
	)
	(gr_line
		(start 351.943924 -401.0025)
		(end 351.804478 -401.141946)
		(stroke
			(width 0.0508)
			(type default)
		)
		(layer "F.Cu")
	)
	(gr_line
		(start 351.943924 -400.811238)
		(end 351.943924 -401.0025)
		(stroke
			(width 0.0508)
			(type default)
		)
		(layer "F.Cu")
	)
	(gr_line
		(start 351.964244 -379.88113)
		(end 352.234754 -380.15164)
		(stroke
			(width 0.06477)
			(type default)
		)
		(layer "F.Cu")
	)
	(gr_line
		(start 352.027998 -292.450012)
		(end 351.561146 -292.71595)
		(stroke
			(width 0.06477)
			(type default)
		)
		(layer "F.Cu")
	)
	(gr_line
		(start 352.027998 -290.83)
		(end 351.561146 -291.095938)
		(stroke
			(width 0.06477)
			(type default)
		)
		(layer "F.Cu")
	)
	(gr_line
		(start 352.027998 -289.209988)
		(end 351.561146 -289.475926)
		(stroke
			(width 0.06477)
			(type default)
		)
		(layer "F.Cu")
	)
	(gr_line
		(start 352.027998 -287.59023)
		(end 351.561146 -287.856168)
		(stroke
			(width 0.06477)
			(type default)
		)
		(layer "F.Cu")
	)
	(gr_line
		(start 352.027998 -285.970218)
		(end 351.561146 -286.236156)
		(stroke
			(width 0.06477)
			(type default)
		)
		(layer "F.Cu")
	)
	(gr_line
		(start 352.027998 -284.350206)
		(end 351.561146 -284.616144)
		(stroke
			(width 0.06477)
			(type default)
		)
		(layer "F.Cu")
	)
	(gr_line
		(start 352.027998 -282.730194)
		(end 351.561146 -282.996132)
		(stroke
			(width 0.06477)
			(type default)
		)
		(layer "F.Cu")
	)
	(gr_line
		(start 352.166174 -369.385596)
		(end 351.898204 -369.385596)
		(stroke
			(width 0.06477)
			(type default)
		)
		(layer "F.Cu")
	)
	(gr_line
		(start 352.234754 -380.85522)
		(end 351.938844 -381.15113)
		(stroke
			(width 0.06477)
			(type default)
		)
		(layer "F.Cu")
	)
	(gr_line
		(start 352.288094 -383.403856)
		(end 352.288094 -383.932176)
		(stroke
			(width 0.0508)
			(type default)
		)
		(layer "F.Cu")
	)
	(gr_line
		(start 352.396044 -369.613688)
		(end 351.851468 -370.158264)
		(stroke
			(width 0.06477)
			(type default)
		)
		(layer "F.Cu")
	)
	(gr_line
		(start 352.442272 -368.841528)
		(end 352.442272 -369.109498)
		(stroke
			(width 0.06477)
			(type default)
		)
		(layer "F.Cu")
	)
	(gr_line
		(start 352.5012 -278.136096)
		(end 352.968052 -277.870158)
		(stroke
			(width 0.06477)
			(type default)
		)
		(layer "F.Cu")
	)
	(gr_line
		(start 352.5012 -276.516084)
		(end 352.968052 -276.250146)
		(stroke
			(width 0.06477)
			(type default)
		)
		(layer "F.Cu")
	)
	(gr_line
		(start 352.5012 -274.896072)
		(end 352.968052 -274.630134)
		(stroke
			(width 0.06477)
			(type default)
		)
		(layer "F.Cu")
	)
	(gr_line
		(start 352.5012 -273.27606)
		(end 352.968052 -273.010122)
		(stroke
			(width 0.06477)
			(type default)
		)
		(layer "F.Cu")
	)
	(gr_line
		(start 352.5012 -271.656048)
		(end 352.968052 -271.39011)
		(stroke
			(width 0.06477)
			(type default)
		)
		(layer "F.Cu")
	)
	(gr_line
		(start 352.5012 -270.036036)
		(end 352.968052 -269.770098)
		(stroke
			(width 0.06477)
			(type default)
		)
		(layer "F.Cu")
	)
	(gr_line
		(start 352.505264 -383.405126)
		(end 352.615754 -383.515616)
		(stroke
			(width 0.0508)
			(type default)
		)
		(layer "F.Cu")
	)
	(gr_line
		(start 352.528886 -399.74647)
		(end 352.445574 -399.663158)
		(stroke
			(width 0.0508)
			(type default)
		)
		(layer "F.Cu")
	)
	(gr_line
		(start 352.528886 -391.701274)
		(end 352.445574 -391.784586)
		(stroke
			(width 0.0508)
			(type default)
		)
		(layer "F.Cu")
	)
	(gr_line
		(start 352.557334 -380.85522)
		(end 352.853244 -381.15113)
		(stroke
			(width 0.06477)
			(type default)
		)
		(layer "F.Cu")
	)
	(gr_line
		(start 352.598228 -397.156432)
		(end 353.118928 -397.156432)
		(stroke
			(width 0.0635)
			(type default)
		)
		(layer "F.Cu")
	)
	(gr_line
		(start 352.598228 -393.69238)
		(end 353.118928 -393.69238)
		(stroke
			(width 0.0635)
			(type default)
		)
		(layer "F.Cu")
	)
	(gr_line
		(start 352.615754 -383.820416)
		(end 352.505264 -383.930906)
		(stroke
			(width 0.0508)
			(type default)
		)
		(layer "F.Cu")
	)
	(gr_line
		(start 352.615754 -383.515616)
		(end 352.615754 -383.820416)
		(stroke
			(width 0.0508)
			(type default)
		)
		(layer "F.Cu")
	)
	(gr_line
		(start 352.65233 -390.071102)
		(end 352.652076 -390.070848)
		(stroke
			(width 0.0508)
			(type default)
		)
		(layer "F.Cu")
	)
	(gr_line
		(start 352.717354 -368.566446)
		(end 352.442272 -368.841528)
		(stroke
			(width 0.06477)
			(type default)
		)
		(layer "F.Cu")
	)
	(gr_line
		(start 352.746056 -399.74774)
		(end 352.746056 -399.143982)
		(stroke
			(width 0.0508)
			(type default)
		)
		(layer "F.Cu")
	)
	(gr_line
		(start 352.746056 -399.143982)
		(end 352.745548 -399.143474)
		(stroke
			(width 0.0508)
			(type default)
		)
		(layer "F.Cu")
	)
	(gr_line
		(start 352.746056 -392.303762)
		(end 352.745548 -392.30427)
		(stroke
			(width 0.0508)
			(type default)
		)
		(layer "F.Cu")
	)
	(gr_line
		(start 352.746056 -391.700004)
		(end 352.746056 -392.303762)
		(stroke
			(width 0.0508)
			(type default)
		)
		(layer "F.Cu")
	)
	(gr_line
		(start 352.827844 -379.88113)
		(end 352.557334 -380.15164)
		(stroke
			(width 0.06477)
			(type default)
		)
		(layer "F.Cu")
	)
	(gr_line
		(start 352.853244 -381.68453)
		(end 352.503994 -382.03378)
		(stroke
			(width 0.0508)
			(type default)
		)
		(layer "F.Cu")
	)
	(gr_line
		(start 352.968052 -292.450012)
		(end 352.5012 -292.71595)
		(stroke
			(width 0.06477)
			(type default)
		)
		(layer "F.Cu")
	)
	(gr_line
		(start 352.968052 -290.83)
		(end 352.5012 -291.095938)
		(stroke
			(width 0.06477)
			(type default)
		)
		(layer "F.Cu")
	)
	(gr_line
		(start 352.968052 -289.209988)
		(end 352.5012 -289.475926)
		(stroke
			(width 0.06477)
			(type default)
		)
		(layer "F.Cu")
	)
	(gr_line
		(start 352.968052 -287.59023)
		(end 352.5012 -287.856168)
		(stroke
			(width 0.06477)
			(type default)
		)
		(layer "F.Cu")
	)
	(gr_line
		(start 352.968052 -285.970218)
		(end 352.5012 -286.236156)
		(stroke
			(width 0.06477)
			(type default)
		)
		(layer "F.Cu")
	)
	(gr_line
		(start 352.968052 -284.350206)
		(end 352.5012 -284.616144)
		(stroke
			(width 0.06477)
			(type default)
		)
		(layer "F.Cu")
	)
	(gr_line
		(start 352.968052 -282.730194)
		(end 352.5012 -282.996132)
		(stroke
			(width 0.06477)
			(type default)
		)
		(layer "F.Cu")
	)
	(gr_line
		(start 352.985324 -368.566446)
		(end 352.717354 -368.566446)
		(stroke
			(width 0.06477)
			(type default)
		)
		(layer "F.Cu")
	)
	(gr_line
		(start 352.987356 -401.359116)
		(end 352.976688 -401.359116)
		(stroke
			(width 0.0508)
			(type default)
		)
		(layer "F.Cu")
	)
	(gr_line
		(start 352.998024 -397.849344)
		(end 353.518724 -397.849344)
		(stroke
			(width 0.0635)
			(type default)
		)
		(layer "F.Cu")
	)
	(gr_line
		(start 352.998024 -394.385292)
		(end 353.518724 -394.385292)
		(stroke
			(width 0.0635)
			(type default)
		)
		(layer "F.Cu")
	)
	(gr_line
		(start 353.144074 -401.674838)
		(end 353.144074 -401.515834)
		(stroke
			(width 0.0508)
			(type default)
		)
		(layer "F.Cu")
	)
	(gr_line
		(start 353.144074 -401.515834)
		(end 352.987356 -401.359116)
		(stroke
			(width 0.0508)
			(type default)
		)
		(layer "F.Cu")
	)
	(gr_line
		(start 353.144074 -400.97583)
		(end 352.977958 -401.141946)
		(stroke
			(width 0.0508)
			(type default)
		)
		(layer "F.Cu")
	)
	(gr_line
		(start 353.144074 -400.811238)
		(end 353.144074 -400.97583)
		(stroke
			(width 0.0508)
			(type default)
		)
		(layer "F.Cu")
	)
	(gr_line
		(start 353.21494 -368.794792)
		(end 352.670618 -369.339368)
		(stroke
			(width 0.06477)
			(type default)
		)
		(layer "F.Cu")
	)
	(gr_line
		(start 353.261422 -368.022378)
		(end 353.261422 -368.290348)
		(stroke
			(width 0.06477)
			(type default)
		)
		(layer "F.Cu")
	)
	(gr_line
		(start 353.441 -294.335962)
		(end 353.907852 -294.070024)
		(stroke
			(width 0.06477)
			(type default)
		)
		(layer "F.Cu")
	)
	(gr_line
		(start 353.536504 -367.747296)
		(end 353.261422 -368.022378)
		(stroke
			(width 0.06477)
			(type default)
		)
		(layer "F.Cu")
	)
	(gr_line
		(start 353.640644 -379.22073)
		(end 353.989894 -379.56998)
		(stroke
			(width 0.0508)
			(type default)
		)
		(layer "F.Cu")
	)
	(gr_line
		(start 353.666044 -377.41733)
		(end 353.936554 -377.68784)
		(stroke
			(width 0.06477)
			(type default)
		)
		(layer "F.Cu")
	)
	(gr_line
		(start 353.728782 -399.74647)
		(end 353.64547 -399.663158)
		(stroke
			(width 0.0508)
			(type default)
		)
		(layer "F.Cu")
	)
	(gr_line
		(start 353.728782 -391.701274)
		(end 353.64547 -391.784586)
		(stroke
			(width 0.0508)
			(type default)
		)
		(layer "F.Cu")
	)
	(gr_line
		(start 353.798124 -397.156432)
		(end 354.318824 -397.156432)
		(stroke
			(width 0.0635)
			(type default)
		)
		(layer "F.Cu")
	)
	(gr_line
		(start 353.798124 -393.69238)
		(end 354.318824 -393.69238)
		(stroke
			(width 0.0635)
			(type default)
		)
		(layer "F.Cu")
	)
	(gr_line
		(start 353.804474 -367.747296)
		(end 353.536504 -367.747296)
		(stroke
			(width 0.06477)
			(type default)
		)
		(layer "F.Cu")
	)
	(gr_line
		(start 353.907852 -295.690036)
		(end 354.216716 -295.9989)
		(stroke
			(width 0.06477)
			(type default)
		)
		(layer "F.Cu")
	)
	(gr_line
		(start 353.936554 -378.39142)
		(end 353.640644 -378.68733)
		(stroke
			(width 0.06477)
			(type default)
		)
		(layer "F.Cu")
	)
	(gr_line
		(start 353.945952 -399.74774)
		(end 353.945952 -399.143982)
		(stroke
			(width 0.0508)
			(type default)
		)
		(layer "F.Cu")
	)
	(gr_line
		(start 353.945952 -399.143982)
		(end 353.945444 -399.143474)
		(stroke
			(width 0.0508)
			(type default)
		)
		(layer "F.Cu")
	)
	(gr_line
		(start 353.945952 -392.303762)
		(end 353.945444 -392.30427)
		(stroke
			(width 0.0508)
			(type default)
		)
		(layer "F.Cu")
	)
	(gr_line
		(start 353.945952 -391.700004)
		(end 353.945952 -392.303762)
		(stroke
			(width 0.0508)
			(type default)
		)
		(layer "F.Cu")
	)
	(gr_line
		(start 354.034344 -367.975642)
		(end 353.489768 -368.519964)
		(stroke
			(width 0.06477)
			(type default)
		)
		(layer "F.Cu")
	)
	(gr_line
		(start 354.080572 -367.206784)
		(end 354.080572 -367.471198)
		(stroke
			(width 0.06477)
			(type default)
		)
		(layer "F.Cu")
	)
	(gr_line
		(start 354.188776 -401.359116)
		(end 354.18268 -401.359116)
		(stroke
			(width 0.0508)
			(type default)
		)
		(layer "F.Cu")
	)
	(gr_line
		(start 354.198174 -397.849344)
		(end 354.718874 -397.849344)
		(stroke
			(width 0.0635)
			(type default)
		)
		(layer "F.Cu")
	)
	(gr_line
		(start 354.198174 -394.385292)
		(end 354.718874 -394.385292)
		(stroke
			(width 0.0635)
			(type default)
		)
		(layer "F.Cu")
	)
	(gr_line
		(start 354.259134 -378.39142)
		(end 354.555044 -378.68733)
		(stroke
			(width 0.06477)
			(type default)
		)
		(layer "F.Cu")
	)
	(gr_line
		(start 354.34397 -401.674838)
		(end 354.34397 -401.51431)
		(stroke
			(width 0.0508)
			(type default)
		)
		(layer "F.Cu")
	)
	(gr_line
		(start 354.34397 -401.51431)
		(end 354.188776 -401.359116)
		(stroke
			(width 0.0508)
			(type default)
		)
		(layer "F.Cu")
	)
	(gr_line
		(start 354.34397 -400.981926)
		(end 354.18395 -401.141946)
		(stroke
			(width 0.0508)
			(type default)
		)
		(layer "F.Cu")
	)
	(gr_line
		(start 354.34397 -400.811238)
		(end 354.34397 -400.981926)
		(stroke
			(width 0.0508)
			(type default)
		)
		(layer "F.Cu")
	)
	(gr_line
		(start 354.355654 -366.931702)
		(end 354.080572 -367.206784)
		(stroke
			(width 0.06477)
			(type default)
		)
		(layer "F.Cu")
	)
	(gr_line
		(start 354.381054 -294.335962)
		(end 354.847906 -294.070024)
		(stroke
			(width 0.06477)
			(type default)
		)
		(layer "F.Cu")
	)
	(gr_line
		(start 354.381054 -279.756108)
		(end 354.847906 -279.49017)
		(stroke
			(width 0.06477)
			(type default)
		)
		(layer "F.Cu")
	)
	(gr_line
		(start 354.381054 -278.136096)
		(end 354.847906 -277.870158)
		(stroke
			(width 0.06477)
			(type default)
		)
		(layer "F.Cu")
	)
	(gr_line
		(start 354.381054 -276.516084)
		(end 354.847906 -276.250146)
		(stroke
			(width 0.06477)
			(type default)
		)
		(layer "F.Cu")
	)
	(gr_line
		(start 354.381054 -274.896072)
		(end 354.847906 -274.630134)
		(stroke
			(width 0.06477)
			(type default)
		)
		(layer "F.Cu")
	)
	(gr_line
		(start 354.381054 -273.27606)
		(end 354.847906 -273.010122)
		(stroke
			(width 0.06477)
			(type default)
		)
		(layer "F.Cu")
	)
	(gr_line
		(start 354.381054 -271.656048)
		(end 354.847906 -271.39011)
		(stroke
			(width 0.06477)
			(type default)
		)
		(layer "F.Cu")
	)
	(gr_line
		(start 354.381054 -270.036036)
		(end 354.847906 -269.770098)
		(stroke
			(width 0.06477)
			(type default)
		)
		(layer "F.Cu")
	)
	(gr_line
		(start 354.529644 -377.41733)
		(end 354.259134 -377.68784)
		(stroke
			(width 0.06477)
			(type default)
		)
		(layer "F.Cu")
	)
	(gr_line
		(start 354.547932 -225.310192)
		(end 354.081334 -225.044254)
		(stroke
			(width 0.06477)
			(type default)
		)
		(layer "F.Cu")
	)
	(gr_line
		(start 354.555044 -379.22073)
		(end 354.205794 -379.56998)
		(stroke
			(width 0.0508)
			(type default)
		)
		(layer "F.Cu")
	)
	(gr_line
		(start 354.620068 -366.931702)
		(end 354.355654 -366.931702)
		(stroke
			(width 0.06477)
			(type default)
		)
		(layer "F.Cu")
	)
	(gr_line
		(start 354.847906 -295.690036)
		(end 354.539296 -295.998646)
		(stroke
			(width 0.06477)
			(type default)
		)
		(layer "F.Cu")
	)
	(gr_line
		(start 354.847906 -292.450012)
		(end 354.381054 -292.71595)
		(stroke
			(width 0.06477)
			(type default)
		)
		(layer "F.Cu")
	)
	(gr_line
		(start 354.847906 -290.83)
		(end 354.381054 -291.095938)
		(stroke
			(width 0.06477)
			(type default)
		)
		(layer "F.Cu")
	)
	(gr_line
		(start 354.847906 -289.209988)
		(end 354.381054 -289.475926)
		(stroke
			(width 0.06477)
			(type default)
		)
		(layer "F.Cu")
	)
	(gr_line
		(start 354.847906 -287.59023)
		(end 354.381054 -287.856168)
		(stroke
			(width 0.06477)
			(type default)
		)
		(layer "F.Cu")
	)
	(gr_line
		(start 354.847906 -285.970218)
		(end 354.381054 -286.236156)
		(stroke
			(width 0.06477)
			(type default)
		)
		(layer "F.Cu")
	)
	(gr_line
		(start 354.847906 -284.350206)
		(end 354.381054 -284.616144)
		(stroke
			(width 0.06477)
			(type default)
		)
		(layer "F.Cu")
	)
	(gr_line
		(start 354.847906 -282.730194)
		(end 354.381054 -282.996132)
		(stroke
			(width 0.06477)
			(type default)
		)
		(layer "F.Cu")
	)
	(gr_line
		(start 354.849684 -367.160048)
		(end 354.308918 -367.701068)
		(stroke
			(width 0.06477)
			(type default)
		)
		(layer "F.Cu")
	)
	(gr_line
		(start 354.896166 -366.39119)
		(end 354.896166 -366.655604)
		(stroke
			(width 0.06477)
			(type default)
		)
		(layer "F.Cu")
	)
	(gr_line
		(start 355.171248 -366.116108)
		(end 354.896166 -366.39119)
		(stroke
			(width 0.06477)
			(type default)
		)
		(layer "F.Cu")
	)
	(gr_line
		(start 355.17328 -381.460502)
		(end 355.547168 -381.83439)
		(stroke
			(width 0.0508)
			(type default)
		)
		(layer "F.Cu")
	)
	(gr_line
		(start 355.321108 -279.756108)
		(end 355.78796 -279.49017)
		(stroke
			(width 0.06477)
			(type default)
		)
		(layer "F.Cu")
	)
	(gr_line
		(start 355.321108 -278.136096)
		(end 355.78796 -277.870158)
		(stroke
			(width 0.06477)
			(type default)
		)
		(layer "F.Cu")
	)
	(gr_line
		(start 355.321108 -276.516084)
		(end 355.78796 -276.250146)
		(stroke
			(width 0.06477)
			(type default)
		)
		(layer "F.Cu")
	)
	(gr_line
		(start 355.321108 -274.896072)
		(end 355.78796 -274.630134)
		(stroke
			(width 0.06477)
			(type default)
		)
		(layer "F.Cu")
	)
	(gr_line
		(start 355.321108 -273.27606)
		(end 355.78796 -273.010122)
		(stroke
			(width 0.06477)
			(type default)
		)
		(layer "F.Cu")
	)
	(gr_line
		(start 355.321108 -271.656048)
		(end 355.78796 -271.39011)
		(stroke
			(width 0.06477)
			(type default)
		)
		(layer "F.Cu")
	)
	(gr_line
		(start 355.321108 -270.036036)
		(end 355.78796 -269.770098)
		(stroke
			(width 0.06477)
			(type default)
		)
		(layer "F.Cu")
	)
	(gr_line
		(start 355.327712 -381.307594)
		(end 355.484176 -381.307594)
		(stroke
			(width 0.0508)
			(type default)
		)
		(layer "F.Cu")
	)
	(gr_line
		(start 355.435662 -366.116108)
		(end 355.171248 -366.116108)
		(stroke
			(width 0.06477)
			(type default)
		)
		(layer "F.Cu")
	)
	(gr_line
		(start 355.484176 -381.307594)
		(end 355.700076 -381.523494)
		(stroke
			(width 0.0508)
			(type default)
		)
		(layer "F.Cu")
	)
	(gr_line
		(start 355.487986 -225.310192)
		(end 355.021388 -225.044254)
		(stroke
			(width 0.06477)
			(type default)
		)
		(layer "F.Cu")
	)
	(gr_line
		(start 355.665532 -366.3442)
		(end 355.124512 -366.88522)
		(stroke
			(width 0.06477)
			(type default)
		)
		(layer "F.Cu")
	)
	(gr_line
		(start 355.700076 -381.523494)
		(end 355.700076 -381.679958)
		(stroke
			(width 0.0508)
			(type default)
		)
		(layer "F.Cu")
	)
	(gr_line
		(start 355.71176 -365.575596)
		(end 355.71176 -365.84001)
		(stroke
			(width 0.06477)
			(type default)
		)
		(layer "F.Cu")
	)
	(gr_line
		(start 355.78796 -292.450012)
		(end 355.321108 -292.71595)
		(stroke
			(width 0.06477)
			(type default)
		)
		(layer "F.Cu")
	)
	(gr_line
		(start 355.78796 -290.83)
		(end 355.321108 -291.095938)
		(stroke
			(width 0.06477)
			(type default)
		)
		(layer "F.Cu")
	)
	(gr_line
		(start 355.78796 -289.209988)
		(end 355.321108 -289.475926)
		(stroke
			(width 0.06477)
			(type default)
		)
		(layer "F.Cu")
	)
	(gr_line
		(start 355.78796 -287.59023)
		(end 355.321108 -287.856168)
		(stroke
			(width 0.06477)
			(type default)
		)
		(layer "F.Cu")
	)
	(gr_line
		(start 355.78796 -285.970218)
		(end 355.321108 -286.236156)
		(stroke
			(width 0.06477)
			(type default)
		)
		(layer "F.Cu")
	)
	(gr_line
		(start 355.78796 -284.350206)
		(end 355.321108 -284.616144)
		(stroke
			(width 0.06477)
			(type default)
		)
		(layer "F.Cu")
	)
	(gr_line
		(start 355.78796 -282.730194)
		(end 355.321108 -282.996132)
		(stroke
			(width 0.06477)
			(type default)
		)
		(layer "F.Cu")
	)
	(gr_line
		(start 355.986842 -365.300514)
		(end 355.71176 -365.575596)
		(stroke
			(width 0.06477)
			(type default)
		)
		(layer "F.Cu")
	)
	(gr_line
		(start 356.251256 -365.300514)
		(end 355.986842 -365.300514)
		(stroke
			(width 0.06477)
			(type default)
		)
		(layer "F.Cu")
	)
	(gr_line
		(start 356.480872 -365.52886)
		(end 355.939852 -366.06988)
		(stroke
			(width 0.06477)
			(type default)
		)
		(layer "F.Cu")
	)
	(gr_line
		(start 356.527354 -364.760256)
		(end 356.527354 -365.024416)
		(stroke
			(width 0.06477)
			(type default)
		)
		(layer "F.Cu")
	)
	(gr_line
		(start 356.728014 -295.690036)
		(end 357.036878 -295.9989)
		(stroke
			(width 0.06477)
			(type default)
		)
		(layer "F.Cu")
	)
	(gr_line
		(start 356.731062 -278.946102)
		(end 357.197914 -278.680164)
		(stroke
			(width 0.06477)
			(type default)
		)
		(layer "F.Cu")
	)
	(gr_line
		(start 356.731062 -277.32609)
		(end 357.197914 -277.060152)
		(stroke
			(width 0.06477)
			(type default)
		)
		(layer "F.Cu")
	)
	(gr_line
		(start 356.731062 -275.706078)
		(end 357.197914 -275.44014)
		(stroke
			(width 0.06477)
			(type default)
		)
		(layer "F.Cu")
	)
	(gr_line
		(start 356.731062 -274.086066)
		(end 357.197914 -273.820128)
		(stroke
			(width 0.06477)
			(type default)
		)
		(layer "F.Cu")
	)
	(gr_line
		(start 356.731062 -272.466054)
		(end 357.197914 -272.200116)
		(stroke
			(width 0.06477)
			(type default)
		)
		(layer "F.Cu")
	)
	(gr_line
		(start 356.731062 -270.846042)
		(end 357.197914 -270.580104)
		(stroke
			(width 0.06477)
			(type default)
		)
		(layer "F.Cu")
	)
	(gr_line
		(start 356.731062 -269.22603)
		(end 357.197914 -268.960092)
		(stroke
			(width 0.06477)
			(type default)
		)
		(layer "F.Cu")
	)
	(gr_line
		(start 356.774242 -388.090918)
		(end 356.663752 -388.201408)
		(stroke
			(width 0.0508)
			(type default)
		)
		(layer "F.Cu")
	)
	(gr_line
		(start 356.802436 -364.485174)
		(end 356.527354 -364.760256)
		(stroke
			(width 0.06477)
			(type default)
		)
		(layer "F.Cu")
	)
	(gr_line
		(start 357.044244 -379.22073)
		(end 357.393494 -379.56998)
		(stroke
			(width 0.0508)
			(type default)
		)
		(layer "F.Cu")
	)
	(gr_line
		(start 357.066596 -364.485174)
		(end 356.802436 -364.485174)
		(stroke
			(width 0.06477)
			(type default)
		)
		(layer "F.Cu")
	)
	(gr_line
		(start 357.069644 -377.41733)
		(end 357.340154 -377.68784)
		(stroke
			(width 0.06477)
			(type default)
		)
		(layer "F.Cu")
	)
	(gr_line
		(start 357.079042 -388.090918)
		(end 356.774242 -388.090918)
		(stroke
			(width 0.0508)
			(type default)
		)
		(layer "F.Cu")
	)
	(gr_line
		(start 357.189532 -388.201408)
		(end 357.079042 -388.090918)
		(stroke
			(width 0.0508)
			(type default)
		)
		(layer "F.Cu")
	)
	(gr_line
		(start 357.190802 -388.418578)
		(end 356.662482 -388.418578)
		(stroke
			(width 0.0508)
			(type default)
		)
		(layer "F.Cu")
	)
	(gr_line
		(start 357.197914 -290.019994)
		(end 356.731062 -290.285932)
		(stroke
			(width 0.06477)
			(type default)
		)
		(layer "F.Cu")
	)
	(gr_line
		(start 357.197914 -288.399982)
		(end 356.731062 -288.66592)
		(stroke
			(width 0.06477)
			(type default)
		)
		(layer "F.Cu")
	)
	(gr_line
		(start 357.197914 -286.780224)
		(end 356.731062 -287.045908)
		(stroke
			(width 0.06477)
			(type default)
		)
		(layer "F.Cu")
	)
	(gr_line
		(start 357.197914 -285.160212)
		(end 356.731062 -285.42615)
		(stroke
			(width 0.06477)
			(type default)
		)
		(layer "F.Cu")
	)
	(gr_line
		(start 357.197914 -283.5402)
		(end 356.731062 -283.806138)
		(stroke
			(width 0.06477)
			(type default)
		)
		(layer "F.Cu")
	)
	(gr_line
		(start 357.197914 -281.920188)
		(end 356.731062 -282.186126)
		(stroke
			(width 0.06477)
			(type default)
		)
		(layer "F.Cu")
	)
	(gr_line
		(start 357.296466 -364.71352)
		(end 356.7557 -365.254286)
		(stroke
			(width 0.06477)
			(type default)
		)
		(layer "F.Cu")
	)
	(gr_line
		(start 357.340154 -378.39142)
		(end 357.044244 -378.68733)
		(stroke
			(width 0.06477)
			(type default)
		)
		(layer "F.Cu")
	)
	(gr_line
		(start 357.609394 -379.909832)
		(end 357.609648 -379.909578)
		(stroke
			(width 0.0508)
			(type default)
		)
		(layer "F.Cu")
	)
	(gr_line
		(start 357.656638 -385.10083)
		(end 357.566722 -385.10083)
		(stroke
			(width 0.0508)
			(type default)
		)
		(layer "F.Cu")
	)
	(gr_line
		(start 357.662734 -378.39142)
		(end 357.958644 -378.68733)
		(stroke
			(width 0.06477)
			(type default)
		)
		(layer "F.Cu")
	)
	(gr_line
		(start 357.668068 -295.690036)
		(end 357.359458 -295.998646)
		(stroke
			(width 0.06477)
			(type default)
		)
		(layer "F.Cu")
	)
	(gr_line
		(start 357.671116 -278.946102)
		(end 358.137968 -278.680164)
		(stroke
			(width 0.06477)
			(type default)
		)
		(layer "F.Cu")
	)
	(gr_line
		(start 357.671116 -277.32609)
		(end 358.137968 -277.060152)
		(stroke
			(width 0.06477)
			(type default)
		)
		(layer "F.Cu")
	)
	(gr_line
		(start 357.671116 -275.706078)
		(end 358.137968 -275.44014)
		(stroke
			(width 0.06477)
			(type default)
		)
		(layer "F.Cu")
	)
	(gr_line
		(start 357.671116 -274.086066)
		(end 358.137968 -273.820128)
		(stroke
			(width 0.06477)
			(type default)
		)
		(layer "F.Cu")
	)
	(gr_line
		(start 357.671116 -272.466054)
		(end 358.137968 -272.200116)
		(stroke
			(width 0.06477)
			(type default)
		)
		(layer "F.Cu")
	)
	(gr_line
		(start 357.671116 -270.846042)
		(end 358.137968 -270.580104)
		(stroke
			(width 0.06477)
			(type default)
		)
		(layer "F.Cu")
	)
	(gr_line
		(start 357.671116 -269.22603)
		(end 358.137968 -268.960092)
		(stroke
			(width 0.06477)
			(type default)
		)
		(layer "F.Cu")
	)
	(gr_line
		(start 357.796338 -385.158742)
		(end 357.656638 -385.10083)
		(stroke
			(width 0.0508)
			(type default)
		)
		(layer "F.Cu")
	)
	(gr_line
		(start 357.933244 -377.41733)
		(end 357.662734 -377.68784)
		(stroke
			(width 0.06477)
			(type default)
		)
		(layer "F.Cu")
	)
	(gr_line
		(start 357.958644 -379.22073)
		(end 357.609394 -379.56998)
		(stroke
			(width 0.0508)
			(type default)
		)
		(layer "F.Cu")
	)
	(gr_line
		(start 358.001824 -388.767828)
		(end 357.652574 -388.418578)
		(stroke
			(width 0.0508)
			(type default)
		)
		(layer "F.Cu")
	)
	(gr_line
		(start 358.001824 -387.853428)
		(end 357.652574 -388.202678)
		(stroke
			(width 0.0508)
			(type default)
		)
		(layer "F.Cu")
	)
	(gr_line
		(start 358.001824 -385.364228)
		(end 357.796338 -385.158742)
		(stroke
			(width 0.0508)
			(type default)
		)
		(layer "F.Cu")
	)
	(gr_line
		(start 358.001824 -384.449828)
		(end 357.567992 -384.88366)
		(stroke
			(width 0.0508)
			(type default)
		)
		(layer "F.Cu")
	)
	(gr_line
		(start 358.137968 -290.019994)
		(end 357.671116 -290.285932)
		(stroke
			(width 0.06477)
			(type default)
		)
		(layer "F.Cu")
	)
	(gr_line
		(start 358.137968 -288.399982)
		(end 357.671116 -288.66592)
		(stroke
			(width 0.06477)
			(type default)
		)
		(layer "F.Cu")
	)
	(gr_line
		(start 358.137968 -286.780224)
		(end 357.671116 -287.045908)
		(stroke
			(width 0.06477)
			(type default)
		)
		(layer "F.Cu")
	)
	(gr_line
		(start 358.137968 -285.160212)
		(end 357.671116 -285.42615)
		(stroke
			(width 0.06477)
			(type default)
		)
		(layer "F.Cu")
	)
	(gr_line
		(start 358.137968 -283.5402)
		(end 357.671116 -283.806138)
		(stroke
			(width 0.06477)
			(type default)
		)
		(layer "F.Cu")
	)
	(gr_line
		(start 358.137968 -281.920188)
		(end 357.671116 -282.186126)
		(stroke
			(width 0.06477)
			(type default)
		)
		(layer "F.Cu")
	)
	(gr_line
		(start 358.323896 -381.286258)
		(end 358.697784 -381.660146)
		(stroke
			(width 0.0508)
			(type default)
		)
		(layer "F.Cu")
	)
	(gr_line
		(start 358.478074 -381.13335)
		(end 358.634792 -381.13335)
		(stroke
			(width 0.0508)
			(type default)
		)
		(layer "F.Cu")
	)
	(gr_line
		(start 358.634792 -381.13335)
		(end 358.850692 -381.34925)
		(stroke
			(width 0.0508)
			(type default)
		)
		(layer "F.Cu")
	)
	(gr_line
		(start 358.831134 -388.471918)
		(end 358.535224 -388.767828)
		(stroke
			(width 0.06477)
			(type default)
		)
		(layer "F.Cu")
	)
	(gr_line
		(start 358.831134 -388.149338)
		(end 358.535224 -387.853428)
		(stroke
			(width 0.06477)
			(type default)
		)
		(layer "F.Cu")
	)
	(gr_line
		(start 358.831134 -385.068318)
		(end 358.535224 -385.364228)
		(stroke
			(width 0.06477)
			(type default)
		)
		(layer "F.Cu")
	)
	(gr_line
		(start 358.831134 -384.745738)
		(end 358.535224 -384.449828)
		(stroke
			(width 0.06477)
			(type default)
		)
		(layer "F.Cu")
	)
	(gr_line
		(start 358.850692 -381.34925)
		(end 358.850692 -381.505968)
		(stroke
			(width 0.0508)
			(type default)
		)
		(layer "F.Cu")
	)
	(gr_line
		(start 359.805224 -388.742428)
		(end 359.534714 -388.471918)
		(stroke
			(width 0.06477)
			(type default)
		)
		(layer "F.Cu")
	)
	(gr_line
		(start 359.805224 -387.878828)
		(end 359.534714 -388.149338)
		(stroke
			(width 0.06477)
			(type default)
		)
		(layer "F.Cu")
	)
	(gr_line
		(start 359.805224 -385.338828)
		(end 359.534714 -385.068318)
		(stroke
			(width 0.06477)
			(type default)
		)
		(layer "F.Cu")
	)
	(gr_line
		(start 359.805224 -384.475228)
		(end 359.534714 -384.745738)
		(stroke
			(width 0.06477)
			(type default)
		)
		(layer "F.Cu")
	)
	(gr_line
		(start 360.1212 -319.710308)
		(end 360.098594 -319.732914)
		(stroke
			(width 0.06477)
			(type default)
		)
		(layer "F.Cu")
	)
	(gr_line
		(start 361.597956 -248.800112)
		(end 362.064808 -248.534174)
		(stroke
			(width 0.06477)
			(type default)
		)
		(layer "F.Cu")
	)
	(gr_line
		(start 361.597956 -247.1801)
		(end 362.064808 -246.914162)
		(stroke
			(width 0.06477)
			(type default)
		)
		(layer "F.Cu")
	)
	(gr_line
		(start 361.597956 -245.560088)
		(end 362.064808 -245.29415)
		(stroke
			(width 0.06477)
			(type default)
		)
		(layer "F.Cu")
	)
	(gr_line
		(start 361.597956 -243.940076)
		(end 362.064808 -243.674138)
		(stroke
			(width 0.06477)
			(type default)
		)
		(layer "F.Cu")
	)
	(gr_line
		(start 361.597956 -235.840016)
		(end 362.064808 -235.574078)
		(stroke
			(width 0.06477)
			(type default)
		)
		(layer "F.Cu")
	)
	(gr_line
		(start 361.597956 -234.220004)
		(end 362.064808 -233.954066)
		(stroke
			(width 0.06477)
			(type default)
		)
		(layer "F.Cu")
	)
	(gr_line
		(start 361.597956 -232.599992)
		(end 362.064808 -232.334054)
		(stroke
			(width 0.06477)
			(type default)
		)
		(layer "F.Cu")
	)
	(gr_line
		(start 361.89793 -278.680164)
		(end 362.364782 -278.946102)
		(stroke
			(width 0.06477)
			(type default)
		)
		(layer "F.Cu")
	)
	(gr_line
		(start 361.89793 -277.060152)
		(end 362.364782 -277.32609)
		(stroke
			(width 0.06477)
			(type default)
		)
		(layer "F.Cu")
	)
	(gr_line
		(start 361.89793 -275.44014)
		(end 362.364782 -275.706078)
		(stroke
			(width 0.06477)
			(type default)
		)
		(layer "F.Cu")
	)
	(gr_line
		(start 361.89793 -273.820128)
		(end 362.364782 -274.086066)
		(stroke
			(width 0.06477)
			(type default)
		)
		(layer "F.Cu")
	)
	(gr_line
		(start 361.89793 -272.200116)
		(end 362.364782 -272.466054)
		(stroke
			(width 0.06477)
			(type default)
		)
		(layer "F.Cu")
	)
	(gr_line
		(start 361.89793 -270.580104)
		(end 362.364782 -270.846042)
		(stroke
			(width 0.06477)
			(type default)
		)
		(layer "F.Cu")
	)
	(gr_line
		(start 361.89793 -268.960092)
		(end 362.364782 -269.22603)
		(stroke
			(width 0.06477)
			(type default)
		)
		(layer "F.Cu")
	)
	(gr_line
		(start 362.364782 -290.285932)
		(end 361.89793 -290.019994)
		(stroke
			(width 0.06477)
			(type default)
		)
		(layer "F.Cu")
	)
	(gr_line
		(start 362.364782 -288.66592)
		(end 361.89793 -288.399982)
		(stroke
			(width 0.06477)
			(type default)
		)
		(layer "F.Cu")
	)
	(gr_line
		(start 362.364782 -287.045908)
		(end 361.89793 -286.780224)
		(stroke
			(width 0.06477)
			(type default)
		)
		(layer "F.Cu")
	)
	(gr_line
		(start 362.364782 -285.42615)
		(end 361.89793 -285.160212)
		(stroke
			(width 0.06477)
			(type default)
		)
		(layer "F.Cu")
	)
	(gr_line
		(start 362.364782 -283.806138)
		(end 361.89793 -283.5402)
		(stroke
			(width 0.06477)
			(type default)
		)
		(layer "F.Cu")
	)
	(gr_line
		(start 362.364782 -282.186126)
		(end 361.89793 -281.920188)
		(stroke
			(width 0.06477)
			(type default)
		)
		(layer "F.Cu")
	)
	(gr_line
		(start 362.53801 -248.800112)
		(end 363.004862 -248.534174)
		(stroke
			(width 0.06477)
			(type default)
		)
		(layer "F.Cu")
	)
	(gr_line
		(start 362.53801 -247.1801)
		(end 363.004862 -246.914162)
		(stroke
			(width 0.06477)
			(type default)
		)
		(layer "F.Cu")
	)
	(gr_line
		(start 362.53801 -245.560088)
		(end 363.004862 -245.29415)
		(stroke
			(width 0.06477)
			(type default)
		)
		(layer "F.Cu")
	)
	(gr_line
		(start 362.53801 -243.940076)
		(end 363.004862 -243.674138)
		(stroke
			(width 0.06477)
			(type default)
		)
		(layer "F.Cu")
	)
	(gr_line
		(start 362.837984 -278.680164)
		(end 363.304836 -278.946102)
		(stroke
			(width 0.06477)
			(type default)
		)
		(layer "F.Cu")
	)
	(gr_line
		(start 362.837984 -277.060152)
		(end 363.304836 -277.32609)
		(stroke
			(width 0.06477)
			(type default)
		)
		(layer "F.Cu")
	)
	(gr_line
		(start 362.837984 -275.44014)
		(end 363.304836 -275.706078)
		(stroke
			(width 0.06477)
			(type default)
		)
		(layer "F.Cu")
	)
	(gr_line
		(start 362.837984 -273.820128)
		(end 363.304836 -274.086066)
		(stroke
			(width 0.06477)
			(type default)
		)
		(layer "F.Cu")
	)
	(gr_line
		(start 362.837984 -272.200116)
		(end 363.304836 -272.466054)
		(stroke
			(width 0.06477)
			(type default)
		)
		(layer "F.Cu")
	)
	(gr_line
		(start 362.837984 -270.580104)
		(end 363.304836 -270.846042)
		(stroke
			(width 0.06477)
			(type default)
		)
		(layer "F.Cu")
	)
	(gr_line
		(start 362.837984 -268.960092)
		(end 363.304836 -269.22603)
		(stroke
			(width 0.06477)
			(type default)
		)
		(layer "F.Cu")
	)
	(gr_line
		(start 363.004862 -235.574078)
		(end 362.53801 -235.840016)
		(stroke
			(width 0.06477)
			(type default)
		)
		(layer "F.Cu")
	)
	(gr_line
		(start 363.004862 -233.954066)
		(end 362.53801 -234.220004)
		(stroke
			(width 0.06477)
			(type default)
		)
		(layer "F.Cu")
	)
	(gr_line
		(start 363.004862 -232.334054)
		(end 362.53801 -232.599992)
		(stroke
			(width 0.06477)
			(type default)
		)
		(layer "F.Cu")
	)
	(gr_line
		(start 363.304836 -290.285932)
		(end 362.837984 -290.019994)
		(stroke
			(width 0.06477)
			(type default)
		)
		(layer "F.Cu")
	)
	(gr_line
		(start 363.304836 -288.66592)
		(end 362.837984 -288.399982)
		(stroke
			(width 0.06477)
			(type default)
		)
		(layer "F.Cu")
	)
	(gr_line
		(start 363.304836 -287.045908)
		(end 362.837984 -286.780224)
		(stroke
			(width 0.06477)
			(type default)
		)
		(layer "F.Cu")
	)
	(gr_line
		(start 363.304836 -285.42615)
		(end 362.837984 -285.160212)
		(stroke
			(width 0.06477)
			(type default)
		)
		(layer "F.Cu")
	)
	(gr_line
		(start 363.304836 -283.806138)
		(end 362.837984 -283.5402)
		(stroke
			(width 0.06477)
			(type default)
		)
		(layer "F.Cu")
	)
	(gr_line
		(start 363.304836 -282.186126)
		(end 362.837984 -281.920188)
		(stroke
			(width 0.06477)
			(type default)
		)
		(layer "F.Cu")
	)
	(gr_line
		(start 363.947964 -247.990106)
		(end 364.414816 -247.724168)
		(stroke
			(width 0.06477)
			(type default)
		)
		(layer "F.Cu")
	)
	(gr_line
		(start 363.947964 -246.370094)
		(end 364.414816 -246.104156)
		(stroke
			(width 0.06477)
			(type default)
		)
		(layer "F.Cu")
	)
	(gr_line
		(start 363.947964 -244.750082)
		(end 364.414816 -244.484144)
		(stroke
			(width 0.06477)
			(type default)
		)
		(layer "F.Cu")
	)
	(gr_line
		(start 363.947964 -235.03001)
		(end 364.414816 -234.764072)
		(stroke
			(width 0.06477)
			(type default)
		)
		(layer "F.Cu")
	)
	(gr_line
		(start 363.947964 -233.409998)
		(end 364.414816 -233.14406)
		(stroke
			(width 0.06477)
			(type default)
		)
		(layer "F.Cu")
	)
	(gr_line
		(start 363.947964 -231.789986)
		(end 364.414816 -231.524048)
		(stroke
			(width 0.06477)
			(type default)
		)
		(layer "F.Cu")
	)
	(gr_line
		(start 364.247938 -279.49017)
		(end 364.71479 -279.756108)
		(stroke
			(width 0.06477)
			(type default)
		)
		(layer "F.Cu")
	)
	(gr_line
		(start 364.247938 -277.870158)
		(end 364.71479 -278.136096)
		(stroke
			(width 0.06477)
			(type default)
		)
		(layer "F.Cu")
	)
	(gr_line
		(start 364.247938 -276.250146)
		(end 364.71479 -276.516084)
		(stroke
			(width 0.06477)
			(type default)
		)
		(layer "F.Cu")
	)
	(gr_line
		(start 364.247938 -274.630134)
		(end 364.71479 -274.896072)
		(stroke
			(width 0.06477)
			(type default)
		)
		(layer "F.Cu")
	)
	(gr_line
		(start 364.247938 -273.010122)
		(end 364.71479 -273.27606)
		(stroke
			(width 0.06477)
			(type default)
		)
		(layer "F.Cu")
	)
	(gr_line
		(start 364.247938 -271.39011)
		(end 364.71479 -271.656048)
		(stroke
			(width 0.06477)
			(type default)
		)
		(layer "F.Cu")
	)
	(gr_line
		(start 364.247938 -269.770098)
		(end 364.71479 -270.036036)
		(stroke
			(width 0.06477)
			(type default)
		)
		(layer "F.Cu")
	)
	(gr_line
		(start 364.382812 -396.171674)
		(end 364.653322 -395.901164)
		(stroke
			(width 0.06477)
			(type default)
		)
		(layer "F.Cu")
	)
	(gr_line
		(start 364.382812 -395.308074)
		(end 364.653322 -395.578584)
		(stroke
			(width 0.06477)
			(type default)
		)
		(layer "F.Cu")
	)
	(gr_line
		(start 364.53064 -390.75106)
		(end 364.80115 -390.48055)
		(stroke
			(width 0.06477)
			(type default)
		)
		(layer "F.Cu")
	)
	(gr_line
		(start 364.53064 -389.88746)
		(end 364.80115 -390.15797)
		(stroke
			(width 0.06477)
			(type default)
		)
		(layer "F.Cu")
	)
	(gr_line
		(start 364.53064 -385.21386)
		(end 364.80115 -384.94335)
		(stroke
			(width 0.06477)
			(type default)
		)
		(layer "F.Cu")
	)
	(gr_line
		(start 364.53064 -384.35026)
		(end 364.80115 -384.62077)
		(stroke
			(width 0.06477)
			(type default)
		)
		(layer "F.Cu")
	)
	(gr_line
		(start 364.71479 -291.095938)
		(end 364.247938 -290.83)
		(stroke
			(width 0.06477)
			(type default)
		)
		(layer "F.Cu")
	)
	(gr_line
		(start 364.71479 -289.475926)
		(end 364.247938 -289.209988)
		(stroke
			(width 0.06477)
			(type default)
		)
		(layer "F.Cu")
	)
	(gr_line
		(start 364.71479 -287.856168)
		(end 364.247938 -287.59023)
		(stroke
			(width 0.06477)
			(type default)
		)
		(layer "F.Cu")
	)
	(gr_line
		(start 364.71479 -286.236156)
		(end 364.247938 -285.970218)
		(stroke
			(width 0.06477)
			(type default)
		)
		(layer "F.Cu")
	)
	(gr_line
		(start 364.71479 -284.616144)
		(end 364.247938 -284.350206)
		(stroke
			(width 0.06477)
			(type default)
		)
		(layer "F.Cu")
	)
	(gr_line
		(start 364.71479 -282.996132)
		(end 364.247938 -282.730194)
		(stroke
			(width 0.06477)
			(type default)
		)
		(layer "F.Cu")
	)
	(gr_line
		(start 364.888018 -247.990106)
		(end 365.35487 -247.724168)
		(stroke
			(width 0.06477)
			(type default)
		)
		(layer "F.Cu")
	)
	(gr_line
		(start 364.888018 -246.370094)
		(end 365.35487 -246.104156)
		(stroke
			(width 0.06477)
			(type default)
		)
		(layer "F.Cu")
	)
	(gr_line
		(start 364.888018 -244.750082)
		(end 365.35487 -244.484144)
		(stroke
			(width 0.06477)
			(type default)
		)
		(layer "F.Cu")
	)
	(gr_line
		(start 365.11611 -395.901164)
		(end 365.36122 -396.146274)
		(stroke
			(width 0.06477)
			(type default)
		)
		(layer "F.Cu")
	)
	(gr_line
		(start 365.11611 -395.578584)
		(end 365.36122 -395.333474)
		(stroke
			(width 0.06477)
			(type default)
		)
		(layer "F.Cu")
	)
	(gr_line
		(start 365.187992 -279.49017)
		(end 365.654844 -279.756108)
		(stroke
			(width 0.06477)
			(type default)
		)
		(layer "F.Cu")
	)
	(gr_line
		(start 365.187992 -277.870158)
		(end 365.654844 -278.136096)
		(stroke
			(width 0.06477)
			(type default)
		)
		(layer "F.Cu")
	)
	(gr_line
		(start 365.187992 -276.250146)
		(end 365.654844 -276.516084)
		(stroke
			(width 0.06477)
			(type default)
		)
		(layer "F.Cu")
	)
	(gr_line
		(start 365.187992 -274.630134)
		(end 365.654844 -274.896072)
		(stroke
			(width 0.06477)
			(type default)
		)
		(layer "F.Cu")
	)
	(gr_line
		(start 365.187992 -273.010122)
		(end 365.654844 -273.27606)
		(stroke
			(width 0.06477)
			(type default)
		)
		(layer "F.Cu")
	)
	(gr_line
		(start 365.187992 -271.39011)
		(end 365.654844 -271.656048)
		(stroke
			(width 0.06477)
			(type default)
		)
		(layer "F.Cu")
	)
	(gr_line
		(start 365.187992 -269.770098)
		(end 365.654844 -270.036036)
		(stroke
			(width 0.06477)
			(type default)
		)
		(layer "F.Cu")
	)
	(gr_line
		(start 365.217964 -5.238496)
		(end 365.2139 -5.238496)
		(stroke
			(width 0.06477)
			(type default)
		)
		(layer "F.Cu")
	)
	(gr_line
		(start 365.302546 -4.82727)
		(end 365.21517 -4.914646)
		(stroke
			(width 0.06477)
			(type default)
		)
		(layer "F.Cu")
	)
	(gr_line
		(start 365.30661 -5.327142)
		(end 365.217964 -5.238496)
		(stroke
			(width 0.06477)
			(type default)
		)
		(layer "F.Cu")
	)
	(gr_line
		(start 365.35487 -234.764072)
		(end 364.888018 -235.03001)
		(stroke
			(width 0.06477)
			(type default)
		)
		(layer "F.Cu")
	)
	(gr_line
		(start 365.35487 -233.14406)
		(end 364.888018 -233.409998)
		(stroke
			(width 0.06477)
			(type default)
		)
		(layer "F.Cu")
	)
	(gr_line
		(start 365.35487 -231.524048)
		(end 364.888018 -231.789986)
		(stroke
			(width 0.06477)
			(type default)
		)
		(layer "F.Cu")
	)
	(gr_line
		(start 365.387128 -324.69709)
		(end 365.733838 -325.0438)
		(stroke
			(width 0.06477)
			(type default)
		)
		(layer "F.Cu")
	)
	(gr_line
		(start 365.463074 -5.327142)
		(end 365.30661 -5.327142)
		(stroke
			(width 0.06477)
			(type default)
		)
		(layer "F.Cu")
	)
	(gr_line
		(start 365.463074 -4.82727)
		(end 365.302546 -4.82727)
		(stroke
			(width 0.06477)
			(type default)
		)
		(layer "F.Cu")
	)
	(gr_line
		(start 365.463074 -0.247142)
		(end 364.810802 -0.429006)
		(stroke
			(width 0.06477)
			(type default)
		)
		(layer "F.Cu")
	)
	(gr_line
		(start 365.463074 0.25273)
		(end 364.810802 0.434594)
		(stroke
			(width 0.06477)
			(type default)
		)
		(layer "F.Cu")
	)
	(gr_line
		(start 365.463074 4.832858)
		(end 364.810802 4.650994)
		(stroke
			(width 0.06477)
			(type default)
		)
		(layer "F.Cu")
	)
	(gr_line
		(start 365.463074 5.33273)
		(end 364.810802 5.514594)
		(stroke
			(width 0.06477)
			(type default)
		)
		(layer "F.Cu")
	)
	(gr_line
		(start 365.50473 -390.48055)
		(end 365.80064 -390.77646)
		(stroke
			(width 0.06477)
			(type default)
		)
		(layer "F.Cu")
	)
	(gr_line
		(start 365.50473 -390.15797)
		(end 365.80064 -389.86206)
		(stroke
			(width 0.06477)
			(type default)
		)
		(layer "F.Cu")
	)
	(gr_line
		(start 365.50473 -384.94335)
		(end 365.80064 -385.23926)
		(stroke
			(width 0.06477)
			(type default)
		)
		(layer "F.Cu")
	)
	(gr_line
		(start 365.50473 -384.62077)
		(end 365.80064 -384.32486)
		(stroke
			(width 0.06477)
			(type default)
		)
		(layer "F.Cu")
	)
	(gr_line
		(start 365.654844 -291.095938)
		(end 365.187992 -290.83)
		(stroke
			(width 0.06477)
			(type default)
		)
		(layer "F.Cu")
	)
	(gr_line
		(start 365.654844 -289.475926)
		(end 365.187992 -289.209988)
		(stroke
			(width 0.06477)
			(type default)
		)
		(layer "F.Cu")
	)
	(gr_line
		(start 365.654844 -287.856168)
		(end 365.187992 -287.59023)
		(stroke
			(width 0.06477)
			(type default)
		)
		(layer "F.Cu")
	)
	(gr_line
		(start 365.654844 -286.236156)
		(end 365.187992 -285.970218)
		(stroke
			(width 0.06477)
			(type default)
		)
		(layer "F.Cu")
	)
	(gr_line
		(start 365.654844 -284.616144)
		(end 365.187992 -284.350206)
		(stroke
			(width 0.06477)
			(type default)
		)
		(layer "F.Cu")
	)
	(gr_line
		(start 365.654844 -282.996132)
		(end 365.187992 -282.730194)
		(stroke
			(width 0.06477)
			(type default)
		)
		(layer "F.Cu")
	)
	(gr_line
		(start 365.733838 -323.55028)
		(end 365.387128 -323.89699)
		(stroke
			(width 0.06477)
			(type default)
		)
		(layer "F.Cu")
	)
	(gr_line
		(start 365.89462 -396.146274)
		(end 366.139222 -395.901672)
		(stroke
			(width 0.06477)
			(type default)
		)
		(layer "F.Cu")
	)
	(gr_line
		(start 365.89462 -395.333474)
		(end 366.138968 -395.577822)
		(stroke
			(width 0.06477)
			(type default)
		)
		(layer "F.Cu")
	)
	(gr_line
		(start 366.056418 -323.55028)
		(end 366.403128 -323.89699)
		(stroke
			(width 0.06477)
			(type default)
		)
		(layer "F.Cu")
	)
	(gr_line
		(start 366.089692 -381.68453)
		(end 366.438942 -382.03378)
		(stroke
			(width 0.0508)
			(type default)
		)
		(layer "F.Cu")
	)
	(gr_line
		(start 366.115092 -379.88113)
		(end 366.385602 -380.15164)
		(stroke
			(width 0.06477)
			(type default)
		)
		(layer "F.Cu")
	)
	(gr_line
		(start 366.138968 -395.577822)
		(end 366.140492 -395.577822)
		(stroke
			(width 0.06477)
			(type default)
		)
		(layer "F.Cu")
	)
	(gr_line
		(start 366.33404 -390.77646)
		(end 366.683798 -390.426702)
		(stroke
			(width 0.0508)
			(type default)
		)
		(layer "F.Cu")
	)
	(gr_line
		(start 366.33404 -389.86206)
		(end 366.681512 -390.209532)
		(stroke
			(width 0.0508)
			(type default)
		)
		(layer "F.Cu")
	)
	(gr_line
		(start 366.33404 -385.23926)
		(end 366.703864 -384.869436)
		(stroke
			(width 0.0508)
			(type default)
		)
		(layer "F.Cu")
	)
	(gr_line
		(start 366.33404 -384.32486)
		(end 366.661446 -384.652266)
		(stroke
			(width 0.0508)
			(type default)
		)
		(layer "F.Cu")
	)
	(gr_line
		(start 366.385602 -380.85522)
		(end 366.089692 -381.15113)
		(stroke
			(width 0.06477)
			(type default)
		)
		(layer "F.Cu")
	)
	(gr_line
		(start 366.398048 -395.577822)
		(end 366.399572 -395.577822)
		(stroke
			(width 0.06477)
			(type default)
		)
		(layer "F.Cu")
	)
	(gr_line
		(start 366.399318 -395.901672)
		(end 366.64392 -396.146274)
		(stroke
			(width 0.06477)
			(type default)
		)
		(layer "F.Cu")
	)
	(gr_line
		(start 366.399572 -395.577822)
		(end 366.64392 -395.333474)
		(stroke
			(width 0.06477)
			(type default)
		)
		(layer "F.Cu")
	)
	(gr_line
		(start 366.403128 -324.69709)
		(end 366.056418 -325.0438)
		(stroke
			(width 0.06477)
			(type default)
		)
		(layer "F.Cu")
	)
	(gr_line
		(start 366.64392 -396.146274)
		(end 366.899952 -395.890242)
		(stroke
			(width 0.06477)
			(type default)
		)
		(layer "F.Cu")
	)
	(gr_line
		(start 366.64392 -395.333474)
		(end 366.876838 -395.566392)
		(stroke
			(width 0.06477)
			(type default)
		)
		(layer "F.Cu")
	)
	(gr_line
		(start 366.661446 -384.652266)
		(end 366.705134 -384.652266)
		(stroke
			(width 0.0508)
			(type default)
		)
		(layer "F.Cu")
	)
	(gr_line
		(start 366.681512 -390.209532)
		(end 366.685068 -390.209532)
		(stroke
			(width 0.0508)
			(type default)
		)
		(layer "F.Cu")
	)
	(gr_line
		(start 366.708182 -380.85522)
		(end 367.004092 -381.15113)
		(stroke
			(width 0.06477)
			(type default)
		)
		(layer "F.Cu")
	)
	(gr_line
		(start 366.767872 -247.990106)
		(end 367.234724 -247.724168)
		(stroke
			(width 0.06477)
			(type default)
		)
		(layer "F.Cu")
	)
	(gr_line
		(start 366.767872 -246.370094)
		(end 367.234724 -246.104156)
		(stroke
			(width 0.06477)
			(type default)
		)
		(layer "F.Cu")
	)
	(gr_line
		(start 366.767872 -244.750082)
		(end 367.234724 -244.484144)
		(stroke
			(width 0.06477)
			(type default)
		)
		(layer "F.Cu")
	)
	(gr_line
		(start 366.767872 -235.03001)
		(end 367.234724 -234.764072)
		(stroke
			(width 0.06477)
			(type default)
		)
		(layer "F.Cu")
	)
	(gr_line
		(start 366.767872 -233.409998)
		(end 367.234724 -233.14406)
		(stroke
			(width 0.06477)
			(type default)
		)
		(layer "F.Cu")
	)
	(gr_line
		(start 366.767872 -231.789986)
		(end 367.234724 -231.524048)
		(stroke
			(width 0.06477)
			(type default)
		)
		(layer "F.Cu")
	)
	(gr_line
		(start 366.876838 -395.566392)
		(end 366.901222 -395.566392)
		(stroke
			(width 0.06477)
			(type default)
		)
		(layer "F.Cu")
	)
	(gr_line
		(start 366.978692 -379.88113)
		(end 366.708182 -380.15164)
		(stroke
			(width 0.06477)
			(type default)
		)
		(layer "F.Cu")
	)
	(gr_line
		(start 366.989868 -390.209532)
		(end 367.518188 -390.209532)
		(stroke
			(width 0.0508)
			(type default)
		)
		(layer "F.Cu")
	)
	(gr_line
		(start 366.991138 -390.426702)
		(end 367.101628 -390.537192)
		(stroke
			(width 0.0508)
			(type default)
		)
		(layer "F.Cu")
	)
	(gr_line
		(start 367.004092 -381.68453)
		(end 366.654842 -382.03378)
		(stroke
			(width 0.0508)
			(type default)
		)
		(layer "F.Cu")
	)
	(gr_line
		(start 367.067846 -277.870158)
		(end 367.534698 -278.136096)
		(stroke
			(width 0.06477)
			(type default)
		)
		(layer "F.Cu")
	)
	(gr_line
		(start 367.067846 -276.250146)
		(end 367.534698 -276.516084)
		(stroke
			(width 0.06477)
			(type default)
		)
		(layer "F.Cu")
	)
	(gr_line
		(start 367.067846 -274.630134)
		(end 367.534698 -274.896072)
		(stroke
			(width 0.06477)
			(type default)
		)
		(layer "F.Cu")
	)
	(gr_line
		(start 367.067846 -273.010122)
		(end 367.534698 -273.27606)
		(stroke
			(width 0.06477)
			(type default)
		)
		(layer "F.Cu")
	)
	(gr_line
		(start 367.067846 -271.39011)
		(end 367.534698 -271.656048)
		(stroke
			(width 0.06477)
			(type default)
		)
		(layer "F.Cu")
	)
	(gr_line
		(start 367.067846 -269.770098)
		(end 367.534698 -270.036036)
		(stroke
			(width 0.06477)
			(type default)
		)
		(layer "F.Cu")
	)
	(gr_line
		(start 367.101628 -390.537192)
		(end 367.406428 -390.537192)
		(stroke
			(width 0.0508)
			(type default)
		)
		(layer "F.Cu")
	)
	(gr_line
		(start 367.406428 -390.537192)
		(end 367.516918 -390.426702)
		(stroke
			(width 0.0508)
			(type default)
		)
		(layer "F.Cu")
	)
	(gr_line
		(start 367.534698 -291.095938)
		(end 367.067846 -290.83)
		(stroke
			(width 0.06477)
			(type default)
		)
		(layer "F.Cu")
	)
	(gr_line
		(start 367.534698 -289.475926)
		(end 367.067846 -289.209988)
		(stroke
			(width 0.06477)
			(type default)
		)
		(layer "F.Cu")
	)
	(gr_line
		(start 367.534698 -287.856168)
		(end 367.067846 -287.59023)
		(stroke
			(width 0.06477)
			(type default)
		)
		(layer "F.Cu")
	)
	(gr_line
		(start 367.534698 -286.236156)
		(end 367.067846 -285.970218)
		(stroke
			(width 0.06477)
			(type default)
		)
		(layer "F.Cu")
	)
	(gr_line
		(start 367.534698 -284.616144)
		(end 367.067846 -284.350206)
		(stroke
			(width 0.06477)
			(type default)
		)
		(layer "F.Cu")
	)
	(gr_line
		(start 367.534698 -282.996132)
		(end 367.067846 -282.730194)
		(stroke
			(width 0.06477)
			(type default)
		)
		(layer "F.Cu")
	)
	(gr_line
		(start 367.707926 -247.990106)
		(end 368.174778 -247.724168)
		(stroke
			(width 0.06477)
			(type default)
		)
		(layer "F.Cu")
	)
	(gr_line
		(start 367.707926 -246.370094)
		(end 368.174778 -246.104156)
		(stroke
			(width 0.06477)
			(type default)
		)
		(layer "F.Cu")
	)
	(gr_line
		(start 367.707926 -244.750082)
		(end 368.174778 -244.484144)
		(stroke
			(width 0.06477)
			(type default)
		)
		(layer "F.Cu")
	)
	(gr_line
		(start 367.791492 -379.22073)
		(end 368.140742 -379.56998)
		(stroke
			(width 0.0508)
			(type default)
		)
		(layer "F.Cu")
	)
	(gr_line
		(start 367.816892 -377.41733)
		(end 368.087402 -377.68784)
		(stroke
			(width 0.06477)
			(type default)
		)
		(layer "F.Cu")
	)
	(gr_line
		(start 367.822988 -390.209532)
		(end 368.351308 -390.209532)
		(stroke
			(width 0.0508)
			(type default)
		)
		(layer "F.Cu")
	)
	(gr_line
		(start 367.824258 -390.426702)
		(end 367.934748 -390.537192)
		(stroke
			(width 0.0508)
			(type default)
		)
		(layer "F.Cu")
	)
	(gr_line
		(start 367.934748 -390.537192)
		(end 368.239548 -390.537192)
		(stroke
			(width 0.0508)
			(type default)
		)
		(layer "F.Cu")
	)
	(gr_line
		(start 368.0079 -277.870158)
		(end 368.474752 -278.136096)
		(stroke
			(width 0.06477)
			(type default)
		)
		(layer "F.Cu")
	)
	(gr_line
		(start 368.0079 -276.250146)
		(end 368.474752 -276.516084)
		(stroke
			(width 0.06477)
			(type default)
		)
		(layer "F.Cu")
	)
	(gr_line
		(start 368.0079 -274.630134)
		(end 368.474752 -274.896072)
		(stroke
			(width 0.06477)
			(type default)
		)
		(layer "F.Cu")
	)
	(gr_line
		(start 368.0079 -273.010122)
		(end 368.474752 -273.27606)
		(stroke
			(width 0.06477)
			(type default)
		)
		(layer "F.Cu")
	)
	(gr_line
		(start 368.0079 -271.39011)
		(end 368.474752 -271.656048)
		(stroke
			(width 0.06477)
			(type default)
		)
		(layer "F.Cu")
	)
	(gr_line
		(start 368.0079 -269.770098)
		(end 368.474752 -270.036036)
		(stroke
			(width 0.06477)
			(type default)
		)
		(layer "F.Cu")
	)
	(gr_line
		(start 368.087402 -378.39142)
		(end 367.791492 -378.68733)
		(stroke
			(width 0.06477)
			(type default)
		)
		(layer "F.Cu")
	)
	(gr_line
		(start 368.174778 -234.764072)
		(end 367.707926 -235.03001)
		(stroke
			(width 0.06477)
			(type default)
		)
		(layer "F.Cu")
	)
	(gr_line
		(start 368.174778 -233.14406)
		(end 367.707926 -233.409998)
		(stroke
			(width 0.06477)
			(type default)
		)
		(layer "F.Cu")
	)
	(gr_line
		(start 368.174778 -231.524048)
		(end 367.707926 -231.789986)
		(stroke
			(width 0.06477)
			(type default)
		)
		(layer "F.Cu")
	)
	(gr_line
		(start 368.239548 -390.537192)
		(end 368.350038 -390.426702)
		(stroke
			(width 0.0508)
			(type default)
		)
		(layer "F.Cu")
	)
	(gr_line
		(start 368.409982 -378.39142)
		(end 368.705892 -378.68733)
		(stroke
			(width 0.06477)
			(type default)
		)
		(layer "F.Cu")
	)
	(gr_line
		(start 368.426492 -384.324098)
		(end 368.80038 -384.697986)
		(stroke
			(width 0.0508)
			(type default)
		)
		(layer "F.Cu")
	)
	(gr_line
		(start 368.435382 -386.91439)
		(end 368.551968 -387.19633)
		(stroke
			(width 0.0508)
			(type default)
		)
		(layer "F.Cu")
	)
	(gr_line
		(start 368.474752 -291.095938)
		(end 368.0079 -290.83)
		(stroke
			(width 0.06477)
			(type default)
		)
		(layer "F.Cu")
	)
	(gr_line
		(start 368.474752 -289.475926)
		(end 368.0079 -289.209988)
		(stroke
			(width 0.06477)
			(type default)
		)
		(layer "F.Cu")
	)
	(gr_line
		(start 368.474752 -287.856168)
		(end 368.0079 -287.59023)
		(stroke
			(width 0.06477)
			(type default)
		)
		(layer "F.Cu")
	)
	(gr_line
		(start 368.474752 -286.236156)
		(end 368.0079 -285.970218)
		(stroke
			(width 0.06477)
			(type default)
		)
		(layer "F.Cu")
	)
	(gr_line
		(start 368.474752 -284.616144)
		(end 368.0079 -284.350206)
		(stroke
			(width 0.06477)
			(type default)
		)
		(layer "F.Cu")
	)
	(gr_line
		(start 368.474752 -282.996132)
		(end 368.0079 -282.730194)
		(stroke
			(width 0.06477)
			(type default)
		)
		(layer "F.Cu")
	)
	(gr_line
		(start 368.495326 -386.769864)
		(end 368.435382 -386.91439)
		(stroke
			(width 0.0508)
			(type default)
		)
		(layer "F.Cu")
	)
	(gr_line
		(start 368.551968 -387.19633)
		(end 368.696748 -387.25602)
		(stroke
			(width 0.0508)
			(type default)
		)
		(layer "F.Cu")
	)
	(gr_line
		(start 368.58067 -384.17119)
		(end 368.737388 -384.17119)
		(stroke
			(width 0.0508)
			(type default)
		)
		(layer "F.Cu")
	)
	(gr_line
		(start 368.597942 -395.913102)
		(end 369.2017 -395.913102)
		(stroke
			(width 0.0508)
			(type default)
		)
		(layer "F.Cu")
	)
	(gr_line
		(start 368.599212 -396.130272)
		(end 368.682016 -396.213076)
		(stroke
			(width 0.0508)
			(type default)
		)
		(layer "F.Cu")
	)
	(gr_line
		(start 368.680492 -377.41733)
		(end 368.409982 -377.68784)
		(stroke
			(width 0.06477)
			(type default)
		)
		(layer "F.Cu")
	)
	(gr_line
		(start 368.695732 -386.68579)
		(end 368.897916 -387.174232)
		(stroke
			(width 0.0508)
			(type default)
		)
		(layer "F.Cu")
	)
	(gr_line
		(start 368.705892 -379.22073)
		(end 368.356642 -379.56998)
		(stroke
			(width 0.0508)
			(type default)
		)
		(layer "F.Cu")
	)
	(gr_line
		(start 368.737388 -384.17119)
		(end 368.953288 -384.38709)
		(stroke
			(width 0.0508)
			(type default)
		)
		(layer "F.Cu")
	)
	(gr_line
		(start 368.953288 -384.38709)
		(end 368.953288 -384.543808)
		(stroke
			(width 0.0508)
			(type default)
		)
		(layer "F.Cu")
	)
	(gr_line
		(start 368.979958 -388.01167)
		(end 369.149376 -388.265162)
		(stroke
			(width 0.0508)
			(type default)
		)
		(layer "F.Cu")
	)
	(gr_line
		(start 369.010438 -387.858)
		(end 368.979958 -388.01167)
		(stroke
			(width 0.0508)
			(type default)
		)
		(layer "F.Cu")
	)
	(gr_line
		(start 369.139216 -381.303022)
		(end 369.513104 -381.676656)
		(stroke
			(width 0.0508)
			(type default)
		)
		(layer "F.Cu")
	)
	(gr_line
		(start 369.149376 -388.265162)
		(end 369.303046 -388.295896)
		(stroke
			(width 0.0508)
			(type default)
		)
		(layer "F.Cu")
	)
	(gr_line
		(start 369.19027 -387.736588)
		(end 369.190524 -387.736588)
		(stroke
			(width 0.0508)
			(type default)
		)
		(layer "F.Cu")
	)
	(gr_line
		(start 369.190524 -387.736588)
		(end 369.484148 -388.176008)
		(stroke
			(width 0.0508)
			(type default)
		)
		(layer "F.Cu")
	)
	(gr_line
		(start 369.293648 -381.150114)
		(end 369.450112 -381.150114)
		(stroke
			(width 0.0508)
			(type default)
		)
		(layer "F.Cu")
	)
	(gr_line
		(start 369.450112 -381.150114)
		(end 369.666012 -381.366014)
		(stroke
			(width 0.0508)
			(type default)
		)
		(layer "F.Cu")
	)
	(gr_line
		(start 369.484148 -388.176008)
		(end 369.484148 -388.176262)
		(stroke
			(width 0.0508)
			(type default)
		)
		(layer "F.Cu")
	)
	(gr_line
		(start 369.513104 -381.676656)
		(end 369.513104 -381.67691)
		(stroke
			(width 0.0508)
			(type default)
		)
		(layer "F.Cu")
	)
	(gr_line
		(start 369.588034 -247.990106)
		(end 370.054886 -247.724168)
		(stroke
			(width 0.06477)
			(type default)
		)
		(layer "F.Cu")
	)
	(gr_line
		(start 369.588034 -246.370094)
		(end 370.054886 -246.104156)
		(stroke
			(width 0.06477)
			(type default)
		)
		(layer "F.Cu")
	)
	(gr_line
		(start 369.588034 -244.750082)
		(end 370.054886 -244.484144)
		(stroke
			(width 0.06477)
			(type default)
		)
		(layer "F.Cu")
	)
	(gr_line
		(start 369.588034 -236.650022)
		(end 370.054886 -236.384084)
		(stroke
			(width 0.06477)
			(type default)
		)
		(layer "F.Cu")
	)
	(gr_line
		(start 369.588034 -235.03001)
		(end 370.054886 -234.764072)
		(stroke
			(width 0.06477)
			(type default)
		)
		(layer "F.Cu")
	)
	(gr_line
		(start 369.588034 -233.409998)
		(end 370.054886 -233.14406)
		(stroke
			(width 0.06477)
			(type default)
		)
		(layer "F.Cu")
	)
	(gr_line
		(start 369.588034 -231.789986)
		(end 370.054886 -231.524048)
		(stroke
			(width 0.06477)
			(type default)
		)
		(layer "F.Cu")
	)
	(gr_line
		(start 369.588034 -225.310192)
		(end 370.054886 -225.044254)
		(stroke
			(width 0.06477)
			(type default)
		)
		(layer "F.Cu")
	)
	(gr_line
		(start 369.666012 -381.366014)
		(end 369.666012 -381.522478)
		(stroke
			(width 0.0508)
			(type default)
		)
		(layer "F.Cu")
	)
	(gr_line
		(start 369.888008 -277.870158)
		(end 370.35486 -278.136096)
		(stroke
			(width 0.06477)
			(type default)
		)
		(layer "F.Cu")
	)
	(gr_line
		(start 369.888008 -276.250146)
		(end 370.35486 -276.516084)
		(stroke
			(width 0.06477)
			(type default)
		)
		(layer "F.Cu")
	)
	(gr_line
		(start 369.888008 -274.630134)
		(end 370.35486 -274.896072)
		(stroke
			(width 0.06477)
			(type default)
		)
		(layer "F.Cu")
	)
	(gr_line
		(start 369.888008 -273.010122)
		(end 370.35486 -273.27606)
		(stroke
			(width 0.06477)
			(type default)
		)
		(layer "F.Cu")
	)
	(gr_line
		(start 369.888008 -271.39011)
		(end 370.35486 -271.656048)
		(stroke
			(width 0.06477)
			(type default)
		)
		(layer "F.Cu")
	)
	(gr_line
		(start 369.888008 -269.770098)
		(end 370.35486 -270.036036)
		(stroke
			(width 0.06477)
			(type default)
		)
		(layer "F.Cu")
	)
	(gr_line
		(start 369.915948 -391.88771)
		(end 370.007134 -391.978896)
		(stroke
			(width 0.0508)
			(type default)
		)
		(layer "F.Cu")
	)
	(gr_line
		(start 369.915948 -391.6172)
		(end 369.915948 -391.88771)
		(stroke
			(width 0.0508)
			(type default)
		)
		(layer "F.Cu")
	)
	(gr_line
		(start 370.007134 -391.978896)
		(end 370.1415 -391.978896)
		(stroke
			(width 0.0508)
			(type default)
		)
		(layer "F.Cu")
	)
	(gr_line
		(start 370.1415 -391.978896)
		(end 370.217954 -391.902442)
		(stroke
			(width 0.0508)
			(type default)
		)
		(layer "F.Cu")
	)
	(gr_line
		(start 370.207286 -391.325862)
		(end 369.915948 -391.6172)
		(stroke
			(width 0.0508)
			(type default)
		)
		(layer "F.Cu")
	)
	(gr_line
		(start 370.217954 -391.902442)
		(end 370.217954 -391.784586)
		(stroke
			(width 0.0508)
			(type default)
		)
		(layer "F.Cu")
	)
	(gr_line
		(start 370.301266 -399.74647)
		(end 370.217954 -399.663158)
		(stroke
			(width 0.0508)
			(type default)
		)
		(layer "F.Cu")
	)
	(gr_line
		(start 370.35486 -291.095938)
		(end 369.888008 -290.83)
		(stroke
			(width 0.06477)
			(type default)
		)
		(layer "F.Cu")
	)
	(gr_line
		(start 370.35486 -289.475926)
		(end 369.888008 -289.209988)
		(stroke
			(width 0.06477)
			(type default)
		)
		(layer "F.Cu")
	)
	(gr_line
		(start 370.35486 -287.856168)
		(end 369.888008 -287.59023)
		(stroke
			(width 0.06477)
			(type default)
		)
		(layer "F.Cu")
	)
	(gr_line
		(start 370.35486 -286.236156)
		(end 369.888008 -285.970218)
		(stroke
			(width 0.06477)
			(type default)
		)
		(layer "F.Cu")
	)
	(gr_line
		(start 370.35486 -284.616144)
		(end 369.888008 -284.350206)
		(stroke
			(width 0.06477)
			(type default)
		)
		(layer "F.Cu")
	)
	(gr_line
		(start 370.35486 -282.996132)
		(end 369.888008 -282.730194)
		(stroke
			(width 0.06477)
			(type default)
		)
		(layer "F.Cu")
	)
	(gr_line
		(start 370.35486 -281.37612)
		(end 369.888008 -281.110182)
		(stroke
			(width 0.06477)
			(type default)
		)
		(layer "F.Cu")
	)
	(gr_line
		(start 370.370608 -397.156432)
		(end 370.891308 -397.156432)
		(stroke
			(width 0.0635)
			(type default)
		)
		(layer "F.Cu")
	)
	(gr_line
		(start 370.370608 -393.69238)
		(end 370.891308 -393.69238)
		(stroke
			(width 0.0635)
			(type default)
		)
		(layer "F.Cu")
	)
	(gr_line
		(start 370.424456 -391.51941)
		(end 370.517928 -391.612882)
		(stroke
			(width 0.0508)
			(type default)
		)
		(layer "F.Cu")
	)
	(gr_line
		(start 370.424456 -391.324592)
		(end 370.424456 -391.51941)
		(stroke
			(width 0.0508)
			(type default)
		)
		(layer "F.Cu")
	)
	(gr_line
		(start 370.517928 -391.612882)
		(end 370.517928 -392.30427)
		(stroke
			(width 0.0508)
			(type default)
		)
		(layer "F.Cu")
	)
	(gr_line
		(start 370.518436 -399.74774)
		(end 370.518436 -399.143982)
		(stroke
			(width 0.0508)
			(type default)
		)
		(layer "F.Cu")
	)
	(gr_line
		(start 370.518436 -399.143982)
		(end 370.517928 -399.143474)
		(stroke
			(width 0.0508)
			(type default)
		)
		(layer "F.Cu")
	)
	(gr_line
		(start 370.527834 -247.990106)
		(end 370.994686 -247.724168)
		(stroke
			(width 0.06477)
			(type default)
		)
		(layer "F.Cu")
	)
	(gr_line
		(start 370.527834 -246.370094)
		(end 370.994686 -246.104156)
		(stroke
			(width 0.06477)
			(type default)
		)
		(layer "F.Cu")
	)
	(gr_line
		(start 370.527834 -244.750082)
		(end 370.994686 -244.484144)
		(stroke
			(width 0.06477)
			(type default)
		)
		(layer "F.Cu")
	)
	(gr_line
		(start 370.527834 -225.310192)
		(end 370.994686 -225.044254)
		(stroke
			(width 0.06477)
			(type default)
		)
		(layer "F.Cu")
	)
	(gr_line
		(start 370.527834 -223.69018)
		(end 370.994686 -223.424242)
		(stroke
			(width 0.06477)
			(type default)
		)
		(layer "F.Cu")
	)
	(gr_line
		(start 370.767102 -414.903158)
		(end 371.063012 -415.199068)
		(stroke
			(width 0.06477)
			(type default)
		)
		(layer "F.Cu")
	)
	(gr_line
		(start 370.770658 -397.849344)
		(end 371.291358 -397.849344)
		(stroke
			(width 0.0635)
			(type default)
		)
		(layer "F.Cu")
	)
	(gr_line
		(start 370.770658 -394.385292)
		(end 371.291358 -394.385292)
		(stroke
			(width 0.0635)
			(type default)
		)
		(layer "F.Cu")
	)
	(gr_line
		(start 370.77777 -401.359116)
		(end 370.775738 -401.359116)
		(stroke
			(width 0.0508)
			(type default)
		)
		(layer "F.Cu")
	)
	(gr_line
		(start 370.828062 -277.870158)
		(end 371.294914 -278.136096)
		(stroke
			(width 0.06477)
			(type default)
		)
		(layer "F.Cu")
	)
	(gr_line
		(start 370.828062 -276.250146)
		(end 371.294914 -276.516084)
		(stroke
			(width 0.06477)
			(type default)
		)
		(layer "F.Cu")
	)
	(gr_line
		(start 370.828062 -274.630134)
		(end 371.294914 -274.896072)
		(stroke
			(width 0.06477)
			(type default)
		)
		(layer "F.Cu")
	)
	(gr_line
		(start 370.828062 -273.010122)
		(end 371.294914 -273.27606)
		(stroke
			(width 0.06477)
			(type default)
		)
		(layer "F.Cu")
	)
	(gr_line
		(start 370.828062 -271.39011)
		(end 371.294914 -271.656048)
		(stroke
			(width 0.06477)
			(type default)
		)
		(layer "F.Cu")
	)
	(gr_line
		(start 370.828062 -269.770098)
		(end 371.294914 -270.036036)
		(stroke
			(width 0.06477)
			(type default)
		)
		(layer "F.Cu")
	)
	(gr_line
		(start 370.894102 -412.84652)
		(end 371.164612 -413.11703)
		(stroke
			(width 0.06477)
			(type default)
		)
		(layer "F.Cu")
	)
	(gr_line
		(start 370.916454 -401.674838)
		(end 370.916454 -401.4978)
		(stroke
			(width 0.0508)
			(type default)
		)
		(layer "F.Cu")
	)
	(gr_line
		(start 370.916454 -401.4978)
		(end 370.77777 -401.359116)
		(stroke
			(width 0.0508)
			(type default)
		)
		(layer "F.Cu")
	)
	(gr_line
		(start 370.916454 -401.0025)
		(end 370.777008 -401.141946)
		(stroke
			(width 0.0508)
			(type default)
		)
		(layer "F.Cu")
	)
	(gr_line
		(start 370.916454 -400.811238)
		(end 370.916454 -401.0025)
		(stroke
			(width 0.0508)
			(type default)
		)
		(layer "F.Cu")
	)
	(gr_line
		(start 370.994686 -236.384084)
		(end 370.527834 -236.650022)
		(stroke
			(width 0.06477)
			(type default)
		)
		(layer "F.Cu")
	)
	(gr_line
		(start 370.994686 -234.764072)
		(end 370.527834 -235.03001)
		(stroke
			(width 0.06477)
			(type default)
		)
		(layer "F.Cu")
	)
	(gr_line
		(start 370.994686 -233.14406)
		(end 370.527834 -233.409998)
		(stroke
			(width 0.06477)
			(type default)
		)
		(layer "F.Cu")
	)
	(gr_line
		(start 370.994686 -231.524048)
		(end 370.527834 -231.789986)
		(stroke
			(width 0.06477)
			(type default)
		)
		(layer "F.Cu")
	)
	(gr_line
		(start 370.994686 -221.80423)
		(end 370.527834 -222.070168)
		(stroke
			(width 0.06477)
			(type default)
		)
		(layer "F.Cu")
	)
	(gr_line
		(start 371.063012 -414.073848)
		(end 370.767102 -414.369758)
		(stroke
			(width 0.06477)
			(type default)
		)
		(layer "F.Cu")
	)
	(gr_line
		(start 371.115844 -391.88771)
		(end 371.20703 -391.978896)
		(stroke
			(width 0.0508)
			(type default)
		)
		(layer "F.Cu")
	)
	(gr_line
		(start 371.115844 -391.6172)
		(end 371.115844 -391.88771)
		(stroke
			(width 0.0508)
			(type default)
		)
		(layer "F.Cu")
	)
	(gr_line
		(start 371.164612 -420.681658)
		(end 370.894102 -420.952168)
		(stroke
			(width 0.06477)
			(type default)
		)
		(layer "F.Cu")
	)
	(gr_line
		(start 371.195092 -384.14833)
		(end 371.544342 -384.49758)
		(stroke
			(width 0.0508)
			(type default)
		)
		(layer "F.Cu")
	)
	(gr_line
		(start 371.20703 -391.978896)
		(end 371.341396 -391.978896)
		(stroke
			(width 0.0508)
			(type default)
		)
		(layer "F.Cu")
	)
	(gr_line
		(start 371.220492 -382.34493)
		(end 371.491002 -382.61544)
		(stroke
			(width 0.06477)
			(type default)
		)
		(layer "F.Cu")
	)
	(gr_line
		(start 371.294914 -291.095938)
		(end 370.828062 -290.83)
		(stroke
			(width 0.06477)
			(type default)
		)
		(layer "F.Cu")
	)
	(gr_line
		(start 371.294914 -289.475926)
		(end 370.828062 -289.209988)
		(stroke
			(width 0.06477)
			(type default)
		)
		(layer "F.Cu")
	)
	(gr_line
		(start 371.294914 -287.856168)
		(end 370.828062 -287.59023)
		(stroke
			(width 0.06477)
			(type default)
		)
		(layer "F.Cu")
	)
	(gr_line
		(start 371.294914 -286.236156)
		(end 370.828062 -285.970218)
		(stroke
			(width 0.06477)
			(type default)
		)
		(layer "F.Cu")
	)
	(gr_line
		(start 371.294914 -284.616144)
		(end 370.828062 -284.350206)
		(stroke
			(width 0.06477)
			(type default)
		)
		(layer "F.Cu")
	)
	(gr_line
		(start 371.294914 -282.996132)
		(end 370.828062 -282.730194)
		(stroke
			(width 0.06477)
			(type default)
		)
		(layer "F.Cu")
	)
	(gr_line
		(start 371.294914 -281.37612)
		(end 370.828062 -281.110182)
		(stroke
			(width 0.06477)
			(type default)
		)
		(layer "F.Cu")
	)
	(gr_line
		(start 371.341396 -391.978896)
		(end 371.41785 -391.902442)
		(stroke
			(width 0.0508)
			(type default)
		)
		(layer "F.Cu")
	)
	(gr_line
		(start 371.385592 -414.073848)
		(end 371.681502 -414.369758)
		(stroke
			(width 0.06477)
			(type default)
		)
		(layer "F.Cu")
	)
	(gr_line
		(start 371.407182 -391.325862)
		(end 371.115844 -391.6172)
		(stroke
			(width 0.0508)
			(type default)
		)
		(layer "F.Cu")
	)
	(gr_line
		(start 371.41785 -391.902442)
		(end 371.41785 -391.784586)
		(stroke
			(width 0.0508)
			(type default)
		)
		(layer "F.Cu")
	)
	(gr_line
		(start 371.467888 -223.69018)
		(end 371.93474 -223.424242)
		(stroke
			(width 0.06477)
			(type default)
		)
		(layer "F.Cu")
	)
	(gr_line
		(start 371.487192 -420.681658)
		(end 371.757702 -420.952168)
		(stroke
			(width 0.06477)
			(type default)
		)
		(layer "F.Cu")
	)
	(gr_line
		(start 371.491002 -383.31902)
		(end 371.195092 -383.61493)
		(stroke
			(width 0.06477)
			(type default)
		)
		(layer "F.Cu")
	)
	(gr_line
		(start 371.501162 -399.74647)
		(end 371.41785 -399.663158)
		(stroke
			(width 0.0508)
			(type default)
		)
		(layer "F.Cu")
	)
	(gr_line
		(start 371.570504 -397.156432)
		(end 372.091204 -397.156432)
		(stroke
			(width 0.0635)
			(type default)
		)
		(layer "F.Cu")
	)
	(gr_line
		(start 371.570504 -393.69238)
		(end 372.091204 -393.69238)
		(stroke
			(width 0.0635)
			(type default)
		)
		(layer "F.Cu")
	)
	(gr_line
		(start 371.624352 -391.51941)
		(end 371.717824 -391.612882)
		(stroke
			(width 0.0508)
			(type default)
		)
		(layer "F.Cu")
	)
	(gr_line
		(start 371.624352 -391.324592)
		(end 371.624352 -391.51941)
		(stroke
			(width 0.0508)
			(type default)
		)
		(layer "F.Cu")
	)
	(gr_line
		(start 371.681502 -414.903158)
		(end 371.385592 -415.199068)
		(stroke
			(width 0.06477)
			(type default)
		)
		(layer "F.Cu")
	)
	(gr_line
		(start 371.717824 -391.612882)
		(end 371.717824 -392.30427)
		(stroke
			(width 0.0508)
			(type default)
		)
		(layer "F.Cu")
	)
	(gr_line
		(start 371.718332 -399.74774)
		(end 371.718332 -399.143982)
		(stroke
			(width 0.0508)
			(type default)
		)
		(layer "F.Cu")
	)
	(gr_line
		(start 371.718332 -399.143982)
		(end 371.717824 -399.143474)
		(stroke
			(width 0.0508)
			(type default)
		)
		(layer "F.Cu")
	)
	(gr_line
		(start 371.757702 -412.84652)
		(end 371.487192 -413.11703)
		(stroke
			(width 0.06477)
			(type default)
		)
		(layer "F.Cu")
	)
	(gr_line
		(start 371.813582 -383.31902)
		(end 372.109492 -383.61493)
		(stroke
			(width 0.06477)
			(type default)
		)
		(layer "F.Cu")
	)
	(gr_line
		(start 371.93474 -221.80423)
		(end 371.467888 -222.070168)
		(stroke
			(width 0.06477)
			(type default)
		)
		(layer "F.Cu")
	)
	(gr_line
		(start 371.970554 -397.849344)
		(end 372.491254 -397.849344)
		(stroke
			(width 0.0635)
			(type default)
		)
		(layer "F.Cu")
	)
	(gr_line
		(start 371.970554 -394.385292)
		(end 372.491254 -394.385292)
		(stroke
			(width 0.0635)
			(type default)
		)
		(layer "F.Cu")
	)
	(gr_line
		(start 371.977666 -401.359116)
		(end 371.975634 -401.359116)
		(stroke
			(width 0.0508)
			(type default)
		)
		(layer "F.Cu")
	)
	(gr_line
		(start 372.084092 -382.34493)
		(end 371.813582 -382.61544)
		(stroke
			(width 0.06477)
			(type default)
		)
		(layer "F.Cu")
	)
	(gr_line
		(start 372.109492 -384.14833)
		(end 371.760242 -384.49758)
		(stroke
			(width 0.0508)
			(type default)
		)
		(layer "F.Cu")
	)
	(gr_line
		(start 372.11635 -401.674838)
		(end 372.11635 -401.4978)
		(stroke
			(width 0.0508)
			(type default)
		)
		(layer "F.Cu")
	)
	(gr_line
		(start 372.11635 -401.4978)
		(end 371.977666 -401.359116)
		(stroke
			(width 0.0508)
			(type default)
		)
		(layer "F.Cu")
	)
	(gr_line
		(start 372.11635 -401.0025)
		(end 371.976904 -401.141946)
		(stroke
			(width 0.0508)
			(type default)
		)
		(layer "F.Cu")
	)
	(gr_line
		(start 372.11635 -400.811238)
		(end 372.11635 -401.0025)
		(stroke
			(width 0.0508)
			(type default)
		)
		(layer "F.Cu")
	)
	(gr_line
		(start 372.315994 -391.88771)
		(end 372.40718 -391.978896)
		(stroke
			(width 0.0508)
			(type default)
		)
		(layer "F.Cu")
	)
	(gr_line
		(start 372.315994 -391.6172)
		(end 372.315994 -391.88771)
		(stroke
			(width 0.0508)
			(type default)
		)
		(layer "F.Cu")
	)
	(gr_line
		(start 372.351046 -385.988814)
		(end 372.68658 -386.397754)
		(stroke
			(width 0.0508)
			(type default)
		)
		(layer "F.Cu")
	)
	(gr_line
		(start 372.40718 -391.978896)
		(end 372.541546 -391.978896)
		(stroke
			(width 0.0508)
			(type default)
		)
		(layer "F.Cu")
	)
	(gr_line
		(start 372.407942 -247.990106)
		(end 372.874794 -247.724168)
		(stroke
			(width 0.06477)
			(type default)
		)
		(layer "F.Cu")
	)
	(gr_line
		(start 372.407942 -246.370094)
		(end 372.874794 -246.104156)
		(stroke
			(width 0.06477)
			(type default)
		)
		(layer "F.Cu")
	)
	(gr_line
		(start 372.407942 -244.750082)
		(end 372.874794 -244.484144)
		(stroke
			(width 0.06477)
			(type default)
		)
		(layer "F.Cu")
	)
	(gr_line
		(start 372.407942 -236.650022)
		(end 372.874794 -236.384084)
		(stroke
			(width 0.06477)
			(type default)
		)
		(layer "F.Cu")
	)
	(gr_line
		(start 372.407942 -235.03001)
		(end 372.874794 -234.764072)
		(stroke
			(width 0.06477)
			(type default)
		)
		(layer "F.Cu")
	)
	(gr_line
		(start 372.407942 -233.409998)
		(end 372.874794 -233.14406)
		(stroke
			(width 0.06477)
			(type default)
		)
		(layer "F.Cu")
	)
	(gr_line
		(start 372.519702 -385.852162)
		(end 372.67515 -385.867402)
		(stroke
			(width 0.0508)
			(type default)
		)
		(layer "F.Cu")
	)
	(gr_line
		(start 372.541546 -391.978896)
		(end 372.618 -391.902442)
		(stroke
			(width 0.0508)
			(type default)
		)
		(layer "F.Cu")
	)
	(gr_line
		(start 372.607332 -391.325862)
		(end 372.315994 -391.6172)
		(stroke
			(width 0.0508)
			(type default)
		)
		(layer "F.Cu")
	)
	(gr_line
		(start 372.618 -391.902442)
		(end 372.618 -391.784586)
		(stroke
			(width 0.0508)
			(type default)
		)
		(layer "F.Cu")
	)
	(gr_line
		(start 372.67515 -385.867402)
		(end 372.868698 -386.103114)
		(stroke
			(width 0.0508)
			(type default)
		)
		(layer "F.Cu")
	)
	(gr_line
		(start 372.701312 -399.74647)
		(end 372.618 -399.663158)
		(stroke
			(width 0.0508)
			(type default)
		)
		(layer "F.Cu")
	)
	(gr_line
		(start 372.707916 -277.870158)
		(end 373.174768 -278.136096)
		(stroke
			(width 0.06477)
			(type default)
		)
		(layer "F.Cu")
	)
	(gr_line
		(start 372.707916 -276.250146)
		(end 373.174768 -276.516084)
		(stroke
			(width 0.06477)
			(type default)
		)
		(layer "F.Cu")
	)
	(gr_line
		(start 372.707916 -274.630134)
		(end 373.174768 -274.896072)
		(stroke
			(width 0.06477)
			(type default)
		)
		(layer "F.Cu")
	)
	(gr_line
		(start 372.707916 -273.010122)
		(end 373.174768 -273.27606)
		(stroke
			(width 0.06477)
			(type default)
		)
		(layer "F.Cu")
	)
	(gr_line
		(start 372.707916 -271.39011)
		(end 373.174768 -271.656048)
		(stroke
			(width 0.06477)
			(type default)
		)
		(layer "F.Cu")
	)
	(gr_line
		(start 372.707916 -269.770098)
		(end 373.174768 -270.036036)
		(stroke
			(width 0.06477)
			(type default)
		)
		(layer "F.Cu")
	)
	(gr_line
		(start 372.770654 -397.156432)
		(end 373.291354 -397.156432)
		(stroke
			(width 0.0635)
			(type default)
		)
		(layer "F.Cu")
	)
	(gr_line
		(start 372.770654 -393.69238)
		(end 373.291354 -393.69238)
		(stroke
			(width 0.0635)
			(type default)
		)
		(layer "F.Cu")
	)
	(gr_line
		(start 372.824502 -391.51941)
		(end 372.917974 -391.612882)
		(stroke
			(width 0.0508)
			(type default)
		)
		(layer "F.Cu")
	)
	(gr_line
		(start 372.824502 -391.324592)
		(end 372.824502 -391.51941)
		(stroke
			(width 0.0508)
			(type default)
		)
		(layer "F.Cu")
	)
	(gr_line
		(start 372.868698 -386.103114)
		(end 372.853712 -386.25907)
		(stroke
			(width 0.0508)
			(type default)
		)
		(layer "F.Cu")
	)
	(gr_line
		(start 372.896892 -381.68453)
		(end 373.246142 -382.03378)
		(stroke
			(width 0.0508)
			(type default)
		)
		(layer "F.Cu")
	)
	(gr_line
		(start 372.917974 -391.612882)
		(end 372.917974 -392.30427)
		(stroke
			(width 0.0508)
			(type default)
		)
		(layer "F.Cu")
	)
	(gr_line
		(start 372.918482 -399.74774)
		(end 372.918482 -399.143982)
		(stroke
			(width 0.0508)
			(type default)
		)
		(layer "F.Cu")
	)
	(gr_line
		(start 372.918482 -399.143982)
		(end 372.917974 -399.143474)
		(stroke
			(width 0.0508)
			(type default)
		)
		(layer "F.Cu")
	)
	(gr_line
		(start 372.922292 -379.88113)
		(end 373.192802 -380.15164)
		(stroke
			(width 0.06477)
			(type default)
		)
		(layer "F.Cu")
	)
	(gr_line
		(start 373.17045 -397.849344)
		(end 373.69115 -397.849344)
		(stroke
			(width 0.0635)
			(type default)
		)
		(layer "F.Cu")
	)
	(gr_line
		(start 373.17045 -394.385292)
		(end 373.69115 -394.385292)
		(stroke
			(width 0.0635)
			(type default)
		)
		(layer "F.Cu")
	)
	(gr_line
		(start 373.174768 -291.095938)
		(end 372.707916 -290.83)
		(stroke
			(width 0.06477)
			(type default)
		)
		(layer "F.Cu")
	)
	(gr_line
		(start 373.174768 -289.475926)
		(end 372.707916 -289.209988)
		(stroke
			(width 0.06477)
			(type default)
		)
		(layer "F.Cu")
	)
	(gr_line
		(start 373.174768 -287.856168)
		(end 372.707916 -287.59023)
		(stroke
			(width 0.06477)
			(type default)
		)
		(layer "F.Cu")
	)
	(gr_line
		(start 373.174768 -286.236156)
		(end 372.707916 -285.970218)
		(stroke
			(width 0.06477)
			(type default)
		)
		(layer "F.Cu")
	)
	(gr_line
		(start 373.174768 -284.616144)
		(end 372.707916 -284.350206)
		(stroke
			(width 0.06477)
			(type default)
		)
		(layer "F.Cu")
	)
	(gr_line
		(start 373.174768 -282.996132)
		(end 372.707916 -282.730194)
		(stroke
			(width 0.06477)
			(type default)
		)
		(layer "F.Cu")
	)
	(gr_line
		(start 373.174768 -281.37612)
		(end 372.707916 -281.110182)
		(stroke
			(width 0.06477)
			(type default)
		)
		(layer "F.Cu")
	)
	(gr_line
		(start 373.177816 -401.359116)
		(end 373.175784 -401.359116)
		(stroke
			(width 0.0508)
			(type default)
		)
		(layer "F.Cu")
	)
	(gr_line
		(start 373.192802 -380.85522)
		(end 372.896892 -381.15113)
		(stroke
			(width 0.06477)
			(type default)
		)
		(layer "F.Cu")
	)
	(gr_line
		(start 373.246142 -382.911096)
		(end 373.246142 -383.439416)
		(stroke
			(width 0.0508)
			(type default)
		)
		(layer "F.Cu")
	)
	(gr_line
		(start 373.3165 -401.674838)
		(end 373.3165 -401.4978)
		(stroke
			(width 0.0508)
			(type default)
		)
		(layer "F.Cu")
	)
	(gr_line
		(start 373.3165 -401.4978)
		(end 373.177816 -401.359116)
		(stroke
			(width 0.0508)
			(type default)
		)
		(layer "F.Cu")
	)
	(gr_line
		(start 373.3165 -401.0025)
		(end 373.177054 -401.141946)
		(stroke
			(width 0.0508)
			(type default)
		)
		(layer "F.Cu")
	)
	(gr_line
		(start 373.3165 -400.811238)
		(end 373.3165 -401.0025)
		(stroke
			(width 0.0508)
			(type default)
		)
		(layer "F.Cu")
	)
	(gr_line
		(start 373.347996 -247.990106)
		(end 373.814848 -247.724168)
		(stroke
			(width 0.06477)
			(type default)
		)
		(layer "F.Cu")
	)
	(gr_line
		(start 373.347996 -246.370094)
		(end 373.814848 -246.104156)
		(stroke
			(width 0.06477)
			(type default)
		)
		(layer "F.Cu")
	)
	(gr_line
		(start 373.347996 -244.750082)
		(end 373.814848 -244.484144)
		(stroke
			(width 0.06477)
			(type default)
		)
		(layer "F.Cu")
	)
	(gr_line
		(start 373.463312 -382.912366)
		(end 373.573802 -383.022856)
		(stroke
			(width 0.0508)
			(type default)
		)
		(layer "F.Cu")
	)
	(gr_line
		(start 373.515382 -380.85522)
		(end 373.811292 -381.15113)
		(stroke
			(width 0.06477)
			(type default)
		)
		(layer "F.Cu")
	)
	(gr_line
		(start 373.51589 -391.88771)
		(end 373.607076 -391.978896)
		(stroke
			(width 0.0508)
			(type default)
		)
		(layer "F.Cu")
	)
	(gr_line
		(start 373.51589 -391.6172)
		(end 373.51589 -391.88771)
		(stroke
			(width 0.0508)
			(type default)
		)
		(layer "F.Cu")
	)
	(gr_line
		(start 373.573802 -383.327656)
		(end 373.463312 -383.438146)
		(stroke
			(width 0.0508)
			(type default)
		)
		(layer "F.Cu")
	)
	(gr_line
		(start 373.573802 -383.022856)
		(end 373.573802 -383.327656)
		(stroke
			(width 0.0508)
			(type default)
		)
		(layer "F.Cu")
	)
	(gr_line
		(start 373.607076 -391.978896)
		(end 373.741442 -391.978896)
		(stroke
			(width 0.0508)
			(type default)
		)
		(layer "F.Cu")
	)
	(gr_line
		(start 373.64797 -277.870158)
		(end 374.114822 -278.136096)
		(stroke
			(width 0.06477)
			(type default)
		)
		(layer "F.Cu")
	)
	(gr_line
		(start 373.64797 -276.250146)
		(end 374.114822 -276.516084)
		(stroke
			(width 0.06477)
			(type default)
		)
		(layer "F.Cu")
	)
	(gr_line
		(start 373.64797 -274.630134)
		(end 374.114822 -274.896072)
		(stroke
			(width 0.06477)
			(type default)
		)
		(layer "F.Cu")
	)
	(gr_line
		(start 373.64797 -273.010122)
		(end 374.114822 -273.27606)
		(stroke
			(width 0.06477)
			(type default)
		)
		(layer "F.Cu")
	)
	(gr_line
		(start 373.64797 -271.39011)
		(end 374.114822 -271.656048)
		(stroke
			(width 0.06477)
			(type default)
		)
		(layer "F.Cu")
	)
	(gr_line
		(start 373.64797 -269.770098)
		(end 374.114822 -270.036036)
		(stroke
			(width 0.06477)
			(type default)
		)
		(layer "F.Cu")
	)
	(gr_line
		(start 373.741442 -391.978896)
		(end 373.817896 -391.902442)
		(stroke
			(width 0.0508)
			(type default)
		)
		(layer "F.Cu")
	)
	(gr_line
		(start 373.785892 -379.88113)
		(end 373.515382 -380.15164)
		(stroke
			(width 0.06477)
			(type default)
		)
		(layer "F.Cu")
	)
	(gr_line
		(start 373.807228 -391.325862)
		(end 373.51589 -391.6172)
		(stroke
			(width 0.0508)
			(type default)
		)
		(layer "F.Cu")
	)
	(gr_line
		(start 373.811292 -381.68453)
		(end 373.462042 -382.03378)
		(stroke
			(width 0.0508)
			(type default)
		)
		(layer "F.Cu")
	)
	(gr_line
		(start 373.814848 -236.384084)
		(end 373.347996 -236.650022)
		(stroke
			(width 0.06477)
			(type default)
		)
		(layer "F.Cu")
	)
	(gr_line
		(start 373.814848 -234.764072)
		(end 373.347996 -235.03001)
		(stroke
			(width 0.06477)
			(type default)
		)
		(layer "F.Cu")
	)
	(gr_line
		(start 373.814848 -233.14406)
		(end 373.347996 -233.409998)
		(stroke
			(width 0.06477)
			(type default)
		)
		(layer "F.Cu")
	)
	(gr_line
		(start 373.817896 -391.902442)
		(end 373.817896 -391.784586)
		(stroke
			(width 0.0508)
			(type default)
		)
		(layer "F.Cu")
	)
	(gr_line
		(start 373.901208 -399.74647)
		(end 373.817896 -399.663158)
		(stroke
			(width 0.0508)
			(type default)
		)
		(layer "F.Cu")
	)
	(gr_line
		(start 373.931942 -417.166044)
		(end 374.227852 -417.461954)
		(stroke
			(width 0.06477)
			(type default)
		)
		(layer "F.Cu")
	)
	(gr_line
		(start 373.957342 -412.84652)
		(end 374.227852 -413.11703)
		(stroke
			(width 0.06477)
			(type default)
		)
		(layer "F.Cu")
	)
	(gr_line
		(start 373.97055 -397.156432)
		(end 374.49125 -397.156432)
		(stroke
			(width 0.0635)
			(type default)
		)
		(layer "F.Cu")
	)
	(gr_line
		(start 373.97055 -393.69238)
		(end 374.49125 -393.69238)
		(stroke
			(width 0.0635)
			(type default)
		)
		(layer "F.Cu")
	)
	(gr_line
		(start 374.024398 -391.51941)
		(end 374.11787 -391.612882)
		(stroke
			(width 0.0508)
			(type default)
		)
		(layer "F.Cu")
	)
	(gr_line
		(start 374.024398 -391.324592)
		(end 374.024398 -391.51941)
		(stroke
			(width 0.0508)
			(type default)
		)
		(layer "F.Cu")
	)
	(gr_line
		(start 374.114822 -291.095938)
		(end 373.64797 -290.83)
		(stroke
			(width 0.06477)
			(type default)
		)
		(layer "F.Cu")
	)
	(gr_line
		(start 374.114822 -289.475926)
		(end 373.64797 -289.209988)
		(stroke
			(width 0.06477)
			(type default)
		)
		(layer "F.Cu")
	)
	(gr_line
		(start 374.114822 -287.856168)
		(end 373.64797 -287.59023)
		(stroke
			(width 0.06477)
			(type default)
		)
		(layer "F.Cu")
	)
	(gr_line
		(start 374.114822 -286.236156)
		(end 373.64797 -285.970218)
		(stroke
			(width 0.06477)
			(type default)
		)
		(layer "F.Cu")
	)
	(gr_line
		(start 374.114822 -284.616144)
		(end 373.64797 -284.350206)
		(stroke
			(width 0.06477)
			(type default)
		)
		(layer "F.Cu")
	)
	(gr_line
		(start 374.114822 -282.996132)
		(end 373.64797 -282.730194)
		(stroke
			(width 0.06477)
			(type default)
		)
		(layer "F.Cu")
	)
	(gr_line
		(start 374.114822 -281.37612)
		(end 373.64797 -281.110182)
		(stroke
			(width 0.06477)
			(type default)
		)
		(layer "F.Cu")
	)
	(gr_line
		(start 374.11787 -391.612882)
		(end 374.11787 -392.30427)
		(stroke
			(width 0.0508)
			(type default)
		)
		(layer "F.Cu")
	)
	(gr_line
		(start 374.118378 -399.74774)
		(end 374.118378 -399.143982)
		(stroke
			(width 0.0508)
			(type default)
		)
		(layer "F.Cu")
	)
	(gr_line
		(start 374.118378 -399.143982)
		(end 374.11787 -399.143474)
		(stroke
			(width 0.0508)
			(type default)
		)
		(layer "F.Cu")
	)
	(gr_line
		(start 374.227852 -420.681658)
		(end 373.957342 -420.952168)
		(stroke
			(width 0.06477)
			(type default)
		)
		(layer "F.Cu")
	)
	(gr_line
		(start 374.227852 -416.336734)
		(end 373.931942 -416.632644)
		(stroke
			(width 0.06477)
			(type default)
		)
		(layer "F.Cu")
	)
	(gr_line
		(start 374.3706 -397.849344)
		(end 374.8913 -397.849344)
		(stroke
			(width 0.0635)
			(type default)
		)
		(layer "F.Cu")
	)
	(gr_line
		(start 374.3706 -394.385292)
		(end 374.8913 -394.385292)
		(stroke
			(width 0.0635)
			(type default)
		)
		(layer "F.Cu")
	)
	(gr_line
		(start 374.377712 -401.359116)
		(end 374.37568 -401.359116)
		(stroke
			(width 0.0508)
			(type default)
		)
		(layer "F.Cu")
	)
	(gr_line
		(start 374.516396 -401.674838)
		(end 374.516396 -401.4978)
		(stroke
			(width 0.0508)
			(type default)
		)
		(layer "F.Cu")
	)
	(gr_line
		(start 374.516396 -401.4978)
		(end 374.377712 -401.359116)
		(stroke
			(width 0.0508)
			(type default)
		)
		(layer "F.Cu")
	)
	(gr_line
		(start 374.516396 -401.0025)
		(end 374.37695 -401.141946)
		(stroke
			(width 0.0508)
			(type default)
		)
		(layer "F.Cu")
	)
	(gr_line
		(start 374.516396 -400.811238)
		(end 374.516396 -401.0025)
		(stroke
			(width 0.0508)
			(type default)
		)
		(layer "F.Cu")
	)
	(gr_line
		(start 374.550432 -420.681658)
		(end 374.820942 -420.952168)
		(stroke
			(width 0.06477)
			(type default)
		)
		(layer "F.Cu")
	)
	(gr_line
		(start 374.550432 -416.336734)
		(end 374.846342 -416.632644)
		(stroke
			(width 0.06477)
			(type default)
		)
		(layer "F.Cu")
	)
	(gr_line
		(start 374.598692 -379.22073)
		(end 374.947942 -379.56998)
		(stroke
			(width 0.0508)
			(type default)
		)
		(layer "F.Cu")
	)
	(gr_line
		(start 374.624092 -377.41733)
		(end 374.894602 -377.68784)
		(stroke
			(width 0.06477)
			(type default)
		)
		(layer "F.Cu")
	)
	(gr_line
		(start 374.71604 -391.88771)
		(end 374.807226 -391.978896)
		(stroke
			(width 0.0508)
			(type default)
		)
		(layer "F.Cu")
	)
	(gr_line
		(start 374.71604 -391.6172)
		(end 374.71604 -391.88771)
		(stroke
			(width 0.0508)
			(type default)
		)
		(layer "F.Cu")
	)
	(gr_line
		(start 374.807226 -391.978896)
		(end 374.941592 -391.978896)
		(stroke
			(width 0.0508)
			(type default)
		)
		(layer "F.Cu")
	)
	(gr_line
		(start 374.820942 -412.84652)
		(end 374.550432 -413.11703)
		(stroke
			(width 0.06477)
			(type default)
		)
		(layer "F.Cu")
	)
	(gr_line
		(start 374.846342 -417.166044)
		(end 374.550432 -417.461954)
		(stroke
			(width 0.06477)
			(type default)
		)
		(layer "F.Cu")
	)
	(gr_line
		(start 374.894602 -378.39142)
		(end 374.598692 -378.68733)
		(stroke
			(width 0.06477)
			(type default)
		)
		(layer "F.Cu")
	)
	(gr_line
		(start 374.941592 -391.978896)
		(end 375.018046 -391.902442)
		(stroke
			(width 0.0508)
			(type default)
		)
		(layer "F.Cu")
	)
	(gr_line
		(start 375.007378 -391.325862)
		(end 374.71604 -391.6172)
		(stroke
			(width 0.0508)
			(type default)
		)
		(layer "F.Cu")
	)
	(gr_line
		(start 375.018046 -391.902442)
		(end 375.018046 -391.784586)
		(stroke
			(width 0.0508)
			(type default)
		)
		(layer "F.Cu")
	)
	(gr_line
		(start 375.101358 -399.74647)
		(end 375.018046 -399.663158)
		(stroke
			(width 0.0508)
			(type default)
		)
		(layer "F.Cu")
	)
	(gr_line
		(start 375.170446 -397.156432)
		(end 375.691146 -397.156432)
		(stroke
			(width 0.0635)
			(type default)
		)
		(layer "F.Cu")
	)
	(gr_line
		(start 375.170446 -393.69238)
		(end 375.691146 -393.69238)
		(stroke
			(width 0.0635)
			(type default)
		)
		(layer "F.Cu")
	)
	(gr_line
		(start 375.217182 -378.39142)
		(end 375.513092 -378.68733)
		(stroke
			(width 0.06477)
			(type default)
		)
		(layer "F.Cu")
	)
	(gr_line
		(start 375.224548 -391.51941)
		(end 375.31802 -391.612882)
		(stroke
			(width 0.0508)
			(type default)
		)
		(layer "F.Cu")
	)
	(gr_line
		(start 375.224548 -391.324592)
		(end 375.224548 -391.51941)
		(stroke
			(width 0.0508)
			(type default)
		)
		(layer "F.Cu")
	)
	(gr_arc
		(start 375.224548 -389.9535)
		(mid 375.224548 -389.953881)
		(end 375.224548 -389.954262)
		(stroke
			(width 0.0508)
			(type default)
		)
		(layer "F.Cu")
	)
	(gr_line
		(start 375.31802 -391.612882)
		(end 375.31802 -392.30427)
		(stroke
			(width 0.0508)
			(type default)
		)
		(layer "F.Cu")
	)
	(gr_line
		(start 375.318528 -399.74774)
		(end 375.318528 -399.143982)
		(stroke
			(width 0.0508)
			(type default)
		)
		(layer "F.Cu")
	)
	(gr_line
		(start 375.318528 -399.143982)
		(end 375.31802 -399.143474)
		(stroke
			(width 0.0508)
			(type default)
		)
		(layer "F.Cu")
	)
	(gr_line
		(start 375.487692 -377.41733)
		(end 375.217182 -377.68784)
		(stroke
			(width 0.06477)
			(type default)
		)
		(layer "F.Cu")
	)
	(gr_line
		(start 375.513092 -379.22073)
		(end 375.163842 -379.56998)
		(stroke
			(width 0.0508)
			(type default)
		)
		(layer "F.Cu")
	)
	(gr_line
		(start 375.570496 -397.849344)
		(end 376.091196 -397.849344)
		(stroke
			(width 0.0635)
			(type default)
		)
		(layer "F.Cu")
	)
	(gr_line
		(start 375.570496 -394.385292)
		(end 376.091196 -394.385292)
		(stroke
			(width 0.0635)
			(type default)
		)
		(layer "F.Cu")
	)
	(gr_line
		(start 375.577862 -401.359116)
		(end 375.57583 -401.359116)
		(stroke
			(width 0.0508)
			(type default)
		)
		(layer "F.Cu")
	)
	(gr_line
		(start 375.716546 -401.674838)
		(end 375.716546 -401.4978)
		(stroke
			(width 0.0508)
			(type default)
		)
		(layer "F.Cu")
	)
	(gr_line
		(start 375.716546 -401.4978)
		(end 375.577862 -401.359116)
		(stroke
			(width 0.0508)
			(type default)
		)
		(layer "F.Cu")
	)
	(gr_line
		(start 375.716546 -401.0025)
		(end 375.5771 -401.141946)
		(stroke
			(width 0.0508)
			(type default)
		)
		(layer "F.Cu")
	)
	(gr_line
		(start 375.716546 -400.811238)
		(end 375.716546 -401.0025)
		(stroke
			(width 0.0508)
			(type default)
		)
		(layer "F.Cu")
	)
	(gr_line
		(start 375.915936 -391.88771)
		(end 376.007122 -391.978896)
		(stroke
			(width 0.0508)
			(type default)
		)
		(layer "F.Cu")
	)
	(gr_line
		(start 375.915936 -391.6172)
		(end 375.915936 -391.88771)
		(stroke
			(width 0.0508)
			(type default)
		)
		(layer "F.Cu")
	)
	(gr_line
		(start 376.007122 -391.978896)
		(end 376.141488 -391.978896)
		(stroke
			(width 0.0508)
			(type default)
		)
		(layer "F.Cu")
	)
	(gr_line
		(start 376.141488 -391.978896)
		(end 376.217942 -391.902442)
		(stroke
			(width 0.0508)
			(type default)
		)
		(layer "F.Cu")
	)
	(gr_line
		(start 376.167904 -222.070168)
		(end 376.476768 -221.761304)
		(stroke
			(width 0.06477)
			(type default)
		)
		(layer "F.Cu")
	)
	(gr_line
		(start 376.207274 -391.325862)
		(end 375.915936 -391.6172)
		(stroke
			(width 0.0508)
			(type default)
		)
		(layer "F.Cu")
	)
	(gr_line
		(start 376.217942 -391.902442)
		(end 376.217942 -391.784586)
		(stroke
			(width 0.0508)
			(type default)
		)
		(layer "F.Cu")
	)
	(gr_line
		(start 376.301254 -399.74647)
		(end 376.217942 -399.663158)
		(stroke
			(width 0.0508)
			(type default)
		)
		(layer "F.Cu")
	)
	(gr_line
		(start 376.370596 -397.156432)
		(end 376.891296 -397.156432)
		(stroke
			(width 0.0635)
			(type default)
		)
		(layer "F.Cu")
	)
	(gr_line
		(start 376.370596 -393.69238)
		(end 376.891296 -393.69238)
		(stroke
			(width 0.0635)
			(type default)
		)
		(layer "F.Cu")
	)
	(gr_line
		(start 376.424444 -391.51941)
		(end 376.517916 -391.612882)
		(stroke
			(width 0.0508)
			(type default)
		)
		(layer "F.Cu")
	)
	(gr_line
		(start 376.424444 -391.324592)
		(end 376.424444 -391.51941)
		(stroke
			(width 0.0508)
			(type default)
		)
		(layer "F.Cu")
	)
	(gr_line
		(start 376.517916 -391.612882)
		(end 376.517916 -392.30427)
		(stroke
			(width 0.0508)
			(type default)
		)
		(layer "F.Cu")
	)
	(gr_line
		(start 376.518424 -399.74774)
		(end 376.518424 -399.143982)
		(stroke
			(width 0.0508)
			(type default)
		)
		(layer "F.Cu")
	)
	(gr_line
		(start 376.518424 -399.143982)
		(end 376.517916 -399.143474)
		(stroke
			(width 0.0508)
			(type default)
		)
		(layer "F.Cu")
	)
	(gr_line
		(start 376.667268 -383.231136)
		(end 376.667268 -383.759456)
		(stroke
			(width 0.0508)
			(type default)
		)
		(layer "F.Cu")
	)
	(gr_line
		(start 376.770646 -397.849344)
		(end 377.291346 -397.849344)
		(stroke
			(width 0.0635)
			(type default)
		)
		(layer "F.Cu")
	)
	(gr_line
		(start 376.770646 -394.385292)
		(end 377.291346 -394.385292)
		(stroke
			(width 0.0635)
			(type default)
		)
		(layer "F.Cu")
	)
	(gr_line
		(start 376.777758 -401.359116)
		(end 376.775726 -401.359116)
		(stroke
			(width 0.0508)
			(type default)
		)
		(layer "F.Cu")
	)
	(gr_line
		(start 376.799348 -221.761558)
		(end 377.107958 -222.070168)
		(stroke
			(width 0.06477)
			(type default)
		)
		(layer "F.Cu")
	)
	(gr_line
		(start 376.884438 -383.232406)
		(end 376.994928 -383.342896)
		(stroke
			(width 0.0508)
			(type default)
		)
		(layer "F.Cu")
	)
	(gr_line
		(start 376.916442 -401.674838)
		(end 376.916442 -401.4978)
		(stroke
			(width 0.0508)
			(type default)
		)
		(layer "F.Cu")
	)
	(gr_line
		(start 376.916442 -401.4978)
		(end 376.777758 -401.359116)
		(stroke
			(width 0.0508)
			(type default)
		)
		(layer "F.Cu")
	)
	(gr_line
		(start 376.916442 -401.0025)
		(end 376.776996 -401.141946)
		(stroke
			(width 0.0508)
			(type default)
		)
		(layer "F.Cu")
	)
	(gr_line
		(start 376.916442 -400.811238)
		(end 376.916442 -401.0025)
		(stroke
			(width 0.0508)
			(type default)
		)
		(layer "F.Cu")
	)
	(gr_line
		(start 376.994928 -383.647696)
		(end 376.884438 -383.758186)
		(stroke
			(width 0.0508)
			(type default)
		)
		(layer "F.Cu")
	)
	(gr_line
		(start 376.994928 -383.342896)
		(end 376.994928 -383.647696)
		(stroke
			(width 0.0508)
			(type default)
		)
		(layer "F.Cu")
	)
	(gr_line
		(start 376.995182 -417.166044)
		(end 377.291092 -417.461954)
		(stroke
			(width 0.06477)
			(type default)
		)
		(layer "F.Cu")
	)
	(gr_line
		(start 377.020582 -412.84652)
		(end 377.291092 -413.11703)
		(stroke
			(width 0.06477)
			(type default)
		)
		(layer "F.Cu")
	)
	(gr_line
		(start 377.115832 -391.88771)
		(end 377.207018 -391.978896)
		(stroke
			(width 0.0508)
			(type default)
		)
		(layer "F.Cu")
	)
	(gr_line
		(start 377.115832 -391.6172)
		(end 377.115832 -391.88771)
		(stroke
			(width 0.0508)
			(type default)
		)
		(layer "F.Cu")
	)
	(gr_line
		(start 377.207018 -391.978896)
		(end 377.341384 -391.978896)
		(stroke
			(width 0.0508)
			(type default)
		)
		(layer "F.Cu")
	)
	(gr_line
		(start 377.291092 -420.681658)
		(end 377.020582 -420.952168)
		(stroke
			(width 0.06477)
			(type default)
		)
		(layer "F.Cu")
	)
	(gr_line
		(start 377.291092 -416.336734)
		(end 376.995182 -416.632644)
		(stroke
			(width 0.06477)
			(type default)
		)
		(layer "F.Cu")
	)
	(gr_line
		(start 377.341384 -391.978896)
		(end 377.417838 -391.902442)
		(stroke
			(width 0.0508)
			(type default)
		)
		(layer "F.Cu")
	)
	(gr_line
		(start 377.40717 -391.325862)
		(end 377.115832 -391.6172)
		(stroke
			(width 0.0508)
			(type default)
		)
		(layer "F.Cu")
	)
	(gr_line
		(start 377.417838 -391.902442)
		(end 377.417838 -391.784586)
		(stroke
			(width 0.0508)
			(type default)
		)
		(layer "F.Cu")
	)
	(gr_line
		(start 377.501404 -399.746724)
		(end 377.417838 -399.663158)
		(stroke
			(width 0.0508)
			(type default)
		)
		(layer "F.Cu")
	)
	(gr_line
		(start 377.570492 -397.156432)
		(end 378.091192 -397.156432)
		(stroke
			(width 0.0635)
			(type default)
		)
		(layer "F.Cu")
	)
	(gr_line
		(start 377.570492 -393.69238)
		(end 378.091192 -393.69238)
		(stroke
			(width 0.0635)
			(type default)
		)
		(layer "F.Cu")
	)
	(gr_line
		(start 377.613672 -420.681658)
		(end 377.884182 -420.952168)
		(stroke
			(width 0.06477)
			(type default)
		)
		(layer "F.Cu")
	)
	(gr_line
		(start 377.613672 -416.336734)
		(end 377.909582 -416.632644)
		(stroke
			(width 0.06477)
			(type default)
		)
		(layer "F.Cu")
	)
	(gr_line
		(start 377.62434 -391.51941)
		(end 377.718066 -391.613136)
		(stroke
			(width 0.0508)
			(type default)
		)
		(layer "F.Cu")
	)
	(gr_line
		(start 377.62434 -391.324592)
		(end 377.62434 -391.51941)
		(stroke
			(width 0.0508)
			(type default)
		)
		(layer "F.Cu")
	)
	(gr_line
		(start 377.718066 -391.613136)
		(end 377.718066 -392.30427)
		(stroke
			(width 0.0508)
			(type default)
		)
		(layer "F.Cu")
	)
	(gr_line
		(start 377.718574 -399.747486)
		(end 377.71832 -399.74774)
		(stroke
			(width 0.0508)
			(type default)
		)
		(layer "F.Cu")
	)
	(gr_line
		(start 377.718574 -399.747486)
		(end 377.718574 -399.143982)
		(stroke
			(width 0.0508)
			(type default)
		)
		(layer "F.Cu")
	)
	(gr_line
		(start 377.718574 -399.143982)
		(end 377.718066 -399.143474)
		(stroke
			(width 0.0508)
			(type default)
		)
		(layer "F.Cu")
	)
	(gr_line
		(start 377.884182 -412.84652)
		(end 377.613672 -413.11703)
		(stroke
			(width 0.06477)
			(type default)
		)
		(layer "F.Cu")
	)
	(gr_line
		(start 377.909582 -417.166044)
		(end 377.613672 -417.461954)
		(stroke
			(width 0.06477)
			(type default)
		)
		(layer "F.Cu")
	)
	(gr_line
		(start 377.970542 -397.849344)
		(end 378.491242 -397.849344)
		(stroke
			(width 0.0635)
			(type default)
		)
		(layer "F.Cu")
	)
	(gr_line
		(start 377.970542 -394.385292)
		(end 378.491242 -394.385292)
		(stroke
			(width 0.0635)
			(type default)
		)
		(layer "F.Cu")
	)
	(gr_line
		(start 377.977654 -401.359116)
		(end 377.975876 -401.359116)
		(stroke
			(width 0.0508)
			(type default)
		)
		(layer "F.Cu")
	)
	(gr_line
		(start 378.002292 -384.14833)
		(end 378.304044 -384.450082)
		(stroke
			(width 0.0508)
			(type default)
		)
		(layer "F.Cu")
	)
	(gr_line
		(start 378.027692 -382.34493)
		(end 378.298202 -382.61544)
		(stroke
			(width 0.06477)
			(type default)
		)
		(layer "F.Cu")
	)
	(gr_line
		(start 378.116592 -401.674838)
		(end 378.116592 -401.498054)
		(stroke
			(width 0.0508)
			(type default)
		)
		(layer "F.Cu")
	)
	(gr_line
		(start 378.116592 -401.498054)
		(end 377.977654 -401.359116)
		(stroke
			(width 0.0508)
			(type default)
		)
		(layer "F.Cu")
	)
	(gr_line
		(start 378.116592 -401.0025)
		(end 377.977146 -401.141946)
		(stroke
			(width 0.0508)
			(type default)
		)
		(layer "F.Cu")
	)
	(gr_line
		(start 378.116592 -400.811238)
		(end 378.116592 -401.0025)
		(stroke
			(width 0.0508)
			(type default)
		)
		(layer "F.Cu")
	)
	(gr_line
		(start 378.298202 -383.31902)
		(end 378.002292 -383.61493)
		(stroke
			(width 0.06477)
			(type default)
		)
		(layer "F.Cu")
	)
	(gr_line
		(start 378.315982 -391.88771)
		(end 378.407168 -391.978896)
		(stroke
			(width 0.0508)
			(type default)
		)
		(layer "F.Cu")
	)
	(gr_line
		(start 378.315982 -391.6172)
		(end 378.315982 -391.88771)
		(stroke
			(width 0.0508)
			(type default)
		)
		(layer "F.Cu")
	)
	(gr_arc
		(start 378.350526 -384.547872)
		(mid 378.335651 -384.495001)
		(end 378.304044 -384.450082)
		(stroke
			(width 0.0508)
			(type default)
		)
		(layer "F.Cu")
	)
	(gr_line
		(start 378.351542 -385.45643)
		(end 378.351542 -385.98475)
		(stroke
			(width 0.0508)
			(type default)
		)
		(layer "F.Cu")
	)
	(gr_line
		(start 378.407168 -391.978896)
		(end 378.541534 -391.978896)
		(stroke
			(width 0.0508)
			(type default)
		)
		(layer "F.Cu")
	)
	(gr_line
		(start 378.541534 -391.978896)
		(end 378.617988 -391.902442)
		(stroke
			(width 0.0508)
			(type default)
		)
		(layer "F.Cu")
	)
	(gr_line
		(start 378.568712 -385.4577)
		(end 378.679202 -385.56819)
		(stroke
			(width 0.0508)
			(type default)
		)
		(layer "F.Cu")
	)
	(gr_line
		(start 378.60732 -391.325862)
		(end 378.315982 -391.6172)
		(stroke
			(width 0.0508)
			(type default)
		)
		(layer "F.Cu")
	)
	(gr_arc
		(start 378.614686 -384.450336)
		(mid 378.583097 -384.494985)
		(end 378.568204 -384.547618)
		(stroke
			(width 0.0508)
			(type default)
		)
		(layer "F.Cu")
	)
	(gr_line
		(start 378.617988 -391.902442)
		(end 378.617988 -391.784586)
		(stroke
			(width 0.0508)
			(type default)
		)
		(layer "F.Cu")
	)
	(gr_line
		(start 378.620782 -383.31902)
		(end 378.916692 -383.61493)
		(stroke
			(width 0.06477)
			(type default)
		)
		(layer "F.Cu")
	)
	(gr_line
		(start 378.679202 -385.87299)
		(end 378.568712 -385.98348)
		(stroke
			(width 0.0508)
			(type default)
		)
		(layer "F.Cu")
	)
	(gr_line
		(start 378.679202 -385.56819)
		(end 378.679202 -385.87299)
		(stroke
			(width 0.0508)
			(type default)
		)
		(layer "F.Cu")
	)
	(gr_line
		(start 378.7013 -399.74647)
		(end 378.617988 -399.663158)
		(stroke
			(width 0.0508)
			(type default)
		)
		(layer "F.Cu")
	)
	(gr_line
		(start 378.770642 -397.156432)
		(end 379.291342 -397.156432)
		(stroke
			(width 0.0635)
			(type default)
		)
		(layer "F.Cu")
	)
	(gr_line
		(start 378.770642 -393.69238)
		(end 379.291342 -393.69238)
		(stroke
			(width 0.0635)
			(type default)
		)
		(layer "F.Cu")
	)
	(gr_line
		(start 378.82449 -391.51941)
		(end 378.917962 -391.612882)
		(stroke
			(width 0.0508)
			(type default)
		)
		(layer "F.Cu")
	)
	(gr_line
		(start 378.82449 -391.32383)
		(end 378.82449 -391.51941)
		(stroke
			(width 0.0508)
			(type default)
		)
		(layer "F.Cu")
	)
	(gr_line
		(start 378.891292 -382.34493)
		(end 378.620782 -382.61544)
		(stroke
			(width 0.06477)
			(type default)
		)
		(layer "F.Cu")
	)
	(gr_line
		(start 378.916692 -384.14833)
		(end 378.614686 -384.450336)
		(stroke
			(width 0.0508)
			(type default)
		)
		(layer "F.Cu")
	)
	(gr_line
		(start 378.917962 -391.612882)
		(end 378.917962 -392.30427)
		(stroke
			(width 0.0508)
			(type default)
		)
		(layer "F.Cu")
	)
	(gr_line
		(start 378.91847 -399.74774)
		(end 378.91847 -399.143982)
		(stroke
			(width 0.0508)
			(type default)
		)
		(layer "F.Cu")
	)
	(gr_line
		(start 378.91847 -399.143982)
		(end 378.917962 -399.143474)
		(stroke
			(width 0.0508)
			(type default)
		)
		(layer "F.Cu")
	)
	(gr_line
		(start 379.170438 -397.849344)
		(end 379.691138 -397.849344)
		(stroke
			(width 0.0635)
			(type default)
		)
		(layer "F.Cu")
	)
	(gr_line
		(start 379.170438 -394.385292)
		(end 379.691138 -394.385292)
		(stroke
			(width 0.0635)
			(type default)
		)
		(layer "F.Cu")
	)
	(gr_line
		(start 379.177804 -401.359116)
		(end 379.175772 -401.359116)
		(stroke
			(width 0.0508)
			(type default)
		)
		(layer "F.Cu")
	)
	(gr_line
		(start 379.316488 -401.674838)
		(end 379.316488 -401.4978)
		(stroke
			(width 0.0508)
			(type default)
		)
		(layer "F.Cu")
	)
	(gr_line
		(start 379.316488 -401.4978)
		(end 379.177804 -401.359116)
		(stroke
			(width 0.0508)
			(type default)
		)
		(layer "F.Cu")
	)
	(gr_line
		(start 379.316488 -401.0025)
		(end 379.177042 -401.141946)
		(stroke
			(width 0.0508)
			(type default)
		)
		(layer "F.Cu")
	)
	(gr_line
		(start 379.316488 -400.811238)
		(end 379.316488 -401.0025)
		(stroke
			(width 0.0508)
			(type default)
		)
		(layer "F.Cu")
	)
	(gr_line
		(start 379.515878 -391.88771)
		(end 379.607064 -391.978896)
		(stroke
			(width 0.0508)
			(type default)
		)
		(layer "F.Cu")
	)
	(gr_line
		(start 379.515878 -391.6172)
		(end 379.515878 -391.88771)
		(stroke
			(width 0.0508)
			(type default)
		)
		(layer "F.Cu")
	)
	(gr_line
		(start 379.607064 -391.978896)
		(end 379.74143 -391.978896)
		(stroke
			(width 0.0508)
			(type default)
		)
		(layer "F.Cu")
	)
	(gr_line
		(start 379.704092 -381.68453)
		(end 380.005844 -381.986282)
		(stroke
			(width 0.0508)
			(type default)
		)
		(layer "F.Cu")
	)
	(gr_line
		(start 379.729492 -379.88113)
		(end 380.000002 -380.15164)
		(stroke
			(width 0.06477)
			(type default)
		)
		(layer "F.Cu")
	)
	(gr_line
		(start 379.74143 -391.978896)
		(end 379.817884 -391.902442)
		(stroke
			(width 0.0508)
			(type default)
		)
		(layer "F.Cu")
	)
	(gr_line
		(start 379.807216 -391.325862)
		(end 379.515878 -391.6172)
		(stroke
			(width 0.0508)
			(type default)
		)
		(layer "F.Cu")
	)
	(gr_line
		(start 379.817884 -391.902442)
		(end 379.817884 -391.784586)
		(stroke
			(width 0.0508)
			(type default)
		)
		(layer "F.Cu")
	)
	(gr_line
		(start 379.901196 -399.74647)
		(end 379.817884 -399.663158)
		(stroke
			(width 0.0508)
			(type default)
		)
		(layer "F.Cu")
	)
	(gr_line
		(start 379.970538 -397.156432)
		(end 380.491238 -397.156432)
		(stroke
			(width 0.0635)
			(type default)
		)
		(layer "F.Cu")
	)
	(gr_line
		(start 379.970538 -393.69238)
		(end 380.491238 -393.69238)
		(stroke
			(width 0.0635)
			(type default)
		)
		(layer "F.Cu")
	)
	(gr_line
		(start 380.000002 -380.85522)
		(end 379.704092 -381.15113)
		(stroke
			(width 0.06477)
			(type default)
		)
		(layer "F.Cu")
	)
	(gr_line
		(start 380.024386 -391.51941)
		(end 380.117858 -391.612882)
		(stroke
			(width 0.0508)
			(type default)
		)
		(layer "F.Cu")
	)
	(gr_line
		(start 380.024386 -391.324592)
		(end 380.024386 -391.51941)
		(stroke
			(width 0.0508)
			(type default)
		)
		(layer "F.Cu")
	)
	(gr_arc
		(start 380.052326 -382.084072)
		(mid 380.037451 -382.031201)
		(end 380.005844 -381.986282)
		(stroke
			(width 0.0508)
			(type default)
		)
		(layer "F.Cu")
	)
	(gr_line
		(start 380.053342 -383.22504)
		(end 380.053342 -383.75336)
		(stroke
			(width 0.0508)
			(type default)
		)
		(layer "F.Cu")
	)
	(gr_line
		(start 380.058422 -417.166044)
		(end 380.354332 -417.461954)
		(stroke
			(width 0.06477)
			(type default)
		)
		(layer "F.Cu")
	)
	(gr_line
		(start 380.083822 -412.84652)
		(end 380.354332 -413.11703)
		(stroke
			(width 0.06477)
			(type default)
		)
		(layer "F.Cu")
	)
	(gr_line
		(start 380.117858 -391.612882)
		(end 380.117858 -392.30427)
		(stroke
			(width 0.0508)
			(type default)
		)
		(layer "F.Cu")
	)
	(gr_line
		(start 380.118366 -399.74774)
		(end 380.118366 -399.143982)
		(stroke
			(width 0.0508)
			(type default)
		)
		(layer "F.Cu")
	)
	(gr_line
		(start 380.118366 -399.143982)
		(end 380.117858 -399.143474)
		(stroke
			(width 0.0508)
			(type default)
		)
		(layer "F.Cu")
	)
	(gr_line
		(start 380.270512 -383.22631)
		(end 380.381002 -383.3368)
		(stroke
			(width 0.0508)
			(type default)
		)
		(layer "F.Cu")
	)
	(gr_arc
		(start 380.31674 -381.986282)
		(mid 380.285094 -382.03118)
		(end 380.270258 -382.084072)
		(stroke
			(width 0.0508)
			(type default)
		)
		(layer "F.Cu")
	)
	(gr_line
		(start 380.322582 -380.85522)
		(end 380.618492 -381.15113)
		(stroke
			(width 0.06477)
			(type default)
		)
		(layer "F.Cu")
	)
	(gr_line
		(start 380.354332 -420.681658)
		(end 380.083822 -420.952168)
		(stroke
			(width 0.06477)
			(type default)
		)
		(layer "F.Cu")
	)
	(gr_line
		(start 380.354332 -416.336734)
		(end 380.058422 -416.632644)
		(stroke
			(width 0.06477)
			(type default)
		)
		(layer "F.Cu")
	)
	(gr_line
		(start 380.370588 -397.849344)
		(end 380.891288 -397.849344)
		(stroke
			(width 0.0635)
			(type default)
		)
		(layer "F.Cu")
	)
	(gr_line
		(start 380.370588 -394.385292)
		(end 380.891288 -394.385292)
		(stroke
			(width 0.0635)
			(type default)
		)
		(layer "F.Cu")
	)
	(gr_line
		(start 380.3777 -401.359116)
		(end 380.375668 -401.359116)
		(stroke
			(width 0.0508)
			(type default)
		)
		(layer "F.Cu")
	)
	(gr_line
		(start 380.381002 -383.6416)
		(end 380.270512 -383.75209)
		(stroke
			(width 0.0508)
			(type default)
		)
		(layer "F.Cu")
	)
	(gr_line
		(start 380.381002 -383.3368)
		(end 380.381002 -383.6416)
		(stroke
			(width 0.0508)
			(type default)
		)
		(layer "F.Cu")
	)
	(gr_line
		(start 380.516638 -401.674838)
		(end 380.516638 -401.498054)
		(stroke
			(width 0.0508)
			(type default)
		)
		(layer "F.Cu")
	)
	(gr_line
		(start 380.516638 -401.498054)
		(end 380.3777 -401.359116)
		(stroke
			(width 0.0508)
			(type default)
		)
		(layer "F.Cu")
	)
	(gr_line
		(start 380.516638 -401.002246)
		(end 380.376938 -401.141946)
		(stroke
			(width 0.0508)
			(type default)
		)
		(layer "F.Cu")
	)
	(gr_line
		(start 380.516638 -400.811238)
		(end 380.516638 -401.002246)
		(stroke
			(width 0.0508)
			(type default)
		)
		(layer "F.Cu")
	)
	(gr_line
		(start 380.593092 -379.88113)
		(end 380.322582 -380.15164)
		(stroke
			(width 0.06477)
			(type default)
		)
		(layer "F.Cu")
	)
	(gr_line
		(start 380.618492 -381.68453)
		(end 380.31674 -381.986282)
		(stroke
			(width 0.0508)
			(type default)
		)
		(layer "F.Cu")
	)
	(gr_line
		(start 380.676912 -420.681658)
		(end 380.947422 -420.952168)
		(stroke
			(width 0.06477)
			(type default)
		)
		(layer "F.Cu")
	)
	(gr_line
		(start 380.676912 -416.336734)
		(end 380.972822 -416.632644)
		(stroke
			(width 0.06477)
			(type default)
		)
		(layer "F.Cu")
	)
	(gr_line
		(start 380.716028 -391.88771)
		(end 380.807214 -391.978896)
		(stroke
			(width 0.0508)
			(type default)
		)
		(layer "F.Cu")
	)
	(gr_line
		(start 380.716028 -391.6172)
		(end 380.716028 -391.88771)
		(stroke
			(width 0.0508)
			(type default)
		)
		(layer "F.Cu")
	)
	(gr_line
		(start 380.807214 -391.978896)
		(end 380.94158 -391.978896)
		(stroke
			(width 0.0508)
			(type default)
		)
		(layer "F.Cu")
	)
	(gr_line
		(start 380.94158 -391.978896)
		(end 381.018034 -391.902442)
		(stroke
			(width 0.0508)
			(type default)
		)
		(layer "F.Cu")
	)
	(gr_line
		(start 380.947422 -412.84652)
		(end 380.676912 -413.11703)
		(stroke
			(width 0.06477)
			(type default)
		)
		(layer "F.Cu")
	)
	(gr_line
		(start 380.972822 -417.166044)
		(end 380.676912 -417.461954)
		(stroke
			(width 0.06477)
			(type default)
		)
		(layer "F.Cu")
	)
	(gr_line
		(start 381.007366 -391.325862)
		(end 380.716028 -391.6172)
		(stroke
			(width 0.0508)
			(type default)
		)
		(layer "F.Cu")
	)
	(gr_line
		(start 381.018034 -391.902442)
		(end 381.018034 -391.784586)
		(stroke
			(width 0.0508)
			(type default)
		)
		(layer "F.Cu")
	)
	(gr_line
		(start 381.101346 -399.74647)
		(end 381.018034 -399.663158)
		(stroke
			(width 0.0508)
			(type default)
		)
		(layer "F.Cu")
	)
	(gr_line
		(start 381.170434 -397.156432)
		(end 381.691134 -397.156432)
		(stroke
			(width 0.0635)
			(type default)
		)
		(layer "F.Cu")
	)
	(gr_line
		(start 381.170434 -393.69238)
		(end 381.691134 -393.69238)
		(stroke
			(width 0.0635)
			(type default)
		)
		(layer "F.Cu")
	)
	(gr_line
		(start 381.224536 -391.51941)
		(end 381.318008 -391.612882)
		(stroke
			(width 0.0508)
			(type default)
		)
		(layer "F.Cu")
	)
	(gr_line
		(start 381.224536 -391.324592)
		(end 381.224536 -391.51941)
		(stroke
			(width 0.0508)
			(type default)
		)
		(layer "F.Cu")
	)
	(gr_line
		(start 381.318008 -391.612882)
		(end 381.318008 -392.30427)
		(stroke
			(width 0.0508)
			(type default)
		)
		(layer "F.Cu")
	)
	(gr_line
		(start 381.318516 -399.74774)
		(end 381.318516 -399.143982)
		(stroke
			(width 0.0508)
			(type default)
		)
		(layer "F.Cu")
	)
	(gr_line
		(start 381.318516 -399.143982)
		(end 381.318008 -399.143474)
		(stroke
			(width 0.0508)
			(type default)
		)
		(layer "F.Cu")
	)
	(gr_line
		(start 381.405892 -379.22073)
		(end 381.755142 -379.56998)
		(stroke
			(width 0.0508)
			(type default)
		)
		(layer "F.Cu")
	)
	(gr_line
		(start 381.431292 -377.41733)
		(end 381.701802 -377.68784)
		(stroke
			(width 0.06477)
			(type default)
		)
		(layer "F.Cu")
	)
	(gr_line
		(start 381.570484 -397.849344)
		(end 382.091184 -397.849344)
		(stroke
			(width 0.0635)
			(type default)
		)
		(layer "F.Cu")
	)
	(gr_line
		(start 381.570484 -394.385292)
		(end 382.091184 -394.385292)
		(stroke
			(width 0.0635)
			(type default)
		)
		(layer "F.Cu")
	)
	(gr_line
		(start 381.57785 -401.359116)
		(end 381.575818 -401.359116)
		(stroke
			(width 0.0508)
			(type default)
		)
		(layer "F.Cu")
	)
	(gr_line
		(start 381.701802 -378.39142)
		(end 381.405892 -378.68733)
		(stroke
			(width 0.06477)
			(type default)
		)
		(layer "F.Cu")
	)
	(gr_line
		(start 381.716534 -401.674838)
		(end 381.716534 -401.4978)
		(stroke
			(width 0.0508)
			(type default)
		)
		(layer "F.Cu")
	)
	(gr_line
		(start 381.716534 -401.4978)
		(end 381.57785 -401.359116)
		(stroke
			(width 0.0508)
			(type default)
		)
		(layer "F.Cu")
	)
	(gr_line
		(start 381.716534 -401.0025)
		(end 381.577088 -401.141946)
		(stroke
			(width 0.0508)
			(type default)
		)
		(layer "F.Cu")
	)
	(gr_line
		(start 381.716534 -400.811238)
		(end 381.716534 -401.0025)
		(stroke
			(width 0.0508)
			(type default)
		)
		(layer "F.Cu")
	)
	(gr_line
		(start 381.915924 -391.88771)
		(end 382.00711 -391.978896)
		(stroke
			(width 0.0508)
			(type default)
		)
		(layer "F.Cu")
	)
	(gr_line
		(start 381.915924 -391.6172)
		(end 381.915924 -391.88771)
		(stroke
			(width 0.0508)
			(type default)
		)
		(layer "F.Cu")
	)
	(gr_line
		(start 382.00711 -391.978896)
		(end 382.141476 -391.978896)
		(stroke
			(width 0.0508)
			(type default)
		)
		(layer "F.Cu")
	)
	(gr_line
		(start 382.024382 -378.39142)
		(end 382.320292 -378.68733)
		(stroke
			(width 0.06477)
			(type default)
		)
		(layer "F.Cu")
	)
	(gr_line
		(start 382.141476 -391.978896)
		(end 382.21793 -391.902442)
		(stroke
			(width 0.0508)
			(type default)
		)
		(layer "F.Cu")
	)
	(gr_line
		(start 382.207262 -391.325862)
		(end 381.915924 -391.6172)
		(stroke
			(width 0.0508)
			(type default)
		)
		(layer "F.Cu")
	)
	(gr_line
		(start 382.21793 -391.902442)
		(end 382.21793 -391.784586)
		(stroke
			(width 0.0508)
			(type default)
		)
		(layer "F.Cu")
	)
	(gr_line
		(start 382.294892 -377.41733)
		(end 382.024382 -377.68784)
		(stroke
			(width 0.06477)
			(type default)
		)
		(layer "F.Cu")
	)
	(gr_line
		(start 382.300734 -399.745962)
		(end 382.21793 -399.663158)
		(stroke
			(width 0.0508)
			(type default)
		)
		(layer "F.Cu")
	)
	(gr_line
		(start 382.320292 -379.22073)
		(end 381.971042 -379.56998)
		(stroke
			(width 0.0508)
			(type default)
		)
		(layer "F.Cu")
	)
	(gr_line
		(start 382.370584 -397.156432)
		(end 382.891284 -397.156432)
		(stroke
			(width 0.0635)
			(type default)
		)
		(layer "F.Cu")
	)
	(gr_line
		(start 382.370584 -393.69238)
		(end 382.891284 -393.69238)
		(stroke
			(width 0.0635)
			(type default)
		)
		(layer "F.Cu")
	)
	(gr_line
		(start 382.424432 -391.51941)
		(end 382.517904 -391.612882)
		(stroke
			(width 0.0508)
			(type default)
		)
		(layer "F.Cu")
	)
	(gr_line
		(start 382.424432 -391.324592)
		(end 382.424432 -391.51941)
		(stroke
			(width 0.0508)
			(type default)
		)
		(layer "F.Cu")
	)
	(gr_line
		(start 382.438402 -384.935984)
		(end 382.281684 -384.935984)
		(stroke
			(width 0.0508)
			(type default)
		)
		(layer "F.Cu")
	)
	(gr_line
		(start 382.487932 -386.86486)
		(end 382.487678 -386.86486)
		(stroke
			(width 0.0508)
			(type default)
		)
		(layer "F.Cu")
	)
	(gr_line
		(start 382.501394 -384.409188)
		(end 382.127506 -384.783076)
		(stroke
			(width 0.0508)
			(type default)
		)
		(layer "F.Cu")
	)
	(gr_line
		(start 382.517904 -399.747232)
		(end 382.517904 -399.143474)
		(stroke
			(width 0.0508)
			(type default)
		)
		(layer "F.Cu")
	)
	(gr_line
		(start 382.517904 -391.612882)
		(end 382.517904 -392.30427)
		(stroke
			(width 0.0508)
			(type default)
		)
		(layer "F.Cu")
	)
	(gr_line
		(start 382.654302 -384.720084)
		(end 382.438402 -384.935984)
		(stroke
			(width 0.0508)
			(type default)
		)
		(layer "F.Cu")
	)
	(gr_line
		(start 382.654302 -384.563366)
		(end 382.654302 -384.720084)
		(stroke
			(width 0.0508)
			(type default)
		)
		(layer "F.Cu")
	)
	(gr_line
		(start 382.770634 -397.849344)
		(end 383.291334 -397.849344)
		(stroke
			(width 0.0635)
			(type default)
		)
		(layer "F.Cu")
	)
	(gr_line
		(start 382.770634 -394.385292)
		(end 383.291334 -394.385292)
		(stroke
			(width 0.0635)
			(type default)
		)
		(layer "F.Cu")
	)
	(gr_line
		(start 382.777746 -401.359116)
		(end 382.775714 -401.359116)
		(stroke
			(width 0.0508)
			(type default)
		)
		(layer "F.Cu")
	)
	(gr_line
		(start 382.798574 -387.017768)
		(end 382.64211 -387.017768)
		(stroke
			(width 0.0508)
			(type default)
		)
		(layer "F.Cu")
	)
	(gr_line
		(start 382.861312 -386.49148)
		(end 382.487932 -386.86486)
		(stroke
			(width 0.0508)
			(type default)
		)
		(layer "F.Cu")
	)
	(gr_line
		(start 382.916684 -401.674838)
		(end 382.916684 -401.498054)
		(stroke
			(width 0.0508)
			(type default)
		)
		(layer "F.Cu")
	)
	(gr_line
		(start 382.916684 -401.498054)
		(end 382.777746 -401.359116)
		(stroke
			(width 0.0508)
			(type default)
		)
		(layer "F.Cu")
	)
	(gr_line
		(start 382.916684 -401.002246)
		(end 382.776984 -401.141946)
		(stroke
			(width 0.0508)
			(type default)
		)
		(layer "F.Cu")
	)
	(gr_line
		(start 382.916684 -400.811238)
		(end 382.916684 -401.002246)
		(stroke
			(width 0.0508)
			(type default)
		)
		(layer "F.Cu")
	)
	(gr_line
		(start 383.01422 -386.802122)
		(end 382.798574 -387.017768)
		(stroke
			(width 0.0508)
			(type default)
		)
		(layer "F.Cu")
	)
	(gr_line
		(start 383.01422 -386.645658)
		(end 383.01422 -386.802122)
		(stroke
			(width 0.0508)
			(type default)
		)
		(layer "F.Cu")
	)
	(gr_line
		(start 383.11582 -391.88771)
		(end 383.207006 -391.978896)
		(stroke
			(width 0.0508)
			(type default)
		)
		(layer "F.Cu")
	)
	(gr_line
		(start 383.11582 -391.6172)
		(end 383.11582 -391.88771)
		(stroke
			(width 0.0508)
			(type default)
		)
		(layer "F.Cu")
	)
	(gr_line
		(start 383.121662 -417.166044)
		(end 383.417572 -417.461954)
		(stroke
			(width 0.06477)
			(type default)
		)
		(layer "F.Cu")
	)
	(gr_line
		(start 383.147062 -412.84652)
		(end 383.417572 -413.11703)
		(stroke
			(width 0.06477)
			(type default)
		)
		(layer "F.Cu")
	)
	(gr_line
		(start 383.207006 -391.978896)
		(end 383.341372 -391.978896)
		(stroke
			(width 0.0508)
			(type default)
		)
		(layer "F.Cu")
	)
	(gr_line
		(start 383.341372 -391.978896)
		(end 383.417826 -391.902442)
		(stroke
			(width 0.0508)
			(type default)
		)
		(layer "F.Cu")
	)
	(gr_line
		(start 383.407158 -391.325862)
		(end 383.11582 -391.6172)
		(stroke
			(width 0.0508)
			(type default)
		)
		(layer "F.Cu")
	)
	(gr_line
		(start 383.417572 -420.681658)
		(end 383.147062 -420.952168)
		(stroke
			(width 0.06477)
			(type default)
		)
		(layer "F.Cu")
	)
	(gr_line
		(start 383.417572 -416.336734)
		(end 383.121662 -416.632644)
		(stroke
			(width 0.06477)
			(type default)
		)
		(layer "F.Cu")
	)
	(gr_line
		(start 383.417826 -391.902442)
		(end 383.417826 -391.784586)
		(stroke
			(width 0.0508)
			(type default)
		)
		(layer "F.Cu")
	)
	(gr_line
		(start 383.501138 -399.74647)
		(end 383.417826 -399.663158)
		(stroke
			(width 0.0508)
			(type default)
		)
		(layer "F.Cu")
	)
	(gr_line
		(start 383.57048 -397.156432)
		(end 384.09118 -397.156432)
		(stroke
			(width 0.0635)
			(type default)
		)
		(layer "F.Cu")
	)
	(gr_line
		(start 383.57048 -393.69238)
		(end 384.09118 -393.69238)
		(stroke
			(width 0.0635)
			(type default)
		)
		(layer "F.Cu")
	)
	(gr_line
		(start 383.624328 -391.51941)
		(end 383.718054 -391.613136)
		(stroke
			(width 0.0508)
			(type default)
		)
		(layer "F.Cu")
	)
	(gr_line
		(start 383.624328 -391.324592)
		(end 383.624328 -391.51941)
		(stroke
			(width 0.0508)
			(type default)
		)
		(layer "F.Cu")
	)
	(gr_line
		(start 383.718054 -391.613136)
		(end 383.718054 -392.30427)
		(stroke
			(width 0.0508)
			(type default)
		)
		(layer "F.Cu")
	)
	(gr_line
		(start 383.718308 -399.74774)
		(end 383.718308 -399.143728)
		(stroke
			(width 0.0508)
			(type default)
		)
		(layer "F.Cu")
	)
	(gr_line
		(start 383.718308 -399.143728)
		(end 383.718054 -399.143474)
		(stroke
			(width 0.0508)
			(type default)
		)
		(layer "F.Cu")
	)
	(gr_line
		(start 383.740152 -420.681658)
		(end 384.010662 -420.952168)
		(stroke
			(width 0.06477)
			(type default)
		)
		(layer "F.Cu")
	)
	(gr_line
		(start 383.740152 -416.336734)
		(end 384.036062 -416.632644)
		(stroke
			(width 0.06477)
			(type default)
		)
		(layer "F.Cu")
	)
	(gr_line
		(start 383.97053 -397.849344)
		(end 384.49123 -397.849344)
		(stroke
			(width 0.0635)
			(type default)
		)
		(layer "F.Cu")
	)
	(gr_line
		(start 383.97053 -394.385292)
		(end 384.49123 -394.385292)
		(stroke
			(width 0.0635)
			(type default)
		)
		(layer "F.Cu")
	)
	(gr_line
		(start 383.977642 -401.359116)
		(end 383.97561 -401.359116)
		(stroke
			(width 0.0508)
			(type default)
		)
		(layer "F.Cu")
	)
	(gr_line
		(start 384.010662 -412.84652)
		(end 383.740152 -413.11703)
		(stroke
			(width 0.06477)
			(type default)
		)
		(layer "F.Cu")
	)
	(gr_line
		(start 384.036062 -417.166044)
		(end 383.740152 -417.461954)
		(stroke
			(width 0.06477)
			(type default)
		)
		(layer "F.Cu")
	)
	(gr_line
		(start 384.11658 -401.674838)
		(end 384.11658 -401.498054)
		(stroke
			(width 0.0508)
			(type default)
		)
		(layer "F.Cu")
	)
	(gr_line
		(start 384.11658 -401.498054)
		(end 383.977642 -401.359116)
		(stroke
			(width 0.0508)
			(type default)
		)
		(layer "F.Cu")
	)
	(gr_line
		(start 384.11658 -401.002246)
		(end 383.97688 -401.141946)
		(stroke
			(width 0.0508)
			(type default)
		)
		(layer "F.Cu")
	)
	(gr_line
		(start 384.11658 -400.811238)
		(end 384.11658 -401.002246)
		(stroke
			(width 0.0508)
			(type default)
		)
		(layer "F.Cu")
	)
	(gr_line
		(start 384.154934 -223.424242)
		(end 383.688082 -223.69018)
		(stroke
			(width 0.06477)
			(type default)
		)
		(layer "F.Cu")
	)
	(gr_line
		(start 384.157982 -222.880174)
		(end 384.624834 -222.614236)
		(stroke
			(width 0.06477)
			(type default)
		)
		(layer "F.Cu")
	)
	(gr_line
		(start 384.31597 -391.88771)
		(end 384.407156 -391.978896)
		(stroke
			(width 0.0508)
			(type default)
		)
		(layer "F.Cu")
	)
	(gr_line
		(start 384.31597 -391.6172)
		(end 384.31597 -391.88771)
		(stroke
			(width 0.0508)
			(type default)
		)
		(layer "F.Cu")
	)
	(gr_line
		(start 384.407156 -391.978896)
		(end 384.541522 -391.978896)
		(stroke
			(width 0.0508)
			(type default)
		)
		(layer "F.Cu")
	)
	(gr_line
		(start 384.541522 -391.978896)
		(end 384.617976 -391.902442)
		(stroke
			(width 0.0508)
			(type default)
		)
		(layer "F.Cu")
	)
	(gr_line
		(start 384.607308 -391.325862)
		(end 384.31597 -391.6172)
		(stroke
			(width 0.0508)
			(type default)
		)
		(layer "F.Cu")
	)
	(gr_line
		(start 384.617976 -391.902442)
		(end 384.617976 -391.784586)
		(stroke
			(width 0.0508)
			(type default)
		)
		(layer "F.Cu")
	)
	(gr_line
		(start 384.701288 -399.74647)
		(end 384.617976 -399.663158)
		(stroke
			(width 0.0508)
			(type default)
		)
		(layer "F.Cu")
	)
	(gr_line
		(start 384.77063 -397.156432)
		(end 385.29133 -397.156432)
		(stroke
			(width 0.0635)
			(type default)
		)
		(layer "F.Cu")
	)
	(gr_line
		(start 384.77063 -393.69238)
		(end 385.29133 -393.69238)
		(stroke
			(width 0.0635)
			(type default)
		)
		(layer "F.Cu")
	)
	(gr_line
		(start 384.809492 -384.14833)
		(end 385.157726 -384.496564)
		(stroke
			(width 0.0508)
			(type default)
		)
		(layer "F.Cu")
	)
	(gr_line
		(start 384.824478 -391.51941)
		(end 384.91795 -391.612882)
		(stroke
			(width 0.0508)
			(type default)
		)
		(layer "F.Cu")
	)
	(gr_line
		(start 384.824478 -391.324592)
		(end 384.824478 -391.51941)
		(stroke
			(width 0.0508)
			(type default)
		)
		(layer "F.Cu")
	)
	(gr_line
		(start 384.834892 -382.34493)
		(end 385.105402 -382.61544)
		(stroke
			(width 0.06477)
			(type default)
		)
		(layer "F.Cu")
	)
	(gr_line
		(start 384.91795 -391.612882)
		(end 384.91795 -392.30427)
		(stroke
			(width 0.0508)
			(type default)
		)
		(layer "F.Cu")
	)
	(gr_line
		(start 384.918458 -399.74774)
		(end 384.918458 -399.143982)
		(stroke
			(width 0.0508)
			(type default)
		)
		(layer "F.Cu")
	)
	(gr_line
		(start 384.918458 -399.143982)
		(end 384.91795 -399.143474)
		(stroke
			(width 0.0508)
			(type default)
		)
		(layer "F.Cu")
	)
	(gr_line
		(start 385.094734 -221.80423)
		(end 384.627882 -222.070168)
		(stroke
			(width 0.06477)
			(type default)
		)
		(layer "F.Cu")
	)
	(gr_line
		(start 385.105402 -383.31902)
		(end 384.809492 -383.61493)
		(stroke
			(width 0.06477)
			(type default)
		)
		(layer "F.Cu")
	)
	(gr_line
		(start 385.157726 -384.496564)
		(end 385.157726 -384.498596)
		(stroke
			(width 0.0508)
			(type default)
		)
		(layer "F.Cu")
	)
	(gr_line
		(start 385.170426 -397.849344)
		(end 385.691126 -397.849344)
		(stroke
			(width 0.0635)
			(type default)
		)
		(layer "F.Cu")
	)
	(gr_line
		(start 385.170426 -394.385292)
		(end 385.691126 -394.385292)
		(stroke
			(width 0.0635)
			(type default)
		)
		(layer "F.Cu")
	)
	(gr_line
		(start 385.17449 -401.359116)
		(end 385.151122 -401.359116)
		(stroke
			(width 0.0508)
			(type default)
		)
		(layer "F.Cu")
	)
	(gr_line
		(start 385.316476 -401.674838)
		(end 385.316476 -401.501102)
		(stroke
			(width 0.0508)
			(type default)
		)
		(layer "F.Cu")
	)
	(gr_line
		(start 385.316476 -401.501102)
		(end 385.17449 -401.359116)
		(stroke
			(width 0.0508)
			(type default)
		)
		(layer "F.Cu")
	)
	(gr_line
		(start 385.316476 -400.977862)
		(end 385.152392 -401.141946)
		(stroke
			(width 0.0508)
			(type default)
		)
		(layer "F.Cu")
	)
	(gr_line
		(start 385.316476 -400.811238)
		(end 385.316476 -400.977862)
		(stroke
			(width 0.0508)
			(type default)
		)
		(layer "F.Cu")
	)
	(gr_line
		(start 385.427982 -383.31902)
		(end 385.723892 -383.61493)
		(stroke
			(width 0.06477)
			(type default)
		)
		(layer "F.Cu")
	)
	(gr_line
		(start 385.515866 -391.88771)
		(end 385.607052 -391.978896)
		(stroke
			(width 0.0508)
			(type default)
		)
		(layer "F.Cu")
	)
	(gr_line
		(start 385.515866 -391.6172)
		(end 385.515866 -391.88771)
		(stroke
			(width 0.0508)
			(type default)
		)
		(layer "F.Cu")
	)
	(gr_line
		(start 385.567936 -222.070168)
		(end 386.034788 -221.80423)
		(stroke
			(width 0.06477)
			(type default)
		)
		(layer "F.Cu")
	)
	(gr_line
		(start 385.607052 -391.978896)
		(end 385.741418 -391.978896)
		(stroke
			(width 0.0508)
			(type default)
		)
		(layer "F.Cu")
	)
	(gr_line
		(start 385.698492 -382.34493)
		(end 385.427982 -382.61544)
		(stroke
			(width 0.06477)
			(type default)
		)
		(layer "F.Cu")
	)
	(gr_line
		(start 385.723892 -384.14833)
		(end 385.374896 -384.497326)
		(stroke
			(width 0.0508)
			(type default)
		)
		(layer "F.Cu")
	)
	(gr_line
		(start 385.741418 -391.978896)
		(end 385.817872 -391.902442)
		(stroke
			(width 0.0508)
			(type default)
		)
		(layer "F.Cu")
	)
	(gr_line
		(start 385.807204 -391.325862)
		(end 385.515866 -391.6172)
		(stroke
			(width 0.0508)
			(type default)
		)
		(layer "F.Cu")
	)
	(gr_line
		(start 385.817872 -391.902442)
		(end 385.817872 -391.784586)
		(stroke
			(width 0.0508)
			(type default)
		)
		(layer "F.Cu")
	)
	(gr_line
		(start 385.901184 -399.74647)
		(end 385.817872 -399.663158)
		(stroke
			(width 0.0508)
			(type default)
		)
		(layer "F.Cu")
	)
	(gr_line
		(start 385.970526 -397.156432)
		(end 386.491226 -397.156432)
		(stroke
			(width 0.0635)
			(type default)
		)
		(layer "F.Cu")
	)
	(gr_line
		(start 385.970526 -393.69238)
		(end 386.491226 -393.69238)
		(stroke
			(width 0.0635)
			(type default)
		)
		(layer "F.Cu")
	)
	(gr_line
		(start 386.024374 -391.51941)
		(end 386.117846 -391.612882)
		(stroke
			(width 0.0508)
			(type default)
		)
		(layer "F.Cu")
	)
	(gr_line
		(start 386.024374 -391.324592)
		(end 386.024374 -391.51941)
		(stroke
			(width 0.0508)
			(type default)
		)
		(layer "F.Cu")
	)
	(gr_line
		(start 386.117846 -391.612882)
		(end 386.117846 -392.30427)
		(stroke
			(width 0.0508)
			(type default)
		)
		(layer "F.Cu")
	)
	(gr_line
		(start 386.118354 -399.74774)
		(end 386.118354 -399.143982)
		(stroke
			(width 0.0508)
			(type default)
		)
		(layer "F.Cu")
	)
	(gr_line
		(start 386.118354 -399.143982)
		(end 386.117846 -399.143474)
		(stroke
			(width 0.0508)
			(type default)
		)
		(layer "F.Cu")
	)
	(gr_line
		(start 386.184902 -417.166044)
		(end 386.480812 -417.461954)
		(stroke
			(width 0.06477)
			(type default)
		)
		(layer "F.Cu")
	)
	(gr_line
		(start 386.210302 -412.84652)
		(end 386.480812 -413.11703)
		(stroke
			(width 0.06477)
			(type default)
		)
		(layer "F.Cu")
	)
	(gr_line
		(start 386.370576 -397.849344)
		(end 386.891276 -397.849344)
		(stroke
			(width 0.0635)
			(type default)
		)
		(layer "F.Cu")
	)
	(gr_line
		(start 386.370576 -394.385292)
		(end 386.891276 -394.385292)
		(stroke
			(width 0.0635)
			(type default)
		)
		(layer "F.Cu")
	)
	(gr_line
		(start 386.377688 -401.359116)
		(end 386.375656 -401.359116)
		(stroke
			(width 0.0508)
			(type default)
		)
		(layer "F.Cu")
	)
	(gr_line
		(start 386.480812 -420.681658)
		(end 386.210302 -420.952168)
		(stroke
			(width 0.06477)
			(type default)
		)
		(layer "F.Cu")
	)
	(gr_line
		(start 386.480812 -416.336734)
		(end 386.184902 -416.632644)
		(stroke
			(width 0.06477)
			(type default)
		)
		(layer "F.Cu")
	)
	(gr_line
		(start 386.511292 -381.68453)
		(end 386.860542 -382.03378)
		(stroke
			(width 0.0508)
			(type default)
		)
		(layer "F.Cu")
	)
	(gr_line
		(start 386.516372 -401.674838)
		(end 386.516372 -401.4978)
		(stroke
			(width 0.0508)
			(type default)
		)
		(layer "F.Cu")
	)
	(gr_line
		(start 386.516372 -401.4978)
		(end 386.377688 -401.359116)
		(stroke
			(width 0.0508)
			(type default)
		)
		(layer "F.Cu")
	)
	(gr_line
		(start 386.516372 -401.0025)
		(end 386.376926 -401.141946)
		(stroke
			(width 0.0508)
			(type default)
		)
		(layer "F.Cu")
	)
	(gr_line
		(start 386.516372 -400.811238)
		(end 386.516372 -401.0025)
		(stroke
			(width 0.0508)
			(type default)
		)
		(layer "F.Cu")
	)
	(gr_line
		(start 386.536692 -379.88113)
		(end 386.807202 -380.15164)
		(stroke
			(width 0.06477)
			(type default)
		)
		(layer "F.Cu")
	)
	(gr_line
		(start 386.803392 -420.681658)
		(end 387.073902 -420.952168)
		(stroke
			(width 0.06477)
			(type default)
		)
		(layer "F.Cu")
	)
	(gr_line
		(start 386.803392 -416.336734)
		(end 387.099302 -416.632644)
		(stroke
			(width 0.06477)
			(type default)
		)
		(layer "F.Cu")
	)
	(gr_line
		(start 386.807202 -380.85522)
		(end 386.511292 -381.15113)
		(stroke
			(width 0.06477)
			(type default)
		)
		(layer "F.Cu")
	)
	(gr_line
		(start 386.860542 -383.403856)
		(end 386.860542 -383.932176)
		(stroke
			(width 0.0508)
			(type default)
		)
		(layer "F.Cu")
	)
	(gr_line
		(start 386.974842 -223.424242)
		(end 386.50799 -223.69018)
		(stroke
			(width 0.06477)
			(type default)
		)
		(layer "F.Cu")
	)
	(gr_line
		(start 386.97789 -222.880174)
		(end 387.444742 -222.614236)
		(stroke
			(width 0.06477)
			(type default)
		)
		(layer "F.Cu")
	)
	(gr_line
		(start 387.073902 -412.84652)
		(end 386.803392 -413.11703)
		(stroke
			(width 0.06477)
			(type default)
		)
		(layer "F.Cu")
	)
	(gr_line
		(start 387.077712 -383.405126)
		(end 387.188202 -383.515616)
		(stroke
			(width 0.0508)
			(type default)
		)
		(layer "F.Cu")
	)
	(gr_line
		(start 387.099302 -417.166044)
		(end 386.803392 -417.461954)
		(stroke
			(width 0.06477)
			(type default)
		)
		(layer "F.Cu")
	)
	(gr_line
		(start 387.101334 -399.74647)
		(end 387.018022 -399.663158)
		(stroke
			(width 0.0508)
			(type default)
		)
		(layer "F.Cu")
	)
	(gr_line
		(start 387.101334 -391.701274)
		(end 387.018022 -391.784586)
		(stroke
			(width 0.0508)
			(type default)
		)
		(layer "F.Cu")
	)
	(gr_line
		(start 387.129782 -380.85522)
		(end 387.425692 -381.15113)
		(stroke
			(width 0.06477)
			(type default)
		)
		(layer "F.Cu")
	)
	(gr_line
		(start 387.170676 -397.156432)
		(end 387.691376 -397.156432)
		(stroke
			(width 0.0635)
			(type default)
		)
		(layer "F.Cu")
	)
	(gr_line
		(start 387.170676 -393.69238)
		(end 387.691376 -393.69238)
		(stroke
			(width 0.0635)
			(type default)
		)
		(layer "F.Cu")
	)
	(gr_line
		(start 387.188202 -383.820416)
		(end 387.077712 -383.930906)
		(stroke
			(width 0.0508)
			(type default)
		)
		(layer "F.Cu")
	)
	(gr_line
		(start 387.188202 -383.515616)
		(end 387.188202 -383.820416)
		(stroke
			(width 0.0508)
			(type default)
		)
		(layer "F.Cu")
	)
	(gr_line
		(start 387.224778 -390.071102)
		(end 387.224524 -390.070848)
		(stroke
			(width 0.0508)
			(type default)
		)
		(layer "F.Cu")
	)
	(gr_line
		(start 387.318504 -399.74774)
		(end 387.318504 -399.143982)
		(stroke
			(width 0.0508)
			(type default)
		)
		(layer "F.Cu")
	)
	(gr_line
		(start 387.318504 -399.143982)
		(end 387.317996 -399.143474)
		(stroke
			(width 0.0508)
			(type default)
		)
		(layer "F.Cu")
	)
	(gr_line
		(start 387.318504 -392.303762)
		(end 387.317996 -392.30427)
		(stroke
			(width 0.0508)
			(type default)
		)
		(layer "F.Cu")
	)
	(gr_line
		(start 387.318504 -391.700004)
		(end 387.318504 -392.303762)
		(stroke
			(width 0.0508)
			(type default)
		)
		(layer "F.Cu")
	)
	(gr_line
		(start 387.400292 -379.88113)
		(end 387.129782 -380.15164)
		(stroke
			(width 0.06477)
			(type default)
		)
		(layer "F.Cu")
	)
	(gr_line
		(start 387.425692 -381.68453)
		(end 387.076442 -382.03378)
		(stroke
			(width 0.0508)
			(type default)
		)
		(layer "F.Cu")
	)
	(gr_line
		(start 387.448044 -222.070168)
		(end 387.914896 -221.80423)
		(stroke
			(width 0.06477)
			(type default)
		)
		(layer "F.Cu")
	)
	(gr_line
		(start 387.54939 -15.511526)
		(end 387.54939 -14.744446)
		(stroke
			(width 0.06477)
			(type default)
		)
		(layer "F.Cu")
	)
	(gr_line
		(start 387.54939 -14.358366)
		(end 387.54939 -13.591286)
		(stroke
			(width 0.06477)
			(type default)
		)
		(layer "F.Cu")
	)
	(gr_line
		(start 387.559804 -401.359116)
		(end 387.549136 -401.359116)
		(stroke
			(width 0.0508)
			(type default)
		)
		(layer "F.Cu")
	)
	(gr_line
		(start 387.570472 -397.849344)
		(end 388.091172 -397.849344)
		(stroke
			(width 0.0635)
			(type default)
		)
		(layer "F.Cu")
	)
	(gr_line
		(start 387.570472 -394.385292)
		(end 388.091172 -394.385292)
		(stroke
			(width 0.0635)
			(type default)
		)
		(layer "F.Cu")
	)
	(gr_line
		(start 387.716522 -401.674838)
		(end 387.716522 -401.515834)
		(stroke
			(width 0.0508)
			(type default)
		)
		(layer "F.Cu")
	)
	(gr_line
		(start 387.716522 -401.515834)
		(end 387.559804 -401.359116)
		(stroke
			(width 0.0508)
			(type default)
		)
		(layer "F.Cu")
	)
	(gr_line
		(start 387.716522 -400.97583)
		(end 387.550406 -401.141946)
		(stroke
			(width 0.0508)
			(type default)
		)
		(layer "F.Cu")
	)
	(gr_line
		(start 387.716522 -400.811238)
		(end 387.716522 -400.97583)
		(stroke
			(width 0.0508)
			(type default)
		)
		(layer "F.Cu")
	)
	(gr_line
		(start 387.87324 -14.745716)
		(end 388.06247 -14.934946)
		(stroke
			(width 0.06477)
			(type default)
		)
		(layer "F.Cu")
	)
	(gr_line
		(start 387.87324 -13.592556)
		(end 388.06247 -13.781786)
		(stroke
			(width 0.06477)
			(type default)
		)
		(layer "F.Cu")
	)
	(gr_line
		(start 388.06247 -15.321026)
		(end 387.87324 -15.510256)
		(stroke
			(width 0.06477)
			(type default)
		)
		(layer "F.Cu")
	)
	(gr_line
		(start 388.06247 -14.934946)
		(end 388.06247 -15.321026)
		(stroke
			(width 0.06477)
			(type default)
		)
		(layer "F.Cu")
	)
	(gr_line
		(start 388.06247 -14.167866)
		(end 387.87324 -14.357096)
		(stroke
			(width 0.06477)
			(type default)
		)
		(layer "F.Cu")
	)
	(gr_line
		(start 388.06247 -13.781786)
		(end 388.06247 -14.167866)
		(stroke
			(width 0.06477)
			(type default)
		)
		(layer "F.Cu")
	)
	(gr_line
		(start 388.213092 -379.22073)
		(end 388.562342 -379.56998)
		(stroke
			(width 0.0508)
			(type default)
		)
		(layer "F.Cu")
	)
	(gr_line
		(start 388.238492 -377.41733)
		(end 388.509002 -377.68784)
		(stroke
			(width 0.06477)
			(type default)
		)
		(layer "F.Cu")
	)
	(gr_line
		(start 388.293864 -12.326874)
		(end 388.836662 -11.784076)
		(stroke
			(width 0.06477)
			(type default)
		)
		(layer "F.Cu")
	)
	(gr_line
		(start 388.30123 -399.74647)
		(end 388.217918 -399.663158)
		(stroke
			(width 0.0508)
			(type default)
		)
		(layer "F.Cu")
	)
	(gr_line
		(start 388.30123 -391.701274)
		(end 388.217918 -391.784586)
		(stroke
			(width 0.0508)
			(type default)
		)
		(layer "F.Cu")
	)
	(gr_line
		(start 388.370572 -397.156432)
		(end 388.891272 -397.156432)
		(stroke
			(width 0.0635)
			(type default)
		)
		(layer "F.Cu")
	)
	(gr_line
		(start 388.370572 -393.69238)
		(end 388.891272 -393.69238)
		(stroke
			(width 0.0635)
			(type default)
		)
		(layer "F.Cu")
	)
	(gr_line
		(start 388.509002 -378.39142)
		(end 388.213092 -378.68733)
		(stroke
			(width 0.06477)
			(type default)
		)
		(layer "F.Cu")
	)
	(gr_line
		(start 388.5184 -399.74774)
		(end 388.5184 -399.143982)
		(stroke
			(width 0.0508)
			(type default)
		)
		(layer "F.Cu")
	)
	(gr_line
		(start 388.5184 -399.143982)
		(end 388.517892 -399.143474)
		(stroke
			(width 0.0508)
			(type default)
		)
		(layer "F.Cu")
	)
	(gr_line
		(start 388.5184 -392.303762)
		(end 388.517892 -392.30427)
		(stroke
			(width 0.0508)
			(type default)
		)
		(layer "F.Cu")
	)
	(gr_line
		(start 388.5184 -391.700004)
		(end 388.5184 -392.303762)
		(stroke
			(width 0.0508)
			(type default)
		)
		(layer "F.Cu")
	)
	(gr_line
		(start 388.761224 -401.359116)
		(end 388.755128 -401.359116)
		(stroke
			(width 0.0508)
			(type default)
		)
		(layer "F.Cu")
	)
	(gr_line
		(start 388.770622 -397.849344)
		(end 389.291322 -397.849344)
		(stroke
			(width 0.0635)
			(type default)
		)
		(layer "F.Cu")
	)
	(gr_line
		(start 388.770622 -394.385292)
		(end 389.291322 -394.385292)
		(stroke
			(width 0.0635)
			(type default)
		)
		(layer "F.Cu")
	)
	(gr_line
		(start 388.79145 -12.55522)
		(end 388.6962 -12.55522)
		(stroke
			(width 0.06477)
			(type default)
		)
		(layer "F.Cu")
	)
	(gr_line
		(start 388.831582 -378.39142)
		(end 389.127492 -378.68733)
		(stroke
			(width 0.06477)
			(type default)
		)
		(layer "F.Cu")
	)
	(gr_line
		(start 388.854696 -221.80423)
		(end 388.387844 -222.070168)
		(stroke
			(width 0.06477)
			(type default)
		)
		(layer "F.Cu")
	)
	(gr_line
		(start 388.916418 -401.674838)
		(end 388.916418 -401.51431)
		(stroke
			(width 0.0508)
			(type default)
		)
		(layer "F.Cu")
	)
	(gr_line
		(start 388.916418 -401.51431)
		(end 388.761224 -401.359116)
		(stroke
			(width 0.0508)
			(type default)
		)
		(layer "F.Cu")
	)
	(gr_line
		(start 388.916418 -400.981926)
		(end 388.756398 -401.141946)
		(stroke
			(width 0.0508)
			(type default)
		)
		(layer "F.Cu")
	)
	(gr_line
		(start 388.916418 -400.811238)
		(end 388.916418 -400.981926)
		(stroke
			(width 0.0508)
			(type default)
		)
		(layer "F.Cu")
	)
	(gr_line
		(start 389.01497 -11.353546)
		(end 389.01497 -10.586466)
		(stroke
			(width 0.06477)
			(type default)
		)
		(layer "F.Cu")
	)
	(gr_line
		(start 389.01497 -9.981184)
		(end 389.01497 -9.214104)
		(stroke
			(width 0.06477)
			(type default)
		)
		(layer "F.Cu")
	)
	(gr_line
		(start 389.01497 -8.828024)
		(end 389.01497 -8.060944)
		(stroke
			(width 0.06477)
			(type default)
		)
		(layer "F.Cu")
	)
	(gr_line
		(start 389.064754 -12.281916)
		(end 388.79145 -12.55522)
		(stroke
			(width 0.06477)
			(type default)
		)
		(layer "F.Cu")
	)
	(gr_line
		(start 389.064754 -12.013946)
		(end 389.064754 -12.281916)
		(stroke
			(width 0.06477)
			(type default)
		)
		(layer "F.Cu")
	)
	(gr_line
		(start 389.102092 -377.41733)
		(end 388.831582 -377.68784)
		(stroke
			(width 0.06477)
			(type default)
		)
		(layer "F.Cu")
	)
	(gr_line
		(start 389.127492 -379.22073)
		(end 388.778242 -379.56998)
		(stroke
			(width 0.0508)
			(type default)
		)
		(layer "F.Cu")
	)
	(gr_line
		(start 389.248142 -417.166044)
		(end 389.544052 -417.461954)
		(stroke
			(width 0.06477)
			(type default)
		)
		(layer "F.Cu")
	)
	(gr_line
		(start 389.273542 -412.84652)
		(end 389.544052 -413.11703)
		(stroke
			(width 0.06477)
			(type default)
		)
		(layer "F.Cu")
	)
	(gr_line
		(start 389.327898 -223.69018)
		(end 389.79475 -223.424242)
		(stroke
			(width 0.06477)
			(type default)
		)
		(layer "F.Cu")
	)
	(gr_line
		(start 389.33882 -10.587736)
		(end 389.52805 -10.776966)
		(stroke
			(width 0.06477)
			(type default)
		)
		(layer "F.Cu")
	)
	(gr_line
		(start 389.33882 -9.215374)
		(end 389.52805 -9.404604)
		(stroke
			(width 0.06477)
			(type default)
		)
		(layer "F.Cu")
	)
	(gr_line
		(start 389.33882 -8.062214)
		(end 389.52805 -8.251444)
		(stroke
			(width 0.06477)
			(type default)
		)
		(layer "F.Cu")
	)
	(gr_line
		(start 389.382 -7.173722)
		(end 389.924798 -6.630924)
		(stroke
			(width 0.06477)
			(type default)
		)
		(layer "F.Cu")
	)
	(gr_line
		(start 389.497316 -22.389084)
		(end 389.841486 -22.044914)
		(stroke
			(width 0.06477)
			(type default)
		)
		(layer "F.Cu")
	)
	(gr_line
		(start 389.52805 -11.163046)
		(end 389.33882 -11.352276)
		(stroke
			(width 0.06477)
			(type default)
		)
		(layer "F.Cu")
	)
	(gr_line
		(start 389.52805 -10.776966)
		(end 389.52805 -11.163046)
		(stroke
			(width 0.06477)
			(type default)
		)
		(layer "F.Cu")
	)
	(gr_line
		(start 389.52805 -9.790684)
		(end 389.33882 -9.979914)
		(stroke
			(width 0.06477)
			(type default)
		)
		(layer "F.Cu")
	)
	(gr_line
		(start 389.52805 -9.404604)
		(end 389.52805 -9.790684)
		(stroke
			(width 0.06477)
			(type default)
		)
		(layer "F.Cu")
	)
	(gr_line
		(start 389.52805 -8.637524)
		(end 389.33882 -8.826754)
		(stroke
			(width 0.06477)
			(type default)
		)
		(layer "F.Cu")
	)
	(gr_line
		(start 389.52805 -8.251444)
		(end 389.52805 -8.637524)
		(stroke
			(width 0.06477)
			(type default)
		)
		(layer "F.Cu")
	)
	(gr_line
		(start 389.544052 -420.681658)
		(end 389.273542 -420.952168)
		(stroke
			(width 0.06477)
			(type default)
		)
		(layer "F.Cu")
	)
	(gr_line
		(start 389.544052 -416.336734)
		(end 389.248142 -416.632644)
		(stroke
			(width 0.06477)
			(type default)
		)
		(layer "F.Cu")
	)
	(gr_line
		(start 389.745728 -381.460502)
		(end 390.119616 -381.83439)
		(stroke
			(width 0.0508)
			(type default)
		)
		(layer "F.Cu")
	)
	(gr_line
		(start 389.798052 -222.880174)
		(end 390.264904 -222.614236)
		(stroke
			(width 0.06477)
			(type default)
		)
		(layer "F.Cu")
	)
	(gr_line
		(start 389.841486 -22.044914)
		(end 389.841486 -22.039834)
		(stroke
			(width 0.06477)
			(type default)
		)
		(layer "F.Cu")
	)
	(gr_line
		(start 389.844026 -23.535894)
		(end 389.497316 -23.189184)
		(stroke
			(width 0.06477)
			(type default)
		)
		(layer "F.Cu")
	)
	(gr_line
		(start 389.866632 -420.681658)
		(end 390.137142 -420.952168)
		(stroke
			(width 0.06477)
			(type default)
		)
		(layer "F.Cu")
	)
	(gr_line
		(start 389.866632 -416.336734)
		(end 390.162542 -416.632644)
		(stroke
			(width 0.06477)
			(type default)
		)
		(layer "F.Cu")
	)
	(gr_line
		(start 389.87984 -7.402068)
		(end 389.61187 -7.402068)
		(stroke
			(width 0.06477)
			(type default)
		)
		(layer "F.Cu")
	)
	(gr_line
		(start 389.90016 -381.307594)
		(end 390.056624 -381.307594)
		(stroke
			(width 0.0508)
			(type default)
		)
		(layer "F.Cu")
	)
	(gr_line
		(start 390.007348 -15.833598)
		(end 390.303004 -15.537942)
		(stroke
			(width 0.06477)
			(type default)
		)
		(layer "F.Cu")
	)
	(gr_line
		(start 390.033764 -17.61236)
		(end 390.304274 -17.34185)
		(stroke
			(width 0.06477)
			(type default)
		)
		(layer "F.Cu")
	)
	(gr_line
		(start 390.056624 -381.307594)
		(end 390.272524 -381.523494)
		(stroke
			(width 0.0508)
			(type default)
		)
		(layer "F.Cu")
	)
	(gr_line
		(start 390.137142 -412.84652)
		(end 389.866632 -413.11703)
		(stroke
			(width 0.06477)
			(type default)
		)
		(layer "F.Cu")
	)
	(gr_line
		(start 390.153144 -7.128764)
		(end 389.87984 -7.402068)
		(stroke
			(width 0.06477)
			(type default)
		)
		(layer "F.Cu")
	)
	(gr_line
		(start 390.153144 -6.860794)
		(end 390.153144 -7.128764)
		(stroke
			(width 0.06477)
			(type default)
		)
		(layer "F.Cu")
	)
	(gr_line
		(start 390.162542 -417.166044)
		(end 389.866632 -417.461954)
		(stroke
			(width 0.06477)
			(type default)
		)
		(layer "F.Cu")
	)
	(gr_line
		(start 390.165336 -22.041104)
		(end 390.513316 -22.389084)
		(stroke
			(width 0.06477)
			(type default)
		)
		(layer "F.Cu")
	)
	(gr_line
		(start 390.272524 -381.523494)
		(end 390.272524 -381.679958)
		(stroke
			(width 0.0508)
			(type default)
		)
		(layer "F.Cu")
	)
	(gr_line
		(start 390.302496 -16.662146)
		(end 390.007348 -16.366998)
		(stroke
			(width 0.06477)
			(type default)
		)
		(layer "F.Cu")
	)
	(gr_line
		(start 390.303004 -16.662146)
		(end 390.302496 -16.662146)
		(stroke
			(width 0.06477)
			(type default)
		)
		(layer "F.Cu")
	)
	(gr_line
		(start 390.513316 -23.189184)
		(end 390.166606 -23.535894)
		(stroke
			(width 0.06477)
			(type default)
		)
		(layer "F.Cu")
	)
	(gr_line
		(start 390.626854 -17.34185)
		(end 390.897364 -17.61236)
		(stroke
			(width 0.06477)
			(type default)
		)
		(layer "F.Cu")
	)
	(gr_line
		(start 390.626854 -15.538704)
		(end 390.921748 -15.833598)
		(stroke
			(width 0.06477)
			(type default)
		)
		(layer "F.Cu")
	)
	(gr_line
		(start 390.626854 -15.536672)
		(end 390.626854 -15.538704)
		(stroke
			(width 0.06477)
			(type default)
		)
		(layer "F.Cu")
	)
	(gr_line
		(start 390.921748 -16.366998)
		(end 390.626854 -16.661892)
		(stroke
			(width 0.06477)
			(type default)
		)
		(layer "F.Cu")
	)
	(gr_line
		(start 390.940036 5.718048)
		(end 390.287764 5.899912)
		(stroke
			(width 0.06477)
			(type default)
		)
		(layer "F.Cu")
	)
	(gr_line
		(start 390.940036 6.581648)
		(end 390.287764 6.399784)
		(stroke
			(width 0.06477)
			(type default)
		)
		(layer "F.Cu")
	)
	(gr_line
		(start 391.34669 -388.090918)
		(end 391.2362 -388.201408)
		(stroke
			(width 0.0508)
			(type default)
		)
		(layer "F.Cu")
	)
	(gr_line
		(start 391.616692 -379.22073)
		(end 391.965942 -379.56998)
		(stroke
			(width 0.0508)
			(type default)
		)
		(layer "F.Cu")
	)
	(gr_line
		(start 391.642092 -377.41733)
		(end 391.912602 -377.68784)
		(stroke
			(width 0.06477)
			(type default)
		)
		(layer "F.Cu")
	)
	(gr_line
		(start 391.65149 -388.090918)
		(end 391.34669 -388.090918)
		(stroke
			(width 0.0508)
			(type default)
		)
		(layer "F.Cu")
	)
	(gr_line
		(start 391.76198 -388.201408)
		(end 391.65149 -388.090918)
		(stroke
			(width 0.0508)
			(type default)
		)
		(layer "F.Cu")
	)
	(gr_line
		(start 391.76325 -388.418578)
		(end 391.23493 -388.418578)
		(stroke
			(width 0.0508)
			(type default)
		)
		(layer "F.Cu")
	)
	(gr_line
		(start 391.846816 -8.320024)
		(end 391.846816 -7.709154)
		(stroke
			(width 0.06477)
			(type default)
		)
		(layer "F.Cu")
	)
	(gr_line
		(start 391.846816 -7.709154)
		(end 391.9855 -7.57047)
		(stroke
			(width 0.06477)
			(type default)
		)
		(layer "F.Cu")
	)
	(gr_line
		(start 391.912602 -378.39142)
		(end 391.616692 -378.68733)
		(stroke
			(width 0.06477)
			(type default)
		)
		(layer "F.Cu")
	)
	(gr_line
		(start 392.181842 -379.909832)
		(end 392.182096 -379.909578)
		(stroke
			(width 0.0508)
			(type default)
		)
		(layer "F.Cu")
	)
	(gr_line
		(start 392.229086 -385.10083)
		(end 392.13917 -385.10083)
		(stroke
			(width 0.0508)
			(type default)
		)
		(layer "F.Cu")
	)
	(gr_line
		(start 392.235182 -378.39142)
		(end 392.531092 -378.68733)
		(stroke
			(width 0.06477)
			(type default)
		)
		(layer "F.Cu")
	)
	(gr_line
		(start 392.30808 -7.57047)
		(end 392.446764 -7.709154)
		(stroke
			(width 0.06477)
			(type default)
		)
		(layer "F.Cu")
	)
	(gr_line
		(start 392.311382 -417.166044)
		(end 392.607292 -417.461954)
		(stroke
			(width 0.06477)
			(type default)
		)
		(layer "F.Cu")
	)
	(gr_line
		(start 392.336782 -412.84652)
		(end 392.607292 -413.11703)
		(stroke
			(width 0.06477)
			(type default)
		)
		(layer "F.Cu")
	)
	(gr_line
		(start 392.368786 -385.158742)
		(end 392.229086 -385.10083)
		(stroke
			(width 0.0508)
			(type default)
		)
		(layer "F.Cu")
	)
	(gr_line
		(start 392.446764 -7.709154)
		(end 392.446764 -8.320024)
		(stroke
			(width 0.06477)
			(type default)
		)
		(layer "F.Cu")
	)
	(gr_line
		(start 392.505692 -377.41733)
		(end 392.235182 -377.68784)
		(stroke
			(width 0.06477)
			(type default)
		)
		(layer "F.Cu")
	)
	(gr_line
		(start 392.531092 -379.22073)
		(end 392.181842 -379.56998)
		(stroke
			(width 0.0508)
			(type default)
		)
		(layer "F.Cu")
	)
	(gr_line
		(start 392.574272 -388.767828)
		(end 392.225022 -388.418578)
		(stroke
			(width 0.0508)
			(type default)
		)
		(layer "F.Cu")
	)
	(gr_line
		(start 392.574272 -387.853428)
		(end 392.225022 -388.202678)
		(stroke
			(width 0.0508)
			(type default)
		)
		(layer "F.Cu")
	)
	(gr_line
		(start 392.574272 -385.364228)
		(end 392.368786 -385.158742)
		(stroke
			(width 0.0508)
			(type default)
		)
		(layer "F.Cu")
	)
	(gr_line
		(start 392.574272 -384.449828)
		(end 392.14044 -384.88366)
		(stroke
			(width 0.0508)
			(type default)
		)
		(layer "F.Cu")
	)
	(gr_line
		(start 392.607292 -420.681658)
		(end 392.336782 -420.952168)
		(stroke
			(width 0.06477)
			(type default)
		)
		(layer "F.Cu")
	)
	(gr_line
		(start 392.607292 -416.336734)
		(end 392.311382 -416.632644)
		(stroke
			(width 0.06477)
			(type default)
		)
		(layer "F.Cu")
	)
	(gr_line
		(start 392.801348 -17.357598)
		(end 393.097004 -17.061942)
		(stroke
			(width 0.06477)
			(type default)
		)
		(layer "F.Cu")
	)
	(gr_line
		(start 392.826748 -19.137122)
		(end 393.097004 -18.866866)
		(stroke
			(width 0.06477)
			(type default)
		)
		(layer "F.Cu")
	)
	(gr_line
		(start 392.896344 -381.286258)
		(end 393.270232 -381.660146)
		(stroke
			(width 0.0508)
			(type default)
		)
		(layer "F.Cu")
	)
	(gr_line
		(start 392.929872 -420.681658)
		(end 393.200382 -420.952168)
		(stroke
			(width 0.06477)
			(type default)
		)
		(layer "F.Cu")
	)
	(gr_line
		(start 392.929872 -416.336734)
		(end 393.225782 -416.632644)
		(stroke
			(width 0.06477)
			(type default)
		)
		(layer "F.Cu")
	)
	(gr_line
		(start 393.050522 -381.13335)
		(end 393.20724 -381.13335)
		(stroke
			(width 0.0508)
			(type default)
		)
		(layer "F.Cu")
	)
	(gr_line
		(start 393.097004 -18.186654)
		(end 392.801348 -17.890998)
		(stroke
			(width 0.06477)
			(type default)
		)
		(layer "F.Cu")
	)
	(gr_line
		(start 393.200382 -412.84652)
		(end 392.929872 -413.11703)
		(stroke
			(width 0.06477)
			(type default)
		)
		(layer "F.Cu")
	)
	(gr_line
		(start 393.20724 -381.13335)
		(end 393.42314 -381.34925)
		(stroke
			(width 0.0508)
			(type default)
		)
		(layer "F.Cu")
	)
	(gr_line
		(start 393.225782 -417.166044)
		(end 392.929872 -417.461954)
		(stroke
			(width 0.06477)
			(type default)
		)
		(layer "F.Cu")
	)
	(gr_line
		(start 393.403582 -388.471918)
		(end 393.107672 -388.767828)
		(stroke
			(width 0.06477)
			(type default)
		)
		(layer "F.Cu")
	)
	(gr_line
		(start 393.403582 -388.149338)
		(end 393.107672 -387.853428)
		(stroke
			(width 0.06477)
			(type default)
		)
		(layer "F.Cu")
	)
	(gr_line
		(start 393.403582 -385.068318)
		(end 393.107672 -385.364228)
		(stroke
			(width 0.06477)
			(type default)
		)
		(layer "F.Cu")
	)
	(gr_line
		(start 393.403582 -384.745738)
		(end 393.107672 -384.449828)
		(stroke
			(width 0.06477)
			(type default)
		)
		(layer "F.Cu")
	)
	(gr_line
		(start 393.420854 -18.867628)
		(end 393.690348 -19.137122)
		(stroke
			(width 0.06477)
			(type default)
		)
		(layer "F.Cu")
	)
	(gr_line
		(start 393.420854 -18.865596)
		(end 393.420854 -18.867628)
		(stroke
			(width 0.06477)
			(type default)
		)
		(layer "F.Cu")
	)
	(gr_line
		(start 393.420854 -18.185892)
		(end 393.420854 -18.187924)
		(stroke
			(width 0.06477)
			(type default)
		)
		(layer "F.Cu")
	)
	(gr_line
		(start 393.420854 -17.062704)
		(end 393.715748 -17.357598)
		(stroke
			(width 0.06477)
			(type default)
		)
		(layer "F.Cu")
	)
	(gr_line
		(start 393.420854 -17.060672)
		(end 393.420854 -17.062704)
		(stroke
			(width 0.06477)
			(type default)
		)
		(layer "F.Cu")
	)
	(gr_line
		(start 393.42314 -381.34925)
		(end 393.42314 -381.505968)
		(stroke
			(width 0.0508)
			(type default)
		)
		(layer "F.Cu")
	)
	(gr_line
		(start 393.515596 -6.725158)
		(end 393.785598 -6.99516)
		(stroke
			(width 0.06477)
			(type default)
		)
		(layer "F.Cu")
	)
	(gr_line
		(start 393.646914 -11.881104)
		(end 393.646914 -11.26998)
		(stroke
			(width 0.06477)
			(type default)
		)
		(layer "F.Cu")
	)
	(gr_line
		(start 393.646914 -7.709154)
		(end 393.646914 -8.320024)
		(stroke
			(width 0.06477)
			(type default)
		)
		(layer "F.Cu")
	)
	(gr_line
		(start 393.715748 -17.890998)
		(end 393.420854 -18.185892)
		(stroke
			(width 0.06477)
			(type default)
		)
		(layer "F.Cu")
	)
	(gr_line
		(start 393.785598 -12.019788)
		(end 393.646914 -11.881104)
		(stroke
			(width 0.06477)
			(type default)
		)
		(layer "F.Cu")
	)
	(gr_line
		(start 393.785598 -7.57047)
		(end 393.646914 -7.709154)
		(stroke
			(width 0.06477)
			(type default)
		)
		(layer "F.Cu")
	)
	(gr_line
		(start 393.785598 -6.99516)
		(end 393.785598 -6.996176)
		(stroke
			(width 0.06477)
			(type default)
		)
		(layer "F.Cu")
	)
	(gr_line
		(start 394.108178 -7.57047)
		(end 394.246862 -7.709154)
		(stroke
			(width 0.06477)
			(type default)
		)
		(layer "F.Cu")
	)
	(gr_line
		(start 394.246862 -11.881104)
		(end 394.108178 -12.019788)
		(stroke
			(width 0.06477)
			(type default)
		)
		(layer "F.Cu")
	)
	(gr_line
		(start 394.246862 -11.26998)
		(end 394.246862 -11.881104)
		(stroke
			(width 0.06477)
			(type default)
		)
		(layer "F.Cu")
	)
	(gr_line
		(start 394.246862 -7.709154)
		(end 394.246862 -8.320024)
		(stroke
			(width 0.06477)
			(type default)
		)
		(layer "F.Cu")
	)
	(gr_line
		(start 394.377672 -388.742428)
		(end 394.107162 -388.471918)
		(stroke
			(width 0.06477)
			(type default)
		)
		(layer "F.Cu")
	)
	(gr_line
		(start 394.377672 -387.878828)
		(end 394.107162 -388.149338)
		(stroke
			(width 0.06477)
			(type default)
		)
		(layer "F.Cu")
	)
	(gr_line
		(start 394.377672 -385.338828)
		(end 394.107162 -385.068318)
		(stroke
			(width 0.06477)
			(type default)
		)
		(layer "F.Cu")
	)
	(gr_line
		(start 394.377672 -384.475228)
		(end 394.107162 -384.745738)
		(stroke
			(width 0.06477)
			(type default)
		)
		(layer "F.Cu")
	)
	(gr_line
		(start 394.379196 -6.725158)
		(end 394.109194 -6.99516)
		(stroke
			(width 0.06477)
			(type default)
		)
		(layer "F.Cu")
	)
	(gr_line
		(start 395.320266 -4.963414)
		(end 395.585442 -5.22859)
		(stroke
			(width 0.06477)
			(type default)
		)
		(layer "F.Cu")
	)
	(gr_line
		(start 395.374622 -417.166044)
		(end 395.670532 -417.461954)
		(stroke
			(width 0.06477)
			(type default)
		)
		(layer "F.Cu")
	)
	(gr_line
		(start 395.400022 -412.84652)
		(end 395.670532 -413.11703)
		(stroke
			(width 0.06477)
			(type default)
		)
		(layer "F.Cu")
	)
	(gr_line
		(start 395.446758 -11.881104)
		(end 395.446758 -11.26998)
		(stroke
			(width 0.06477)
			(type default)
		)
		(layer "F.Cu")
	)
	(gr_line
		(start 395.446758 -7.709154)
		(end 395.446758 -8.320024)
		(stroke
			(width 0.06477)
			(type default)
		)
		(layer "F.Cu")
	)
	(gr_line
		(start 395.585442 -12.019788)
		(end 395.446758 -11.881104)
		(stroke
			(width 0.06477)
			(type default)
		)
		(layer "F.Cu")
	)
	(gr_line
		(start 395.585442 -7.57047)
		(end 395.446758 -7.709154)
		(stroke
			(width 0.06477)
			(type default)
		)
		(layer "F.Cu")
	)
	(gr_line
		(start 395.585442 -5.22859)
		(end 395.585442 -5.239258)
		(stroke
			(width 0.06477)
			(type default)
		)
		(layer "F.Cu")
	)
	(gr_line
		(start 395.595348 -15.833598)
		(end 395.595602 -15.833598)
		(stroke
			(width 0.06477)
			(type default)
		)
		(layer "F.Cu")
	)
	(gr_line
		(start 395.595602 -15.833598)
		(end 395.892274 -15.536926)
		(stroke
			(width 0.06477)
			(type default)
		)
		(layer "F.Cu")
	)
	(gr_line
		(start 395.597126 -16.366998)
		(end 395.595348 -16.366998)
		(stroke
			(width 0.06477)
			(type default)
		)
		(layer "F.Cu")
	)
	(gr_line
		(start 395.621764 -17.61236)
		(end 395.892274 -17.34185)
		(stroke
			(width 0.06477)
			(type default)
		)
		(layer "F.Cu")
	)
	(gr_line
		(start 395.670532 -420.681658)
		(end 395.400022 -420.952168)
		(stroke
			(width 0.06477)
			(type default)
		)
		(layer "F.Cu")
	)
	(gr_line
		(start 395.670532 -416.336734)
		(end 395.374622 -416.632644)
		(stroke
			(width 0.06477)
			(type default)
		)
		(layer "F.Cu")
	)
	(gr_line
		(start 395.89202 -16.661892)
		(end 395.597126 -16.366998)
		(stroke
			(width 0.06477)
			(type default)
		)
		(layer "F.Cu")
	)
	(gr_line
		(start 395.908022 -7.57047)
		(end 396.04696 -7.709408)
		(stroke
			(width 0.06477)
			(type default)
		)
		(layer "F.Cu")
	)
	(gr_line
		(start 395.993112 -420.681658)
		(end 396.263622 -420.952168)
		(stroke
			(width 0.06477)
			(type default)
		)
		(layer "F.Cu")
	)
	(gr_line
		(start 395.993112 -416.336734)
		(end 396.289022 -416.632644)
		(stroke
			(width 0.06477)
			(type default)
		)
		(layer "F.Cu")
	)
	(gr_line
		(start 396.04696 -11.88085)
		(end 395.908022 -12.019788)
		(stroke
			(width 0.06477)
			(type default)
		)
		(layer "F.Cu")
	)
	(gr_line
		(start 396.04696 -11.26998)
		(end 396.04696 -11.88085)
		(stroke
			(width 0.06477)
			(type default)
		)
		(layer "F.Cu")
	)
	(gr_line
		(start 396.04696 -7.709408)
		(end 396.04696 -8.320024)
		(stroke
			(width 0.06477)
			(type default)
		)
		(layer "F.Cu")
	)
	(gr_line
		(start 396.183866 -4.963414)
		(end 395.909292 -5.237988)
		(stroke
			(width 0.06477)
			(type default)
		)
		(layer "F.Cu")
	)
	(gr_line
		(start 396.214854 -17.34185)
		(end 396.485364 -17.61236)
		(stroke
			(width 0.06477)
			(type default)
		)
		(layer "F.Cu")
	)
	(gr_line
		(start 396.214854 -15.536926)
		(end 396.509748 -15.83182)
		(stroke
			(width 0.06477)
			(type default)
		)
		(layer "F.Cu")
	)
	(gr_line
		(start 396.263622 -412.84652)
		(end 395.993112 -413.11703)
		(stroke
			(width 0.06477)
			(type default)
		)
		(layer "F.Cu")
	)
	(gr_line
		(start 396.289022 -417.166044)
		(end 395.993112 -417.461954)
		(stroke
			(width 0.06477)
			(type default)
		)
		(layer "F.Cu")
	)
	(gr_line
		(start 396.509748 -16.366998)
		(end 396.214854 -16.661892)
		(stroke
			(width 0.06477)
			(type default)
		)
		(layer "F.Cu")
	)
	(gr_line
		(start 396.509748 -15.83182)
		(end 396.509748 -15.833598)
		(stroke
			(width 0.06477)
			(type default)
		)
		(layer "F.Cu")
	)
	(gr_line
		(start 396.91056 -396.171674)
		(end 397.18107 -395.901164)
		(stroke
			(width 0.06477)
			(type default)
		)
		(layer "F.Cu")
	)
	(gr_line
		(start 396.91056 -395.308074)
		(end 397.18107 -395.578584)
		(stroke
			(width 0.06477)
			(type default)
		)
		(layer "F.Cu")
	)
	(gr_line
		(start 397.058388 -390.75106)
		(end 397.328898 -390.48055)
		(stroke
			(width 0.06477)
			(type default)
		)
		(layer "F.Cu")
	)
	(gr_line
		(start 397.058388 -389.88746)
		(end 397.328898 -390.15797)
		(stroke
			(width 0.06477)
			(type default)
		)
		(layer "F.Cu")
	)
	(gr_line
		(start 397.058388 -385.21386)
		(end 397.328898 -384.94335)
		(stroke
			(width 0.06477)
			(type default)
		)
		(layer "F.Cu")
	)
	(gr_line
		(start 397.058388 -384.35026)
		(end 397.328898 -384.62077)
		(stroke
			(width 0.06477)
			(type default)
		)
		(layer "F.Cu")
	)
	(gr_line
		(start 397.115538 -6.725158)
		(end 397.38554 -6.99516)
		(stroke
			(width 0.06477)
			(type default)
		)
		(layer "F.Cu")
	)
	(gr_line
		(start 397.246856 -11.881104)
		(end 397.246856 -11.26998)
		(stroke
			(width 0.06477)
			(type default)
		)
		(layer "F.Cu")
	)
	(gr_line
		(start 397.246856 -7.709154)
		(end 397.246856 -8.320024)
		(stroke
			(width 0.06477)
			(type default)
		)
		(layer "F.Cu")
	)
	(gr_line
		(start 397.38554 -12.019788)
		(end 397.246856 -11.881104)
		(stroke
			(width 0.06477)
			(type default)
		)
		(layer "F.Cu")
	)
	(gr_line
		(start 397.38554 -7.57047)
		(end 397.246856 -7.709154)
		(stroke
			(width 0.06477)
			(type default)
		)
		(layer "F.Cu")
	)
	(gr_line
		(start 397.38554 -6.99516)
		(end 397.38554 -6.996176)
		(stroke
			(width 0.06477)
			(type default)
		)
		(layer "F.Cu")
	)
	(gr_line
		(start 397.643858 -395.901164)
		(end 397.888968 -396.146274)
		(stroke
			(width 0.06477)
			(type default)
		)
		(layer "F.Cu")
	)
	(gr_line
		(start 397.643858 -395.578584)
		(end 397.888968 -395.333474)
		(stroke
			(width 0.06477)
			(type default)
		)
		(layer "F.Cu")
	)
	(gr_line
		(start 397.70812 -7.57047)
		(end 397.846804 -7.709154)
		(stroke
			(width 0.06477)
			(type default)
		)
		(layer "F.Cu")
	)
	(gr_line
		(start 397.846804 -11.881104)
		(end 397.70812 -12.019788)
		(stroke
			(width 0.06477)
			(type default)
		)
		(layer "F.Cu")
	)
	(gr_line
		(start 397.846804 -11.26998)
		(end 397.846804 -11.881104)
		(stroke
			(width 0.06477)
			(type default)
		)
		(layer "F.Cu")
	)
	(gr_line
		(start 397.846804 -7.709154)
		(end 397.846804 -8.320024)
		(stroke
			(width 0.06477)
			(type default)
		)
		(layer "F.Cu")
	)
	(gr_line
		(start 397.979138 -6.725158)
		(end 397.709136 -6.99516)
		(stroke
			(width 0.06477)
			(type default)
		)
		(layer "F.Cu")
	)
	(gr_line
		(start 398.032478 -390.48055)
		(end 398.328388 -390.77646)
		(stroke
			(width 0.06477)
			(type default)
		)
		(layer "F.Cu")
	)
	(gr_line
		(start 398.032478 -390.15797)
		(end 398.328388 -389.86206)
		(stroke
			(width 0.06477)
			(type default)
		)
		(layer "F.Cu")
	)
	(gr_line
		(start 398.032478 -384.94335)
		(end 398.328388 -385.23926)
		(stroke
			(width 0.06477)
			(type default)
		)
		(layer "F.Cu")
	)
	(gr_line
		(start 398.032478 -384.62077)
		(end 398.328388 -384.32486)
		(stroke
			(width 0.06477)
			(type default)
		)
		(layer "F.Cu")
	)
	(gr_line
		(start 398.389348 -17.357598)
		(end 398.389602 -17.357598)
		(stroke
			(width 0.06477)
			(type default)
		)
		(layer "F.Cu")
	)
	(gr_line
		(start 398.389602 -17.357598)
		(end 398.685004 -17.062196)
		(stroke
			(width 0.06477)
			(type default)
		)
		(layer "F.Cu")
	)
	(gr_line
		(start 398.391126 -17.890998)
		(end 398.389348 -17.890998)
		(stroke
			(width 0.06477)
			(type default)
		)
		(layer "F.Cu")
	)
	(gr_line
		(start 398.415764 -19.13636)
		(end 398.686274 -18.86585)
		(stroke
			(width 0.06477)
			(type default)
		)
		(layer "F.Cu")
	)
	(gr_line
		(start 398.422368 -396.146274)
		(end 398.66697 -395.901672)
		(stroke
			(width 0.06477)
			(type default)
		)
		(layer "F.Cu")
	)
	(gr_line
		(start 398.422368 -395.333474)
		(end 398.666716 -395.577822)
		(stroke
			(width 0.06477)
			(type default)
		)
		(layer "F.Cu")
	)
	(gr_line
		(start 398.437862 -417.166044)
		(end 398.733772 -417.461954)
		(stroke
			(width 0.06477)
			(type default)
		)
		(layer "F.Cu")
	)
	(gr_line
		(start 398.463262 -412.84652)
		(end 398.733772 -413.11703)
		(stroke
			(width 0.06477)
			(type default)
		)
		(layer "F.Cu")
	)
	(gr_line
		(start 398.61744 -381.68453)
		(end 398.96669 -382.03378)
		(stroke
			(width 0.0508)
			(type default)
		)
		(layer "F.Cu")
	)
	(gr_line
		(start 398.64284 -379.88113)
		(end 398.91335 -380.15164)
		(stroke
			(width 0.06477)
			(type default)
		)
		(layer "F.Cu")
	)
	(gr_line
		(start 398.666716 -395.577822)
		(end 398.66824 -395.577822)
		(stroke
			(width 0.06477)
			(type default)
		)
		(layer "F.Cu")
	)
	(gr_line
		(start 398.68602 -18.185892)
		(end 398.391126 -17.890998)
		(stroke
			(width 0.06477)
			(type default)
		)
		(layer "F.Cu")
	)
	(gr_line
		(start 398.733772 -420.681658)
		(end 398.463262 -420.952168)
		(stroke
			(width 0.06477)
			(type default)
		)
		(layer "F.Cu")
	)
	(gr_line
		(start 398.733772 -416.336734)
		(end 398.437862 -416.632644)
		(stroke
			(width 0.06477)
			(type default)
		)
		(layer "F.Cu")
	)
	(gr_line
		(start 398.861788 -390.77646)
		(end 399.211546 -390.426702)
		(stroke
			(width 0.0508)
			(type default)
		)
		(layer "F.Cu")
	)
	(gr_line
		(start 398.861788 -389.86206)
		(end 399.20926 -390.209532)
		(stroke
			(width 0.0508)
			(type default)
		)
		(layer "F.Cu")
	)
	(gr_line
		(start 398.861788 -385.23926)
		(end 399.231612 -384.869436)
		(stroke
			(width 0.0508)
			(type default)
		)
		(layer "F.Cu")
	)
	(gr_line
		(start 398.861788 -384.32486)
		(end 399.189194 -384.652266)
		(stroke
			(width 0.0508)
			(type default)
		)
		(layer "F.Cu")
	)
	(gr_line
		(start 398.91335 -380.85522)
		(end 398.61744 -381.15113)
		(stroke
			(width 0.06477)
			(type default)
		)
		(layer "F.Cu")
	)
	(gr_line
		(start 398.920208 -4.963414)
		(end 399.185638 -5.228844)
		(stroke
			(width 0.06477)
			(type default)
		)
		(layer "F.Cu")
	)
	(gr_line
		(start 398.925796 -395.577822)
		(end 398.92732 -395.577822)
		(stroke
			(width 0.06477)
			(type default)
		)
		(layer "F.Cu")
	)
	(gr_line
		(start 398.927066 -395.901672)
		(end 399.171668 -396.146274)
		(stroke
			(width 0.06477)
			(type default)
		)
		(layer "F.Cu")
	)
	(gr_line
		(start 398.92732 -395.577822)
		(end 399.171668 -395.333474)
		(stroke
			(width 0.06477)
			(type default)
		)
		(layer "F.Cu")
	)
	(gr_line
		(start 399.008854 -18.86585)
		(end 399.279364 -19.13636)
		(stroke
			(width 0.06477)
			(type default)
		)
		(layer "F.Cu")
	)
	(gr_line
		(start 399.008854 -17.062704)
		(end 399.303748 -17.357598)
		(stroke
			(width 0.06477)
			(type default)
		)
		(layer "F.Cu")
	)
	(gr_line
		(start 399.008854 -17.060926)
		(end 399.008854 -17.062704)
		(stroke
			(width 0.06477)
			(type default)
		)
		(layer "F.Cu")
	)
	(gr_line
		(start 399.046954 -11.881104)
		(end 399.046954 -11.26998)
		(stroke
			(width 0.06477)
			(type default)
		)
		(layer "F.Cu")
	)
	(gr_line
		(start 399.046954 -7.709154)
		(end 399.046954 -8.320024)
		(stroke
			(width 0.06477)
			(type default)
		)
		(layer "F.Cu")
	)
	(gr_line
		(start 399.056352 -420.681658)
		(end 399.326862 -420.952168)
		(stroke
			(width 0.06477)
			(type default)
		)
		(layer "F.Cu")
	)
	(gr_line
		(start 399.056352 -416.336734)
		(end 399.352262 -416.632644)
		(stroke
			(width 0.06477)
			(type default)
		)
		(layer "F.Cu")
	)
	(gr_line
		(start 399.171668 -396.146274)
		(end 399.4277 -395.890242)
		(stroke
			(width 0.06477)
			(type default)
		)
		(layer "F.Cu")
	)
	(gr_line
		(start 399.171668 -395.333474)
		(end 399.404586 -395.566392)
		(stroke
			(width 0.06477)
			(type default)
		)
		(layer "F.Cu")
	)
	(gr_line
		(start 399.185638 -12.019788)
		(end 399.046954 -11.881104)
		(stroke
			(width 0.06477)
			(type default)
		)
		(layer "F.Cu")
	)
	(gr_line
		(start 399.185638 -7.57047)
		(end 399.046954 -7.709154)
		(stroke
			(width 0.06477)
			(type default)
		)
		(layer "F.Cu")
	)
	(gr_line
		(start 399.185638 -5.228844)
		(end 399.185638 -5.239004)
		(stroke
			(width 0.06477)
			(type default)
		)
		(layer "F.Cu")
	)
	(gr_line
		(start 399.189194 -384.652266)
		(end 399.232882 -384.652266)
		(stroke
			(width 0.0508)
			(type default)
		)
		(layer "F.Cu")
	)
	(gr_line
		(start 399.20926 -390.209532)
		(end 399.212816 -390.209532)
		(stroke
			(width 0.0508)
			(type default)
		)
		(layer "F.Cu")
	)
	(gr_line
		(start 399.23593 -380.85522)
		(end 399.53184 -381.15113)
		(stroke
			(width 0.06477)
			(type default)
		)
		(layer "F.Cu")
	)
	(gr_line
		(start 399.303748 -17.890998)
		(end 399.008854 -18.185892)
		(stroke
			(width 0.06477)
			(type default)
		)
		(layer "F.Cu")
	)
	(gr_line
		(start 399.326862 -412.84652)
		(end 399.056352 -413.11703)
		(stroke
			(width 0.06477)
			(type default)
		)
		(layer "F.Cu")
	)
	(gr_line
		(start 399.352262 -417.166044)
		(end 399.056352 -417.461954)
		(stroke
			(width 0.06477)
			(type default)
		)
		(layer "F.Cu")
	)
	(gr_line
		(start 399.404586 -395.566392)
		(end 399.42897 -395.566392)
		(stroke
			(width 0.06477)
			(type default)
		)
		(layer "F.Cu")
	)
	(gr_line
		(start 399.50644 -379.88113)
		(end 399.23593 -380.15164)
		(stroke
			(width 0.06477)
			(type default)
		)
		(layer "F.Cu")
	)
	(gr_line
		(start 399.508218 -7.57047)
		(end 399.647156 -7.709408)
		(stroke
			(width 0.06477)
			(type default)
		)
		(layer "F.Cu")
	)
	(gr_line
		(start 399.517616 -390.209532)
		(end 400.045936 -390.209532)
		(stroke
			(width 0.0508)
			(type default)
		)
		(layer "F.Cu")
	)
	(gr_line
		(start 399.518886 -390.426702)
		(end 399.629376 -390.537192)
		(stroke
			(width 0.0508)
			(type default)
		)
		(layer "F.Cu")
	)
	(gr_line
		(start 399.53184 -381.68453)
		(end 399.18259 -382.03378)
		(stroke
			(width 0.0508)
			(type default)
		)
		(layer "F.Cu")
	)
	(gr_line
		(start 399.629376 -390.537192)
		(end 399.934176 -390.537192)
		(stroke
			(width 0.0508)
			(type default)
		)
		(layer "F.Cu")
	)
	(gr_line
		(start 399.646902 -11.881104)
		(end 399.508218 -12.019788)
		(stroke
			(width 0.06477)
			(type default)
		)
		(layer "F.Cu")
	)
	(gr_line
		(start 399.646902 -11.26998)
		(end 399.646902 -11.881104)
		(stroke
			(width 0.06477)
			(type default)
		)
		(layer "F.Cu")
	)
	(gr_line
		(start 399.646902 -7.709662)
		(end 399.646902 -8.320024)
		(stroke
			(width 0.06477)
			(type default)
		)
		(layer "F.Cu")
	)
	(gr_line
		(start 399.647156 -7.709408)
		(end 399.646902 -7.709662)
		(stroke
			(width 0.06477)
			(type default)
		)
		(layer "F.Cu")
	)
	(gr_line
		(start 399.783808 -4.963414)
		(end 399.509488 -5.237734)
		(stroke
			(width 0.06477)
			(type default)
		)
		(layer "F.Cu")
	)
	(gr_line
		(start 399.934176 -390.537192)
		(end 400.044666 -390.426702)
		(stroke
			(width 0.0508)
			(type default)
		)
		(layer "F.Cu")
	)
	(gr_line
		(start 400.31924 -379.22073)
		(end 400.66849 -379.56998)
		(stroke
			(width 0.0508)
			(type default)
		)
		(layer "F.Cu")
	)
	(gr_line
		(start 400.34464 -377.41733)
		(end 400.61515 -377.68784)
		(stroke
			(width 0.06477)
			(type default)
		)
		(layer "F.Cu")
	)
	(gr_line
		(start 400.350736 -390.209532)
		(end 400.879056 -390.209532)
		(stroke
			(width 0.0508)
			(type default)
		)
		(layer "F.Cu")
	)
	(gr_line
		(start 400.352006 -390.426702)
		(end 400.462496 -390.537192)
		(stroke
			(width 0.0508)
			(type default)
		)
		(layer "F.Cu")
	)
	(gr_line
		(start 400.462496 -390.537192)
		(end 400.767296 -390.537192)
		(stroke
			(width 0.0508)
			(type default)
		)
		(layer "F.Cu")
	)
	(gr_line
		(start 400.61515 -378.39142)
		(end 400.31924 -378.68733)
		(stroke
			(width 0.06477)
			(type default)
		)
		(layer "F.Cu")
	)
	(gr_line
		(start 400.71548 -6.725158)
		(end 400.985482 -6.99516)
		(stroke
			(width 0.06477)
			(type default)
		)
		(layer "F.Cu")
	)
	(gr_line
		(start 400.767296 -390.537192)
		(end 400.877786 -390.426702)
		(stroke
			(width 0.0508)
			(type default)
		)
		(layer "F.Cu")
	)
	(gr_line
		(start 400.846798 -11.881104)
		(end 400.846798 -11.26998)
		(stroke
			(width 0.06477)
			(type default)
		)
		(layer "F.Cu")
	)
	(gr_line
		(start 400.846798 -7.709154)
		(end 400.846798 -8.320024)
		(stroke
			(width 0.06477)
			(type default)
		)
		(layer "F.Cu")
	)
	(gr_line
		(start 400.93773 -378.39142)
		(end 401.23364 -378.68733)
		(stroke
			(width 0.06477)
			(type default)
		)
		(layer "F.Cu")
	)
	(gr_line
		(start 400.95424 -384.324098)
		(end 401.328128 -384.697986)
		(stroke
			(width 0.0508)
			(type default)
		)
		(layer "F.Cu")
	)
	(gr_line
		(start 400.96313 -386.91439)
		(end 401.079716 -387.19633)
		(stroke
			(width 0.0508)
			(type default)
		)
		(layer "F.Cu")
	)
	(gr_line
		(start 400.985482 -12.019788)
		(end 400.846798 -11.881104)
		(stroke
			(width 0.06477)
			(type default)
		)
		(layer "F.Cu")
	)
	(gr_line
		(start 400.985482 -7.57047)
		(end 400.846798 -7.709154)
		(stroke
			(width 0.06477)
			(type default)
		)
		(layer "F.Cu")
	)
	(gr_line
		(start 400.985482 -6.99516)
		(end 400.985482 -6.996176)
		(stroke
			(width 0.06477)
			(type default)
		)
		(layer "F.Cu")
	)
	(gr_line
		(start 401.023074 -386.769864)
		(end 400.96313 -386.91439)
		(stroke
			(width 0.0508)
			(type default)
		)
		(layer "F.Cu")
	)
	(gr_line
		(start 401.079716 -387.19633)
		(end 401.224496 -387.25602)
		(stroke
			(width 0.0508)
			(type default)
		)
		(layer "F.Cu")
	)
	(gr_line
		(start 401.108418 -384.17119)
		(end 401.265136 -384.17119)
		(stroke
			(width 0.0508)
			(type default)
		)
		(layer "F.Cu")
	)
	(gr_line
		(start 401.12569 -395.913102)
		(end 401.729448 -395.913102)
		(stroke
			(width 0.0508)
			(type default)
		)
		(layer "F.Cu")
	)
	(gr_line
		(start 401.12696 -396.130272)
		(end 401.209764 -396.213076)
		(stroke
			(width 0.0508)
			(type default)
		)
		(layer "F.Cu")
	)
	(gr_line
		(start 401.183348 -15.833598)
		(end 401.479258 -15.537688)
		(stroke
			(width 0.06477)
			(type default)
		)
		(layer "F.Cu")
	)
	(gr_line
		(start 401.185126 -16.366998)
		(end 401.183348 -16.366998)
		(stroke
			(width 0.06477)
			(type default)
		)
		(layer "F.Cu")
	)
	(gr_line
		(start 401.20824 -377.41733)
		(end 400.93773 -377.68784)
		(stroke
			(width 0.06477)
			(type default)
		)
		(layer "F.Cu")
	)
	(gr_line
		(start 401.209764 -17.61236)
		(end 401.480274 -17.34185)
		(stroke
			(width 0.06477)
			(type default)
		)
		(layer "F.Cu")
	)
	(gr_line
		(start 401.22348 -386.68579)
		(end 401.425664 -387.174232)
		(stroke
			(width 0.0508)
			(type default)
		)
		(layer "F.Cu")
	)
	(gr_line
		(start 401.23364 -379.22073)
		(end 400.88439 -379.56998)
		(stroke
			(width 0.0508)
			(type default)
		)
		(layer "F.Cu")
	)
	(gr_line
		(start 401.265136 -384.17119)
		(end 401.481036 -384.38709)
		(stroke
			(width 0.0508)
			(type default)
		)
		(layer "F.Cu")
	)
	(gr_line
		(start 401.308062 -7.57047)
		(end 401.446746 -7.709154)
		(stroke
			(width 0.06477)
			(type default)
		)
		(layer "F.Cu")
	)
	(gr_line
		(start 401.446746 -11.881104)
		(end 401.308062 -12.019788)
		(stroke
			(width 0.06477)
			(type default)
		)
		(layer "F.Cu")
	)
	(gr_line
		(start 401.446746 -11.26998)
		(end 401.446746 -11.881104)
		(stroke
			(width 0.06477)
			(type default)
		)
		(layer "F.Cu")
	)
	(gr_line
		(start 401.446746 -7.709154)
		(end 401.446746 -8.320024)
		(stroke
			(width 0.06477)
			(type default)
		)
		(layer "F.Cu")
	)
	(gr_line
		(start 401.48002 -16.661892)
		(end 401.185126 -16.366998)
		(stroke
			(width 0.06477)
			(type default)
		)
		(layer "F.Cu")
	)
	(gr_line
		(start 401.481036 -384.38709)
		(end 401.481036 -384.543808)
		(stroke
			(width 0.0508)
			(type default)
		)
		(layer "F.Cu")
	)
	(gr_line
		(start 401.501102 -417.166044)
		(end 401.797012 -417.461954)
		(stroke
			(width 0.06477)
			(type default)
		)
		(layer "F.Cu")
	)
	(gr_line
		(start 401.507706 -388.01167)
		(end 401.677124 -388.265162)
		(stroke
			(width 0.0508)
			(type default)
		)
		(layer "F.Cu")
	)
	(gr_line
		(start 401.526502 -412.84652)
		(end 401.797012 -413.11703)
		(stroke
			(width 0.06477)
			(type default)
		)
		(layer "F.Cu")
	)
	(gr_line
		(start 401.538186 -387.858)
		(end 401.507706 -388.01167)
		(stroke
			(width 0.0508)
			(type default)
		)
		(layer "F.Cu")
	)
	(gr_line
		(start 401.57908 -6.725158)
		(end 401.309078 -6.99516)
		(stroke
			(width 0.06477)
			(type default)
		)
		(layer "F.Cu")
	)
	(gr_line
		(start 401.666964 -381.303022)
		(end 402.040852 -381.676656)
		(stroke
			(width 0.0508)
			(type default)
		)
		(layer "F.Cu")
	)
	(gr_line
		(start 401.677124 -388.265162)
		(end 401.830794 -388.295896)
		(stroke
			(width 0.0508)
			(type default)
		)
		(layer "F.Cu")
	)
	(gr_line
		(start 401.718018 -387.736588)
		(end 401.718272 -387.736588)
		(stroke
			(width 0.0508)
			(type default)
		)
		(layer "F.Cu")
	)
	(gr_line
		(start 401.718272 -387.736588)
		(end 402.011896 -388.176008)
		(stroke
			(width 0.0508)
			(type default)
		)
		(layer "F.Cu")
	)
	(gr_line
		(start 401.797012 -420.681658)
		(end 401.526502 -420.952168)
		(stroke
			(width 0.06477)
			(type default)
		)
		(layer "F.Cu")
	)
	(gr_line
		(start 401.797012 -416.336734)
		(end 401.501102 -416.632644)
		(stroke
			(width 0.06477)
			(type default)
		)
		(layer "F.Cu")
	)
	(gr_line
		(start 401.801838 -15.537688)
		(end 402.097748 -15.833598)
		(stroke
			(width 0.06477)
			(type default)
		)
		(layer "F.Cu")
	)
	(gr_line
		(start 401.802854 -17.34185)
		(end 402.073364 -17.61236)
		(stroke
			(width 0.06477)
			(type default)
		)
		(layer "F.Cu")
	)
	(gr_line
		(start 401.821396 -381.150114)
		(end 401.97786 -381.150114)
		(stroke
			(width 0.0508)
			(type default)
		)
		(layer "F.Cu")
	)
	(gr_line
		(start 401.97786 -381.150114)
		(end 402.19376 -381.366014)
		(stroke
			(width 0.0508)
			(type default)
		)
		(layer "F.Cu")
	)
	(gr_line
		(start 402.011896 -388.176008)
		(end 402.011896 -388.176262)
		(stroke
			(width 0.0508)
			(type default)
		)
		(layer "F.Cu")
	)
	(gr_line
		(start 402.040852 -381.676656)
		(end 402.040852 -381.67691)
		(stroke
			(width 0.0508)
			(type default)
		)
		(layer "F.Cu")
	)
	(gr_line
		(start 402.097748 -16.366998)
		(end 401.802854 -16.661892)
		(stroke
			(width 0.06477)
			(type default)
		)
		(layer "F.Cu")
	)
	(gr_line
		(start 402.119592 -420.681658)
		(end 402.390102 -420.952168)
		(stroke
			(width 0.06477)
			(type default)
		)
		(layer "F.Cu")
	)
	(gr_line
		(start 402.119592 -416.336734)
		(end 402.415502 -416.632644)
		(stroke
			(width 0.06477)
			(type default)
		)
		(layer "F.Cu")
	)
	(gr_line
		(start 402.19376 -381.366014)
		(end 402.19376 -381.522478)
		(stroke
			(width 0.0508)
			(type default)
		)
		(layer "F.Cu")
	)
	(gr_line
		(start 402.390102 -412.84652)
		(end 402.119592 -413.11703)
		(stroke
			(width 0.06477)
			(type default)
		)
		(layer "F.Cu")
	)
	(gr_line
		(start 402.415502 -417.166044)
		(end 402.119592 -417.461954)
		(stroke
			(width 0.06477)
			(type default)
		)
		(layer "F.Cu")
	)
	(gr_line
		(start 402.443696 -391.88771)
		(end 402.534882 -391.978896)
		(stroke
			(width 0.0508)
			(type default)
		)
		(layer "F.Cu")
	)
	(gr_line
		(start 402.443696 -391.6172)
		(end 402.443696 -391.88771)
		(stroke
			(width 0.0508)
			(type default)
		)
		(layer "F.Cu")
	)
	(gr_line
		(start 402.52015 -4.963414)
		(end 402.78558 -5.228844)
		(stroke
			(width 0.06477)
			(type default)
		)
		(layer "F.Cu")
	)
	(gr_line
		(start 402.534882 -391.978896)
		(end 402.669248 -391.978896)
		(stroke
			(width 0.0508)
			(type default)
		)
		(layer "F.Cu")
	)
	(gr_line
		(start 402.646896 -11.881104)
		(end 402.646896 -11.26998)
		(stroke
			(width 0.06477)
			(type default)
		)
		(layer "F.Cu")
	)
	(gr_line
		(start 402.646896 -7.709154)
		(end 402.646896 -8.320024)
		(stroke
			(width 0.06477)
			(type default)
		)
		(layer "F.Cu")
	)
	(gr_line
		(start 402.669248 -391.978896)
		(end 402.745702 -391.902442)
		(stroke
			(width 0.0508)
			(type default)
		)
		(layer "F.Cu")
	)
	(gr_line
		(start 402.735034 -391.325862)
		(end 402.443696 -391.6172)
		(stroke
			(width 0.0508)
			(type default)
		)
		(layer "F.Cu")
	)
	(gr_line
		(start 402.745702 -391.902442)
		(end 402.745702 -391.784586)
		(stroke
			(width 0.0508)
			(type default)
		)
		(layer "F.Cu")
	)
	(gr_line
		(start 402.78558 -12.019788)
		(end 402.646896 -11.881104)
		(stroke
			(width 0.06477)
			(type default)
		)
		(layer "F.Cu")
	)
	(gr_line
		(start 402.78558 -7.57047)
		(end 402.646896 -7.709154)
		(stroke
			(width 0.06477)
			(type default)
		)
		(layer "F.Cu")
	)
	(gr_line
		(start 402.78558 -5.228844)
		(end 402.78558 -5.239004)
		(stroke
			(width 0.06477)
			(type default)
		)
		(layer "F.Cu")
	)
	(gr_line
		(start 402.829014 -399.74647)
		(end 402.745702 -399.663158)
		(stroke
			(width 0.0508)
			(type default)
		)
		(layer "F.Cu")
	)
	(gr_line
		(start 402.898356 -397.156432)
		(end 403.419056 -397.156432)
		(stroke
			(width 0.0635)
			(type default)
		)
		(layer "F.Cu")
	)
	(gr_line
		(start 402.898356 -393.69238)
		(end 403.419056 -393.69238)
		(stroke
			(width 0.0635)
			(type default)
		)
		(layer "F.Cu")
	)
	(gr_line
		(start 402.952204 -391.51941)
		(end 403.045676 -391.612882)
		(stroke
			(width 0.0508)
			(type default)
		)
		(layer "F.Cu")
	)
	(gr_line
		(start 402.952204 -391.324592)
		(end 402.952204 -391.51941)
		(stroke
			(width 0.0508)
			(type default)
		)
		(layer "F.Cu")
	)
	(gr_line
		(start 403.045676 -391.612882)
		(end 403.045676 -392.30427)
		(stroke
			(width 0.0508)
			(type default)
		)
		(layer "F.Cu")
	)
	(gr_line
		(start 403.046184 -399.74774)
		(end 403.046184 -399.143982)
		(stroke
			(width 0.0508)
			(type default)
		)
		(layer "F.Cu")
	)
	(gr_line
		(start 403.046184 -399.143982)
		(end 403.045676 -399.143474)
		(stroke
			(width 0.0508)
			(type default)
		)
		(layer "F.Cu")
	)
	(gr_line
		(start 403.10816 -7.57047)
		(end 403.247098 -7.709408)
		(stroke
			(width 0.06477)
			(type default)
		)
		(layer "F.Cu")
	)
	(gr_line
		(start 403.246844 -11.881104)
		(end 403.10816 -12.019788)
		(stroke
			(width 0.06477)
			(type default)
		)
		(layer "F.Cu")
	)
	(gr_line
		(start 403.246844 -11.26998)
		(end 403.246844 -11.881104)
		(stroke
			(width 0.06477)
			(type default)
		)
		(layer "F.Cu")
	)
	(gr_line
		(start 403.246844 -7.709662)
		(end 403.246844 -8.320024)
		(stroke
			(width 0.06477)
			(type default)
		)
		(layer "F.Cu")
	)
	(gr_line
		(start 403.247098 -7.709408)
		(end 403.246844 -7.709662)
		(stroke
			(width 0.06477)
			(type default)
		)
		(layer "F.Cu")
	)
	(gr_line
		(start 403.298406 -397.849344)
		(end 403.819106 -397.849344)
		(stroke
			(width 0.0635)
			(type default)
		)
		(layer "F.Cu")
	)
	(gr_line
		(start 403.298406 -394.385292)
		(end 403.819106 -394.385292)
		(stroke
			(width 0.0635)
			(type default)
		)
		(layer "F.Cu")
	)
	(gr_line
		(start 403.305518 -401.359116)
		(end 403.303486 -401.359116)
		(stroke
			(width 0.0508)
			(type default)
		)
		(layer "F.Cu")
	)
	(gr_line
		(start 403.38375 -4.963414)
		(end 403.10943 -5.237734)
		(stroke
			(width 0.06477)
			(type default)
		)
		(layer "F.Cu")
	)
	(gr_line
		(start 403.444202 -401.674838)
		(end 403.444202 -401.4978)
		(stroke
			(width 0.0508)
			(type default)
		)
		(layer "F.Cu")
	)
	(gr_line
		(start 403.444202 -401.4978)
		(end 403.305518 -401.359116)
		(stroke
			(width 0.0508)
			(type default)
		)
		(layer "F.Cu")
	)
	(gr_line
		(start 403.444202 -401.0025)
		(end 403.304756 -401.141946)
		(stroke
			(width 0.0508)
			(type default)
		)
		(layer "F.Cu")
	)
	(gr_line
		(start 403.444202 -400.811238)
		(end 403.444202 -401.0025)
		(stroke
			(width 0.0508)
			(type default)
		)
		(layer "F.Cu")
	)
	(gr_line
		(start 403.643592 -391.88771)
		(end 403.734778 -391.978896)
		(stroke
			(width 0.0508)
			(type default)
		)
		(layer "F.Cu")
	)
	(gr_line
		(start 403.643592 -391.6172)
		(end 403.643592 -391.88771)
		(stroke
			(width 0.0508)
			(type default)
		)
		(layer "F.Cu")
	)
	(gr_line
		(start 403.72284 -384.14833)
		(end 404.07209 -384.49758)
		(stroke
			(width 0.0508)
			(type default)
		)
		(layer "F.Cu")
	)
	(gr_line
		(start 403.734778 -391.978896)
		(end 403.869144 -391.978896)
		(stroke
			(width 0.0508)
			(type default)
		)
		(layer "F.Cu")
	)
	(gr_line
		(start 403.74824 -382.34493)
		(end 404.01875 -382.61544)
		(stroke
			(width 0.06477)
			(type default)
		)
		(layer "F.Cu")
	)
	(gr_line
		(start 403.869144 -391.978896)
		(end 403.945598 -391.902442)
		(stroke
			(width 0.0508)
			(type default)
		)
		(layer "F.Cu")
	)
	(gr_line
		(start 403.93493 -391.325862)
		(end 403.643592 -391.6172)
		(stroke
			(width 0.0508)
			(type default)
		)
		(layer "F.Cu")
	)
	(gr_line
		(start 403.945598 -391.902442)
		(end 403.945598 -391.784586)
		(stroke
			(width 0.0508)
			(type default)
		)
		(layer "F.Cu")
	)
	(gr_line
		(start 403.977348 -17.357598)
		(end 404.273258 -17.061688)
		(stroke
			(width 0.06477)
			(type default)
		)
		(layer "F.Cu")
	)
	(gr_line
		(start 403.979126 -17.890998)
		(end 403.977348 -17.890998)
		(stroke
			(width 0.06477)
			(type default)
		)
		(layer "F.Cu")
	)
	(gr_line
		(start 404.003764 -19.13636)
		(end 404.274274 -18.86585)
		(stroke
			(width 0.06477)
			(type default)
		)
		(layer "F.Cu")
	)
	(gr_line
		(start 404.01875 -383.31902)
		(end 403.72284 -383.61493)
		(stroke
			(width 0.06477)
			(type default)
		)
		(layer "F.Cu")
	)
	(gr_line
		(start 404.02891 -399.74647)
		(end 403.945598 -399.663158)
		(stroke
			(width 0.0508)
			(type default)
		)
		(layer "F.Cu")
	)
	(gr_line
		(start 404.098252 -397.156432)
		(end 404.618952 -397.156432)
		(stroke
			(width 0.0635)
			(type default)
		)
		(layer "F.Cu")
	)
	(gr_line
		(start 404.098252 -393.69238)
		(end 404.618952 -393.69238)
		(stroke
			(width 0.0635)
			(type default)
		)
		(layer "F.Cu")
	)
	(gr_line
		(start 404.1521 -391.51941)
		(end 404.245572 -391.612882)
		(stroke
			(width 0.0508)
			(type default)
		)
		(layer "F.Cu")
	)
	(gr_line
		(start 404.1521 -391.324592)
		(end 404.1521 -391.51941)
		(stroke
			(width 0.0508)
			(type default)
		)
		(layer "F.Cu")
	)
	(gr_line
		(start 404.245572 -391.612882)
		(end 404.245572 -392.30427)
		(stroke
			(width 0.0508)
			(type default)
		)
		(layer "F.Cu")
	)
	(gr_line
		(start 404.24608 -399.74774)
		(end 404.24608 -399.143982)
		(stroke
			(width 0.0508)
			(type default)
		)
		(layer "F.Cu")
	)
	(gr_line
		(start 404.24608 -399.143982)
		(end 404.245572 -399.143474)
		(stroke
			(width 0.0508)
			(type default)
		)
		(layer "F.Cu")
	)
	(gr_line
		(start 404.27402 -18.185892)
		(end 403.979126 -17.890998)
		(stroke
			(width 0.06477)
			(type default)
		)
		(layer "F.Cu")
	)
	(gr_line
		(start 404.315676 -6.725158)
		(end 404.585678 -6.99516)
		(stroke
			(width 0.06477)
			(type default)
		)
		(layer "F.Cu")
	)
	(gr_line
		(start 404.34133 -383.31902)
		(end 404.63724 -383.61493)
		(stroke
			(width 0.06477)
			(type default)
		)
		(layer "F.Cu")
	)
	(gr_line
		(start 404.446994 -11.881104)
		(end 404.446994 -11.26998)
		(stroke
			(width 0.06477)
			(type default)
		)
		(layer "F.Cu")
	)
	(gr_line
		(start 404.446994 -7.709154)
		(end 404.446994 -8.320024)
		(stroke
			(width 0.06477)
			(type default)
		)
		(layer "F.Cu")
	)
	(gr_line
		(start 404.498302 -397.849344)
		(end 405.019002 -397.849344)
		(stroke
			(width 0.0635)
			(type default)
		)
		(layer "F.Cu")
	)
	(gr_line
		(start 404.498302 -394.385292)
		(end 405.019002 -394.385292)
		(stroke
			(width 0.0635)
			(type default)
		)
		(layer "F.Cu")
	)
	(gr_line
		(start 404.505414 -401.359116)
		(end 404.503382 -401.359116)
		(stroke
			(width 0.0508)
			(type default)
		)
		(layer "F.Cu")
	)
	(gr_line
		(start 404.564342 -417.166044)
		(end 404.860252 -417.461954)
		(stroke
			(width 0.06477)
			(type default)
		)
		(layer "F.Cu")
	)
	(gr_line
		(start 404.585678 -12.019788)
		(end 404.446994 -11.881104)
		(stroke
			(width 0.06477)
			(type default)
		)
		(layer "F.Cu")
	)
	(gr_line
		(start 404.585678 -7.57047)
		(end 404.446994 -7.709154)
		(stroke
			(width 0.06477)
			(type default)
		)
		(layer "F.Cu")
	)
	(gr_line
		(start 404.585678 -6.99516)
		(end 404.585678 -6.996176)
		(stroke
			(width 0.06477)
			(type default)
		)
		(layer "F.Cu")
	)
	(gr_line
		(start 404.589742 -412.84652)
		(end 404.860252 -413.11703)
		(stroke
			(width 0.06477)
			(type default)
		)
		(layer "F.Cu")
	)
	(gr_line
		(start 404.595838 -17.061688)
		(end 404.891748 -17.357598)
		(stroke
			(width 0.06477)
			(type default)
		)
		(layer "F.Cu")
	)
	(gr_line
		(start 404.596854 -18.86585)
		(end 404.867364 -19.13636)
		(stroke
			(width 0.06477)
			(type default)
		)
		(layer "F.Cu")
	)
	(gr_line
		(start 404.61184 -382.34493)
		(end 404.34133 -382.61544)
		(stroke
			(width 0.06477)
			(type default)
		)
		(layer "F.Cu")
	)
	(gr_line
		(start 404.63724 -384.14833)
		(end 404.28799 -384.49758)
		(stroke
			(width 0.0508)
			(type default)
		)
		(layer "F.Cu")
	)
	(gr_line
		(start 404.644098 -401.674838)
		(end 404.644098 -401.4978)
		(stroke
			(width 0.0508)
			(type default)
		)
		(layer "F.Cu")
	)
	(gr_line
		(start 404.644098 -401.4978)
		(end 404.505414 -401.359116)
		(stroke
			(width 0.0508)
			(type default)
		)
		(layer "F.Cu")
	)
	(gr_line
		(start 404.644098 -401.0025)
		(end 404.504652 -401.141946)
		(stroke
			(width 0.0508)
			(type default)
		)
		(layer "F.Cu")
	)
	(gr_line
		(start 404.644098 -400.811238)
		(end 404.644098 -401.0025)
		(stroke
			(width 0.0508)
			(type default)
		)
		(layer "F.Cu")
	)
	(gr_line
		(start 404.843742 -391.88771)
		(end 404.934928 -391.978896)
		(stroke
			(width 0.0508)
			(type default)
		)
		(layer "F.Cu")
	)
	(gr_line
		(start 404.843742 -391.6172)
		(end 404.843742 -391.88771)
		(stroke
			(width 0.0508)
			(type default)
		)
		(layer "F.Cu")
	)
	(gr_line
		(start 404.860252 -420.681658)
		(end 404.589742 -420.952168)
		(stroke
			(width 0.06477)
			(type default)
		)
		(layer "F.Cu")
	)
	(gr_line
		(start 404.860252 -416.336734)
		(end 404.564342 -416.632644)
		(stroke
			(width 0.06477)
			(type default)
		)
		(layer "F.Cu")
	)
	(gr_line
		(start 404.878794 -385.988814)
		(end 405.214328 -386.397754)
		(stroke
			(width 0.0508)
			(type default)
		)
		(layer "F.Cu")
	)
	(gr_line
		(start 404.891748 -17.890998)
		(end 404.596854 -18.185892)
		(stroke
			(width 0.06477)
			(type default)
		)
		(layer "F.Cu")
	)
	(gr_line
		(start 404.908258 -7.57047)
		(end 405.046942 -7.709154)
		(stroke
			(width 0.06477)
			(type default)
		)
		(layer "F.Cu")
	)
	(gr_line
		(start 404.934928 -391.978896)
		(end 405.069294 -391.978896)
		(stroke
			(width 0.0508)
			(type default)
		)
		(layer "F.Cu")
	)
	(gr_line
		(start 405.046942 -11.881104)
		(end 404.908258 -12.019788)
		(stroke
			(width 0.06477)
			(type default)
		)
		(layer "F.Cu")
	)
	(gr_line
		(start 405.046942 -11.26998)
		(end 405.046942 -11.881104)
		(stroke
			(width 0.06477)
			(type default)
		)
		(layer "F.Cu")
	)
	(gr_line
		(start 405.046942 -7.709154)
		(end 405.046942 -8.320024)
		(stroke
			(width 0.06477)
			(type default)
		)
		(layer "F.Cu")
	)
	(gr_line
		(start 405.04745 -385.852162)
		(end 405.202898 -385.867402)
		(stroke
			(width 0.0508)
			(type default)
		)
		(layer "F.Cu")
	)
	(gr_line
		(start 405.069294 -391.978896)
		(end 405.145748 -391.902442)
		(stroke
			(width 0.0508)
			(type default)
		)
		(layer "F.Cu")
	)
	(gr_line
		(start 405.13508 -391.325862)
		(end 404.843742 -391.6172)
		(stroke
			(width 0.0508)
			(type default)
		)
		(layer "F.Cu")
	)
	(gr_line
		(start 405.145748 -391.902442)
		(end 405.145748 -391.784586)
		(stroke
			(width 0.0508)
			(type default)
		)
		(layer "F.Cu")
	)
	(gr_line
		(start 405.179276 -6.725158)
		(end 404.909274 -6.99516)
		(stroke
			(width 0.06477)
			(type default)
		)
		(layer "F.Cu")
	)
	(gr_line
		(start 405.182832 -420.681658)
		(end 405.453342 -420.952168)
		(stroke
			(width 0.06477)
			(type default)
		)
		(layer "F.Cu")
	)
	(gr_line
		(start 405.182832 -416.336734)
		(end 405.478742 -416.632644)
		(stroke
			(width 0.06477)
			(type default)
		)
		(layer "F.Cu")
	)
	(gr_line
		(start 405.202898 -385.867402)
		(end 405.396446 -386.103114)
		(stroke
			(width 0.0508)
			(type default)
		)
		(layer "F.Cu")
	)
	(gr_line
		(start 405.22906 -399.74647)
		(end 405.145748 -399.663158)
		(stroke
			(width 0.0508)
			(type default)
		)
		(layer "F.Cu")
	)
	(gr_line
		(start 405.298402 -397.156432)
		(end 405.819102 -397.156432)
		(stroke
			(width 0.0635)
			(type default)
		)
		(layer "F.Cu")
	)
	(gr_line
		(start 405.298402 -393.69238)
		(end 405.819102 -393.69238)
		(stroke
			(width 0.0635)
			(type default)
		)
		(layer "F.Cu")
	)
	(gr_line
		(start 405.35225 -391.51941)
		(end 405.445722 -391.612882)
		(stroke
			(width 0.0508)
			(type default)
		)
		(layer "F.Cu")
	)
	(gr_line
		(start 405.35225 -391.324592)
		(end 405.35225 -391.51941)
		(stroke
			(width 0.0508)
			(type default)
		)
		(layer "F.Cu")
	)
	(gr_line
		(start 405.396446 -386.103114)
		(end 405.38146 -386.25907)
		(stroke
			(width 0.0508)
			(type default)
		)
		(layer "F.Cu")
	)
	(gr_line
		(start 405.42464 -381.68453)
		(end 405.77389 -382.03378)
		(stroke
			(width 0.0508)
			(type default)
		)
		(layer "F.Cu")
	)
	(gr_line
		(start 405.445722 -391.612882)
		(end 405.445722 -392.30427)
		(stroke
			(width 0.0508)
			(type default)
		)
		(layer "F.Cu")
	)
	(gr_line
		(start 405.44623 -399.74774)
		(end 405.44623 -399.143982)
		(stroke
			(width 0.0508)
			(type default)
		)
		(layer "F.Cu")
	)
	(gr_line
		(start 405.44623 -399.143982)
		(end 405.445722 -399.143474)
		(stroke
			(width 0.0508)
			(type default)
		)
		(layer "F.Cu")
	)
	(gr_line
		(start 405.45004 -379.88113)
		(end 405.72055 -380.15164)
		(stroke
			(width 0.06477)
			(type default)
		)
		(layer "F.Cu")
	)
	(gr_line
		(start 405.453342 -412.84652)
		(end 405.182832 -413.11703)
		(stroke
			(width 0.06477)
			(type default)
		)
		(layer "F.Cu")
	)
	(gr_line
		(start 405.478742 -417.166044)
		(end 405.182832 -417.461954)
		(stroke
			(width 0.06477)
			(type default)
		)
		(layer "F.Cu")
	)
	(gr_line
		(start 405.698198 -397.849344)
		(end 406.218898 -397.849344)
		(stroke
			(width 0.0635)
			(type default)
		)
		(layer "F.Cu")
	)
	(gr_line
		(start 405.698198 -394.385292)
		(end 406.218898 -394.385292)
		(stroke
			(width 0.0635)
			(type default)
		)
		(layer "F.Cu")
	)
	(gr_line
		(start 405.705564 -401.359116)
		(end 405.703532 -401.359116)
		(stroke
			(width 0.0508)
			(type default)
		)
		(layer "F.Cu")
	)
	(gr_line
		(start 405.72055 -380.85522)
		(end 405.42464 -381.15113)
		(stroke
			(width 0.06477)
			(type default)
		)
		(layer "F.Cu")
	)
	(gr_line
		(start 405.77389 -382.911096)
		(end 405.77389 -383.439416)
		(stroke
			(width 0.0508)
			(type default)
		)
		(layer "F.Cu")
	)
	(gr_line
		(start 405.844248 -401.674838)
		(end 405.844248 -401.4978)
		(stroke
			(width 0.0508)
			(type default)
		)
		(layer "F.Cu")
	)
	(gr_line
		(start 405.844248 -401.4978)
		(end 405.705564 -401.359116)
		(stroke
			(width 0.0508)
			(type default)
		)
		(layer "F.Cu")
	)
	(gr_line
		(start 405.844248 -401.0025)
		(end 405.704802 -401.141946)
		(stroke
			(width 0.0508)
			(type default)
		)
		(layer "F.Cu")
	)
	(gr_line
		(start 405.844248 -400.811238)
		(end 405.844248 -401.0025)
		(stroke
			(width 0.0508)
			(type default)
		)
		(layer "F.Cu")
	)
	(gr_line
		(start 405.99106 -382.912366)
		(end 406.10155 -383.022856)
		(stroke
			(width 0.0508)
			(type default)
		)
		(layer "F.Cu")
	)
	(gr_line
		(start 406.04313 -380.85522)
		(end 406.33904 -381.15113)
		(stroke
			(width 0.06477)
			(type default)
		)
		(layer "F.Cu")
	)
	(gr_line
		(start 406.043638 -391.88771)
		(end 406.134824 -391.978896)
		(stroke
			(width 0.0508)
			(type default)
		)
		(layer "F.Cu")
	)
	(gr_line
		(start 406.043638 -391.6172)
		(end 406.043638 -391.88771)
		(stroke
			(width 0.0508)
			(type default)
		)
		(layer "F.Cu")
	)
	(gr_line
		(start 406.10155 -383.327656)
		(end 405.99106 -383.438146)
		(stroke
			(width 0.0508)
			(type default)
		)
		(layer "F.Cu")
	)
	(gr_line
		(start 406.10155 -383.022856)
		(end 406.10155 -383.327656)
		(stroke
			(width 0.0508)
			(type default)
		)
		(layer "F.Cu")
	)
	(gr_line
		(start 406.120346 -4.963414)
		(end 406.386538 -5.229606)
		(stroke
			(width 0.06477)
			(type default)
		)
		(layer "F.Cu")
	)
	(gr_line
		(start 406.134824 -391.978896)
		(end 406.26919 -391.978896)
		(stroke
			(width 0.0508)
			(type default)
		)
		(layer "F.Cu")
	)
	(gr_line
		(start 406.246838 -11.881104)
		(end 406.246838 -11.26998)
		(stroke
			(width 0.06477)
			(type default)
		)
		(layer "F.Cu")
	)
	(gr_line
		(start 406.246838 -7.709154)
		(end 406.246838 -8.320024)
		(stroke
			(width 0.06477)
			(type default)
		)
		(layer "F.Cu")
	)
	(gr_line
		(start 406.26919 -391.978896)
		(end 406.345644 -391.902442)
		(stroke
			(width 0.0508)
			(type default)
		)
		(layer "F.Cu")
	)
	(gr_line
		(start 406.31364 -379.88113)
		(end 406.04313 -380.15164)
		(stroke
			(width 0.06477)
			(type default)
		)
		(layer "F.Cu")
	)
	(gr_line
		(start 406.334976 -391.325862)
		(end 406.043638 -391.6172)
		(stroke
			(width 0.0508)
			(type default)
		)
		(layer "F.Cu")
	)
	(gr_line
		(start 406.33904 -381.68453)
		(end 405.98979 -382.03378)
		(stroke
			(width 0.0508)
			(type default)
		)
		(layer "F.Cu")
	)
	(gr_line
		(start 406.345644 -391.902442)
		(end 406.345644 -391.784586)
		(stroke
			(width 0.0508)
			(type default)
		)
		(layer "F.Cu")
	)
	(gr_line
		(start 406.385268 -7.570724)
		(end 406.246838 -7.709154)
		(stroke
			(width 0.06477)
			(type default)
		)
		(layer "F.Cu")
	)
	(gr_line
		(start 406.385522 -12.019788)
		(end 406.246838 -11.881104)
		(stroke
			(width 0.06477)
			(type default)
		)
		(layer "F.Cu")
	)
	(gr_line
		(start 406.386538 -5.229606)
		(end 406.386538 -5.238242)
		(stroke
			(width 0.06477)
			(type default)
		)
		(layer "F.Cu")
	)
	(gr_line
		(start 406.428956 -399.74647)
		(end 406.345644 -399.663158)
		(stroke
			(width 0.0508)
			(type default)
		)
		(layer "F.Cu")
	)
	(gr_line
		(start 406.498298 -397.156432)
		(end 407.018998 -397.156432)
		(stroke
			(width 0.0635)
			(type default)
		)
		(layer "F.Cu")
	)
	(gr_line
		(start 406.498298 -393.69238)
		(end 407.018998 -393.69238)
		(stroke
			(width 0.0635)
			(type default)
		)
		(layer "F.Cu")
	)
	(gr_line
		(start 406.552146 -391.51941)
		(end 406.645618 -391.612882)
		(stroke
			(width 0.0508)
			(type default)
		)
		(layer "F.Cu")
	)
	(gr_line
		(start 406.552146 -391.324592)
		(end 406.552146 -391.51941)
		(stroke
			(width 0.0508)
			(type default)
		)
		(layer "F.Cu")
	)
	(gr_line
		(start 406.645618 -391.612882)
		(end 406.645618 -392.30427)
		(stroke
			(width 0.0508)
			(type default)
		)
		(layer "F.Cu")
	)
	(gr_line
		(start 406.646126 -399.74774)
		(end 406.646126 -399.143982)
		(stroke
			(width 0.0508)
			(type default)
		)
		(layer "F.Cu")
	)
	(gr_line
		(start 406.646126 -399.143982)
		(end 406.645618 -399.143474)
		(stroke
			(width 0.0508)
			(type default)
		)
		(layer "F.Cu")
	)
	(gr_line
		(start 406.709118 -7.571486)
		(end 406.846786 -7.709154)
		(stroke
			(width 0.06477)
			(type default)
		)
		(layer "F.Cu")
	)
	(gr_line
		(start 406.709118 -7.569454)
		(end 406.709118 -7.571486)
		(stroke
			(width 0.06477)
			(type default)
		)
		(layer "F.Cu")
	)
	(gr_line
		(start 406.771348 -15.833598)
		(end 407.067258 -15.537688)
		(stroke
			(width 0.06477)
			(type default)
		)
		(layer "F.Cu")
	)
	(gr_line
		(start 406.796748 -17.613122)
		(end 407.067258 -17.342612)
		(stroke
			(width 0.06477)
			(type default)
		)
		(layer "F.Cu")
	)
	(gr_line
		(start 406.846786 -11.881104)
		(end 406.708102 -12.019788)
		(stroke
			(width 0.06477)
			(type default)
		)
		(layer "F.Cu")
	)
	(gr_line
		(start 406.846786 -11.26998)
		(end 406.846786 -11.881104)
		(stroke
			(width 0.06477)
			(type default)
		)
		(layer "F.Cu")
	)
	(gr_line
		(start 406.846786 -7.709154)
		(end 406.846786 -8.320024)
		(stroke
			(width 0.06477)
			(type default)
		)
		(layer "F.Cu")
	)
	(gr_line
		(start 406.898348 -397.849344)
		(end 407.419048 -397.849344)
		(stroke
			(width 0.0635)
			(type default)
		)
		(layer "F.Cu")
	)
	(gr_line
		(start 406.898348 -394.385292)
		(end 407.419048 -394.385292)
		(stroke
			(width 0.0635)
			(type default)
		)
		(layer "F.Cu")
	)
	(gr_line
		(start 406.90546 -401.359116)
		(end 406.903428 -401.359116)
		(stroke
			(width 0.0508)
			(type default)
		)
		(layer "F.Cu")
	)
	(gr_line
		(start 406.983946 -4.963414)
		(end 406.710388 -5.236972)
		(stroke
			(width 0.06477)
			(type default)
		)
		(layer "F.Cu")
	)
	(gr_line
		(start 407.044144 -401.674838)
		(end 407.044144 -401.4978)
		(stroke
			(width 0.0508)
			(type default)
		)
		(layer "F.Cu")
	)
	(gr_line
		(start 407.044144 -401.4978)
		(end 406.90546 -401.359116)
		(stroke
			(width 0.0508)
			(type default)
		)
		(layer "F.Cu")
	)
	(gr_line
		(start 407.044144 -401.0025)
		(end 406.904698 -401.141946)
		(stroke
			(width 0.0508)
			(type default)
		)
		(layer "F.Cu")
	)
	(gr_line
		(start 407.044144 -400.811238)
		(end 407.044144 -401.0025)
		(stroke
			(width 0.0508)
			(type default)
		)
		(layer "F.Cu")
	)
	(gr_line
		(start 407.067258 -16.662908)
		(end 406.771348 -16.366998)
		(stroke
			(width 0.06477)
			(type default)
		)
		(layer "F.Cu")
	)
	(gr_line
		(start 407.12644 -379.22073)
		(end 407.47569 -379.56998)
		(stroke
			(width 0.0508)
			(type default)
		)
		(layer "F.Cu")
	)
	(gr_line
		(start 407.15184 -377.41733)
		(end 407.42235 -377.68784)
		(stroke
			(width 0.06477)
			(type default)
		)
		(layer "F.Cu")
	)
	(gr_line
		(start 407.243788 -391.88771)
		(end 407.334974 -391.978896)
		(stroke
			(width 0.0508)
			(type default)
		)
		(layer "F.Cu")
	)
	(gr_line
		(start 407.243788 -391.6172)
		(end 407.243788 -391.88771)
		(stroke
			(width 0.0508)
			(type default)
		)
		(layer "F.Cu")
	)
	(gr_line
		(start 407.334974 -391.978896)
		(end 407.46934 -391.978896)
		(stroke
			(width 0.0508)
			(type default)
		)
		(layer "F.Cu")
	)
	(gr_line
		(start 407.389838 -17.342612)
		(end 407.660348 -17.613122)
		(stroke
			(width 0.06477)
			(type default)
		)
		(layer "F.Cu")
	)
	(gr_line
		(start 407.389838 -15.537688)
		(end 407.685748 -15.833598)
		(stroke
			(width 0.06477)
			(type default)
		)
		(layer "F.Cu")
	)
	(gr_line
		(start 407.42235 -378.39142)
		(end 407.12644 -378.68733)
		(stroke
			(width 0.06477)
			(type default)
		)
		(layer "F.Cu")
	)
	(gr_line
		(start 407.46934 -391.978896)
		(end 407.545794 -391.902442)
		(stroke
			(width 0.0508)
			(type default)
		)
		(layer "F.Cu")
	)
	(gr_line
		(start 407.535126 -391.325862)
		(end 407.243788 -391.6172)
		(stroke
			(width 0.0508)
			(type default)
		)
		(layer "F.Cu")
	)
	(gr_line
		(start 407.545794 -391.902442)
		(end 407.545794 -391.784586)
		(stroke
			(width 0.0508)
			(type default)
		)
		(layer "F.Cu")
	)
	(gr_line
		(start 407.627582 -417.166044)
		(end 407.923492 -417.461954)
		(stroke
			(width 0.06477)
			(type default)
		)
		(layer "F.Cu")
	)
	(gr_line
		(start 407.629106 -399.74647)
		(end 407.545794 -399.663158)
		(stroke
			(width 0.0508)
			(type default)
		)
		(layer "F.Cu")
	)
	(gr_line
		(start 407.652982 -412.84652)
		(end 407.923492 -413.11703)
		(stroke
			(width 0.06477)
			(type default)
		)
		(layer "F.Cu")
	)
	(gr_line
		(start 407.685748 -16.366998)
		(end 407.389838 -16.662908)
		(stroke
			(width 0.06477)
			(type default)
		)
		(layer "F.Cu")
	)
	(gr_line
		(start 407.698194 -397.156432)
		(end 408.218894 -397.156432)
		(stroke
			(width 0.0635)
			(type default)
		)
		(layer "F.Cu")
	)
	(gr_line
		(start 407.698194 -393.69238)
		(end 408.218894 -393.69238)
		(stroke
			(width 0.0635)
			(type default)
		)
		(layer "F.Cu")
	)
	(gr_line
		(start 407.74493 -378.39142)
		(end 408.04084 -378.68733)
		(stroke
			(width 0.06477)
			(type default)
		)
		(layer "F.Cu")
	)
	(gr_line
		(start 407.752296 -391.51941)
		(end 407.845768 -391.612882)
		(stroke
			(width 0.0508)
			(type default)
		)
		(layer "F.Cu")
	)
	(gr_line
		(start 407.752296 -391.324592)
		(end 407.752296 -391.51941)
		(stroke
			(width 0.0508)
			(type default)
		)
		(layer "F.Cu")
	)
	(gr_arc
		(start 407.752296 -389.9535)
		(mid 407.752296 -389.953881)
		(end 407.752296 -389.954262)
		(stroke
			(width 0.0508)
			(type default)
		)
		(layer "F.Cu")
	)
	(gr_line
		(start 407.845768 -391.612882)
		(end 407.845768 -392.30427)
		(stroke
			(width 0.0508)
			(type default)
		)
		(layer "F.Cu")
	)
	(gr_line
		(start 407.846276 -399.74774)
		(end 407.846276 -399.143982)
		(stroke
			(width 0.0508)
			(type default)
		)
		(layer "F.Cu")
	)
	(gr_line
		(start 407.846276 -399.143982)
		(end 407.845768 -399.143474)
		(stroke
			(width 0.0508)
			(type default)
		)
		(layer "F.Cu")
	)
	(gr_line
		(start 407.923492 -420.681658)
		(end 407.652982 -420.952168)
		(stroke
			(width 0.06477)
			(type default)
		)
		(layer "F.Cu")
	)
	(gr_line
		(start 407.923492 -416.336734)
		(end 407.627582 -416.632644)
		(stroke
			(width 0.06477)
			(type default)
		)
		(layer "F.Cu")
	)
	(gr_line
		(start 408.01544 -377.41733)
		(end 407.74493 -377.68784)
		(stroke
			(width 0.06477)
			(type default)
		)
		(layer "F.Cu")
	)
	(gr_line
		(start 408.04084 -379.22073)
		(end 407.69159 -379.56998)
		(stroke
			(width 0.0508)
			(type default)
		)
		(layer "F.Cu")
	)
	(gr_line
		(start 408.098244 -397.849344)
		(end 408.618944 -397.849344)
		(stroke
			(width 0.0635)
			(type default)
		)
		(layer "F.Cu")
	)
	(gr_line
		(start 408.098244 -394.385292)
		(end 408.618944 -394.385292)
		(stroke
			(width 0.0635)
			(type default)
		)
		(layer "F.Cu")
	)
	(gr_line
		(start 408.10561 -401.359116)
		(end 408.103578 -401.359116)
		(stroke
			(width 0.0508)
			(type default)
		)
		(layer "F.Cu")
	)
	(gr_line
		(start 408.244294 -401.674838)
		(end 408.244294 -401.4978)
		(stroke
			(width 0.0508)
			(type default)
		)
		(layer "F.Cu")
	)
	(gr_line
		(start 408.244294 -401.4978)
		(end 408.10561 -401.359116)
		(stroke
			(width 0.0508)
			(type default)
		)
		(layer "F.Cu")
	)
	(gr_line
		(start 408.244294 -401.0025)
		(end 408.104848 -401.141946)
		(stroke
			(width 0.0508)
			(type default)
		)
		(layer "F.Cu")
	)
	(gr_line
		(start 408.244294 -400.811238)
		(end 408.244294 -401.0025)
		(stroke
			(width 0.0508)
			(type default)
		)
		(layer "F.Cu")
	)
	(gr_line
		(start 408.246072 -420.681658)
		(end 408.516582 -420.952168)
		(stroke
			(width 0.06477)
			(type default)
		)
		(layer "F.Cu")
	)
	(gr_line
		(start 408.246072 -416.336734)
		(end 408.541982 -416.632644)
		(stroke
			(width 0.06477)
			(type default)
		)
		(layer "F.Cu")
	)
	(gr_line
		(start 408.443684 -391.88771)
		(end 408.53487 -391.978896)
		(stroke
			(width 0.0508)
			(type default)
		)
		(layer "F.Cu")
	)
	(gr_line
		(start 408.443684 -391.6172)
		(end 408.443684 -391.88771)
		(stroke
			(width 0.0508)
			(type default)
		)
		(layer "F.Cu")
	)
	(gr_line
		(start 408.516582 -412.84652)
		(end 408.246072 -413.11703)
		(stroke
			(width 0.06477)
			(type default)
		)
		(layer "F.Cu")
	)
	(gr_line
		(start 408.53487 -391.978896)
		(end 408.669236 -391.978896)
		(stroke
			(width 0.0508)
			(type default)
		)
		(layer "F.Cu")
	)
	(gr_line
		(start 408.541982 -417.166044)
		(end 408.246072 -417.461954)
		(stroke
			(width 0.06477)
			(type default)
		)
		(layer "F.Cu")
	)
	(gr_line
		(start 408.669236 -391.978896)
		(end 408.74569 -391.902442)
		(stroke
			(width 0.0508)
			(type default)
		)
		(layer "F.Cu")
	)
	(gr_line
		(start 408.735022 -391.325862)
		(end 408.443684 -391.6172)
		(stroke
			(width 0.0508)
			(type default)
		)
		(layer "F.Cu")
	)
	(gr_line
		(start 408.74569 -391.902442)
		(end 408.74569 -391.784586)
		(stroke
			(width 0.0508)
			(type default)
		)
		(layer "F.Cu")
	)
	(gr_line
		(start 408.829002 -399.74647)
		(end 408.74569 -399.663158)
		(stroke
			(width 0.0508)
			(type default)
		)
		(layer "F.Cu")
	)
	(gr_line
		(start 408.898344 -397.156432)
		(end 409.419044 -397.156432)
		(stroke
			(width 0.0635)
			(type default)
		)
		(layer "F.Cu")
	)
	(gr_line
		(start 408.898344 -393.69238)
		(end 409.419044 -393.69238)
		(stroke
			(width 0.0635)
			(type default)
		)
		(layer "F.Cu")
	)
	(gr_line
		(start 408.952192 -391.51941)
		(end 409.045664 -391.612882)
		(stroke
			(width 0.0508)
			(type default)
		)
		(layer "F.Cu")
	)
	(gr_line
		(start 408.952192 -391.324592)
		(end 408.952192 -391.51941)
		(stroke
			(width 0.0508)
			(type default)
		)
		(layer "F.Cu")
	)
	(gr_line
		(start 409.045664 -391.612882)
		(end 409.045664 -392.30427)
		(stroke
			(width 0.0508)
			(type default)
		)
		(layer "F.Cu")
	)
	(gr_line
		(start 409.046172 -399.74774)
		(end 409.046172 -399.143982)
		(stroke
			(width 0.0508)
			(type default)
		)
		(layer "F.Cu")
	)
	(gr_line
		(start 409.046172 -399.143982)
		(end 409.045664 -399.143474)
		(stroke
			(width 0.0508)
			(type default)
		)
		(layer "F.Cu")
	)
	(gr_line
		(start 409.195016 -383.231136)
		(end 409.195016 -383.759456)
		(stroke
			(width 0.0508)
			(type default)
		)
		(layer "F.Cu")
	)
	(gr_line
		(start 409.298394 -397.849344)
		(end 409.819094 -397.849344)
		(stroke
			(width 0.0635)
			(type default)
		)
		(layer "F.Cu")
	)
	(gr_line
		(start 409.298394 -394.385292)
		(end 409.819094 -394.385292)
		(stroke
			(width 0.0635)
			(type default)
		)
		(layer "F.Cu")
	)
	(gr_line
		(start 409.305506 -401.359116)
		(end 409.303474 -401.359116)
		(stroke
			(width 0.0508)
			(type default)
		)
		(layer "F.Cu")
	)
	(gr_line
		(start 409.412186 -383.232406)
		(end 409.522676 -383.342896)
		(stroke
			(width 0.0508)
			(type default)
		)
		(layer "F.Cu")
	)
	(gr_line
		(start 409.44419 -401.674838)
		(end 409.44419 -401.4978)
		(stroke
			(width 0.0508)
			(type default)
		)
		(layer "F.Cu")
	)
	(gr_line
		(start 409.44419 -401.4978)
		(end 409.305506 -401.359116)
		(stroke
			(width 0.0508)
			(type default)
		)
		(layer "F.Cu")
	)
	(gr_line
		(start 409.44419 -401.0025)
		(end 409.304744 -401.141946)
		(stroke
			(width 0.0508)
			(type default)
		)
		(layer "F.Cu")
	)
	(gr_line
		(start 409.44419 -400.811238)
		(end 409.44419 -401.0025)
		(stroke
			(width 0.0508)
			(type default)
		)
		(layer "F.Cu")
	)
	(gr_line
		(start 409.522676 -383.647696)
		(end 409.412186 -383.758186)
		(stroke
			(width 0.0508)
			(type default)
		)
		(layer "F.Cu")
	)
	(gr_line
		(start 409.522676 -383.342896)
		(end 409.522676 -383.647696)
		(stroke
			(width 0.0508)
			(type default)
		)
		(layer "F.Cu")
	)
	(gr_line
		(start 409.565348 -17.357598)
		(end 409.861004 -17.061942)
		(stroke
			(width 0.06477)
			(type default)
		)
		(layer "F.Cu")
	)
	(gr_line
		(start 409.591764 -19.13636)
		(end 409.862274 -18.86585)
		(stroke
			(width 0.06477)
			(type default)
		)
		(layer "F.Cu")
	)
	(gr_line
		(start 409.64358 -391.88771)
		(end 409.734766 -391.978896)
		(stroke
			(width 0.0508)
			(type default)
		)
		(layer "F.Cu")
	)
	(gr_line
		(start 409.64358 -391.6172)
		(end 409.64358 -391.88771)
		(stroke
			(width 0.0508)
			(type default)
		)
		(layer "F.Cu")
	)
	(gr_line
		(start 409.734766 -391.978896)
		(end 409.869132 -391.978896)
		(stroke
			(width 0.0508)
			(type default)
		)
		(layer "F.Cu")
	)
	(gr_line
		(start 409.861004 -18.186654)
		(end 409.565348 -17.890998)
		(stroke
			(width 0.06477)
			(type default)
		)
		(layer "F.Cu")
	)
	(gr_line
		(start 409.869132 -391.978896)
		(end 409.945586 -391.902442)
		(stroke
			(width 0.0508)
			(type default)
		)
		(layer "F.Cu")
	)
	(gr_line
		(start 409.934918 -391.325862)
		(end 409.64358 -391.6172)
		(stroke
			(width 0.0508)
			(type default)
		)
		(layer "F.Cu")
	)
	(gr_line
		(start 409.945586 -391.902442)
		(end 409.945586 -391.784586)
		(stroke
			(width 0.0508)
			(type default)
		)
		(layer "F.Cu")
	)
	(gr_line
		(start 410.029152 -399.746724)
		(end 409.945586 -399.663158)
		(stroke
			(width 0.0508)
			(type default)
		)
		(layer "F.Cu")
	)
	(gr_line
		(start 410.09824 -397.156432)
		(end 410.61894 -397.156432)
		(stroke
			(width 0.0635)
			(type default)
		)
		(layer "F.Cu")
	)
	(gr_line
		(start 410.09824 -393.69238)
		(end 410.61894 -393.69238)
		(stroke
			(width 0.0635)
			(type default)
		)
		(layer "F.Cu")
	)
	(gr_line
		(start 410.152088 -391.51941)
		(end 410.245814 -391.613136)
		(stroke
			(width 0.0508)
			(type default)
		)
		(layer "F.Cu")
	)
	(gr_line
		(start 410.152088 -391.324592)
		(end 410.152088 -391.51941)
		(stroke
			(width 0.0508)
			(type default)
		)
		(layer "F.Cu")
	)
	(gr_line
		(start 410.184854 -18.86585)
		(end 410.455364 -19.13636)
		(stroke
			(width 0.06477)
			(type default)
		)
		(layer "F.Cu")
	)
	(gr_line
		(start 410.184854 -18.185892)
		(end 410.184854 -18.187924)
		(stroke
			(width 0.06477)
			(type default)
		)
		(layer "F.Cu")
	)
	(gr_line
		(start 410.184854 -17.062704)
		(end 410.479748 -17.357598)
		(stroke
			(width 0.06477)
			(type default)
		)
		(layer "F.Cu")
	)
	(gr_line
		(start 410.184854 -17.060672)
		(end 410.184854 -17.062704)
		(stroke
			(width 0.06477)
			(type default)
		)
		(layer "F.Cu")
	)
	(gr_line
		(start 410.245814 -391.613136)
		(end 410.245814 -392.30427)
		(stroke
			(width 0.0508)
			(type default)
		)
		(layer "F.Cu")
	)
	(gr_line
		(start 410.246322 -399.747486)
		(end 410.246068 -399.74774)
		(stroke
			(width 0.0508)
			(type default)
		)
		(layer "F.Cu")
	)
	(gr_line
		(start 410.246322 -399.747486)
		(end 410.246322 -399.143982)
		(stroke
			(width 0.0508)
			(type default)
		)
		(layer "F.Cu")
	)
	(gr_line
		(start 410.246322 -399.143982)
		(end 410.245814 -399.143474)
		(stroke
			(width 0.0508)
			(type default)
		)
		(layer "F.Cu")
	)
	(gr_line
		(start 410.479748 -17.890998)
		(end 410.184854 -18.185892)
		(stroke
			(width 0.06477)
			(type default)
		)
		(layer "F.Cu")
	)
	(gr_line
		(start 410.49829 -397.849344)
		(end 411.01899 -397.849344)
		(stroke
			(width 0.0635)
			(type default)
		)
		(layer "F.Cu")
	)
	(gr_line
		(start 410.49829 -394.385292)
		(end 411.01899 -394.385292)
		(stroke
			(width 0.0635)
			(type default)
		)
		(layer "F.Cu")
	)
	(gr_line
		(start 410.505402 -401.359116)
		(end 410.503624 -401.359116)
		(stroke
			(width 0.0508)
			(type default)
		)
		(layer "F.Cu")
	)
	(gr_line
		(start 410.53004 -384.14833)
		(end 410.831792 -384.450082)
		(stroke
			(width 0.0508)
			(type default)
		)
		(layer "F.Cu")
	)
	(gr_line
		(start 410.55544 -382.34493)
		(end 410.82595 -382.61544)
		(stroke
			(width 0.06477)
			(type default)
		)
		(layer "F.Cu")
	)
	(gr_line
		(start 410.64434 -401.674838)
		(end 410.64434 -401.498054)
		(stroke
			(width 0.0508)
			(type default)
		)
		(layer "F.Cu")
	)
	(gr_line
		(start 410.64434 -401.498054)
		(end 410.505402 -401.359116)
		(stroke
			(width 0.0508)
			(type default)
		)
		(layer "F.Cu")
	)
	(gr_line
		(start 410.64434 -401.0025)
		(end 410.504894 -401.141946)
		(stroke
			(width 0.0508)
			(type default)
		)
		(layer "F.Cu")
	)
	(gr_line
		(start 410.64434 -400.811238)
		(end 410.64434 -401.0025)
		(stroke
			(width 0.0508)
			(type default)
		)
		(layer "F.Cu")
	)
	(gr_line
		(start 410.690822 -417.166044)
		(end 410.986732 -417.461954)
		(stroke
			(width 0.06477)
			(type default)
		)
		(layer "F.Cu")
	)
	(gr_line
		(start 410.716222 -412.84652)
		(end 410.986732 -413.11703)
		(stroke
			(width 0.06477)
			(type default)
		)
		(layer "F.Cu")
	)
	(gr_line
		(start 410.82595 -383.31902)
		(end 410.53004 -383.61493)
		(stroke
			(width 0.06477)
			(type default)
		)
		(layer "F.Cu")
	)
	(gr_line
		(start 410.84373 -391.88771)
		(end 410.934916 -391.978896)
		(stroke
			(width 0.0508)
			(type default)
		)
		(layer "F.Cu")
	)
	(gr_line
		(start 410.84373 -391.6172)
		(end 410.84373 -391.88771)
		(stroke
			(width 0.0508)
			(type default)
		)
		(layer "F.Cu")
	)
	(gr_arc
		(start 410.878274 -384.547872)
		(mid 410.863395 -384.495004)
		(end 410.831792 -384.450082)
		(stroke
			(width 0.0508)
			(type default)
		)
		(layer "F.Cu")
	)
	(gr_line
		(start 410.87929 -385.45643)
		(end 410.87929 -385.98475)
		(stroke
			(width 0.0508)
			(type default)
		)
		(layer "F.Cu")
	)
	(gr_line
		(start 410.934916 -391.978896)
		(end 411.069282 -391.978896)
		(stroke
			(width 0.0508)
			(type default)
		)
		(layer "F.Cu")
	)
	(gr_line
		(start 410.986732 -420.681658)
		(end 410.716222 -420.952168)
		(stroke
			(width 0.06477)
			(type default)
		)
		(layer "F.Cu")
	)
	(gr_line
		(start 410.986732 -416.336734)
		(end 410.690822 -416.632644)
		(stroke
			(width 0.06477)
			(type default)
		)
		(layer "F.Cu")
	)
	(gr_line
		(start 411.069282 -391.978896)
		(end 411.145736 -391.902442)
		(stroke
			(width 0.0508)
			(type default)
		)
		(layer "F.Cu")
	)
	(gr_line
		(start 411.09646 -385.4577)
		(end 411.20695 -385.56819)
		(stroke
			(width 0.0508)
			(type default)
		)
		(layer "F.Cu")
	)
	(gr_line
		(start 411.135068 -391.325862)
		(end 410.84373 -391.6172)
		(stroke
			(width 0.0508)
			(type default)
		)
		(layer "F.Cu")
	)
	(gr_arc
		(start 411.142434 -384.450336)
		(mid 411.110836 -384.494982)
		(end 411.095952 -384.547618)
		(stroke
			(width 0.0508)
			(type default)
		)
		(layer "F.Cu")
	)
	(gr_line
		(start 411.145736 -391.902442)
		(end 411.145736 -391.784586)
		(stroke
			(width 0.0508)
			(type default)
		)
		(layer "F.Cu")
	)
	(gr_line
		(start 411.14853 -383.31902)
		(end 411.44444 -383.61493)
		(stroke
			(width 0.06477)
			(type default)
		)
		(layer "F.Cu")
	)
	(gr_line
		(start 411.20695 -385.87299)
		(end 411.09646 -385.98348)
		(stroke
			(width 0.0508)
			(type default)
		)
		(layer "F.Cu")
	)
	(gr_line
		(start 411.20695 -385.56819)
		(end 411.20695 -385.87299)
		(stroke
			(width 0.0508)
			(type default)
		)
		(layer "F.Cu")
	)
	(gr_line
		(start 411.229048 -399.74647)
		(end 411.145736 -399.663158)
		(stroke
			(width 0.0508)
			(type default)
		)
		(layer "F.Cu")
	)
	(gr_line
		(start 411.29839 -397.156432)
		(end 411.81909 -397.156432)
		(stroke
			(width 0.0635)
			(type default)
		)
		(layer "F.Cu")
	)
	(gr_line
		(start 411.29839 -393.69238)
		(end 411.81909 -393.69238)
		(stroke
			(width 0.0635)
			(type default)
		)
		(layer "F.Cu")
	)
	(gr_line
		(start 411.309312 -420.681658)
		(end 411.579822 -420.952168)
		(stroke
			(width 0.06477)
			(type default)
		)
		(layer "F.Cu")
	)
	(gr_line
		(start 411.309312 -416.336734)
		(end 411.605222 -416.632644)
		(stroke
			(width 0.06477)
			(type default)
		)
		(layer "F.Cu")
	)
	(gr_line
		(start 411.352238 -391.51941)
		(end 411.44571 -391.612882)
		(stroke
			(width 0.0508)
			(type default)
		)
		(layer "F.Cu")
	)
	(gr_line
		(start 411.352238 -391.32383)
		(end 411.352238 -391.51941)
		(stroke
			(width 0.0508)
			(type default)
		)
		(layer "F.Cu")
	)
	(gr_line
		(start 411.41904 -382.34493)
		(end 411.14853 -382.61544)
		(stroke
			(width 0.06477)
			(type default)
		)
		(layer "F.Cu")
	)
	(gr_line
		(start 411.44444 -384.14833)
		(end 411.142434 -384.450336)
		(stroke
			(width 0.0508)
			(type default)
		)
		(layer "F.Cu")
	)
	(gr_line
		(start 411.44571 -391.612882)
		(end 411.44571 -392.30427)
		(stroke
			(width 0.0508)
			(type default)
		)
		(layer "F.Cu")
	)
	(gr_line
		(start 411.446218 -399.74774)
		(end 411.446218 -399.143982)
		(stroke
			(width 0.0508)
			(type default)
		)
		(layer "F.Cu")
	)
	(gr_line
		(start 411.446218 -399.143982)
		(end 411.44571 -399.143474)
		(stroke
			(width 0.0508)
			(type default)
		)
		(layer "F.Cu")
	)
	(gr_line
		(start 411.579822 -412.84652)
		(end 411.309312 -413.11703)
		(stroke
			(width 0.06477)
			(type default)
		)
		(layer "F.Cu")
	)
	(gr_line
		(start 411.605222 -417.166044)
		(end 411.309312 -417.461954)
		(stroke
			(width 0.06477)
			(type default)
		)
		(layer "F.Cu")
	)
	(gr_line
		(start 411.698186 -397.849344)
		(end 412.218886 -397.849344)
		(stroke
			(width 0.0635)
			(type default)
		)
		(layer "F.Cu")
	)
	(gr_line
		(start 411.698186 -394.385292)
		(end 412.218886 -394.385292)
		(stroke
			(width 0.0635)
			(type default)
		)
		(layer "F.Cu")
	)
	(gr_line
		(start 411.705552 -401.359116)
		(end 411.70352 -401.359116)
		(stroke
			(width 0.0508)
			(type default)
		)
		(layer "F.Cu")
	)
	(gr_line
		(start 411.844236 -401.674838)
		(end 411.844236 -401.4978)
		(stroke
			(width 0.0508)
			(type default)
		)
		(layer "F.Cu")
	)
	(gr_line
		(start 411.844236 -401.4978)
		(end 411.705552 -401.359116)
		(stroke
			(width 0.0508)
			(type default)
		)
		(layer "F.Cu")
	)
	(gr_line
		(start 411.844236 -401.0025)
		(end 411.70479 -401.141946)
		(stroke
			(width 0.0508)
			(type default)
		)
		(layer "F.Cu")
	)
	(gr_line
		(start 411.844236 -400.811238)
		(end 411.844236 -401.0025)
		(stroke
			(width 0.0508)
			(type default)
		)
		(layer "F.Cu")
	)
	(gr_line
		(start 412.043626 -391.88771)
		(end 412.134812 -391.978896)
		(stroke
			(width 0.0508)
			(type default)
		)
		(layer "F.Cu")
	)
	(gr_line
		(start 412.043626 -391.6172)
		(end 412.043626 -391.88771)
		(stroke
			(width 0.0508)
			(type default)
		)
		(layer "F.Cu")
	)
	(gr_line
		(start 412.134812 -391.978896)
		(end 412.269178 -391.978896)
		(stroke
			(width 0.0508)
			(type default)
		)
		(layer "F.Cu")
	)
	(gr_line
		(start 412.23184 -381.68453)
		(end 412.533592 -381.986282)
		(stroke
			(width 0.0508)
			(type default)
		)
		(layer "F.Cu")
	)
	(gr_line
		(start 412.25724 -379.88113)
		(end 412.52775 -380.15164)
		(stroke
			(width 0.06477)
			(type default)
		)
		(layer "F.Cu")
	)
	(gr_line
		(start 412.269178 -391.978896)
		(end 412.345632 -391.902442)
		(stroke
			(width 0.0508)
			(type default)
		)
		(layer "F.Cu")
	)
	(gr_line
		(start 412.334964 -391.325862)
		(end 412.043626 -391.6172)
		(stroke
			(width 0.0508)
			(type default)
		)
		(layer "F.Cu")
	)
	(gr_line
		(start 412.345632 -391.902442)
		(end 412.345632 -391.784586)
		(stroke
			(width 0.0508)
			(type default)
		)
		(layer "F.Cu")
	)
	(gr_line
		(start 412.359348 -15.833598)
		(end 412.359602 -15.833598)
		(stroke
			(width 0.06477)
			(type default)
		)
		(layer "F.Cu")
	)
	(gr_line
		(start 412.359602 -15.833598)
		(end 412.656274 -15.536926)
		(stroke
			(width 0.06477)
			(type default)
		)
		(layer "F.Cu")
	)
	(gr_line
		(start 412.384748 -17.613122)
		(end 412.655004 -17.342866)
		(stroke
			(width 0.06477)
			(type default)
		)
		(layer "F.Cu")
	)
	(gr_line
		(start 412.428944 -399.74647)
		(end 412.345632 -399.663158)
		(stroke
			(width 0.0508)
			(type default)
		)
		(layer "F.Cu")
	)
	(gr_line
		(start 412.498286 -397.156432)
		(end 413.018986 -397.156432)
		(stroke
			(width 0.0635)
			(type default)
		)
		(layer "F.Cu")
	)
	(gr_line
		(start 412.498286 -393.69238)
		(end 413.018986 -393.69238)
		(stroke
			(width 0.0635)
			(type default)
		)
		(layer "F.Cu")
	)
	(gr_line
		(start 412.52775 -380.85522)
		(end 412.23184 -381.15113)
		(stroke
			(width 0.06477)
			(type default)
		)
		(layer "F.Cu")
	)
	(gr_line
		(start 412.552134 -391.51941)
		(end 412.645606 -391.612882)
		(stroke
			(width 0.0508)
			(type default)
		)
		(layer "F.Cu")
	)
	(gr_line
		(start 412.552134 -391.324592)
		(end 412.552134 -391.51941)
		(stroke
			(width 0.0508)
			(type default)
		)
		(layer "F.Cu")
	)
	(gr_arc
		(start 412.580074 -382.084072)
		(mid 412.565195 -382.031204)
		(end 412.533592 -381.986282)
		(stroke
			(width 0.0508)
			(type default)
		)
		(layer "F.Cu")
	)
	(gr_line
		(start 412.58109 -383.22504)
		(end 412.58109 -383.75336)
		(stroke
			(width 0.0508)
			(type default)
		)
		(layer "F.Cu")
	)
	(gr_line
		(start 412.645606 -391.612882)
		(end 412.645606 -392.30427)
		(stroke
			(width 0.0508)
			(type default)
		)
		(layer "F.Cu")
	)
	(gr_line
		(start 412.646114 -399.74774)
		(end 412.646114 -399.143982)
		(stroke
			(width 0.0508)
			(type default)
		)
		(layer "F.Cu")
	)
	(gr_line
		(start 412.646114 -399.143982)
		(end 412.645606 -399.143474)
		(stroke
			(width 0.0508)
			(type default)
		)
		(layer "F.Cu")
	)
	(gr_line
		(start 412.655004 -16.662654)
		(end 412.359348 -16.366998)
		(stroke
			(width 0.06477)
			(type default)
		)
		(layer "F.Cu")
	)
	(gr_line
		(start 412.79826 -383.22631)
		(end 412.90875 -383.3368)
		(stroke
			(width 0.0508)
			(type default)
		)
		(layer "F.Cu")
	)
	(gr_arc
		(start 412.844488 -381.986282)
		(mid 412.812833 -382.031178)
		(end 412.798006 -382.084072)
		(stroke
			(width 0.0508)
			(type default)
		)
		(layer "F.Cu")
	)
	(gr_line
		(start 412.85033 -380.85522)
		(end 413.14624 -381.15113)
		(stroke
			(width 0.06477)
			(type default)
		)
		(layer "F.Cu")
	)
	(gr_line
		(start 412.898336 -397.849344)
		(end 413.419036 -397.849344)
		(stroke
			(width 0.0635)
			(type default)
		)
		(layer "F.Cu")
	)
	(gr_line
		(start 412.898336 -394.385292)
		(end 413.419036 -394.385292)
		(stroke
			(width 0.0635)
			(type default)
		)
		(layer "F.Cu")
	)
	(gr_line
		(start 412.905448 -401.359116)
		(end 412.903416 -401.359116)
		(stroke
			(width 0.0508)
			(type default)
		)
		(layer "F.Cu")
	)
	(gr_line
		(start 412.90875 -383.6416)
		(end 412.79826 -383.75209)
		(stroke
			(width 0.0508)
			(type default)
		)
		(layer "F.Cu")
	)
	(gr_line
		(start 412.90875 -383.3368)
		(end 412.90875 -383.6416)
		(stroke
			(width 0.0508)
			(type default)
		)
		(layer "F.Cu")
	)
	(gr_line
		(start 412.978854 -17.343628)
		(end 413.248348 -17.613122)
		(stroke
			(width 0.06477)
			(type default)
		)
		(layer "F.Cu")
	)
	(gr_line
		(start 412.978854 -17.341596)
		(end 412.978854 -17.343628)
		(stroke
			(width 0.06477)
			(type default)
		)
		(layer "F.Cu")
	)
	(gr_line
		(start 412.978854 -16.661892)
		(end 412.978854 -16.663924)
		(stroke
			(width 0.06477)
			(type default)
		)
		(layer "F.Cu")
	)
	(gr_line
		(start 412.978854 -15.536926)
		(end 413.273748 -15.83182)
		(stroke
			(width 0.06477)
			(type default)
		)
		(layer "F.Cu")
	)
	(gr_line
		(start 413.044386 -401.674838)
		(end 413.044386 -401.498054)
		(stroke
			(width 0.0508)
			(type default)
		)
		(layer "F.Cu")
	)
	(gr_line
		(start 413.044386 -401.498054)
		(end 412.905448 -401.359116)
		(stroke
			(width 0.0508)
			(type default)
		)
		(layer "F.Cu")
	)
	(gr_line
		(start 413.044386 -401.002246)
		(end 412.904686 -401.141946)
		(stroke
			(width 0.0508)
			(type default)
		)
		(layer "F.Cu")
	)
	(gr_line
		(start 413.044386 -400.811238)
		(end 413.044386 -401.002246)
		(stroke
			(width 0.0508)
			(type default)
		)
		(layer "F.Cu")
	)
	(gr_line
		(start 413.12084 -379.88113)
		(end 412.85033 -380.15164)
		(stroke
			(width 0.06477)
			(type default)
		)
		(layer "F.Cu")
	)
	(gr_line
		(start 413.14624 -381.68453)
		(end 412.844488 -381.986282)
		(stroke
			(width 0.0508)
			(type default)
		)
		(layer "F.Cu")
	)
	(gr_line
		(start 413.243776 -391.88771)
		(end 413.334962 -391.978896)
		(stroke
			(width 0.0508)
			(type default)
		)
		(layer "F.Cu")
	)
	(gr_line
		(start 413.243776 -391.6172)
		(end 413.243776 -391.88771)
		(stroke
			(width 0.0508)
			(type default)
		)
		(layer "F.Cu")
	)
	(gr_line
		(start 413.273748 -16.366998)
		(end 412.978854 -16.661892)
		(stroke
			(width 0.06477)
			(type default)
		)
		(layer "F.Cu")
	)
	(gr_line
		(start 413.273748 -15.83182)
		(end 413.273748 -15.833598)
		(stroke
			(width 0.06477)
			(type default)
		)
		(layer "F.Cu")
	)
	(gr_line
		(start 413.334962 -391.978896)
		(end 413.469328 -391.978896)
		(stroke
			(width 0.0508)
			(type default)
		)
		(layer "F.Cu")
	)
	(gr_line
		(start 413.42564 -6.725158)
		(end 413.695642 -6.99516)
		(stroke
			(width 0.06477)
			(type default)
		)
		(layer "F.Cu")
	)
	(gr_line
		(start 413.469328 -391.978896)
		(end 413.545782 -391.902442)
		(stroke
			(width 0.0508)
			(type default)
		)
		(layer "F.Cu")
	)
	(gr_line
		(start 413.535114 -391.325862)
		(end 413.243776 -391.6172)
		(stroke
			(width 0.0508)
			(type default)
		)
		(layer "F.Cu")
	)
	(gr_line
		(start 413.545782 -391.902442)
		(end 413.545782 -391.784586)
		(stroke
			(width 0.0508)
			(type default)
		)
		(layer "F.Cu")
	)
	(gr_line
		(start 413.556958 -11.881104)
		(end 413.556958 -11.26998)
		(stroke
			(width 0.06477)
			(type default)
		)
		(layer "F.Cu")
	)
	(gr_line
		(start 413.556958 -7.709154)
		(end 413.556958 -8.320024)
		(stroke
			(width 0.06477)
			(type default)
		)
		(layer "F.Cu")
	)
	(gr_line
		(start 413.629094 -399.74647)
		(end 413.545782 -399.663158)
		(stroke
			(width 0.0508)
			(type default)
		)
		(layer "F.Cu")
	)
	(gr_line
		(start 413.695642 -12.019788)
		(end 413.556958 -11.881104)
		(stroke
			(width 0.06477)
			(type default)
		)
		(layer "F.Cu")
	)
	(gr_line
		(start 413.695642 -7.57047)
		(end 413.556958 -7.709154)
		(stroke
			(width 0.06477)
			(type default)
		)
		(layer "F.Cu")
	)
	(gr_line
		(start 413.695642 -6.99516)
		(end 413.695642 -6.996176)
		(stroke
			(width 0.06477)
			(type default)
		)
		(layer "F.Cu")
	)
	(gr_line
		(start 413.698182 -397.156432)
		(end 414.218882 -397.156432)
		(stroke
			(width 0.0635)
			(type default)
		)
		(layer "F.Cu")
	)
	(gr_line
		(start 413.698182 -393.69238)
		(end 414.218882 -393.69238)
		(stroke
			(width 0.0635)
			(type default)
		)
		(layer "F.Cu")
	)
	(gr_line
		(start 413.752284 -391.51941)
		(end 413.845756 -391.612882)
		(stroke
			(width 0.0508)
			(type default)
		)
		(layer "F.Cu")
	)
	(gr_line
		(start 413.752284 -391.324592)
		(end 413.752284 -391.51941)
		(stroke
			(width 0.0508)
			(type default)
		)
		(layer "F.Cu")
	)
	(gr_line
		(start 413.754062 -417.166044)
		(end 414.049972 -417.461954)
		(stroke
			(width 0.06477)
			(type default)
		)
		(layer "F.Cu")
	)
	(gr_line
		(start 413.779462 -412.84652)
		(end 414.049972 -413.11703)
		(stroke
			(width 0.06477)
			(type default)
		)
		(layer "F.Cu")
	)
	(gr_line
		(start 413.845756 -391.612882)
		(end 413.845756 -392.30427)
		(stroke
			(width 0.0508)
			(type default)
		)
		(layer "F.Cu")
	)
	(gr_line
		(start 413.846264 -399.74774)
		(end 413.846264 -399.143982)
		(stroke
			(width 0.0508)
			(type default)
		)
		(layer "F.Cu")
	)
	(gr_line
		(start 413.846264 -399.143982)
		(end 413.845756 -399.143474)
		(stroke
			(width 0.0508)
			(type default)
		)
		(layer "F.Cu")
	)
	(gr_line
		(start 413.93364 -379.22073)
		(end 414.28289 -379.56998)
		(stroke
			(width 0.0508)
			(type default)
		)
		(layer "F.Cu")
	)
	(gr_line
		(start 413.95904 -377.41733)
		(end 414.22955 -377.68784)
		(stroke
			(width 0.06477)
			(type default)
		)
		(layer "F.Cu")
	)
	(gr_line
		(start 414.018222 -7.57047)
		(end 414.156906 -7.709154)
		(stroke
			(width 0.06477)
			(type default)
		)
		(layer "F.Cu")
	)
	(gr_line
		(start 414.049972 -420.681658)
		(end 413.779462 -420.952168)
		(stroke
			(width 0.06477)
			(type default)
		)
		(layer "F.Cu")
	)
	(gr_line
		(start 414.049972 -416.336734)
		(end 413.754062 -416.632644)
		(stroke
			(width 0.06477)
			(type default)
		)
		(layer "F.Cu")
	)
	(gr_line
		(start 414.098232 -397.849344)
		(end 414.618932 -397.849344)
		(stroke
			(width 0.0635)
			(type default)
		)
		(layer "F.Cu")
	)
	(gr_line
		(start 414.098232 -394.385292)
		(end 414.618932 -394.385292)
		(stroke
			(width 0.0635)
			(type default)
		)
		(layer "F.Cu")
	)
	(gr_line
		(start 414.105598 -401.359116)
		(end 414.103566 -401.359116)
		(stroke
			(width 0.0508)
			(type default)
		)
		(layer "F.Cu")
	)
	(gr_line
		(start 414.156906 -11.881104)
		(end 414.018222 -12.019788)
		(stroke
			(width 0.06477)
			(type default)
		)
		(layer "F.Cu")
	)
	(gr_line
		(start 414.156906 -11.26998)
		(end 414.156906 -11.881104)
		(stroke
			(width 0.06477)
			(type default)
		)
		(layer "F.Cu")
	)
	(gr_line
		(start 414.156906 -7.709154)
		(end 414.156906 -8.320024)
		(stroke
			(width 0.06477)
			(type default)
		)
		(layer "F.Cu")
	)
	(gr_line
		(start 414.22955 -378.39142)
		(end 413.93364 -378.68733)
		(stroke
			(width 0.06477)
			(type default)
		)
		(layer "F.Cu")
	)
	(gr_line
		(start 414.244282 -401.674838)
		(end 414.244282 -401.4978)
		(stroke
			(width 0.0508)
			(type default)
		)
		(layer "F.Cu")
	)
	(gr_line
		(start 414.244282 -401.4978)
		(end 414.105598 -401.359116)
		(stroke
			(width 0.0508)
			(type default)
		)
		(layer "F.Cu")
	)
	(gr_line
		(start 414.244282 -401.0025)
		(end 414.104836 -401.141946)
		(stroke
			(width 0.0508)
			(type default)
		)
		(layer "F.Cu")
	)
	(gr_line
		(start 414.244282 -400.811238)
		(end 414.244282 -401.0025)
		(stroke
			(width 0.0508)
			(type default)
		)
		(layer "F.Cu")
	)
	(gr_line
		(start 414.28924 -6.725158)
		(end 414.019238 -6.99516)
		(stroke
			(width 0.06477)
			(type default)
		)
		(layer "F.Cu")
	)
	(gr_line
		(start 414.372552 -420.681658)
		(end 414.643062 -420.952168)
		(stroke
			(width 0.06477)
			(type default)
		)
		(layer "F.Cu")
	)
	(gr_line
		(start 414.372552 -416.336734)
		(end 414.668462 -416.632644)
		(stroke
			(width 0.06477)
			(type default)
		)
		(layer "F.Cu")
	)
	(gr_line
		(start 414.443672 -391.88771)
		(end 414.534858 -391.978896)
		(stroke
			(width 0.0508)
			(type default)
		)
		(layer "F.Cu")
	)
	(gr_line
		(start 414.443672 -391.6172)
		(end 414.443672 -391.88771)
		(stroke
			(width 0.0508)
			(type default)
		)
		(layer "F.Cu")
	)
	(gr_line
		(start 414.534858 -391.978896)
		(end 414.669224 -391.978896)
		(stroke
			(width 0.0508)
			(type default)
		)
		(layer "F.Cu")
	)
	(gr_line
		(start 414.55213 -378.39142)
		(end 414.84804 -378.68733)
		(stroke
			(width 0.06477)
			(type default)
		)
		(layer "F.Cu")
	)
	(gr_line
		(start 414.643062 -412.84652)
		(end 414.372552 -413.11703)
		(stroke
			(width 0.06477)
			(type default)
		)
		(layer "F.Cu")
	)
	(gr_line
		(start 414.668462 -417.166044)
		(end 414.372552 -417.461954)
		(stroke
			(width 0.06477)
			(type default)
		)
		(layer "F.Cu")
	)
	(gr_line
		(start 414.669224 -391.978896)
		(end 414.745678 -391.902442)
		(stroke
			(width 0.0508)
			(type default)
		)
		(layer "F.Cu")
	)
	(gr_line
		(start 414.73501 -391.325862)
		(end 414.443672 -391.6172)
		(stroke
			(width 0.0508)
			(type default)
		)
		(layer "F.Cu")
	)
	(gr_line
		(start 414.745678 -391.902442)
		(end 414.745678 -391.784586)
		(stroke
			(width 0.0508)
			(type default)
		)
		(layer "F.Cu")
	)
	(gr_line
		(start 414.82264 -377.41733)
		(end 414.55213 -377.68784)
		(stroke
			(width 0.06477)
			(type default)
		)
		(layer "F.Cu")
	)
	(gr_line
		(start 414.828482 -399.745962)
		(end 414.745678 -399.663158)
		(stroke
			(width 0.0508)
			(type default)
		)
		(layer "F.Cu")
	)
	(gr_line
		(start 414.84804 -379.22073)
		(end 414.49879 -379.56998)
		(stroke
			(width 0.0508)
			(type default)
		)
		(layer "F.Cu")
	)
	(gr_line
		(start 414.898332 -397.156432)
		(end 415.419032 -397.156432)
		(stroke
			(width 0.0635)
			(type default)
		)
		(layer "F.Cu")
	)
	(gr_line
		(start 414.898332 -393.69238)
		(end 415.419032 -393.69238)
		(stroke
			(width 0.0635)
			(type default)
		)
		(layer "F.Cu")
	)
	(gr_line
		(start 414.95218 -391.51941)
		(end 415.045652 -391.612882)
		(stroke
			(width 0.0508)
			(type default)
		)
		(layer "F.Cu")
	)
	(gr_line
		(start 414.95218 -391.324592)
		(end 414.95218 -391.51941)
		(stroke
			(width 0.0508)
			(type default)
		)
		(layer "F.Cu")
	)
	(gr_line
		(start 414.96615 -384.935984)
		(end 414.809432 -384.935984)
		(stroke
			(width 0.0508)
			(type default)
		)
		(layer "F.Cu")
	)
	(gr_line
		(start 415.01568 -386.86486)
		(end 415.015426 -386.86486)
		(stroke
			(width 0.0508)
			(type default)
		)
		(layer "F.Cu")
	)
	(gr_line
		(start 415.029142 -384.409188)
		(end 414.655254 -384.783076)
		(stroke
			(width 0.0508)
			(type default)
		)
		(layer "F.Cu")
	)
	(gr_line
		(start 415.045652 -399.747232)
		(end 415.045652 -399.143474)
		(stroke
			(width 0.0508)
			(type default)
		)
		(layer "F.Cu")
	)
	(gr_line
		(start 415.045652 -391.612882)
		(end 415.045652 -392.30427)
		(stroke
			(width 0.0508)
			(type default)
		)
		(layer "F.Cu")
	)
	(gr_line
		(start 415.18205 -384.720084)
		(end 414.96615 -384.935984)
		(stroke
			(width 0.0508)
			(type default)
		)
		(layer "F.Cu")
	)
	(gr_line
		(start 415.18205 -384.563366)
		(end 415.18205 -384.720084)
		(stroke
			(width 0.0508)
			(type default)
		)
		(layer "F.Cu")
	)
	(gr_line
		(start 415.23031 -4.963414)
		(end 415.495486 -5.22859)
		(stroke
			(width 0.06477)
			(type default)
		)
		(layer "F.Cu")
	)
	(gr_line
		(start 415.298382 -397.849344)
		(end 415.819082 -397.849344)
		(stroke
			(width 0.0635)
			(type default)
		)
		(layer "F.Cu")
	)
	(gr_line
		(start 415.298382 -394.385292)
		(end 415.819082 -394.385292)
		(stroke
			(width 0.0635)
			(type default)
		)
		(layer "F.Cu")
	)
	(gr_line
		(start 415.305494 -401.359116)
		(end 415.303462 -401.359116)
		(stroke
			(width 0.0508)
			(type default)
		)
		(layer "F.Cu")
	)
	(gr_line
		(start 415.326322 -387.017768)
		(end 415.169858 -387.017768)
		(stroke
			(width 0.0508)
			(type default)
		)
		(layer "F.Cu")
	)
	(gr_line
		(start 415.356802 -11.881104)
		(end 415.356802 -11.26998)
		(stroke
			(width 0.06477)
			(type default)
		)
		(layer "F.Cu")
	)
	(gr_line
		(start 415.356802 -7.709154)
		(end 415.356802 -8.320024)
		(stroke
			(width 0.06477)
			(type default)
		)
		(layer "F.Cu")
	)
	(gr_line
		(start 415.38906 -386.49148)
		(end 415.01568 -386.86486)
		(stroke
			(width 0.0508)
			(type default)
		)
		(layer "F.Cu")
	)
	(gr_line
		(start 415.444432 -401.674838)
		(end 415.444432 -401.498054)
		(stroke
			(width 0.0508)
			(type default)
		)
		(layer "F.Cu")
	)
	(gr_line
		(start 415.444432 -401.498054)
		(end 415.305494 -401.359116)
		(stroke
			(width 0.0508)
			(type default)
		)
		(layer "F.Cu")
	)
	(gr_line
		(start 415.444432 -401.002246)
		(end 415.304732 -401.141946)
		(stroke
			(width 0.0508)
			(type default)
		)
		(layer "F.Cu")
	)
	(gr_line
		(start 415.444432 -400.811238)
		(end 415.444432 -401.002246)
		(stroke
			(width 0.0508)
			(type default)
		)
		(layer "F.Cu")
	)
	(gr_line
		(start 415.459164 -17.357598)
		(end 415.459418 -17.357598)
		(stroke
			(width 0.06477)
			(type default)
		)
		(layer "F.Cu")
	)
	(gr_line
		(start 415.459418 -17.357598)
		(end 415.75609 -17.060926)
		(stroke
			(width 0.06477)
			(type default)
		)
		(layer "F.Cu")
	)
	(gr_line
		(start 415.460942 -17.890998)
		(end 415.459164 -17.890998)
		(stroke
			(width 0.06477)
			(type default)
		)
		(layer "F.Cu")
	)
	(gr_line
		(start 415.48558 -19.13636)
		(end 415.75609 -18.86585)
		(stroke
			(width 0.06477)
			(type default)
		)
		(layer "F.Cu")
	)
	(gr_line
		(start 415.495486 -12.019788)
		(end 415.356802 -11.881104)
		(stroke
			(width 0.06477)
			(type default)
		)
		(layer "F.Cu")
	)
	(gr_line
		(start 415.495486 -7.57047)
		(end 415.356802 -7.709154)
		(stroke
			(width 0.06477)
			(type default)
		)
		(layer "F.Cu")
	)
	(gr_line
		(start 415.495486 -5.22859)
		(end 415.495486 -5.239258)
		(stroke
			(width 0.06477)
			(type default)
		)
		(layer "F.Cu")
	)
	(gr_line
		(start 415.541968 -386.802122)
		(end 415.326322 -387.017768)
		(stroke
			(width 0.0508)
			(type default)
		)
		(layer "F.Cu")
	)
	(gr_line
		(start 415.541968 -386.645658)
		(end 415.541968 -386.802122)
		(stroke
			(width 0.0508)
			(type default)
		)
		(layer "F.Cu")
	)
	(gr_line
		(start 415.643568 -391.88771)
		(end 415.734754 -391.978896)
		(stroke
			(width 0.0508)
			(type default)
		)
		(layer "F.Cu")
	)
	(gr_line
		(start 415.643568 -391.6172)
		(end 415.643568 -391.88771)
		(stroke
			(width 0.0508)
			(type default)
		)
		(layer "F.Cu")
	)
	(gr_line
		(start 415.734754 -391.978896)
		(end 415.86912 -391.978896)
		(stroke
			(width 0.0508)
			(type default)
		)
		(layer "F.Cu")
	)
	(gr_line
		(start 415.755836 -18.185892)
		(end 415.460942 -17.890998)
		(stroke
			(width 0.06477)
			(type default)
		)
		(layer "F.Cu")
	)
	(gr_line
		(start 415.818066 -7.57047)
		(end 415.95675 -7.709154)
		(stroke
			(width 0.06477)
			(type default)
		)
		(layer "F.Cu")
	)
	(gr_line
		(start 415.86912 -391.978896)
		(end 415.945574 -391.902442)
		(stroke
			(width 0.0508)
			(type default)
		)
		(layer "F.Cu")
	)
	(gr_line
		(start 415.934906 -391.325862)
		(end 415.643568 -391.6172)
		(stroke
			(width 0.0508)
			(type default)
		)
		(layer "F.Cu")
	)
	(gr_line
		(start 415.945574 -391.902442)
		(end 415.945574 -391.784586)
		(stroke
			(width 0.0508)
			(type default)
		)
		(layer "F.Cu")
	)
	(gr_line
		(start 415.95675 -11.881104)
		(end 415.818066 -12.019788)
		(stroke
			(width 0.06477)
			(type default)
		)
		(layer "F.Cu")
	)
	(gr_line
		(start 415.95675 -11.26998)
		(end 415.95675 -11.881104)
		(stroke
			(width 0.06477)
			(type default)
		)
		(layer "F.Cu")
	)
	(gr_line
		(start 415.95675 -7.709154)
		(end 415.95675 -8.320024)
		(stroke
			(width 0.06477)
			(type default)
		)
		(layer "F.Cu")
	)
	(gr_line
		(start 416.028886 -399.74647)
		(end 415.945574 -399.663158)
		(stroke
			(width 0.0508)
			(type default)
		)
		(layer "F.Cu")
	)
	(gr_line
		(start 416.07867 -18.86585)
		(end 416.34918 -19.13636)
		(stroke
			(width 0.06477)
			(type default)
		)
		(layer "F.Cu")
	)
	(gr_line
		(start 416.07867 -17.060926)
		(end 416.373564 -17.35582)
		(stroke
			(width 0.06477)
			(type default)
		)
		(layer "F.Cu")
	)
	(gr_line
		(start 416.09391 -4.963414)
		(end 415.819336 -5.237988)
		(stroke
			(width 0.06477)
			(type default)
		)
		(layer "F.Cu")
	)
	(gr_line
		(start 416.098228 -397.156432)
		(end 416.618928 -397.156432)
		(stroke
			(width 0.0635)
			(type default)
		)
		(layer "F.Cu")
	)
	(gr_line
		(start 416.098228 -393.69238)
		(end 416.618928 -393.69238)
		(stroke
			(width 0.0635)
			(type default)
		)
		(layer "F.Cu")
	)
	(gr_line
		(start 416.152076 -391.51941)
		(end 416.245802 -391.613136)
		(stroke
			(width 0.0508)
			(type default)
		)
		(layer "F.Cu")
	)
	(gr_line
		(start 416.152076 -391.324592)
		(end 416.152076 -391.51941)
		(stroke
			(width 0.0508)
			(type default)
		)
		(layer "F.Cu")
	)
	(gr_line
		(start 416.245802 -391.613136)
		(end 416.245802 -392.30427)
		(stroke
			(width 0.0508)
			(type default)
		)
		(layer "F.Cu")
	)
	(gr_line
		(start 416.246056 -399.74774)
		(end 416.246056 -399.143728)
		(stroke
			(width 0.0508)
			(type default)
		)
		(layer "F.Cu")
	)
	(gr_line
		(start 416.246056 -399.143728)
		(end 416.245802 -399.143474)
		(stroke
			(width 0.0508)
			(type default)
		)
		(layer "F.Cu")
	)
	(gr_line
		(start 416.373564 -17.890998)
		(end 416.07867 -18.185892)
		(stroke
			(width 0.06477)
			(type default)
		)
		(layer "F.Cu")
	)
	(gr_line
		(start 416.373564 -17.35582)
		(end 416.373564 -17.357598)
		(stroke
			(width 0.06477)
			(type default)
		)
		(layer "F.Cu")
	)
	(gr_line
		(start 416.498278 -397.849344)
		(end 417.018978 -397.849344)
		(stroke
			(width 0.0635)
			(type default)
		)
		(layer "F.Cu")
	)
	(gr_line
		(start 416.498278 -394.385292)
		(end 417.018978 -394.385292)
		(stroke
			(width 0.0635)
			(type default)
		)
		(layer "F.Cu")
	)
	(gr_line
		(start 416.50539 -401.359116)
		(end 416.503358 -401.359116)
		(stroke
			(width 0.0508)
			(type default)
		)
		(layer "F.Cu")
	)
	(gr_line
		(start 416.644328 -401.674838)
		(end 416.644328 -401.498054)
		(stroke
			(width 0.0508)
			(type default)
		)
		(layer "F.Cu")
	)
	(gr_line
		(start 416.644328 -401.498054)
		(end 416.50539 -401.359116)
		(stroke
			(width 0.0508)
			(type default)
		)
		(layer "F.Cu")
	)
	(gr_line
		(start 416.644328 -401.002246)
		(end 416.504628 -401.141946)
		(stroke
			(width 0.0508)
			(type default)
		)
		(layer "F.Cu")
	)
	(gr_line
		(start 416.644328 -400.811238)
		(end 416.644328 -401.002246)
		(stroke
			(width 0.0508)
			(type default)
		)
		(layer "F.Cu")
	)
	(gr_line
		(start 416.817302 -417.166044)
		(end 417.113212 -417.461954)
		(stroke
			(width 0.06477)
			(type default)
		)
		(layer "F.Cu")
	)
	(gr_line
		(start 416.842702 -412.84652)
		(end 417.113212 -413.11703)
		(stroke
			(width 0.06477)
			(type default)
		)
		(layer "F.Cu")
	)
	(gr_line
		(start 416.843718 -391.88771)
		(end 416.934904 -391.978896)
		(stroke
			(width 0.0508)
			(type default)
		)
		(layer "F.Cu")
	)
	(gr_line
		(start 416.843718 -391.6172)
		(end 416.843718 -391.88771)
		(stroke
			(width 0.0508)
			(type default)
		)
		(layer "F.Cu")
	)
	(gr_line
		(start 416.934904 -391.978896)
		(end 417.06927 -391.978896)
		(stroke
			(width 0.0508)
			(type default)
		)
		(layer "F.Cu")
	)
	(gr_line
		(start 417.025582 -6.725158)
		(end 417.295584 -6.99516)
		(stroke
			(width 0.06477)
			(type default)
		)
		(layer "F.Cu")
	)
	(gr_line
		(start 417.06927 -391.978896)
		(end 417.145724 -391.902442)
		(stroke
			(width 0.0508)
			(type default)
		)
		(layer "F.Cu")
	)
	(gr_line
		(start 417.113212 -420.681658)
		(end 416.842702 -420.952168)
		(stroke
			(width 0.06477)
			(type default)
		)
		(layer "F.Cu")
	)
	(gr_line
		(start 417.113212 -416.336734)
		(end 416.817302 -416.632644)
		(stroke
			(width 0.06477)
			(type default)
		)
		(layer "F.Cu")
	)
	(gr_line
		(start 417.135056 -391.325862)
		(end 416.843718 -391.6172)
		(stroke
			(width 0.0508)
			(type default)
		)
		(layer "F.Cu")
	)
	(gr_line
		(start 417.145724 -391.902442)
		(end 417.145724 -391.784586)
		(stroke
			(width 0.0508)
			(type default)
		)
		(layer "F.Cu")
	)
	(gr_line
		(start 417.1569 -11.881104)
		(end 417.1569 -11.26998)
		(stroke
			(width 0.06477)
			(type default)
		)
		(layer "F.Cu")
	)
	(gr_line
		(start 417.1569 -7.709154)
		(end 417.1569 -8.320024)
		(stroke
			(width 0.06477)
			(type default)
		)
		(layer "F.Cu")
	)
	(gr_line
		(start 417.229036 -399.74647)
		(end 417.145724 -399.663158)
		(stroke
			(width 0.0508)
			(type default)
		)
		(layer "F.Cu")
	)
	(gr_line
		(start 417.295584 -12.019788)
		(end 417.1569 -11.881104)
		(stroke
			(width 0.06477)
			(type default)
		)
		(layer "F.Cu")
	)
	(gr_line
		(start 417.295584 -7.57047)
		(end 417.1569 -7.709154)
		(stroke
			(width 0.06477)
			(type default)
		)
		(layer "F.Cu")
	)
	(gr_line
		(start 417.295584 -6.99516)
		(end 417.295584 -6.996176)
		(stroke
			(width 0.06477)
			(type default)
		)
		(layer "F.Cu")
	)
	(gr_line
		(start 417.298378 -397.156432)
		(end 417.819078 -397.156432)
		(stroke
			(width 0.0635)
			(type default)
		)
		(layer "F.Cu")
	)
	(gr_line
		(start 417.298378 -393.69238)
		(end 417.819078 -393.69238)
		(stroke
			(width 0.0635)
			(type default)
		)
		(layer "F.Cu")
	)
	(gr_line
		(start 417.33724 -384.14833)
		(end 417.685474 -384.496564)
		(stroke
			(width 0.0508)
			(type default)
		)
		(layer "F.Cu")
	)
	(gr_line
		(start 417.352226 -391.51941)
		(end 417.445698 -391.612882)
		(stroke
			(width 0.0508)
			(type default)
		)
		(layer "F.Cu")
	)
	(gr_line
		(start 417.352226 -391.324592)
		(end 417.352226 -391.51941)
		(stroke
			(width 0.0508)
			(type default)
		)
		(layer "F.Cu")
	)
	(gr_line
		(start 417.36264 -382.34493)
		(end 417.63315 -382.61544)
		(stroke
			(width 0.06477)
			(type default)
		)
		(layer "F.Cu")
	)
	(gr_line
		(start 417.435792 -420.681658)
		(end 417.706302 -420.952168)
		(stroke
			(width 0.06477)
			(type default)
		)
		(layer "F.Cu")
	)
	(gr_line
		(start 417.435792 -416.336734)
		(end 417.731702 -416.632644)
		(stroke
			(width 0.06477)
			(type default)
		)
		(layer "F.Cu")
	)
	(gr_line
		(start 417.445698 -391.612882)
		(end 417.445698 -392.30427)
		(stroke
			(width 0.0508)
			(type default)
		)
		(layer "F.Cu")
	)
	(gr_line
		(start 417.446206 -399.74774)
		(end 417.446206 -399.143982)
		(stroke
			(width 0.0508)
			(type default)
		)
		(layer "F.Cu")
	)
	(gr_line
		(start 417.446206 -399.143982)
		(end 417.445698 -399.143474)
		(stroke
			(width 0.0508)
			(type default)
		)
		(layer "F.Cu")
	)
	(gr_line
		(start 417.618164 -7.57047)
		(end 417.756848 -7.709154)
		(stroke
			(width 0.06477)
			(type default)
		)
		(layer "F.Cu")
	)
	(gr_line
		(start 417.63315 -383.31902)
		(end 417.33724 -383.61493)
		(stroke
			(width 0.06477)
			(type default)
		)
		(layer "F.Cu")
	)
	(gr_line
		(start 417.685474 -384.496564)
		(end 417.685474 -384.498596)
		(stroke
			(width 0.0508)
			(type default)
		)
		(layer "F.Cu")
	)
	(gr_line
		(start 417.698174 -397.849344)
		(end 418.218874 -397.849344)
		(stroke
			(width 0.0635)
			(type default)
		)
		(layer "F.Cu")
	)
	(gr_line
		(start 417.698174 -394.385292)
		(end 418.218874 -394.385292)
		(stroke
			(width 0.0635)
			(type default)
		)
		(layer "F.Cu")
	)
	(gr_line
		(start 417.702238 -401.359116)
		(end 417.67887 -401.359116)
		(stroke
			(width 0.0508)
			(type default)
		)
		(layer "F.Cu")
	)
	(gr_line
		(start 417.706302 -412.84652)
		(end 417.435792 -413.11703)
		(stroke
			(width 0.06477)
			(type default)
		)
		(layer "F.Cu")
	)
	(gr_line
		(start 417.731702 -417.166044)
		(end 417.435792 -417.461954)
		(stroke
			(width 0.06477)
			(type default)
		)
		(layer "F.Cu")
	)
	(gr_line
		(start 417.756848 -11.881104)
		(end 417.618164 -12.019788)
		(stroke
			(width 0.06477)
			(type default)
		)
		(layer "F.Cu")
	)
	(gr_line
		(start 417.756848 -11.26998)
		(end 417.756848 -11.881104)
		(stroke
			(width 0.06477)
			(type default)
		)
		(layer "F.Cu")
	)
	(gr_line
		(start 417.756848 -7.709154)
		(end 417.756848 -8.320024)
		(stroke
			(width 0.06477)
			(type default)
		)
		(layer "F.Cu")
	)
	(gr_line
		(start 417.844224 -401.674838)
		(end 417.844224 -401.501102)
		(stroke
			(width 0.0508)
			(type default)
		)
		(layer "F.Cu")
	)
	(gr_line
		(start 417.844224 -401.501102)
		(end 417.702238 -401.359116)
		(stroke
			(width 0.0508)
			(type default)
		)
		(layer "F.Cu")
	)
	(gr_line
		(start 417.844224 -400.977862)
		(end 417.68014 -401.141946)
		(stroke
			(width 0.0508)
			(type default)
		)
		(layer "F.Cu")
	)
	(gr_line
		(start 417.844224 -400.811238)
		(end 417.844224 -400.977862)
		(stroke
			(width 0.0508)
			(type default)
		)
		(layer "F.Cu")
	)
	(gr_line
		(start 417.889182 -6.725158)
		(end 417.61918 -6.99516)
		(stroke
			(width 0.06477)
			(type default)
		)
		(layer "F.Cu")
	)
	(gr_line
		(start 417.95573 -383.31902)
		(end 418.25164 -383.61493)
		(stroke
			(width 0.06477)
			(type default)
		)
		(layer "F.Cu")
	)
	(gr_line
		(start 418.043614 -391.88771)
		(end 418.1348 -391.978896)
		(stroke
			(width 0.0508)
			(type default)
		)
		(layer "F.Cu")
	)
	(gr_line
		(start 418.043614 -391.6172)
		(end 418.043614 -391.88771)
		(stroke
			(width 0.0508)
			(type default)
		)
		(layer "F.Cu")
	)
	(gr_line
		(start 418.1348 -391.978896)
		(end 418.269166 -391.978896)
		(stroke
			(width 0.0508)
			(type default)
		)
		(layer "F.Cu")
	)
	(gr_line
		(start 418.22624 -382.34493)
		(end 417.95573 -382.61544)
		(stroke
			(width 0.06477)
			(type default)
		)
		(layer "F.Cu")
	)
	(gr_line
		(start 418.25164 -384.14833)
		(end 417.902644 -384.497326)
		(stroke
			(width 0.0508)
			(type default)
		)
		(layer "F.Cu")
	)
	(gr_line
		(start 418.253164 -15.833598)
		(end 418.253418 -15.833598)
		(stroke
			(width 0.06477)
			(type default)
		)
		(layer "F.Cu")
	)
	(gr_line
		(start 418.253418 -15.833598)
		(end 418.55009 -15.536926)
		(stroke
			(width 0.06477)
			(type default)
		)
		(layer "F.Cu")
	)
	(gr_line
		(start 418.254942 -16.366998)
		(end 418.253164 -16.366998)
		(stroke
			(width 0.06477)
			(type default)
		)
		(layer "F.Cu")
	)
	(gr_line
		(start 418.269166 -391.978896)
		(end 418.34562 -391.902442)
		(stroke
			(width 0.0508)
			(type default)
		)
		(layer "F.Cu")
	)
	(gr_line
		(start 418.27958 -17.61236)
		(end 418.55009 -17.34185)
		(stroke
			(width 0.06477)
			(type default)
		)
		(layer "F.Cu")
	)
	(gr_line
		(start 418.334952 -391.325862)
		(end 418.043614 -391.6172)
		(stroke
			(width 0.0508)
			(type default)
		)
		(layer "F.Cu")
	)
	(gr_line
		(start 418.34562 -391.902442)
		(end 418.34562 -391.784586)
		(stroke
			(width 0.0508)
			(type default)
		)
		(layer "F.Cu")
	)
	(gr_line
		(start 418.428932 -399.74647)
		(end 418.34562 -399.663158)
		(stroke
			(width 0.0508)
			(type default)
		)
		(layer "F.Cu")
	)
	(gr_line
		(start 418.498274 -397.156432)
		(end 419.018974 -397.156432)
		(stroke
			(width 0.0635)
			(type default)
		)
		(layer "F.Cu")
	)
	(gr_line
		(start 418.498274 -393.69238)
		(end 419.018974 -393.69238)
		(stroke
			(width 0.0635)
			(type default)
		)
		(layer "F.Cu")
	)
	(gr_line
		(start 418.549836 -16.661892)
		(end 418.254942 -16.366998)
		(stroke
			(width 0.06477)
			(type default)
		)
		(layer "F.Cu")
	)
	(gr_line
		(start 418.552122 -391.51941)
		(end 418.645594 -391.612882)
		(stroke
			(width 0.0508)
			(type default)
		)
		(layer "F.Cu")
	)
	(gr_line
		(start 418.552122 -391.324592)
		(end 418.552122 -391.51941)
		(stroke
			(width 0.0508)
			(type default)
		)
		(layer "F.Cu")
	)
	(gr_line
		(start 418.645594 -391.612882)
		(end 418.645594 -392.30427)
		(stroke
			(width 0.0508)
			(type default)
		)
		(layer "F.Cu")
	)
	(gr_line
		(start 418.646102 -399.74774)
		(end 418.646102 -399.143982)
		(stroke
			(width 0.0508)
			(type default)
		)
		(layer "F.Cu")
	)
	(gr_line
		(start 418.646102 -399.143982)
		(end 418.645594 -399.143474)
		(stroke
			(width 0.0508)
			(type default)
		)
		(layer "F.Cu")
	)
	(gr_line
		(start 418.830252 -4.963414)
		(end 419.095682 -5.228844)
		(stroke
			(width 0.06477)
			(type default)
		)
		(layer "F.Cu")
	)
	(gr_line
		(start 418.87267 -17.34185)
		(end 419.14318 -17.61236)
		(stroke
			(width 0.06477)
			(type default)
		)
		(layer "F.Cu")
	)
	(gr_line
		(start 418.87267 -15.536926)
		(end 419.167564 -15.83182)
		(stroke
			(width 0.06477)
			(type default)
		)
		(layer "F.Cu")
	)
	(gr_line
		(start 418.898324 -397.849344)
		(end 419.419024 -397.849344)
		(stroke
			(width 0.0635)
			(type default)
		)
		(layer "F.Cu")
	)
	(gr_line
		(start 418.898324 -394.385292)
		(end 419.419024 -394.385292)
		(stroke
			(width 0.0635)
			(type default)
		)
		(layer "F.Cu")
	)
	(gr_line
		(start 418.905436 -401.359116)
		(end 418.903404 -401.359116)
		(stroke
			(width 0.0508)
			(type default)
		)
		(layer "F.Cu")
	)
	(gr_line
		(start 418.956998 -11.881104)
		(end 418.956998 -11.26998)
		(stroke
			(width 0.06477)
			(type default)
		)
		(layer "F.Cu")
	)
	(gr_line
		(start 418.956998 -7.709154)
		(end 418.956998 -8.320024)
		(stroke
			(width 0.06477)
			(type default)
		)
		(layer "F.Cu")
	)
	(gr_line
		(start 419.03904 -381.68453)
		(end 419.38829 -382.03378)
		(stroke
			(width 0.0508)
			(type default)
		)
		(layer "F.Cu")
	)
	(gr_line
		(start 419.04412 -401.674838)
		(end 419.04412 -401.4978)
		(stroke
			(width 0.0508)
			(type default)
		)
		(layer "F.Cu")
	)
	(gr_line
		(start 419.04412 -401.4978)
		(end 418.905436 -401.359116)
		(stroke
			(width 0.0508)
			(type default)
		)
		(layer "F.Cu")
	)
	(gr_line
		(start 419.04412 -401.0025)
		(end 418.904674 -401.141946)
		(stroke
			(width 0.0508)
			(type default)
		)
		(layer "F.Cu")
	)
	(gr_line
		(start 419.04412 -400.811238)
		(end 419.04412 -401.0025)
		(stroke
			(width 0.0508)
			(type default)
		)
		(layer "F.Cu")
	)
	(gr_line
		(start 419.06444 -379.88113)
		(end 419.33495 -380.15164)
		(stroke
			(width 0.06477)
			(type default)
		)
		(layer "F.Cu")
	)
	(gr_line
		(start 419.095682 -12.019788)
		(end 418.956998 -11.881104)
		(stroke
			(width 0.06477)
			(type default)
		)
		(layer "F.Cu")
	)
	(gr_line
		(start 419.095682 -7.57047)
		(end 418.956998 -7.709154)
		(stroke
			(width 0.06477)
			(type default)
		)
		(layer "F.Cu")
	)
	(gr_line
		(start 419.095682 -5.228844)
		(end 419.095682 -5.239004)
		(stroke
			(width 0.06477)
			(type default)
		)
		(layer "F.Cu")
	)
	(gr_line
		(start 419.167564 -16.366998)
		(end 418.87267 -16.661892)
		(stroke
			(width 0.06477)
			(type default)
		)
		(layer "F.Cu")
	)
	(gr_line
		(start 419.167564 -15.83182)
		(end 419.167564 -15.833598)
		(stroke
			(width 0.06477)
			(type default)
		)
		(layer "F.Cu")
	)
	(gr_line
		(start 419.33495 -380.85522)
		(end 419.03904 -381.15113)
		(stroke
			(width 0.06477)
			(type default)
		)
		(layer "F.Cu")
	)
	(gr_line
		(start 419.38829 -383.403856)
		(end 419.38829 -383.932176)
		(stroke
			(width 0.0508)
			(type default)
		)
		(layer "F.Cu")
	)
	(gr_line
		(start 419.418262 -7.57047)
		(end 419.5572 -7.709408)
		(stroke
			(width 0.06477)
			(type default)
		)
		(layer "F.Cu")
	)
	(gr_line
		(start 419.556946 -11.881104)
		(end 419.418262 -12.019788)
		(stroke
			(width 0.06477)
			(type default)
		)
		(layer "F.Cu")
	)
	(gr_line
		(start 419.556946 -11.26998)
		(end 419.556946 -11.881104)
		(stroke
			(width 0.06477)
			(type default)
		)
		(layer "F.Cu")
	)
	(gr_line
		(start 419.556946 -7.709662)
		(end 419.556946 -8.320024)
		(stroke
			(width 0.06477)
			(type default)
		)
		(layer "F.Cu")
	)
	(gr_line
		(start 419.5572 -7.709408)
		(end 419.556946 -7.709662)
		(stroke
			(width 0.06477)
			(type default)
		)
		(layer "F.Cu")
	)
	(gr_line
		(start 419.60546 -383.405126)
		(end 419.71595 -383.515616)
		(stroke
			(width 0.0508)
			(type default)
		)
		(layer "F.Cu")
	)
	(gr_line
		(start 419.629082 -399.74647)
		(end 419.54577 -399.663158)
		(stroke
			(width 0.0508)
			(type default)
		)
		(layer "F.Cu")
	)
	(gr_line
		(start 419.629082 -391.701274)
		(end 419.54577 -391.784586)
		(stroke
			(width 0.0508)
			(type default)
		)
		(layer "F.Cu")
	)
	(gr_line
		(start 419.65753 -380.85522)
		(end 419.95344 -381.15113)
		(stroke
			(width 0.06477)
			(type default)
		)
		(layer "F.Cu")
	)
	(gr_line
		(start 419.693852 -4.963414)
		(end 419.419532 -5.237734)
		(stroke
			(width 0.06477)
			(type default)
		)
		(layer "F.Cu")
	)
	(gr_line
		(start 419.698424 -397.156432)
		(end 420.219124 -397.156432)
		(stroke
			(width 0.0635)
			(type default)
		)
		(layer "F.Cu")
	)
	(gr_line
		(start 419.698424 -393.69238)
		(end 420.219124 -393.69238)
		(stroke
			(width 0.0635)
			(type default)
		)
		(layer "F.Cu")
	)
	(gr_line
		(start 419.71595 -383.820416)
		(end 419.60546 -383.930906)
		(stroke
			(width 0.0508)
			(type default)
		)
		(layer "F.Cu")
	)
	(gr_line
		(start 419.71595 -383.515616)
		(end 419.71595 -383.820416)
		(stroke
			(width 0.0508)
			(type default)
		)
		(layer "F.Cu")
	)
	(gr_line
		(start 419.752526 -390.071102)
		(end 419.752272 -390.070848)
		(stroke
			(width 0.0508)
			(type default)
		)
		(layer "F.Cu")
	)
	(gr_line
		(start 419.846252 -399.74774)
		(end 419.846252 -399.143982)
		(stroke
			(width 0.0508)
			(type default)
		)
		(layer "F.Cu")
	)
	(gr_line
		(start 419.846252 -399.143982)
		(end 419.845744 -399.143474)
		(stroke
			(width 0.0508)
			(type default)
		)
		(layer "F.Cu")
	)
	(gr_line
		(start 419.846252 -392.303762)
		(end 419.845744 -392.30427)
		(stroke
			(width 0.0508)
			(type default)
		)
		(layer "F.Cu")
	)
	(gr_line
		(start 419.846252 -391.700004)
		(end 419.846252 -392.303762)
		(stroke
			(width 0.0508)
			(type default)
		)
		(layer "F.Cu")
	)
	(gr_line
		(start 419.92804 -379.88113)
		(end 419.65753 -380.15164)
		(stroke
			(width 0.06477)
			(type default)
		)
		(layer "F.Cu")
	)
	(gr_line
		(start 419.95344 -381.68453)
		(end 419.60419 -382.03378)
		(stroke
			(width 0.0508)
			(type default)
		)
		(layer "F.Cu")
	)
	(gr_line
		(start 420.087552 -401.359116)
		(end 420.076884 -401.359116)
		(stroke
			(width 0.0508)
			(type default)
		)
		(layer "F.Cu")
	)
	(gr_line
		(start 420.09822 -397.849344)
		(end 420.61892 -397.849344)
		(stroke
			(width 0.0635)
			(type default)
		)
		(layer "F.Cu")
	)
	(gr_line
		(start 420.09822 -394.385292)
		(end 420.61892 -394.385292)
		(stroke
			(width 0.0635)
			(type default)
		)
		(layer "F.Cu")
	)
	(gr_line
		(start 420.24427 -401.674838)
		(end 420.24427 -401.515834)
		(stroke
			(width 0.0508)
			(type default)
		)
		(layer "F.Cu")
	)
	(gr_line
		(start 420.24427 -401.515834)
		(end 420.087552 -401.359116)
		(stroke
			(width 0.0508)
			(type default)
		)
		(layer "F.Cu")
	)
	(gr_line
		(start 420.24427 -400.97583)
		(end 420.078154 -401.141946)
		(stroke
			(width 0.0508)
			(type default)
		)
		(layer "F.Cu")
	)
	(gr_line
		(start 420.24427 -400.811238)
		(end 420.24427 -400.97583)
		(stroke
			(width 0.0508)
			(type default)
		)
		(layer "F.Cu")
	)
	(gr_line
		(start 420.74084 -379.22073)
		(end 421.09009 -379.56998)
		(stroke
			(width 0.0508)
			(type default)
		)
		(layer "F.Cu")
	)
	(gr_line
		(start 420.76624 -377.41733)
		(end 421.03675 -377.68784)
		(stroke
			(width 0.06477)
			(type default)
		)
		(layer "F.Cu")
	)
	(gr_line
		(start 420.828978 -399.74647)
		(end 420.745666 -399.663158)
		(stroke
			(width 0.0508)
			(type default)
		)
		(layer "F.Cu")
	)
	(gr_line
		(start 420.828978 -391.701274)
		(end 420.745666 -391.784586)
		(stroke
			(width 0.0508)
			(type default)
		)
		(layer "F.Cu")
	)
	(gr_line
		(start 420.89832 -397.156432)
		(end 421.41902 -397.156432)
		(stroke
			(width 0.0635)
			(type default)
		)
		(layer "F.Cu")
	)
	(gr_line
		(start 420.89832 -393.69238)
		(end 421.41902 -393.69238)
		(stroke
			(width 0.0635)
			(type default)
		)
		(layer "F.Cu")
	)
	(gr_line
		(start 421.03675 -378.39142)
		(end 420.74084 -378.68733)
		(stroke
			(width 0.06477)
			(type default)
		)
		(layer "F.Cu")
	)
	(gr_line
		(start 421.046148 -399.74774)
		(end 421.046148 -399.143982)
		(stroke
			(width 0.0508)
			(type default)
		)
		(layer "F.Cu")
	)
	(gr_line
		(start 421.046148 -399.143982)
		(end 421.04564 -399.143474)
		(stroke
			(width 0.0508)
			(type default)
		)
		(layer "F.Cu")
	)
	(gr_line
		(start 421.046148 -392.303762)
		(end 421.04564 -392.30427)
		(stroke
			(width 0.0508)
			(type default)
		)
		(layer "F.Cu")
	)
	(gr_line
		(start 421.046148 -391.700004)
		(end 421.046148 -392.303762)
		(stroke
			(width 0.0508)
			(type default)
		)
		(layer "F.Cu")
	)
	(gr_line
		(start 421.047164 -17.357598)
		(end 421.047418 -17.357598)
		(stroke
			(width 0.06477)
			(type default)
		)
		(layer "F.Cu")
	)
	(gr_line
		(start 421.047418 -17.357598)
		(end 421.34409 -17.060926)
		(stroke
			(width 0.06477)
			(type default)
		)
		(layer "F.Cu")
	)
	(gr_line
		(start 421.072564 -19.137122)
		(end 421.343074 -18.866612)
		(stroke
			(width 0.06477)
			(type default)
		)
		(layer "F.Cu")
	)
	(gr_line
		(start 421.288972 -401.359116)
		(end 421.282876 -401.359116)
		(stroke
			(width 0.0508)
			(type default)
		)
		(layer "F.Cu")
	)
	(gr_line
		(start 421.29837 -397.849344)
		(end 421.81907 -397.849344)
		(stroke
			(width 0.0635)
			(type default)
		)
		(layer "F.Cu")
	)
	(gr_line
		(start 421.29837 -394.385292)
		(end 421.81907 -394.385292)
		(stroke
			(width 0.0635)
			(type default)
		)
		(layer "F.Cu")
	)
	(gr_line
		(start 421.34282 -18.186654)
		(end 421.047164 -17.890998)
		(stroke
			(width 0.06477)
			(type default)
		)
		(layer "F.Cu")
	)
	(gr_line
		(start 421.35933 -378.39142)
		(end 421.65524 -378.68733)
		(stroke
			(width 0.06477)
			(type default)
		)
		(layer "F.Cu")
	)
	(gr_line
		(start 421.444166 -401.674838)
		(end 421.444166 -401.51431)
		(stroke
			(width 0.0508)
			(type default)
		)
		(layer "F.Cu")
	)
	(gr_line
		(start 421.444166 -401.51431)
		(end 421.288972 -401.359116)
		(stroke
			(width 0.0508)
			(type default)
		)
		(layer "F.Cu")
	)
	(gr_line
		(start 421.444166 -400.981926)
		(end 421.284146 -401.141946)
		(stroke
			(width 0.0508)
			(type default)
		)
		(layer "F.Cu")
	)
	(gr_line
		(start 421.444166 -400.811238)
		(end 421.444166 -400.981926)
		(stroke
			(width 0.0508)
			(type default)
		)
		(layer "F.Cu")
	)
	(gr_line
		(start 421.62984 -377.41733)
		(end 421.35933 -377.68784)
		(stroke
			(width 0.06477)
			(type default)
		)
		(layer "F.Cu")
	)
	(gr_line
		(start 421.65524 -379.22073)
		(end 421.30599 -379.56998)
		(stroke
			(width 0.0508)
			(type default)
		)
		(layer "F.Cu")
	)
	(gr_line
		(start 421.665654 -18.866612)
		(end 421.936164 -19.137122)
		(stroke
			(width 0.06477)
			(type default)
		)
		(layer "F.Cu")
	)
	(gr_line
		(start 421.66667 -17.060926)
		(end 421.961564 -17.35582)
		(stroke
			(width 0.06477)
			(type default)
		)
		(layer "F.Cu")
	)
	(gr_line
		(start 421.96131 -17.890998)
		(end 421.665654 -18.186654)
		(stroke
			(width 0.06477)
			(type default)
		)
		(layer "F.Cu")
	)
	(gr_line
		(start 421.961564 -17.890998)
		(end 421.96131 -17.890998)
		(stroke
			(width 0.06477)
			(type default)
		)
		(layer "F.Cu")
	)
	(gr_line
		(start 421.961564 -17.35582)
		(end 421.961564 -17.357598)
		(stroke
			(width 0.06477)
			(type default)
		)
		(layer "F.Cu")
	)
	(gr_line
		(start 422.273476 -381.460502)
		(end 422.647364 -381.83439)
		(stroke
			(width 0.0508)
			(type default)
		)
		(layer "F.Cu")
	)
	(gr_line
		(start 422.427908 -381.307594)
		(end 422.584372 -381.307594)
		(stroke
			(width 0.0508)
			(type default)
		)
		(layer "F.Cu")
	)
	(gr_line
		(start 422.584372 -381.307594)
		(end 422.800272 -381.523494)
		(stroke
			(width 0.0508)
			(type default)
		)
		(layer "F.Cu")
	)
	(gr_line
		(start 422.800272 -381.523494)
		(end 422.800272 -381.679958)
		(stroke
			(width 0.0508)
			(type default)
		)
		(layer "F.Cu")
	)
	(gr_line
		(start 423.841164 -15.833598)
		(end 424.13682 -15.537942)
		(stroke
			(width 0.06477)
			(type default)
		)
		(layer "F.Cu")
	)
	(gr_line
		(start 423.86758 -17.61236)
		(end 424.13809 -17.34185)
		(stroke
			(width 0.06477)
			(type default)
		)
		(layer "F.Cu")
	)
	(gr_line
		(start 423.874438 -388.090918)
		(end 423.763948 -388.201408)
		(stroke
			(width 0.0508)
			(type default)
		)
		(layer "F.Cu")
	)
	(gr_line
		(start 424.13682 -16.662654)
		(end 423.841164 -16.366998)
		(stroke
			(width 0.06477)
			(type default)
		)
		(layer "F.Cu")
	)
	(gr_line
		(start 424.14444 -379.22073)
		(end 424.49369 -379.56998)
		(stroke
			(width 0.0508)
			(type default)
		)
		(layer "F.Cu")
	)
	(gr_line
		(start 424.16984 -377.41733)
		(end 424.44035 -377.68784)
		(stroke
			(width 0.06477)
			(type default)
		)
		(layer "F.Cu")
	)
	(gr_line
		(start 424.179238 -388.090918)
		(end 423.874438 -388.090918)
		(stroke
			(width 0.0508)
			(type default)
		)
		(layer "F.Cu")
	)
	(gr_line
		(start 424.289728 -388.201408)
		(end 424.179238 -388.090918)
		(stroke
			(width 0.0508)
			(type default)
		)
		(layer "F.Cu")
	)
	(gr_line
		(start 424.290998 -388.418578)
		(end 423.762678 -388.418578)
		(stroke
			(width 0.0508)
			(type default)
		)
		(layer "F.Cu")
	)
	(gr_line
		(start 424.44035 -378.39142)
		(end 424.14444 -378.68733)
		(stroke
			(width 0.06477)
			(type default)
		)
		(layer "F.Cu")
	)
	(gr_line
		(start 424.46067 -17.34185)
		(end 424.73118 -17.61236)
		(stroke
			(width 0.06477)
			(type default)
		)
		(layer "F.Cu")
	)
	(gr_line
		(start 424.46067 -16.661892)
		(end 424.46067 -16.663924)
		(stroke
			(width 0.06477)
			(type default)
		)
		(layer "F.Cu")
	)
	(gr_line
		(start 424.46067 -15.538704)
		(end 424.755564 -15.833598)
		(stroke
			(width 0.06477)
			(type default)
		)
		(layer "F.Cu")
	)
	(gr_line
		(start 424.46067 -15.536672)
		(end 424.46067 -15.538704)
		(stroke
			(width 0.06477)
			(type default)
		)
		(layer "F.Cu")
	)
	(gr_line
		(start 424.635676 -6.725158)
		(end 424.905678 -6.99516)
		(stroke
			(width 0.06477)
			(type default)
		)
		(layer "F.Cu")
	)
	(gr_line
		(start 424.70959 -379.909832)
		(end 424.709844 -379.909578)
		(stroke
			(width 0.0508)
			(type default)
		)
		(layer "F.Cu")
	)
	(gr_line
		(start 424.755564 -16.366998)
		(end 424.46067 -16.661892)
		(stroke
			(width 0.06477)
			(type default)
		)
		(layer "F.Cu")
	)
	(gr_line
		(start 424.756834 -385.10083)
		(end 424.666918 -385.10083)
		(stroke
			(width 0.0508)
			(type default)
		)
		(layer "F.Cu")
	)
	(gr_line
		(start 424.76293 -378.39142)
		(end 425.05884 -378.68733)
		(stroke
			(width 0.06477)
			(type default)
		)
		(layer "F.Cu")
	)
	(gr_line
		(start 424.766994 -11.881104)
		(end 424.766994 -11.26998)
		(stroke
			(width 0.06477)
			(type default)
		)
		(layer "F.Cu")
	)
	(gr_line
		(start 424.766994 -7.709154)
		(end 424.766994 -8.320024)
		(stroke
			(width 0.06477)
			(type default)
		)
		(layer "F.Cu")
	)
	(gr_line
		(start 424.896534 -385.158742)
		(end 424.756834 -385.10083)
		(stroke
			(width 0.0508)
			(type default)
		)
		(layer "F.Cu")
	)
	(gr_line
		(start 424.905678 -12.019788)
		(end 424.766994 -11.881104)
		(stroke
			(width 0.06477)
			(type default)
		)
		(layer "F.Cu")
	)
	(gr_line
		(start 424.905678 -7.57047)
		(end 424.766994 -7.709154)
		(stroke
			(width 0.06477)
			(type default)
		)
		(layer "F.Cu")
	)
	(gr_line
		(start 424.905678 -6.99516)
		(end 424.905678 -6.996176)
		(stroke
			(width 0.06477)
			(type default)
		)
		(layer "F.Cu")
	)
	(gr_line
		(start 425.03344 -377.41733)
		(end 424.76293 -377.68784)
		(stroke
			(width 0.06477)
			(type default)
		)
		(layer "F.Cu")
	)
	(gr_line
		(start 425.05884 -379.22073)
		(end 424.70959 -379.56998)
		(stroke
			(width 0.0508)
			(type default)
		)
		(layer "F.Cu")
	)
	(gr_line
		(start 425.10202 -388.767828)
		(end 424.75277 -388.418578)
		(stroke
			(width 0.0508)
			(type default)
		)
		(layer "F.Cu")
	)
	(gr_line
		(start 425.10202 -387.853428)
		(end 424.75277 -388.202678)
		(stroke
			(width 0.0508)
			(type default)
		)
		(layer "F.Cu")
	)
	(gr_line
		(start 425.10202 -385.364228)
		(end 424.896534 -385.158742)
		(stroke
			(width 0.0508)
			(type default)
		)
		(layer "F.Cu")
	)
	(gr_line
		(start 425.10202 -384.449828)
		(end 424.668188 -384.88366)
		(stroke
			(width 0.0508)
			(type default)
		)
		(layer "F.Cu")
	)
	(gr_line
		(start 425.228258 -7.57047)
		(end 425.366942 -7.709154)
		(stroke
			(width 0.06477)
			(type default)
		)
		(layer "F.Cu")
	)
	(gr_line
		(start 425.366942 -11.881104)
		(end 425.228258 -12.019788)
		(stroke
			(width 0.06477)
			(type default)
		)
		(layer "F.Cu")
	)
	(gr_line
		(start 425.366942 -11.26998)
		(end 425.366942 -11.881104)
		(stroke
			(width 0.06477)
			(type default)
		)
		(layer "F.Cu")
	)
	(gr_line
		(start 425.366942 -7.709154)
		(end 425.366942 -8.320024)
		(stroke
			(width 0.06477)
			(type default)
		)
		(layer "F.Cu")
	)
	(gr_line
		(start 425.424092 -381.286258)
		(end 425.79798 -381.660146)
		(stroke
			(width 0.0508)
			(type default)
		)
		(layer "F.Cu")
	)
	(gr_line
		(start 425.499276 -6.725158)
		(end 425.229274 -6.99516)
		(stroke
			(width 0.06477)
			(type default)
		)
		(layer "F.Cu")
	)
	(gr_line
		(start 425.57827 -381.13335)
		(end 425.734988 -381.13335)
		(stroke
			(width 0.0508)
			(type default)
		)
		(layer "F.Cu")
	)
	(gr_line
		(start 425.734988 -381.13335)
		(end 425.950888 -381.34925)
		(stroke
			(width 0.0508)
			(type default)
		)
		(layer "F.Cu")
	)
	(gr_line
		(start 425.93133 -388.471918)
		(end 425.63542 -388.767828)
		(stroke
			(width 0.06477)
			(type default)
		)
		(layer "F.Cu")
	)
	(gr_line
		(start 425.93133 -388.149338)
		(end 425.63542 -387.853428)
		(stroke
			(width 0.06477)
			(type default)
		)
		(layer "F.Cu")
	)
	(gr_line
		(start 425.93133 -385.068318)
		(end 425.63542 -385.364228)
		(stroke
			(width 0.06477)
			(type default)
		)
		(layer "F.Cu")
	)
	(gr_line
		(start 425.93133 -384.745738)
		(end 425.63542 -384.449828)
		(stroke
			(width 0.06477)
			(type default)
		)
		(layer "F.Cu")
	)
	(gr_line
		(start 425.950888 -381.34925)
		(end 425.950888 -381.505968)
		(stroke
			(width 0.0508)
			(type default)
		)
		(layer "F.Cu")
	)
	(gr_line
		(start 426.440346 -4.963414)
		(end 426.705522 -5.22859)
		(stroke
			(width 0.06477)
			(type default)
		)
		(layer "F.Cu")
	)
	(gr_line
		(start 426.566838 -11.881104)
		(end 426.566838 -11.26998)
		(stroke
			(width 0.06477)
			(type default)
		)
		(layer "F.Cu")
	)
	(gr_line
		(start 426.566838 -7.709154)
		(end 426.566838 -8.320024)
		(stroke
			(width 0.06477)
			(type default)
		)
		(layer "F.Cu")
	)
	(gr_line
		(start 426.6692 -17.357598)
		(end 426.964856 -17.061942)
		(stroke
			(width 0.06477)
			(type default)
		)
		(layer "F.Cu")
	)
	(gr_line
		(start 426.695616 -19.13636)
		(end 426.966126 -18.86585)
		(stroke
			(width 0.06477)
			(type default)
		)
		(layer "F.Cu")
	)
	(gr_line
		(start 426.705522 -12.019788)
		(end 426.566838 -11.881104)
		(stroke
			(width 0.06477)
			(type default)
		)
		(layer "F.Cu")
	)
	(gr_line
		(start 426.705522 -7.57047)
		(end 426.566838 -7.709154)
		(stroke
			(width 0.06477)
			(type default)
		)
		(layer "F.Cu")
	)
	(gr_line
		(start 426.705522 -5.22859)
		(end 426.705522 -5.239258)
		(stroke
			(width 0.06477)
			(type default)
		)
		(layer "F.Cu")
	)
	(gr_line
		(start 426.90542 -388.742428)
		(end 426.63491 -388.471918)
		(stroke
			(width 0.06477)
			(type default)
		)
		(layer "F.Cu")
	)
	(gr_line
		(start 426.90542 -387.878828)
		(end 426.63491 -388.149338)
		(stroke
			(width 0.06477)
			(type default)
		)
		(layer "F.Cu")
	)
	(gr_line
		(start 426.90542 -385.338828)
		(end 426.63491 -385.068318)
		(stroke
			(width 0.06477)
			(type default)
		)
		(layer "F.Cu")
	)
	(gr_line
		(start 426.90542 -384.475228)
		(end 426.63491 -384.745738)
		(stroke
			(width 0.06477)
			(type default)
		)
		(layer "F.Cu")
	)
	(gr_line
		(start 426.964856 -18.186654)
		(end 426.6692 -17.890998)
		(stroke
			(width 0.06477)
			(type default)
		)
		(layer "F.Cu")
	)
	(gr_line
		(start 427.028102 -7.57047)
		(end 427.16704 -7.709408)
		(stroke
			(width 0.06477)
			(type default)
		)
		(layer "F.Cu")
	)
	(gr_line
		(start 427.166786 -11.881104)
		(end 427.028102 -12.019788)
		(stroke
			(width 0.06477)
			(type default)
		)
		(layer "F.Cu")
	)
	(gr_line
		(start 427.166786 -11.26998)
		(end 427.166786 -11.881104)
		(stroke
			(width 0.06477)
			(type default)
		)
		(layer "F.Cu")
	)
	(gr_line
		(start 427.166786 -7.709662)
		(end 427.166786 -8.320024)
		(stroke
			(width 0.06477)
			(type default)
		)
		(layer "F.Cu")
	)
	(gr_line
		(start 427.16704 -7.709408)
		(end 427.166786 -7.709662)
		(stroke
			(width 0.06477)
			(type default)
		)
		(layer "F.Cu")
	)
	(gr_line
		(start 427.288706 -18.86585)
		(end 427.559216 -19.13636)
		(stroke
			(width 0.06477)
			(type default)
		)
		(layer "F.Cu")
	)
	(gr_line
		(start 427.288706 -18.185892)
		(end 427.288706 -18.187924)
		(stroke
			(width 0.06477)
			(type default)
		)
		(layer "F.Cu")
	)
	(gr_line
		(start 427.288706 -17.062704)
		(end 427.5836 -17.357598)
		(stroke
			(width 0.06477)
			(type default)
		)
		(layer "F.Cu")
	)
	(gr_line
		(start 427.288706 -17.060672)
		(end 427.288706 -17.062704)
		(stroke
			(width 0.06477)
			(type default)
		)
		(layer "F.Cu")
	)
	(gr_line
		(start 427.303946 -4.963414)
		(end 427.029372 -5.237988)
		(stroke
			(width 0.06477)
			(type default)
		)
		(layer "F.Cu")
	)
	(gr_line
		(start 427.5836 -17.890998)
		(end 427.288706 -18.185892)
		(stroke
			(width 0.06477)
			(type default)
		)
		(layer "F.Cu")
	)
	(gr_line
		(start 428.235618 -6.725158)
		(end 428.50562 -6.99516)
		(stroke
			(width 0.06477)
			(type default)
		)
		(layer "F.Cu")
	)
	(gr_line
		(start 428.366936 -11.881104)
		(end 428.366936 -11.26998)
		(stroke
			(width 0.06477)
			(type default)
		)
		(layer "F.Cu")
	)
	(gr_line
		(start 428.366936 -7.709154)
		(end 428.366936 -8.320024)
		(stroke
			(width 0.06477)
			(type default)
		)
		(layer "F.Cu")
	)
	(gr_line
		(start 428.50562 -12.019788)
		(end 428.366936 -11.881104)
		(stroke
			(width 0.06477)
			(type default)
		)
		(layer "F.Cu")
	)
	(gr_line
		(start 428.50562 -7.57047)
		(end 428.366936 -7.709154)
		(stroke
			(width 0.06477)
			(type default)
		)
		(layer "F.Cu")
	)
	(gr_line
		(start 428.50562 -6.99516)
		(end 428.50562 -6.996176)
		(stroke
			(width 0.06477)
			(type default)
		)
		(layer "F.Cu")
	)
	(gr_line
		(start 428.8282 -7.57047)
		(end 428.966884 -7.709154)
		(stroke
			(width 0.06477)
			(type default)
		)
		(layer "F.Cu")
	)
	(gr_line
		(start 428.966884 -11.881104)
		(end 428.8282 -12.019788)
		(stroke
			(width 0.06477)
			(type default)
		)
		(layer "F.Cu")
	)
	(gr_line
		(start 428.966884 -11.26998)
		(end 428.966884 -11.881104)
		(stroke
			(width 0.06477)
			(type default)
		)
		(layer "F.Cu")
	)
	(gr_line
		(start 428.966884 -7.709154)
		(end 428.966884 -8.320024)
		(stroke
			(width 0.06477)
			(type default)
		)
		(layer "F.Cu")
	)
	(gr_line
		(start 429.099218 -6.725158)
		(end 428.829216 -6.99516)
		(stroke
			(width 0.06477)
			(type default)
		)
		(layer "F.Cu")
	)
	(gr_line
		(start 429.4632 -15.833598)
		(end 429.758856 -15.537942)
		(stroke
			(width 0.06477)
			(type default)
		)
		(layer "F.Cu")
	)
	(gr_line
		(start 429.4886 -17.613122)
		(end 429.75911 -17.342612)
		(stroke
			(width 0.06477)
			(type default)
		)
		(layer "F.Cu")
	)
	(gr_line
		(start 429.75911 -16.662908)
		(end 429.4632 -16.366998)
		(stroke
			(width 0.06477)
			(type default)
		)
		(layer "F.Cu")
	)
	(gr_line
		(start 430.040288 -4.963414)
		(end 430.305718 -5.228844)
		(stroke
			(width 0.06477)
			(type default)
		)
		(layer "F.Cu")
	)
	(gr_line
		(start 430.08169 -17.342612)
		(end 430.3522 -17.613122)
		(stroke
			(width 0.06477)
			(type default)
		)
		(layer "F.Cu")
	)
	(gr_line
		(start 430.082706 -15.538704)
		(end 430.3776 -15.833598)
		(stroke
			(width 0.06477)
			(type default)
		)
		(layer "F.Cu")
	)
	(gr_line
		(start 430.082706 -15.536672)
		(end 430.082706 -15.538704)
		(stroke
			(width 0.06477)
			(type default)
		)
		(layer "F.Cu")
	)
	(gr_line
		(start 430.16678 -11.881104)
		(end 430.16678 -11.26998)
		(stroke
			(width 0.06477)
			(type default)
		)
		(layer "F.Cu")
	)
	(gr_line
		(start 430.16678 -7.709408)
		(end 430.16678 -8.320024)
		(stroke
			(width 0.06477)
			(type default)
		)
		(layer "F.Cu")
	)
	(gr_line
		(start 430.305464 -12.019788)
		(end 430.16678 -11.881104)
		(stroke
			(width 0.06477)
			(type default)
		)
		(layer "F.Cu")
	)
	(gr_line
		(start 430.305718 -7.57047)
		(end 430.16678 -7.709408)
		(stroke
			(width 0.06477)
			(type default)
		)
		(layer "F.Cu")
	)
	(gr_line
		(start 430.305718 -5.228844)
		(end 430.305718 -5.239004)
		(stroke
			(width 0.06477)
			(type default)
		)
		(layer "F.Cu")
	)
	(gr_line
		(start 430.3776 -16.366998)
		(end 430.08169 -16.662908)
		(stroke
			(width 0.06477)
			(type default)
		)
		(layer "F.Cu")
	)
	(gr_line
		(start 430.628298 -7.57047)
		(end 430.767236 -7.709408)
		(stroke
			(width 0.06477)
			(type default)
		)
		(layer "F.Cu")
	)
	(gr_line
		(start 430.766982 -11.88085)
		(end 430.628044 -12.019788)
		(stroke
			(width 0.06477)
			(type default)
		)
		(layer "F.Cu")
	)
	(gr_line
		(start 430.766982 -11.26998)
		(end 430.766982 -11.88085)
		(stroke
			(width 0.06477)
			(type default)
		)
		(layer "F.Cu")
	)
	(gr_line
		(start 430.766982 -7.709662)
		(end 430.766982 -8.320024)
		(stroke
			(width 0.06477)
			(type default)
		)
		(layer "F.Cu")
	)
	(gr_line
		(start 430.767236 -7.709408)
		(end 430.766982 -7.709662)
		(stroke
			(width 0.06477)
			(type default)
		)
		(layer "F.Cu")
	)
	(gr_line
		(start 430.903888 -4.963414)
		(end 430.629568 -5.237734)
		(stroke
			(width 0.06477)
			(type default)
		)
		(layer "F.Cu")
	)
	(gr_line
		(start 431.834544 -12.864846)
		(end 432.104546 -12.594844)
		(stroke
			(width 0.06477)
			(type default)
		)
		(layer "F.Cu")
	)
	(gr_line
		(start 431.846482 -6.73227)
		(end 432.096926 -6.982714)
		(stroke
			(width 0.06477)
			(type default)
		)
		(layer "F.Cu")
	)
	(gr_line
		(start 431.966878 -11.814048)
		(end 431.966878 -11.26998)
		(stroke
			(width 0.06477)
			(type default)
		)
		(layer "F.Cu")
	)
	(gr_line
		(start 431.966878 -7.755128)
		(end 431.966878 -8.320024)
		(stroke
			(width 0.06477)
			(type default)
		)
		(layer "F.Cu")
	)
	(gr_line
		(start 432.096926 -7.62508)
		(end 431.966878 -7.755128)
		(stroke
			(width 0.06477)
			(type default)
		)
		(layer "F.Cu")
	)
	(gr_line
		(start 432.096926 -7.624572)
		(end 432.096926 -7.62508)
		(stroke
			(width 0.06477)
			(type default)
		)
		(layer "F.Cu")
	)
	(gr_line
		(start 432.096926 -6.982714)
		(end 432.096926 -7.022846)
		(stroke
			(width 0.06477)
			(type default)
		)
		(layer "F.Cu")
	)
	(gr_line
		(start 432.105562 -11.984228)
		(end 432.105562 -11.952732)
		(stroke
			(width 0.06477)
			(type default)
		)
		(layer "F.Cu")
	)
	(gr_line
		(start 432.105562 -11.952732)
		(end 431.966878 -11.814048)
		(stroke
			(width 0.06477)
			(type default)
		)
		(layer "F.Cu")
	)
	(gr_line
		(start 432.221894 -163.716716)
		(end 432.555904 -163.382706)
		(stroke
			(width 0.06477)
			(type default)
		)
		(layer "F.Cu")
	)
	(gr_line
		(start 432.2572 -17.357598)
		(end 432.55311 -17.061688)
		(stroke
			(width 0.06477)
			(type default)
		)
		(layer "F.Cu")
	)
	(gr_line
		(start 432.283616 -19.13636)
		(end 432.554126 -18.86585)
		(stroke
			(width 0.06477)
			(type default)
		)
		(layer "F.Cu")
	)
	(gr_line
		(start 432.420776 -7.021576)
		(end 432.710082 -6.73227)
		(stroke
			(width 0.06477)
			(type default)
		)
		(layer "F.Cu")
	)
	(gr_line
		(start 432.428142 -12.594844)
		(end 432.428142 -12.593828)
		(stroke
			(width 0.06477)
			(type default)
		)
		(layer "F.Cu")
	)
	(gr_line
		(start 432.429412 -11.982958)
		(end 432.566826 -11.845544)
		(stroke
			(width 0.06477)
			(type default)
		)
		(layer "F.Cu")
	)
	(gr_line
		(start 432.552856 -18.186654)
		(end 432.2572 -17.890998)
		(stroke
			(width 0.06477)
			(type default)
		)
		(layer "F.Cu")
	)
	(gr_line
		(start 432.566826 -11.845544)
		(end 432.566826 -11.26998)
		(stroke
			(width 0.06477)
			(type default)
		)
		(layer "F.Cu")
	)
	(gr_line
		(start 432.566826 -8.320024)
		(end 432.566826 -7.771892)
		(stroke
			(width 0.06477)
			(type default)
		)
		(layer "F.Cu")
	)
	(gr_line
		(start 432.566826 -7.771892)
		(end 432.420014 -7.62508)
		(stroke
			(width 0.06477)
			(type default)
		)
		(layer "F.Cu")
	)
	(gr_line
		(start 432.698144 -12.864846)
		(end 432.428142 -12.594844)
		(stroke
			(width 0.06477)
			(type default)
		)
		(layer "F.Cu")
	)
	(gr_line
		(start 432.87569 -17.061688)
		(end 433.1716 -17.357598)
		(stroke
			(width 0.06477)
			(type default)
		)
		(layer "F.Cu")
	)
	(gr_line
		(start 432.876706 -18.86585)
		(end 433.147216 -19.13636)
		(stroke
			(width 0.06477)
			(type default)
		)
		(layer "F.Cu")
	)
	(gr_line
		(start 432.876706 -18.185892)
		(end 432.876706 -18.187924)
		(stroke
			(width 0.06477)
			(type default)
		)
		(layer "F.Cu")
	)
	(gr_line
		(start 432.878484 -163.382706)
		(end 433.212494 -163.716716)
		(stroke
			(width 0.06477)
			(type default)
		)
		(layer "F.Cu")
	)
	(gr_line
		(start 433.1716 -17.890998)
		(end 432.876706 -18.185892)
		(stroke
			(width 0.06477)
			(type default)
		)
		(layer "F.Cu")
	)
	(gr_line
		(start 439.95975 5.899912)
		(end 439.307478 5.718048)
		(stroke
			(width 0.06477)
			(type default)
		)
		(layer "F.Cu")
	)
	(gr_line
		(start 439.95975 6.399784)
		(end 439.307478 6.581648)
		(stroke
			(width 0.06477)
			(type default)
		)
		(layer "F.Cu")
	)
	(gr_line
		(start 445.82969 -12.864846)
		(end 446.099692 -12.594844)
		(stroke
			(width 0.06477)
			(type default)
		)
		(layer "F.Cu")
	)
	(gr_line
		(start 445.830452 -6.725158)
		(end 446.100708 -6.995414)
		(stroke
			(width 0.06477)
			(type default)
		)
		(layer "F.Cu")
	)
	(gr_line
		(start 445.96177 -11.840464)
		(end 445.96177 -11.26998)
		(stroke
			(width 0.06477)
			(type default)
		)
		(layer "F.Cu")
	)
	(gr_line
		(start 445.96177 -7.707122)
		(end 445.96177 -8.320024)
		(stroke
			(width 0.06477)
			(type default)
		)
		(layer "F.Cu")
	)
	(gr_line
		(start 446.100708 -11.985498)
		(end 446.100708 -11.979402)
		(stroke
			(width 0.06477)
			(type default)
		)
		(layer "F.Cu")
	)
	(gr_line
		(start 446.100708 -11.979402)
		(end 445.96177 -11.840464)
		(stroke
			(width 0.06477)
			(type default)
		)
		(layer "F.Cu")
	)
	(gr_line
		(start 446.100708 -7.568184)
		(end 445.96177 -7.707122)
		(stroke
			(width 0.06477)
			(type default)
		)
		(layer "F.Cu")
	)
	(gr_line
		(start 446.100708 -7.567168)
		(end 446.100708 -7.568184)
		(stroke
			(width 0.06477)
			(type default)
		)
		(layer "F.Cu")
	)
	(gr_line
		(start 446.100708 -6.995414)
		(end 446.100708 -6.995922)
		(stroke
			(width 0.06477)
			(type default)
		)
		(layer "F.Cu")
	)
	(gr_line
		(start 446.423288 -12.594844)
		(end 446.69329 -12.864846)
		(stroke
			(width 0.06477)
			(type default)
		)
		(layer "F.Cu")
	)
	(gr_line
		(start 446.423288 -12.593828)
		(end 446.423288 -12.594844)
		(stroke
			(width 0.06477)
			(type default)
		)
		(layer "F.Cu")
	)
	(gr_line
		(start 446.423796 -6.995414)
		(end 446.694052 -6.725158)
		(stroke
			(width 0.06477)
			(type default)
		)
		(layer "F.Cu")
	)
	(gr_line
		(start 446.561972 -11.846814)
		(end 446.424558 -11.984228)
		(stroke
			(width 0.06477)
			(type default)
		)
		(layer "F.Cu")
	)
	(gr_line
		(start 446.561972 -11.26998)
		(end 446.561972 -11.846814)
		(stroke
			(width 0.06477)
			(type default)
		)
		(layer "F.Cu")
	)
	(gr_line
		(start 446.561972 -8.320024)
		(end 446.561972 -7.705852)
		(stroke
			(width 0.06477)
			(type default)
		)
		(layer "F.Cu")
	)
	(gr_line
		(start 446.561972 -7.705852)
		(end 446.424304 -7.568184)
		(stroke
			(width 0.06477)
			(type default)
		)
		(layer "F.Cu")
	)
	(gr_poly
		(pts
			(xy 126.348236 -30.24759) (xy 126.348236 -26.767282) (xy 122.571764 -26.767282) (xy 122.571764 -30.942026)
			(xy 125.6538 -30.942026)
		)
		(stroke
			(width 0)
			(type solid)
		)
		(fill yes)
		(layer "B.Cu")
		(net "GND")
	)
	(gr_poly
		(pts
			(xy 16.952468 -135.121904) (xy 16.952468 -133.096) (xy 16.762222 -132.905754) (xy 15.333726 -132.905754)
			(xy 15.188692 -133.050788) (xy 15.188692 -135.326374) (xy 15.223236 -135.360918) (xy 16.713454 -135.360918)
		)
		(stroke
			(width 0)
			(type solid)
		)
		(fill yes)
		(layer "B.Cu")
		(net "VFG_3P3A_CLK_GEN")
	)
	(gr_poly
		(pts
			(xy 18.005552 -424.623992) (xy 18.005552 -421.99179) (xy 17.73936 -421.725598) (xy 15.461742 -421.725598)
			(xy 15.216378 -421.970962) (xy 15.216378 -424.43527) (xy 15.48892 -424.707812) (xy 17.921732 -424.707812)
		)
		(stroke
			(width 0)
			(type solid)
		)
		(fill yes)
		(layer "B.Cu")
		(net "GND")
	)
	(gr_poly
		(pts
			(xy 20.12188 -96.957388) (xy 20.12188 -95.992188) (xy 19.99488 -95.865188) (xy 18.67408 -95.865188)
			(xy 18.57248 -95.966788) (xy 18.57248 -97.135188) (xy 18.59788 -97.160588) (xy 19.91868 -97.160588)
		)
		(stroke
			(width 0)
			(type solid)
		)
		(fill yes)
		(layer "B.Cu")
		(net "P3V3_AUX")
	)
	(gr_poly
		(pts
			(xy 34.79419 -426.906182) (xy 34.79419 -422.308782) (xy 34.59099 -422.105582) (xy 33.87979 -422.105582)
			(xy 33.60039 -422.384982) (xy 33.60039 -426.982382) (xy 33.82899 -427.210982) (xy 34.48939 -427.210982)
		)
		(stroke
			(width 0)
			(type solid)
		)
		(fill yes)
		(layer "B.Cu")
		(net "GND")
	)
	(gr_poly
		(pts
			(xy 64.911224 -10.16) (xy 64.911224 -9.26465) (xy 64.831214 -9.18464) (xy 60.177934 -9.18464) (xy 59.490864 -9.87171)
			(xy 59.490864 -10.1727) (xy 59.755024 -10.43686) (xy 64.634364 -10.43686)
		)
		(stroke
			(width 0)
			(type solid)
		)
		(fill yes)
		(layer "B.Cu")
		(net "P3V3_OCP_V3_2")
	)
	(gr_poly
		(pts
			(xy 133.88594 -80.021176) (xy 133.88594 -71.039736) (xy 133.83514 -70.988936) (xy 130.322828 -70.988936)
			(xy 130.272028 -71.039736) (xy 130.272028 -80.021176) (xy 130.322828 -80.071976) (xy 133.83514 -80.071976)
		)
		(stroke
			(width 0)
			(type solid)
		)
		(fill yes)
		(layer "B.Cu")
		(net "P1V2_AUX")
	)
	(gr_poly
		(pts
			(xy 138.646662 -75.673712) (xy 138.646662 -73.211182) (xy 138.583162 -73.147682) (xy 137.43305 -73.147682)
			(xy 137.36955 -73.211182) (xy 137.36955 -75.710542) (xy 137.544302 -75.885294) (xy 138.43508 -75.885294)
		)
		(stroke
			(width 0)
			(type solid)
		)
		(fill yes)
		(layer "B.Cu")
		(net "P12V_AUX")
	)
	(gr_poly
		(pts
			(xy 155.98394 -82.307176) (xy 155.98394 -74.63536) (xy 154.623516 -73.274936) (xy 152.420828 -73.274936)
			(xy 152.370028 -73.325736) (xy 152.370028 -82.307176) (xy 152.420828 -82.357976) (xy 155.93314 -82.357976)
		)
		(stroke
			(width 0)
			(type solid)
		)
		(fill yes)
		(layer "B.Cu")
		(net "P1V8_AUX")
	)
	(gr_poly
		(pts
			(xy 182.428642 -364.105952) (xy 182.428642 -359.152952) (xy 182.174642 -358.898952) (xy 180.142642 -358.898952)
			(xy 179.888642 -359.152952) (xy 179.888642 -364.105952) (xy 180.015642 -364.232952) (xy 182.301642 -364.232952)
		)
		(stroke
			(width 0)
			(type solid)
		)
		(fill yes)
		(layer "B.Cu")
		(net "P12V_AUX")
	)
	(gr_poly
		(pts
			(xy 185.6994 -111.2012) (xy 185.6994 -110.8964) (xy 185.5978 -110.7948) (xy 184.7088 -110.7948) (xy 184.5818 -110.9218)
			(xy 184.5818 -111.125) (xy 184.7596 -111.3028) (xy 185.5978 -111.3028)
		)
		(stroke
			(width 0)
			(type solid)
		)
		(fill yes)
		(layer "B.Cu")
		(net "PVDD11_S3_P0_PMALERT")
	)
	(gr_poly
		(pts
			(xy 202.0189 -346.7481) (xy 202.0189 -343.9287) (xy 201.549 -343.4588) (xy 200.4314 -343.4588) (xy 200.2663 -343.6239)
			(xy 200.2663 -346.6973) (xy 200.4314 -346.8624) (xy 201.9046 -346.8624)
		)
		(stroke
			(width 0)
			(type solid)
		)
		(fill yes)
		(layer "B.Cu")
		(net "SW_P12V_AUX_PVDD_33_S5_FLT")
	)
	(gr_poly
		(pts
			(xy 210.271614 -35.535108) (xy 210.271614 -34.016188) (xy 210.192874 -33.937448) (xy 208.442814 -33.937448)
			(xy 208.306416 -34.073846) (xy 208.306416 -35.622484) (xy 208.364074 -35.679888) (xy 210.126834 -35.679888)
		)
		(stroke
			(width 0)
			(type solid)
		)
		(fill yes)
		(layer "B.Cu")
		(net "GND")
	)
	(gr_poly
		(pts
			(xy 212.738716 -324.672452) (xy 212.738716 -323.505322) (xy 212.657436 -323.424042) (xy 211.1248 -323.424042)
			(xy 211.031836 -323.517006) (xy 211.031836 -324.620128) (xy 211.118958 -324.70725) (xy 212.703918 -324.70725)
		)
		(stroke
			(width 0)
			(type solid)
		)
		(fill yes)
		(layer "B.Cu")
		(net "P3V3_AUX")
	)
	(gr_poly
		(pts
			(xy 216.052654 -55.982108) (xy 216.052654 -52.931568) (xy 215.935814 -52.814728) (xy 214.828374 -52.814728)
			(xy 214.493094 -53.150008) (xy 214.493094 -56.162448) (xy 214.637874 -56.307228) (xy 215.727534 -56.307228)
		)
		(stroke
			(width 0)
			(type solid)
		)
		(fill yes)
		(layer "B.Cu")
		(net "GND")
	)
	(gr_poly
		(pts
			(xy 244.3734 -383.6416) (xy 244.3734 -383.1336) (xy 244.2972 -383.0574) (xy 242.9764 -383.0574) (xy 242.82908 -383.20472)
			(xy 242.82908 -383.69748) (xy 242.9002 -383.7686) (xy 244.2464 -383.7686)
		)
		(stroke
			(width 0)
			(type solid)
		)
		(fill yes)
		(layer "B.Cu")
		(net "P12V_HSC_GATE_RC")
	)
	(gr_poly
		(pts
			(xy 291.70249 -364.352332) (xy 291.70249 -361.217972) (xy 291.445696 -360.961178) (xy 285.129732 -360.961178)
			(xy 284.697932 -361.392978) (xy 284.697932 -364.272576) (xy 285.110428 -364.685072) (xy 291.36975 -364.685072)
		)
		(stroke
			(width 0)
			(type solid)
		)
		(fill yes)
		(layer "B.Cu")
		(net "P12V_AUX")
	)
	(gr_poly
		(pts
			(xy 332.761336 -133.729476) (xy 332.761336 -132.832856) (xy 332.523084 -132.594604) (xy 331.133196 -132.594604)
			(xy 330.52893 -133.19887) (xy 330.52893 -133.638036) (xy 330.730098 -133.839204) (xy 332.651608 -133.839204)
		)
		(stroke
			(width 0)
			(type solid)
		)
		(fill yes)
		(layer "B.Cu")
		(net "P12V_AUX")
	)
	(gr_poly
		(pts
			(xy 422.28897 -155.650692) (xy 422.28897 -151.983186) (xy 422.051734 -151.74595) (xy 408.044396 -151.74595)
			(xy 407.90622 -151.884126) (xy 407.90622 -155.699968) (xy 408.163014 -155.956762) (xy 421.9829 -155.956762)
		)
		(stroke
			(width 0)
			(type solid)
		)
		(fill yes)
		(layer "B.Cu")
		(net "P5V_AUX")
	)
	(gr_poly
		(pts
			(xy 435.327044 -13.514832) (xy 435.327044 -9.933432) (xy 435.225444 -9.831832) (xy 434.184044 -9.831832)
			(xy 433.803044 -10.212832) (xy 433.803044 -13.489432) (xy 433.980844 -13.667232) (xy 435.174644 -13.667232)
		)
		(stroke
			(width 0)
			(type solid)
		)
		(fill yes)
		(layer "B.Cu")
		(net "P3V3_OCP_SFF")
	)
	(gr_poly
		(pts
			(xy 443.730634 -77.980286) (xy 443.730634 -73.599294) (xy 443.6364 -73.50506) (xy 438.5945 -73.50506)
			(xy 438.23636 -73.8632) (xy 438.23636 -77.65288) (xy 438.6707 -78.08722) (xy 443.6237 -78.08722)
		)
		(stroke
			(width 0)
			(type solid)
		)
		(fill yes)
		(layer "B.Cu")
		(net "P3V3")
	)
	(gr_poly
		(pts
			(xy 174.930054 -26.741628) (xy 174.930054 -22.799548) (xy 174.873158 -22.742652) (xy 173.26102 -22.742652)
			(xy 172.776134 -23.227538) (xy 172.776134 -25.827228) (xy 172.900594 -25.951688) (xy 173.863254 -26.914348)
			(xy 174.757334 -26.914348)
		)
		(stroke
			(width 0)
			(type solid)
		)
		(fill yes)
		(layer "B.Cu")
		(net "GND")
	)
	(gr_poly
		(pts
			(xy 247.439434 -56.024526) (xy 247.439434 -54.627526) (xy 247.076214 -54.264306) (xy 245.28018 -54.264306)
			(xy 245.16842 -54.376066) (xy 245.16842 -56.117236) (xy 245.31193 -56.260746) (xy 246.639334 -56.260746)
			(xy 247.203214 -56.260746)
		)
		(stroke
			(width 0)
			(type solid)
		)
		(fill yes)
		(layer "B.Cu")
		(net "GND")
	)
	(gr_poly
		(pts
			(xy 106.222546 -27.4828) (xy 106.222546 -26.394918) (xy 106.220514 -26.392886) (xy 106.220514 -26.185114)
			(xy 106.0958 -26.0604) (xy 103.9114 -26.0604) (xy 103.7082 -26.2636) (xy 103.7082 -27.3812) (xy 103.8606 -27.5336)
			(xy 106.171746 -27.5336)
		)
		(stroke
			(width 0)
			(type solid)
		)
		(fill yes)
		(layer "B.Cu")
		(net "P3V3_AUX")
	)
	(gr_poly
		(pts
			(xy 116.264182 -73.54697) (xy 116.358162 -73.45299) (xy 116.398802 -73.41235) (xy 116.398802 -70.94982)
			(xy 116.335302 -70.88632) (xy 115.26139 -70.88632) (xy 115.19789 -70.94982) (xy 115.19789 -73.44918)
			(xy 115.372642 -73.623932) (xy 116.18722 -73.623932)
		)
		(stroke
			(width 0)
			(type solid)
		)
		(fill yes)
		(layer "B.Cu")
		(net "P12V_AUX")
	)
	(gr_poly
		(pts
			(xy 132.43052 -42.799) (xy 132.43052 -42.6847) (xy 131.858258 -42.112438) (xy 131.858258 -41.1734)
			(xy 131.81965 -41.134792) (xy 130.264408 -41.134792) (xy 130.17754 -41.22166) (xy 130.17754 -41.53154)
			(xy 131.6228 -42.9768) (xy 132.25272 -42.9768)
		)
		(stroke
			(width 0)
			(type solid)
		)
		(fill yes)
		(layer "B.Cu")
		(net "P3V3_AUX")
	)
	(gr_poly
		(pts
			(xy 132.49275 -151.632412) (xy 135.913876 -151.632412) (xy 136.056878 -151.48941) (xy 136.056878 -150.60041)
			(xy 135.81888 -150.362412) (xy 130.721354 -150.362412) (xy 130.391154 -150.692612) (xy 130.391154 -152.242012)
			(xy 130.518154 -152.369012) (xy 131.75615 -152.369012)
		)
		(stroke
			(width 0)
			(type solid)
		)
		(fill yes)
		(layer "B.Cu")
		(net "GND")
	)
	(gr_poly
		(pts
			(xy 169.603674 -53.579268) (xy 169.603674 -50.843688) (xy 169.814494 -50.632868) (xy 169.814494 -49.530508)
			(xy 169.585894 -49.301908) (xy 167.952674 -49.301908) (xy 167.259254 -49.995328) (xy 167.259254 -53.670708)
			(xy 167.614854 -54.026308) (xy 169.156634 -54.026308)
		)
		(stroke
			(width 0)
			(type solid)
		)
		(fill yes)
		(layer "B.Cu")
		(net "P3V3_M2_0")
	)
	(gr_poly
		(pts
			(xy 205.509114 -330.641452) (xy 205.509114 -328.865992) (xy 205.509114 -327.281032) (xy 205.272894 -327.044812)
			(xy 197.470014 -327.044812) (xy 197.155054 -327.359772) (xy 197.155054 -328.873612) (xy 197.155054 -330.712572)
			(xy 197.269354 -330.826872) (xy 205.323694 -330.826872)
		)
		(stroke
			(width 0)
			(type solid)
		)
		(fill yes)
		(layer "B.Cu")
		(net "PVDD_33_S5")
	)
	(gr_poly
		(pts
			(xy 235.142024 -315.606938) (xy 235.142024 -309.856124) (xy 234.312206 -309.026306) (xy 233.533188 -309.026306)
			(xy 223.3803 -309.026306) (xy 222.313754 -310.092852) (xy 222.313754 -315.649356) (xy 222.43034 -315.765942)
			(xy 234.047284 -315.765942) (xy 234.98302 -315.765942)
		)
		(stroke
			(width 0)
			(type solid)
		)
		(fill yes)
		(layer "B.Cu")
		(net "P1V8_CPU1_RT_1D")
	)
	(gr_poly
		(pts
			(xy 249.074178 -315.60008) (xy 249.074178 -310.016652) (xy 248.140982 -309.083456) (xy 238.312706 -309.083456)
			(xy 237.41761 -309.978552) (xy 237.383574 -309.978552) (xy 237.383574 -315.708284) (xy 237.440978 -315.765942)
			(xy 247.9802 -315.765942) (xy 248.908316 -315.765942)
		)
		(stroke
			(width 0)
			(type solid)
		)
		(fill yes)
		(layer "B.Cu")
		(net "P1V8_CPU0_RT_1D")
	)
	(gr_poly
		(pts
			(xy 405.41448 -151.11603) (xy 405.41448 -147.112482) (xy 404.91918 -146.617182) (xy 400.244564 -146.617182)
			(xy 396.663164 -146.617182) (xy 396.282164 -146.998182) (xy 396.282164 -149.614382) (xy 396.282164 -150.900892)
			(xy 396.752064 -151.370792) (xy 405.159718 -151.370792)
		)
		(stroke
			(width 0)
			(type solid)
		)
		(fill yes)
		(layer "B.Cu")
		(net "P5V")
	)
	(gr_poly
		(pts
			(xy 443.940438 -362.998512) (xy 443.940438 -357.886) (xy 443.813438 -357.759) (xy 439.964068 -357.759)
			(xy 439.837068 -357.886) (xy 439.837068 -358.101138) (xy 439.837068 -363.054138) (xy 440.091068 -363.308138)
			(xy 442.123068 -363.308138) (xy 443.630812 -363.308138)
		)
		(stroke
			(width 0)
			(type solid)
		)
		(fill yes)
		(layer "B.Cu")
		(net "P12V_AUX")
	)
	(gr_poly
		(pts
			(xy 460.911956 -181.840124) (xy 460.911956 -179.937918) (xy 460.911956 -176.78781) (xy 460.800196 -176.67605)
			(xy 456.92441 -176.67605) (xy 456.5396 -177.06086) (xy 456.5396 -179.856892) (xy 456.5396 -180.17744)
			(xy 458.52334 -182.16118) (xy 460.5909 -182.16118)
		)
		(stroke
			(width 0)
			(type solid)
		)
		(fill yes)
		(layer "B.Cu")
		(net "P12V_AUX")
	)
	(gr_poly
		(pts
			(xy 10.696448 -137.66419) (xy 10.696448 -135.95731) (xy 9.766808 -135.02767) (xy 9.52246 -134.783322)
			(xy 9.52246 -134.008622) (xy 9.450324 -133.936486) (xy 9.074912 -133.936486) (xy 8.943594 -134.067804)
			(xy 8.943594 -137.519156) (xy 9.256268 -137.83183) (xy 10.528808 -137.83183)
		)
		(stroke
			(width 0)
			(type solid)
		)
		(fill yes)
		(layer "B.Cu")
		(net "GND")
	)
	(gr_poly
		(pts
			(xy 17.015968 -412.607252) (xy 17.015968 -412.143194) (xy 17.015968 -408.536394) (xy 16.859758 -408.380184)
			(xy 13.536168 -408.380184) (xy 13.358368 -408.557984) (xy 13.358368 -409.123388) (xy 13.358368 -412.137606)
			(xy 13.358368 -412.713424) (xy 13.546582 -412.901638) (xy 16.721582 -412.901638)
		)
		(stroke
			(width 0)
			(type solid)
		)
		(fill yes)
		(layer "B.Cu")
		(net "GND")
	)
	(gr_poly
		(pts
			(xy 108.12018 -33.9852) (xy 109.2454 -33.9852) (xy 109.423454 -33.807146) (xy 109.423454 -31.343854)
			(xy 109.3724 -31.2928) (xy 108.966 -31.2928) (xy 107.4674 -32.7914) (xy 107.4674 -33.8582) (xy 107.4674 -33.98266)
			(xy 107.60202 -34.11728) (xy 107.9881 -34.11728)
		)
		(stroke
			(width 0)
			(type solid)
		)
		(fill yes)
		(layer "B.Cu")
		(net "P3V3_AUX_CPU0_USB2_AVDD33")
	)
	(gr_poly
		(pts
			(xy 164.248084 -350.866202) (xy 164.248084 -347.88983) (xy 164.66693 -347.470984) (xy 164.66693 -347.080078)
			(xy 164.66693 -346.064078) (xy 164.38753 -345.784678) (xy 160.42513 -345.784678) (xy 160.04413 -346.165678)
			(xy 160.04413 -350.686878) (xy 160.37433 -351.017078) (xy 164.097208 -351.017078)
		)
		(stroke
			(width 0)
			(type solid)
		)
		(fill yes)
		(layer "B.Cu")
		(net "GND")
	)
	(gr_poly
		(pts
			(xy 279.32126 -392.0617) (xy 279.32126 -384.12928) (xy 279.07234 -383.88036) (xy 275.005292 -383.88036)
			(xy 274.751292 -384.13436) (xy 274.751292 -392.18616) (xy 274.802092 -392.23696) (xy 276.81174 -392.23696)
			(xy 277.4696 -392.23696) (xy 277.63216 -392.23696) (xy 279.146 -392.23696)
		)
		(stroke
			(width 0)
			(type solid)
		)
		(fill yes)
		(layer "B.Cu")
		(net "P12V_MAIN_R_0")
	)
	(gr_poly
		(pts
			(xy 312.415174 -362.617766) (xy 312.415174 -360.875834) (xy 312.415174 -359.598214) (xy 312.989468 -359.02392)
			(xy 312.989468 -358.356154) (xy 312.912252 -358.278938) (xy 308.323996 -358.278938) (xy 307.90642 -358.696514)
			(xy 307.90642 -362.726478) (xy 308.081426 -362.901484) (xy 312.131456 -362.901484)
		)
		(stroke
			(width 0)
			(type solid)
		)
		(fill yes)
		(layer "B.Cu")
		(net "GND")
	)
	(gr_poly
		(pts
			(xy 405.378158 -155.332684) (xy 405.378158 -154.905964) (xy 405.378158 -153.126694) (xy 404.980648 -152.729184)
			(xy 397.796004 -152.729184) (xy 395.852396 -152.729184) (xy 395.630654 -152.950926) (xy 395.630654 -155.000198)
			(xy 395.630654 -155.509976) (xy 395.772386 -155.651708) (xy 405.059134 -155.651708)
		)
		(stroke
			(width 0)
			(type solid)
		)
		(fill yes)
		(layer "B.Cu")
		(net "VR_P5V_EN_D")
	)
	(gr_poly
		(pts
			(xy 410.157676 -135.123428) (xy 410.157676 -132.890514) (xy 410.098494 -132.831332) (xy 409.796488 -132.831332)
			(xy 408.652472 -132.831332) (xy 408.531314 -132.95249) (xy 408.481784 -133.00202) (xy 408.481784 -134.191502)
			(xy 408.478736 -134.19455) (xy 409.521914 -135.237728) (xy 410.043376 -135.237728)
		)
		(stroke
			(width 0)
			(type solid)
		)
		(fill yes)
		(layer "B.Cu")
		(net "P12V_AUX")
	)
	(gr_poly
		(pts
			(xy 446.152016 -425.66971) (xy 446.152016 -425.104306) (xy 446.152016 -422.090088) (xy 446.152016 -421.51427)
			(xy 445.963802 -421.326056) (xy 442.788802 -421.326056) (xy 442.494416 -421.620442) (xy 442.494416 -422.0845)
			(xy 442.494416 -425.6913) (xy 442.650626 -425.84751) (xy 445.974216 -425.84751)
		)
		(stroke
			(width 0)
			(type solid)
		)
		(fill yes)
		(layer "B.Cu")
		(net "GND")
	)
	(gr_poly
		(pts
			(xy 16.10868 -100.691188) (xy 16.10868 -97.338388) (xy 16.28648 -97.160588) (xy 17.91208 -97.160588)
			(xy 17.98828 -97.084388) (xy 17.98828 -96.322388) (xy 17.86128 -96.195388) (xy 12.65428 -96.195388)
			(xy 12.17168 -96.677988) (xy 12.17168 -100.741988) (xy 12.524232 -101.09454) (xy 15.705328 -101.09454)
		)
		(stroke
			(width 0)
			(type solid)
		)
		(fill yes)
		(layer "B.Cu")
		(net "GND")
	)
	(gr_poly
		(pts
			(xy 66.58864 -8.312912) (xy 66.58864 -7.33425) (xy 66.232786 -6.978396) (xy 63.274702 -6.978396)
			(xy 62.651894 -7.601204) (xy 61.673232 -7.601204) (xy 60.8838 -8.390636) (xy 60.249816 -8.390636)
			(xy 60.094114 -8.546338) (xy 60.094114 -8.846566) (xy 60.160916 -8.913368) (xy 65.988184 -8.913368)
		)
		(stroke
			(width 0)
			(type solid)
		)
		(fill yes)
		(layer "B.Cu")
		(net "GND")
	)
	(gr_poly
		(pts
			(xy 179.872894 -26.97734) (xy 179.872894 -25.527) (xy 179.55514 -25.209246) (xy 179.55514 -25.19426)
			(xy 179.2224 -24.86152) (xy 179.2224 -20.406868) (xy 178.51882 -19.703288) (xy 176.369472 -19.703288)
			(xy 175.344328 -20.728432) (xy 175.344328 -27.00782) (xy 175.664368 -27.32786) (xy 179.522374 -27.32786)
		)
		(stroke
			(width 0)
			(type solid)
		)
		(fill yes)
		(layer "B.Cu")
		(net "P12V_SCM_R")
	)
	(gr_poly
		(pts
			(xy 196.08292 -341.9602) (xy 196.08292 -333.32928) (xy 195.68668 -332.93304) (xy 195.039742 -332.93304)
			(xy 194.8053 -332.93304) (xy 175.753522 -332.93304) (xy 173.735746 -332.93304) (xy 170.756834 -335.911952)
			(xy 170.756834 -341.880952) (xy 171.021502 -342.14562) (xy 194.914266 -342.14562) (xy 195.8975 -342.14562)
		)
		(stroke
			(width 0)
			(type solid)
		)
		(fill yes)
		(layer "B.Cu")
		(net "PVDD11_S3_P1")
	)
	(gr_poly
		(pts
			(xy 245.04396 -382.08204) (xy 245.04396 -380.91872) (xy 244.94744 -380.8222) (xy 244.348 -380.8222)
			(xy 244.1956 -380.9746) (xy 244.1956 -381.635) (xy 243.6876 -382.143) (xy 242.9764 -382.143) (xy 242.83162 -382.28778)
			(xy 242.83162 -382.68402) (xy 242.951 -382.8034) (xy 244.3226 -382.8034)
		)
		(stroke
			(width 0)
			(type solid)
		)
		(fill yes)
		(layer "B.Cu")
		(net "P12V_HSC_GATE2")
	)
	(gr_poly
		(pts
			(xy 383.348738 -158.619952) (xy 383.348738 -151.891492) (xy 383.015998 -151.558752) (xy 381.857758 -151.558752)
			(xy 366.066578 -151.558752) (xy 365.695992 -151.929338) (xy 365.695992 -158.392876) (xy 365.814102 -158.510986)
			(xy 366.156748 -158.853632) (xy 371.636798 -158.853632) (xy 381.823976 -158.853632) (xy 383.115058 -158.853632)
		)
		(stroke
			(width 0)
			(type solid)
		)
		(fill yes)
		(layer "B.Cu")
		(net "P12V_AUX")
	)
	(gr_poly
		(pts
			(xy 441.045092 -43.578018) (xy 441.045092 -43.451018) (xy 441.045092 -38.853618) (xy 440.918092 -38.726618)
			(xy 434.288692 -38.726618) (xy 433.780692 -38.726618) (xy 433.628292 -38.879018) (xy 433.628292 -43.001946)
			(xy 433.628292 -43.618658) (xy 433.780692 -43.771058) (xy 438.893458 -43.771058) (xy 440.852052 -43.771058)
		)
		(stroke
			(width 0)
			(type solid)
		)
		(fill yes)
		(layer "B.Cu")
		(net "P12V_AUX")
	)
	(gr_poly
		(pts
			(xy 454.297034 -415.897568) (xy 454.297034 -415.688018) (xy 454.297034 -414.193228) (xy 454.109074 -414.005268)
			(xy 453.664828 -414.005268) (xy 449.753228 -414.005268) (xy 449.575428 -414.183068) (xy 449.403216 -414.35528)
			(xy 449.403216 -415.935414) (xy 449.527168 -416.059366) (xy 453.925686 -416.059366) (xy 454.135236 -416.059366)
		)
		(stroke
			(width 0)
			(type solid)
		)
		(fill yes)
		(layer "B.Cu")
		(net "P12V_AUX")
	)
	(gr_poly
		(pts
			(xy 127.128524 -31.748222) (xy 127.192024 -31.684722) (xy 127.192024 -30.833822) (xy 127.128524 -30.770322)
			(xy 126.303278 -30.770322) (xy 126.042674 -31.030926) (xy 125.7554 -31.3182) (xy 124.9172 -31.3182)
			(xy 124.7902 -31.4452) (xy 124.7902 -31.75) (xy 124.8918 -31.8516) (xy 125.222 -31.8516) (xy 127.025146 -31.8516)
		)
		(stroke
			(width 0)
			(type solid)
		)
		(fill yes)
		(layer "B.Cu")
		(net "GND")
	)
	(gr_poly
		(pts
			(xy 194.23634 -16.78686) (xy 194.23634 -16.110458) (xy 194.23634 -13.300202) (xy 193.393314 -12.457176)
			(xy 191.936624 -12.457176) (xy 191.644778 -12.749022) (xy 191.644778 -14.520418) (xy 191.644778 -14.783308)
			(xy 191.644778 -16.407384) (xy 192.034922 -16.797528) (xy 193.459608 -16.797528) (xy 193.53276 -16.87068)
			(xy 194.15252 -16.87068)
		)
		(stroke
			(width 0)
			(type solid)
		)
		(fill yes)
		(layer "B.Cu")
		(net "P12V_SCM")
	)
	(gr_poly
		(pts
			(xy 344.969846 -361.29214) (xy 345.425522 -360.836464) (xy 345.425522 -359.818178) (xy 345.425522 -357.408988)
			(xy 345.18346 -357.166926) (xy 335.54924 -357.166926) (xy 335.419446 -357.29672) (xy 335.419446 -361.12704)
			(xy 335.605374 -361.312968) (xy 335.610708 -361.318302) (xy 337.938872 -361.318302) (xy 343.925398 -361.318302)
			(xy 344.943684 -361.318302)
		)
		(stroke
			(width 0)
			(type solid)
		)
		(fill yes)
		(layer "B.Cu")
		(net "P12V_AUX")
	)
	(gr_poly
		(pts
			(xy 464.467956 -388.92861) (xy 464.467956 -380.846584) (xy 464.156552 -380.53518) (xy 462.047844 -380.53518)
			(xy 460.318358 -380.53518) (xy 439.173112 -380.53518) (xy 438.955434 -380.752858) (xy 438.955434 -386.816092)
			(xy 438.955434 -388.45744) (xy 439.506106 -389.008112) (xy 439.60288 -389.104886) (xy 445.454532 -389.104886)
			(xy 464.29168 -389.104886)
		)
		(stroke
			(width 0)
			(type solid)
		)
		(fill yes)
		(layer "B.Cu")
		(net "P0V9_CPU0_RT_2D")
	)
	(gr_poly
		(pts
			(xy 9.54024 -101.379528) (xy 9.63803 -101.281738) (xy 9.63803 -100.86848) (xy 9.48944 -100.71989)
			(xy 9.48944 -99.88042) (xy 9.48944 -98.58248) (xy 10.26414 -97.80778) (xy 10.26414 -97.55886) (xy 9.94156 -97.23628)
			(xy 6.206998 -97.23628) (xy 5.102606 -98.340672) (xy 5.102606 -100.78847) (xy 6.549136 -102.235)
			(xy 8.684768 -102.235)
		)
		(stroke
			(width 0)
			(type solid)
		)
		(fill yes)
		(layer "B.Cu")
		(net "GND")
	)
	(gr_poly
		(pts
			(xy 98.871278 -142.57401) (xy 98.871278 -141.417802) (xy 99.734878 -140.554202) (xy 99.734878 -140.11021)
			(xy 99.684078 -140.05941) (xy 98.210878 -140.05941) (xy 98.170746 -140.099542) (xy 98.170746 -140.400278)
			(xy 98.464878 -140.69441) (xy 98.464878 -141.20241) (xy 98.210878 -141.45641) (xy 98.210878 -142.59941)
			(xy 98.236278 -142.62481) (xy 98.821494 -142.62481)
		)
		(stroke
			(width 0)
			(type solid)
		)
		(fill yes)
		(layer "B.Cu")
		(net "PVDDCR_CPU0_P1_VCCS")
	)
	(gr_poly
		(pts
			(xy 381.598678 -140.176758) (xy 381.598678 -139.02055) (xy 382.462278 -138.15695) (xy 382.462278 -137.712958)
			(xy 382.411478 -137.662158) (xy 380.938278 -137.662158) (xy 380.898146 -137.70229) (xy 380.898146 -138.003026)
			(xy 381.192278 -138.297158) (xy 381.192278 -138.805158) (xy 380.938278 -139.059158) (xy 380.938278 -140.202158)
			(xy 380.963678 -140.227558) (xy 381.548894 -140.227558)
		)
		(stroke
			(width 0)
			(type solid)
		)
		(fill yes)
		(layer "B.Cu")
		(net "PVDDCR_CPU0_P0_VCCS")
	)
	(gr_poly
		(pts
			(xy 442.30544 -341.37854) (xy 442.30544 -333.79664) (xy 441.263532 -332.754732) (xy 437.227218 -332.754732)
			(xy 435.531768 -332.754732) (xy 417.524438 -332.754732) (xy 417.126928 -333.152242) (xy 416.763454 -334.175862)
			(xy 416.383978 -336.465164) (xy 416.383978 -341.683086) (xy 416.665918 -341.965026) (xy 437.250078 -341.965026)
			(xy 439.982864 -341.965026) (xy 441.718954 -341.965026)
		)
		(stroke
			(width 0)
			(type solid)
		)
		(fill yes)
		(layer "B.Cu")
		(net "PVDD11_S3_P0")
	)
	(gr_poly
		(pts
			(xy 68.88226 -18.53692) (xy 68.88226 -12.72286) (xy 68.53682 -12.37742) (xy 67.7164 -11.557) (xy 62.8396 -11.557)
			(xy 62.56528 -11.831066) (xy 62.56528 -13.466826) (xy 62.755272 -13.656818) (xy 65.191386 -13.656818)
			(xy 65.527174 -13.992606) (xy 65.527174 -17.796002) (xy 65.60185 -17.870678) (xy 67.365626 -17.870678)
			(xy 68.187062 -18.692114) (xy 68.727066 -18.692114)
		)
		(stroke
			(width 0)
			(type solid)
		)
		(fill yes)
		(layer "B.Cu")
		(net "P12V_OCP_V3_2_R")
	)
	(gr_poly
		(pts
			(arc
				(start 90.467434 -178.087528)
				(mid 90.487222 -178.066168)
				(end 90.508582 -178.04638)
			)
			(xy 90.667078 -177.887884) (xy 90.747342 -177.80762) (xy 94.555056 -177.80762) (xy 94.654116 -177.70856)
			(xy 94.654116 -177.128678) (xy 94.219522 -176.694084) (xy 89.219278 -176.694084) (xy 88.911684 -177.001678)
			(xy 88.911684 -178.413156) (xy 88.964262 -178.465734) (xy 90.089228 -178.465734)
		)
		(stroke
			(width 0)
			(type solid)
		)
		(fill yes)
		(layer "B.Cu")
		(net "GND")
	)
	(gr_poly
		(pts
			(xy 136.802114 -36.941506) (xy 136.802114 -34.82594) (xy 137.358374 -34.26968) (xy 138.14298 -34.26968)
			(xy 138.29538 -34.11728) (xy 138.29538 -33.89884) (xy 138.1506 -33.75406) (xy 137.6172 -33.75406)
			(xy 136.8044 -32.94126) (xy 136.57834 -32.94126) (xy 136.167114 -33.352486) (xy 136.167114 -33.4899)
			(xy 136.167114 -37.08146) (xy 136.235694 -37.15004) (xy 136.59358 -37.15004)
		)
		(stroke
			(width 0)
			(type solid)
		)
		(fill yes)
		(layer "B.Cu")
		(net "P1V2_CPU0_USB_DVDD12")
	)
	(gr_poly
		(pts
			(xy 108.472478 -29.246322) (xy 108.472478 -28.832302) (xy 108.72851 -28.57627) (xy 111.464598 -28.57627)
			(xy 112.2426 -27.798268) (xy 112.2426 -27.130248) (xy 112.1918 -27.079448) (xy 106.557318 -27.079448)
			(xy 106.51871 -27.118056) (xy 106.51871 -27.89809) (xy 106.428032 -27.988768) (xy 104.749346 -27.988768)
			(xy 104.685846 -28.052268) (xy 104.685846 -29.328618) (xy 104.785668 -29.42844) (xy 108.29036 -29.42844)
		)
		(stroke
			(width 0)
			(type solid)
		)
		(fill yes)
		(layer "B.Cu")
		(net "P3V3_AUX_CPU0_USB2_AVDD33")
	)
	(gr_poly
		(pts
			(xy 127.73533 -36.96843) (xy 129.40538 -36.96843) (xy 129.45872 -36.91509) (xy 129.45872 -36.52012)
			(xy 129.27203 -36.33343) (xy 128.530604 -36.33343) (xy 128.378204 -36.18103) (xy 128.378204 -35.341814)
			(xy 128.378204 -34.659824) (xy 127.92456 -34.20618) (xy 127.231902 -34.20618) (xy 126.541276 -34.896806)
			(xy 126.502668 -34.935414) (xy 126.502668 -37.67836) (xy 126.553468 -37.72916) (xy 126.9746 -37.72916)
		)
		(stroke
			(width 0)
			(type solid)
		)
		(fill yes)
		(layer "B.Cu")
		(net "P1V2_AUX")
	)
	(gr_poly
		(pts
			(xy 64.969898 -20.77212) (xy 64.969898 -17.709896) (xy 64.969898 -16.508984) (xy 65.245488 -16.233394)
			(xy 65.245488 -14.635988) (xy 65.077086 -14.467586) (xy 64.140588 -14.467586) (xy 63.831978 -14.467586)
			(xy 63.695834 -14.60373) (xy 63.695834 -17.909286) (xy 63.52921 -18.07591) (xy 63.250064 -18.07591)
			(xy 62.640464 -18.07591) (xy 62.411864 -18.30451) (xy 62.411864 -20.86991) (xy 62.615064 -21.07311)
			(xy 64.668908 -21.07311)
		)
		(stroke
			(width 0)
			(type solid)
		)
		(fill yes)
		(layer "B.Cu")
		(net "GND")
	)
	(gr_poly
		(pts
			(xy 335.8896 -160.1724) (xy 335.8896 -155.748228) (xy 335.8896 -153.55443) (xy 336.229706 -153.214324)
			(xy 338.068412 -153.214324) (xy 338.4042 -152.878536) (xy 338.4042 -151.4348) (xy 338.2518 -151.2824)
			(xy 330.9366 -151.2824) (xy 328.8284 -151.2824) (xy 328.6506 -151.4602) (xy 328.6506 -154.9908) (xy 330.6826 -157.0228)
			(xy 330.6826 -160.0962) (xy 331.0128 -160.4264) (xy 332.0542 -160.4264) (xy 335.6356 -160.4264)
		)
		(stroke
			(width 0)
			(type solid)
		)
		(fill yes)
		(layer "B.Cu")
		(net "PVDD18_S5_P0")
	)
	(gr_poly
		(pts
			(xy 12.982448 -135.64235) (xy 12.982448 -135.36041) (xy 13.045948 -135.29691) (xy 14.483588 -135.29691)
			(xy 14.874748 -134.90575) (xy 14.874748 -132.58165) (xy 14.841728 -132.54863) (xy 12.258548 -132.54863)
			(xy 12.073128 -132.73405) (xy 11.552428 -132.73405) (xy 11.445748 -132.84073) (xy 11.445748 -133.14299)
			(xy 11.631168 -133.32841) (xy 12.052808 -133.32841) (xy 12.192508 -133.46811) (xy 12.192508 -135.76173)
			(xy 12.278868 -135.84809) (xy 12.776708 -135.84809)
		)
		(stroke
			(width 0)
			(type solid)
		)
		(fill yes)
		(layer "B.Cu")
		(net "GND")
	)
	(gr_poly
		(pts
			(xy 58.439812 -160.810702) (xy 58.439812 -147.484846) (xy 58.439812 -145.624296) (xy 58.438288 -145.622772)
			(xy 58.438288 -145.055844) (xy 58.236612 -144.854168) (xy 57.669684 -144.854168) (xy 53.02123 -144.854168)
			(xy 52.472336 -145.403062) (xy 52.472336 -146.061938) (xy 52.50561 -146.095212) (xy 52.50561 -147.486116)
			(xy 52.486814 -147.504912) (xy 52.486814 -157.141672) (xy 53.756814 -158.411672) (xy 53.756814 -160.742376)
			(xy 54.26583 -161.251392) (xy 57.999122 -161.251392)
		)
		(stroke
			(width 0)
			(type solid)
		)
		(fill yes)
		(layer "B.Cu")
		(net "PVDD18_S5_P1")
	)
	(gr_poly
		(pts
			(xy 242.76304 -44.47921) (xy 245.065296 -44.47921) (xy 245.61292 -43.931586) (xy 245.61292 -41.09593)
			(xy 244.992398 -40.475408)
			(arc
				(start 242.698016 -40.475408)
				(mid 242.678493 -40.479309)
				(end 242.661948 -40.490394)
			)
			(arc
				(start 239.761522 -43.39082)
				(mid 239.744988 -43.401931)
				(end 239.725454 -43.405806)
			)
			(xy 237.385098 -43.405806) (xy 237.176056 -43.614848) (xy 237.176056 -44.878752) (xy 237.33379 -45.036486)
			(xy 242.205764 -45.036486)
		)
		(stroke
			(width 0)
			(type solid)
		)
		(fill yes)
		(layer "B.Cu")
		(net "P12V_E1S_0_R")
	)
	(gr_poly
		(pts
			(xy 15.72768 -141.96314) (xy 15.72768 -140.22324) (xy 15.5702 -140.06576) (xy 13.4366 -140.06576)
			(xy 13.27912 -140.22324) (xy 13.27912 -140.75156) (xy 13.30452 -140.77696) (xy 12.82954 -141.25194)
			(xy 11.12012 -141.25194) (xy 10.559288 -140.691108) (xy 10.559288 -140.44041) (xy 10.559288 -138.43127)
			(xy 10.376408 -138.24839) (xy 7.391908 -138.24839) (xy 7.176008 -138.46429) (xy 7.176008 -140.53947)
			(xy 7.176008 -141.732508) (xy 7.747 -142.3035) (xy 15.38732 -142.3035)
		)
		(stroke
			(width 0)
			(type solid)
		)
		(fill yes)
		(layer "B.Cu")
		(net "P3V3_AUX")
	)
	(gr_poly
		(pts
			(xy 16.44396 -111.618014)
			(arc
				(start 16.44396 -111.37519)
				(mid 16.440059 -111.355667)
				(end 16.428974 -111.339122)
			)
			(arc
				(start 16.281146 -111.191294)
				(mid 16.264612 -111.180183)
				(end 16.245078 -111.176308)
			)
			(arc
				(start 13.467842 -111.176308)
				(mid 13.448319 -111.180209)
				(end 13.431774 -111.191294)
			)
			(xy 12.992608 -111.63046) (xy 12.598908 -111.63046) (xy 12.574016 -111.655352) (xy 12.574016 -111.779558)
			(xy 12.602718 -111.80826) (xy 16.253714 -111.80826)
		)
		(stroke
			(width 0)
			(type solid)
		)
		(fill yes)
		(layer "B.Cu")
		(net "P3V3_AUX")
	)
	(gr_poly
		(pts
			(xy 82.258154 -177.921412) (xy 84.13877 -177.921412)
			(arc
				(start 84.145628 -177.91938)
				(mid 84.197322 -177.908514)
				(end 84.250022 -177.904902)
			)
			(arc
				(start 84.250022 -177.904902)
				(mid 84.30272 -177.908524)
				(end 84.354416 -177.91938)
			)
			(xy 84.361274 -177.921412) (xy 86.190074 -177.921412) (xy 86.270846 -177.84064) (xy 86.270846 -177.357024)
			(xy 85.734906 -176.821084) (xy 80.676242 -176.821084) (xy 80.279494 -177.217832) (xy 80.279494 -178.602132)
			(xy 80.297274 -178.619912) (xy 81.559654 -178.619912)
		)
		(stroke
			(width 0)
			(type solid)
		)
		(fill yes)
		(layer "B.Cu")
		(net "GND")
	)
	(gr_poly
		(pts
			(xy 32.56407 -366.239044) (xy 32.56407 -363.841284) (xy 32.64662 -363.758734) (xy 33.125664 -363.27969)
			(xy 34.262822 -363.27969) (xy 34.407856 -363.134656) (xy 34.407856 -362.157772) (xy 33.953958 -361.703874)
			(xy 28.356306 -361.703874) (xy 28.25242 -361.80776) (xy 28.25242 -362.731304)
			(arc
				(start 28.25242 -366.25911)
				(mid 28.256246 -366.278233)
				(end 28.267152 -366.294416)
			)
			(arc
				(start 28.288488 -366.315752)
				(mid 28.304699 -366.326592)
				(end 28.323794 -366.330484)
			)
			(xy 32.47263 -366.330484)
		)
		(stroke
			(width 0)
			(type solid)
		)
		(fill yes)
		(layer "B.Cu")
		(net "GND")
	)
	(gr_poly
		(pts
			(xy 36.74999 -428.607982) (xy 36.74999 -422.207182) (xy 35.475672 -420.932864) (xy 31.902908 -420.932864)
			(xy 31.72079 -421.114982) (xy 31.72079 -421.648382) (xy 31.92399 -421.851582) (xy 34.97199 -421.851582)
			(xy 35.14979 -422.029382) (xy 35.14979 -427.287182) (xy 34.92119 -427.515782) (xy 33.42259 -427.515782)
			(xy 33.24479 -427.337982) (xy 33.24479 -426.728382) (xy 33.06699 -426.550582) (xy 31.92399 -426.550582)
			(xy 31.82239 -426.652182) (xy 31.82239 -429.395382) (xy 32.17799 -429.750982) (xy 35.60699 -429.750982)
		)
		(stroke
			(width 0)
			(type solid)
		)
		(fill yes)
		(layer "B.Cu")
		(net "P3V3_AUX")
	)
	(gr_poly
		(pts
			(xy 99.531678 -142.80261) (xy 99.531678 -142.195042) (xy 100.65131 -141.07541) (xy 101.776276 -141.07541)
			(xy 102.178612 -140.673074) (xy 102.571804 -140.673074) (xy 102.782878 -140.462) (xy 102.782878 -140.130784)
			(xy 102.711504 -140.05941) (xy 100.242878 -140.05941) (xy 100.115878 -140.18641) (xy 100.115878 -140.56741)
			(xy 99.125278 -141.55801) (xy 99.125278 -142.71117) (xy 98.957638 -142.87881) (xy 98.217736 -142.87881)
			(xy 98.204528 -142.892018) (xy 98.204528 -143.037814) (xy 98.211386 -143.044672) (xy 99.289616 -143.044672)
		)
		(stroke
			(width 0)
			(type solid)
		)
		(fill yes)
		(layer "B.Cu")
		(net "PVDDCR_CPU0_P1_VCC")
	)
	(gr_poly
		(pts
			(arc
				(start 463.395314 -76.834746)
				(mid 463.414837 -76.830845)
				(end 463.431382 -76.81976)
			)
			(arc
				(start 464.03641 -76.214732)
				(mid 464.047521 -76.198198)
				(end 464.051396 -76.178664)
			)
			(arc
				(start 464.051396 -73.807828)
				(mid 464.047495 -73.788305)
				(end 464.03641 -73.77176)
			)
			(arc
				(start 463.761582 -73.496932)
				(mid 463.745048 -73.485821)
				(end 463.725514 -73.481946)
			)
			(xy 445.810894 -73.481946) (xy 445.71158 -73.58126) (xy 445.71158 -76.598526) (xy 445.9478 -76.834746)
		)
		(stroke
			(width 0)
			(type solid)
		)
		(fill yes)
		(layer "B.Cu")
		(net "GND")
	)
	(gr_poly
		(pts
			(xy 18.297652 -102.824788) (xy 19.20748 -101.91496) (xy 19.20748 -97.592388) (xy 19.05508 -97.439988)
			(xy 16.59128 -97.439988) (xy 16.36268 -97.668588) (xy 16.36268 -101.173788) (xy 16.15948 -101.376988)
			(xy 12.27328 -101.376988) (xy 11.79068 -100.894388) (xy 11.79068 -97.163128) (xy 11.64082 -97.013268)
			(xy 10.596372 -97.013268) (xy 10.52322 -97.08642) (xy 10.52322 -97.69856) (xy 10.96264 -98.13798)
			(xy 10.96264 -99.57054) (xy 10.40638 -100.1268) (xy 10.40638 -102.744016) (xy 10.785602 -103.123238)
			(xy 17.999202 -103.123238)
		)
		(stroke
			(width 0)
			(type solid)
		)
		(fill yes)
		(layer "B.Cu")
		(net "P3V3_AUX_USB_HUB")
	)
	(gr_poly
		(pts
			(arc
				(start 97.764854 -146.947382)
				(mid 97.783977 -146.943556)
				(end 97.80016 -146.93265)
			)
			(arc
				(start 97.846896 -146.885914)
				(mid 97.857736 -146.869703)
				(end 97.861628 -146.850608)
			)
			(xy 97.861628 -142.692628) (xy 97.793556 -142.624556) (xy 93.467428 -142.624556)
			(arc
				(start 93.467428 -146.876008)
				(mid 93.471254 -146.895131)
				(end 93.48216 -146.911314)
			)
			(arc
				(start 93.503496 -146.93265)
				(mid 93.519707 -146.94349)
				(end 93.538802 -146.947382)
			)
			(xy 95.982028 -146.947382) (xy 97.353628 -146.947382)
		)
		(stroke
			(width 0)
			(type solid)
		)
		(fill yes)
		(layer "B.Cu")
		(net "GND")
	)
	(gr_poly
		(pts
			(xy 98.93935 -177.870612) (xy 100.92817 -177.870612)
			(arc
				(start 100.935028 -177.86858)
				(mid 100.986722 -177.857714)
				(end 101.039422 -177.854102)
			)
			(arc
				(start 101.039422 -177.854102)
				(mid 101.09212 -177.857724)
				(end 101.143816 -177.86858)
			)
			(xy 101.150674 -177.870612) (xy 102.18928 -177.870612) (xy 102.799388 -177.870612) (xy 103.0732 -177.5968)
			(xy 103.0732 -177.3428) (xy 102.297484 -176.567084) (xy 102.189026 -176.567084) (xy 97.912682 -176.567084)
			(xy 97.142554 -177.337212) (xy 97.142554 -178.454812) (xy 97.218754 -178.531012) (xy 98.27895 -178.531012)
		)
		(stroke
			(width 0)
			(type solid)
		)
		(fill yes)
		(layer "B.Cu")
		(net "GND")
	)
	(gr_poly
		(pts
			(arc
				(start 397.967962 -310.359044)
				(mid 397.996108 -310.350534)
				(end 398.014698 -310.327802)
			)
			(xy 398.020794 -310.313324) (xy 398.014698 -310.283606)
			(arc
				(start 397.753078 -310.021732)
				(mid 397.736515 -310.010758)
				(end 397.71701 -310.007)
			)
			(arc
				(start 393.04722 -310.007)
				(mid 393.027726 -310.010784)
				(end 393.011152 -310.021732)
			)
			(arc
				(start 392.760454 -310.27243)
				(mid 392.746644 -310.298459)
				(end 392.749532 -310.327802)
			)
			(xy 392.755374 -310.34228) (xy 392.780774 -310.359044)
		)
		(stroke
			(width 0)
			(type solid)
		)
		(fill yes)
		(layer "B.Cu")
		(net "GND")
	)
	(gr_poly
		(pts
			(arc
				(start 59.351672 -438.651396)
				(mid 59.147964 -438.651396)
				(end 59.351672 -438.651396)
			)
		)
		(stroke
			(width 0)
			(type solid)
		)
		(fill yes)
		(layer "B.Cu")
		(net "GND")
	)
	(gr_poly
		(pts
			(arc
				(start 59.351672 -437.49976)
				(mid 59.147964 -437.49976)
				(end 59.351672 -437.49976)
			)
		)
		(stroke
			(width 0)
			(type solid)
		)
		(fill yes)
		(layer "B.Cu")
		(net "GND")
	)
	(gr_poly
		(pts
			(arc
				(start 59.351672 -436.347362)
				(mid 59.147964 -436.347362)
				(end 59.351672 -436.347362)
			)
		)
		(stroke
			(width 0)
			(type solid)
		)
		(fill yes)
		(layer "B.Cu")
		(net "GND")
	)
	(gr_poly
		(pts
			(arc
				(start 59.351672 -435.0512)
				(mid 59.147964 -435.0512)
				(end 59.351672 -435.0512)
			)
		)
		(stroke
			(width 0)
			(type solid)
		)
		(fill yes)
		(layer "B.Cu")
		(net "GND")
	)
	(gr_poly
		(pts
			(arc
				(start 59.351672 -433.899564)
				(mid 59.147964 -433.899564)
				(end 59.351672 -433.899564)
			)
		)
		(stroke
			(width 0)
			(type solid)
		)
		(fill yes)
		(layer "B.Cu")
		(net "GND")
	)
	(gr_poly
		(pts
			(arc
				(start 59.351672 -432.747166)
				(mid 59.147964 -432.747166)
				(end 59.351672 -432.747166)
			)
		)
		(stroke
			(width 0)
			(type solid)
		)
		(fill yes)
		(layer "B.Cu")
		(net "GND")
	)
	(gr_poly
		(pts
			(arc
				(start 59.351672 -431.451258)
				(mid 59.147964 -431.451258)
				(end 59.351672 -431.451258)
			)
		)
		(stroke
			(width 0)
			(type solid)
		)
		(fill yes)
		(layer "B.Cu")
		(net "GND")
	)
	(gr_poly
		(pts
			(arc
				(start 59.351672 -430.299622)
				(mid 59.147964 -430.299622)
				(end 59.351672 -430.299622)
			)
		)
		(stroke
			(width 0)
			(type solid)
		)
		(fill yes)
		(layer "B.Cu")
		(net "GND")
	)
	(gr_poly
		(pts
			(arc
				(start 59.351672 -429.147224)
				(mid 59.147964 -429.147224)
				(end 59.351672 -429.147224)
			)
		)
		(stroke
			(width 0)
			(type solid)
		)
		(fill yes)
		(layer "B.Cu")
		(net "GND")
	)
	(gr_poly
		(pts
			(arc
				(start 59.351672 -427.851316)
				(mid 59.147964 -427.851316)
				(end 59.351672 -427.851316)
			)
		)
		(stroke
			(width 0)
			(type solid)
		)
		(fill yes)
		(layer "B.Cu")
		(net "GND")
	)
	(gr_poly
		(pts
			(arc
				(start 59.351672 -426.69968)
				(mid 59.147964 -426.69968)
				(end 59.351672 -426.69968)
			)
		)
		(stroke
			(width 0)
			(type solid)
		)
		(fill yes)
		(layer "B.Cu")
		(net "GND")
	)
	(gr_poly
		(pts
			(arc
				(start 59.351672 -425.547282)
				(mid 59.147964 -425.547282)
				(end 59.351672 -425.547282)
			)
		)
		(stroke
			(width 0)
			(type solid)
		)
		(fill yes)
		(layer "B.Cu")
		(net "GND")
	)
	(gr_poly
		(pts
			(arc
				(start 61.351668 -439.651394)
				(mid 61.14796 -439.651394)
				(end 61.351668 -439.651394)
			)
		)
		(stroke
			(width 0)
			(type solid)
		)
		(fill yes)
		(layer "B.Cu")
		(net "GND")
	)
	(gr_poly
		(pts
			(arc
				(start 61.351668 -438.499758)
				(mid 61.14796 -438.499758)
				(end 61.351668 -438.499758)
			)
		)
		(stroke
			(width 0)
			(type solid)
		)
		(fill yes)
		(layer "B.Cu")
		(net "GND")
	)
	(gr_poly
		(pts
			(arc
				(start 61.351668 -437.34736)
				(mid 61.14796 -437.34736)
				(end 61.351668 -437.34736)
			)
		)
		(stroke
			(width 0)
			(type solid)
		)
		(fill yes)
		(layer "B.Cu")
		(net "GND")
	)
	(gr_poly
		(pts
			(arc
				(start 61.351668 -436.051198)
				(mid 61.14796 -436.051198)
				(end 61.351668 -436.051198)
			)
		)
		(stroke
			(width 0)
			(type solid)
		)
		(fill yes)
		(layer "B.Cu")
		(net "GND")
	)
	(gr_poly
		(pts
			(arc
				(start 61.351668 -434.899562)
				(mid 61.14796 -434.899562)
				(end 61.351668 -434.899562)
			)
		)
		(stroke
			(width 0)
			(type solid)
		)
		(fill yes)
		(layer "B.Cu")
		(net "GND")
	)
	(gr_poly
		(pts
			(arc
				(start 61.351668 -433.747164)
				(mid 61.14796 -433.747164)
				(end 61.351668 -433.747164)
			)
		)
		(stroke
			(width 0)
			(type solid)
		)
		(fill yes)
		(layer "B.Cu")
		(net "GND")
	)
	(gr_poly
		(pts
			(arc
				(start 61.351668 -432.451256)
				(mid 61.14796 -432.451256)
				(end 61.351668 -432.451256)
			)
		)
		(stroke
			(width 0)
			(type solid)
		)
		(fill yes)
		(layer "B.Cu")
		(net "GND")
	)
	(gr_poly
		(pts
			(arc
				(start 61.351668 -431.29962)
				(mid 61.14796 -431.29962)
				(end 61.351668 -431.29962)
			)
		)
		(stroke
			(width 0)
			(type solid)
		)
		(fill yes)
		(layer "B.Cu")
		(net "GND")
	)
	(gr_poly
		(pts
			(arc
				(start 61.351668 -430.147222)
				(mid 61.14796 -430.147222)
				(end 61.351668 -430.147222)
			)
		)
		(stroke
			(width 0)
			(type solid)
		)
		(fill yes)
		(layer "B.Cu")
		(net "GND")
	)
	(gr_poly
		(pts
			(arc
				(start 61.351668 -428.851314)
				(mid 61.14796 -428.851314)
				(end 61.351668 -428.851314)
			)
		)
		(stroke
			(width 0)
			(type solid)
		)
		(fill yes)
		(layer "B.Cu")
		(net "GND")
	)
	(gr_poly
		(pts
			(arc
				(start 61.351668 -427.699678)
				(mid 61.14796 -427.699678)
				(end 61.351668 -427.699678)
			)
		)
		(stroke
			(width 0)
			(type solid)
		)
		(fill yes)
		(layer "B.Cu")
		(net "GND")
	)
	(gr_poly
		(pts
			(arc
				(start 61.351668 -426.54728)
				(mid 61.14796 -426.54728)
				(end 61.351668 -426.54728)
			)
		)
		(stroke
			(width 0)
			(type solid)
		)
		(fill yes)
		(layer "B.Cu")
		(net "GND")
	)
	(gr_poly
		(pts
			(arc
				(start 63.351664 -438.651396)
				(mid 63.147956 -438.651396)
				(end 63.351664 -438.651396)
			)
		)
		(stroke
			(width 0)
			(type solid)
		)
		(fill yes)
		(layer "B.Cu")
		(net "GND")
	)
	(gr_poly
		(pts
			(arc
				(start 63.351664 -437.49976)
				(mid 63.147956 -437.49976)
				(end 63.351664 -437.49976)
			)
		)
		(stroke
			(width 0)
			(type solid)
		)
		(fill yes)
		(layer "B.Cu")
		(net "GND")
	)
	(gr_poly
		(pts
			(arc
				(start 63.351664 -436.347362)
				(mid 63.147956 -436.347362)
				(end 63.351664 -436.347362)
			)
		)
		(stroke
			(width 0)
			(type solid)
		)
		(fill yes)
		(layer "B.Cu")
		(net "GND")
	)
	(gr_poly
		(pts
			(arc
				(start 63.351664 -435.0512)
				(mid 63.147956 -435.0512)
				(end 63.351664 -435.0512)
			)
		)
		(stroke
			(width 0)
			(type solid)
		)
		(fill yes)
		(layer "B.Cu")
		(net "GND")
	)
	(gr_poly
		(pts
			(arc
				(start 63.351664 -433.899564)
				(mid 63.147956 -433.899564)
				(end 63.351664 -433.899564)
			)
		)
		(stroke
			(width 0)
			(type solid)
		)
		(fill yes)
		(layer "B.Cu")
		(net "GND")
	)
	(gr_poly
		(pts
			(arc
				(start 63.351664 -432.747166)
				(mid 63.147956 -432.747166)
				(end 63.351664 -432.747166)
			)
		)
		(stroke
			(width 0)
			(type solid)
		)
		(fill yes)
		(layer "B.Cu")
		(net "GND")
	)
	(gr_poly
		(pts
			(arc
				(start 63.351664 -431.451258)
				(mid 63.147956 -431.451258)
				(end 63.351664 -431.451258)
			)
		)
		(stroke
			(width 0)
			(type solid)
		)
		(fill yes)
		(layer "B.Cu")
		(net "GND")
	)
	(gr_poly
		(pts
			(arc
				(start 63.351664 -430.299622)
				(mid 63.147956 -430.299622)
				(end 63.351664 -430.299622)
			)
		)
		(stroke
			(width 0)
			(type solid)
		)
		(fill yes)
		(layer "B.Cu")
		(net "GND")
	)
	(gr_poly
		(pts
			(arc
				(start 63.351664 -429.147224)
				(mid 63.147956 -429.147224)
				(end 63.351664 -429.147224)
			)
		)
		(stroke
			(width 0)
			(type solid)
		)
		(fill yes)
		(layer "B.Cu")
		(net "GND")
	)
	(gr_poly
		(pts
			(arc
				(start 63.351664 -427.851316)
				(mid 63.147956 -427.851316)
				(end 63.351664 -427.851316)
			)
		)
		(stroke
			(width 0)
			(type solid)
		)
		(fill yes)
		(layer "B.Cu")
		(net "GND")
	)
	(gr_poly
		(pts
			(arc
				(start 63.351664 -426.69968)
				(mid 63.147956 -426.69968)
				(end 63.351664 -426.69968)
			)
		)
		(stroke
			(width 0)
			(type solid)
		)
		(fill yes)
		(layer "B.Cu")
		(net "GND")
	)
	(gr_poly
		(pts
			(arc
				(start 63.351664 -425.547282)
				(mid 63.147956 -425.547282)
				(end 63.351664 -425.547282)
			)
		)
		(stroke
			(width 0)
			(type solid)
		)
		(fill yes)
		(layer "B.Cu")
		(net "GND")
	)
	(gr_poly
		(pts
			(arc
				(start 65.35166 -439.651394)
				(mid 65.147952 -439.651394)
				(end 65.35166 -439.651394)
			)
		)
		(stroke
			(width 0)
			(type solid)
		)
		(fill yes)
		(layer "B.Cu")
		(net "GND")
	)
	(gr_poly
		(pts
			(arc
				(start 65.35166 -438.499758)
				(mid 65.147952 -438.499758)
				(end 65.35166 -438.499758)
			)
		)
		(stroke
			(width 0)
			(type solid)
		)
		(fill yes)
		(layer "B.Cu")
		(net "GND")
	)
	(gr_poly
		(pts
			(arc
				(start 65.35166 -437.34736)
				(mid 65.147952 -437.34736)
				(end 65.35166 -437.34736)
			)
		)
		(stroke
			(width 0)
			(type solid)
		)
		(fill yes)
		(layer "B.Cu")
		(net "GND")
	)
	(gr_poly
		(pts
			(arc
				(start 65.35166 -436.051198)
				(mid 65.147952 -436.051198)
				(end 65.35166 -436.051198)
			)
		)
		(stroke
			(width 0)
			(type solid)
		)
		(fill yes)
		(layer "B.Cu")
		(net "GND")
	)
	(gr_poly
		(pts
			(arc
				(start 65.35166 -434.899562)
				(mid 65.147952 -434.899562)
				(end 65.35166 -434.899562)
			)
		)
		(stroke
			(width 0)
			(type solid)
		)
		(fill yes)
		(layer "B.Cu")
		(net "GND")
	)
	(gr_poly
		(pts
			(arc
				(start 65.35166 -433.747164)
				(mid 65.147952 -433.747164)
				(end 65.35166 -433.747164)
			)
		)
		(stroke
			(width 0)
			(type solid)
		)
		(fill yes)
		(layer "B.Cu")
		(net "GND")
	)
	(gr_poly
		(pts
			(arc
				(start 65.35166 -432.451256)
				(mid 65.147952 -432.451256)
				(end 65.35166 -432.451256)
			)
		)
		(stroke
			(width 0)
			(type solid)
		)
		(fill yes)
		(layer "B.Cu")
		(net "GND")
	)
	(gr_poly
		(pts
			(arc
				(start 65.35166 -431.29962)
				(mid 65.147952 -431.29962)
				(end 65.35166 -431.29962)
			)
		)
		(stroke
			(width 0)
			(type solid)
		)
		(fill yes)
		(layer "B.Cu")
		(net "GND")
	)
	(gr_poly
		(pts
			(arc
				(start 65.35166 -430.147222)
				(mid 65.147952 -430.147222)
				(end 65.35166 -430.147222)
			)
		)
		(stroke
			(width 0)
			(type solid)
		)
		(fill yes)
		(layer "B.Cu")
		(net "GND")
	)
	(gr_poly
		(pts
			(arc
				(start 65.35166 -428.851314)
				(mid 65.147952 -428.851314)
				(end 65.35166 -428.851314)
			)
		)
		(stroke
			(width 0)
			(type solid)
		)
		(fill yes)
		(layer "B.Cu")
		(net "GND")
	)
	(gr_poly
		(pts
			(arc
				(start 65.35166 -427.699678)
				(mid 65.147952 -427.699678)
				(end 65.35166 -427.699678)
			)
		)
		(stroke
			(width 0)
			(type solid)
		)
		(fill yes)
		(layer "B.Cu")
		(net "GND")
	)
	(gr_poly
		(pts
			(arc
				(start 65.35166 -426.54728)
				(mid 65.147952 -426.54728)
				(end 65.35166 -426.54728)
			)
		)
		(stroke
			(width 0)
			(type solid)
		)
		(fill yes)
		(layer "B.Cu")
		(net "GND")
	)
	(gr_poly
		(pts
			(arc
				(start 67.351656 -438.651396)
				(mid 67.147948 -438.651396)
				(end 67.351656 -438.651396)
			)
		)
		(stroke
			(width 0)
			(type solid)
		)
		(fill yes)
		(layer "B.Cu")
		(net "GND")
	)
	(gr_poly
		(pts
			(arc
				(start 67.351656 -437.49976)
				(mid 67.147948 -437.49976)
				(end 67.351656 -437.49976)
			)
		)
		(stroke
			(width 0)
			(type solid)
		)
		(fill yes)
		(layer "B.Cu")
		(net "GND")
	)
	(gr_poly
		(pts
			(arc
				(start 67.351656 -436.347362)
				(mid 67.147948 -436.347362)
				(end 67.351656 -436.347362)
			)
		)
		(stroke
			(width 0)
			(type solid)
		)
		(fill yes)
		(layer "B.Cu")
		(net "GND")
	)
	(gr_poly
		(pts
			(arc
				(start 67.351656 -435.0512)
				(mid 67.147948 -435.0512)
				(end 67.351656 -435.0512)
			)
		)
		(stroke
			(width 0)
			(type solid)
		)
		(fill yes)
		(layer "B.Cu")
		(net "GND")
	)
	(gr_poly
		(pts
			(arc
				(start 67.351656 -433.899564)
				(mid 67.147948 -433.899564)
				(end 67.351656 -433.899564)
			)
		)
		(stroke
			(width 0)
			(type solid)
		)
		(fill yes)
		(layer "B.Cu")
		(net "GND")
	)
	(gr_poly
		(pts
			(arc
				(start 67.351656 -432.747166)
				(mid 67.147948 -432.747166)
				(end 67.351656 -432.747166)
			)
		)
		(stroke
			(width 0)
			(type solid)
		)
		(fill yes)
		(layer "B.Cu")
		(net "GND")
	)
	(gr_poly
		(pts
			(arc
				(start 67.351656 -431.451258)
				(mid 67.147948 -431.451258)
				(end 67.351656 -431.451258)
			)
		)
		(stroke
			(width 0)
			(type solid)
		)
		(fill yes)
		(layer "B.Cu")
		(net "GND")
	)
	(gr_poly
		(pts
			(arc
				(start 67.351656 -430.299622)
				(mid 67.147948 -430.299622)
				(end 67.351656 -430.299622)
			)
		)
		(stroke
			(width 0)
			(type solid)
		)
		(fill yes)
		(layer "B.Cu")
		(net "GND")
	)
	(gr_poly
		(pts
			(arc
				(start 67.351656 -429.147224)
				(mid 67.147948 -429.147224)
				(end 67.351656 -429.147224)
			)
		)
		(stroke
			(width 0)
			(type solid)
		)
		(fill yes)
		(layer "B.Cu")
		(net "GND")
	)
	(gr_poly
		(pts
			(arc
				(start 67.351656 -427.851316)
				(mid 67.147948 -427.851316)
				(end 67.351656 -427.851316)
			)
		)
		(stroke
			(width 0)
			(type solid)
		)
		(fill yes)
		(layer "B.Cu")
		(net "GND")
	)
	(gr_poly
		(pts
			(arc
				(start 67.351656 -426.69968)
				(mid 67.147948 -426.69968)
				(end 67.351656 -426.69968)
			)
		)
		(stroke
			(width 0)
			(type solid)
		)
		(fill yes)
		(layer "B.Cu")
		(net "GND")
	)
	(gr_poly
		(pts
			(arc
				(start 67.351656 -425.547282)
				(mid 67.147948 -425.547282)
				(end 67.351656 -425.547282)
			)
		)
		(stroke
			(width 0)
			(type solid)
		)
		(fill yes)
		(layer "B.Cu")
		(net "GND")
	)
	(gr_poly
		(pts
			(arc
				(start 69.351652 -439.651394)
				(mid 69.147944 -439.651394)
				(end 69.351652 -439.651394)
			)
		)
		(stroke
			(width 0)
			(type solid)
		)
		(fill yes)
		(layer "B.Cu")
		(net "GND")
	)
	(gr_poly
		(pts
			(arc
				(start 69.351652 -438.499758)
				(mid 69.147944 -438.499758)
				(end 69.351652 -438.499758)
			)
		)
		(stroke
			(width 0)
			(type solid)
		)
		(fill yes)
		(layer "B.Cu")
		(net "GND")
	)
	(gr_poly
		(pts
			(arc
				(start 69.351652 -437.34736)
				(mid 69.147944 -437.34736)
				(end 69.351652 -437.34736)
			)
		)
		(stroke
			(width 0)
			(type solid)
		)
		(fill yes)
		(layer "B.Cu")
		(net "GND")
	)
	(gr_poly
		(pts
			(arc
				(start 69.351652 -436.051198)
				(mid 69.147944 -436.051198)
				(end 69.351652 -436.051198)
			)
		)
		(stroke
			(width 0)
			(type solid)
		)
		(fill yes)
		(layer "B.Cu")
		(net "GND")
	)
	(gr_poly
		(pts
			(arc
				(start 69.351652 -434.899562)
				(mid 69.147944 -434.899562)
				(end 69.351652 -434.899562)
			)
		)
		(stroke
			(width 0)
			(type solid)
		)
		(fill yes)
		(layer "B.Cu")
		(net "GND")
	)
	(gr_poly
		(pts
			(arc
				(start 69.351652 -433.747164)
				(mid 69.147944 -433.747164)
				(end 69.351652 -433.747164)
			)
		)
		(stroke
			(width 0)
			(type solid)
		)
		(fill yes)
		(layer "B.Cu")
		(net "GND")
	)
	(gr_poly
		(pts
			(arc
				(start 69.351652 -432.451256)
				(mid 69.147944 -432.451256)
				(end 69.351652 -432.451256)
			)
		)
		(stroke
			(width 0)
			(type solid)
		)
		(fill yes)
		(layer "B.Cu")
		(net "GND")
	)
	(gr_poly
		(pts
			(arc
				(start 69.351652 -431.29962)
				(mid 69.147944 -431.29962)
				(end 69.351652 -431.29962)
			)
		)
		(stroke
			(width 0)
			(type solid)
		)
		(fill yes)
		(layer "B.Cu")
		(net "GND")
	)
	(gr_poly
		(pts
			(arc
				(start 69.351652 -430.147222)
				(mid 69.147944 -430.147222)
				(end 69.351652 -430.147222)
			)
		)
		(stroke
			(width 0)
			(type solid)
		)
		(fill yes)
		(layer "B.Cu")
		(net "GND")
	)
	(gr_poly
		(pts
			(arc
				(start 69.351652 -428.851314)
				(mid 69.147944 -428.851314)
				(end 69.351652 -428.851314)
			)
		)
		(stroke
			(width 0)
			(type solid)
		)
		(fill yes)
		(layer "B.Cu")
		(net "GND")
	)
	(gr_poly
		(pts
			(arc
				(start 69.351652 -427.699678)
				(mid 69.147944 -427.699678)
				(end 69.351652 -427.699678)
			)
		)
		(stroke
			(width 0)
			(type solid)
		)
		(fill yes)
		(layer "B.Cu")
		(net "GND")
	)
	(gr_poly
		(pts
			(arc
				(start 69.351652 -426.54728)
				(mid 69.147944 -426.54728)
				(end 69.351652 -426.54728)
			)
		)
		(stroke
			(width 0)
			(type solid)
		)
		(fill yes)
		(layer "B.Cu")
		(net "GND")
	)
	(gr_poly
		(pts
			(arc
				(start 71.351648 -438.651396)
				(mid 71.14794 -438.651396)
				(end 71.351648 -438.651396)
			)
		)
		(stroke
			(width 0)
			(type solid)
		)
		(fill yes)
		(layer "B.Cu")
		(net "GND")
	)
	(gr_poly
		(pts
			(arc
				(start 71.351648 -437.49976)
				(mid 71.14794 -437.49976)
				(end 71.351648 -437.49976)
			)
		)
		(stroke
			(width 0)
			(type solid)
		)
		(fill yes)
		(layer "B.Cu")
		(net "GND")
	)
	(gr_poly
		(pts
			(arc
				(start 71.351648 -436.347362)
				(mid 71.14794 -436.347362)
				(end 71.351648 -436.347362)
			)
		)
		(stroke
			(width 0)
			(type solid)
		)
		(fill yes)
		(layer "B.Cu")
		(net "GND")
	)
	(gr_poly
		(pts
			(arc
				(start 71.351648 -435.0512)
				(mid 71.14794 -435.0512)
				(end 71.351648 -435.0512)
			)
		)
		(stroke
			(width 0)
			(type solid)
		)
		(fill yes)
		(layer "B.Cu")
		(net "GND")
	)
	(gr_poly
		(pts
			(arc
				(start 71.351648 -433.899564)
				(mid 71.14794 -433.899564)
				(end 71.351648 -433.899564)
			)
		)
		(stroke
			(width 0)
			(type solid)
		)
		(fill yes)
		(layer "B.Cu")
		(net "GND")
	)
	(gr_poly
		(pts
			(arc
				(start 71.351648 -432.747166)
				(mid 71.14794 -432.747166)
				(end 71.351648 -432.747166)
			)
		)
		(stroke
			(width 0)
			(type solid)
		)
		(fill yes)
		(layer "B.Cu")
		(net "GND")
	)
	(gr_poly
		(pts
			(arc
				(start 71.351648 -431.451258)
				(mid 71.14794 -431.451258)
				(end 71.351648 -431.451258)
			)
		)
		(stroke
			(width 0)
			(type solid)
		)
		(fill yes)
		(layer "B.Cu")
		(net "GND")
	)
	(gr_poly
		(pts
			(arc
				(start 71.351648 -430.299622)
				(mid 71.14794 -430.299622)
				(end 71.351648 -430.299622)
			)
		)
		(stroke
			(width 0)
			(type solid)
		)
		(fill yes)
		(layer "B.Cu")
		(net "GND")
	)
	(gr_poly
		(pts
			(arc
				(start 71.351648 -429.147224)
				(mid 71.14794 -429.147224)
				(end 71.351648 -429.147224)
			)
		)
		(stroke
			(width 0)
			(type solid)
		)
		(fill yes)
		(layer "B.Cu")
		(net "GND")
	)
	(gr_poly
		(pts
			(arc
				(start 71.351648 -427.851316)
				(mid 71.14794 -427.851316)
				(end 71.351648 -427.851316)
			)
		)
		(stroke
			(width 0)
			(type solid)
		)
		(fill yes)
		(layer "B.Cu")
		(net "GND")
	)
	(gr_poly
		(pts
			(arc
				(start 71.351648 -426.69968)
				(mid 71.14794 -426.69968)
				(end 71.351648 -426.69968)
			)
		)
		(stroke
			(width 0)
			(type solid)
		)
		(fill yes)
		(layer "B.Cu")
		(net "GND")
	)
	(gr_poly
		(pts
			(arc
				(start 71.351648 -425.547282)
				(mid 71.14794 -425.547282)
				(end 71.351648 -425.547282)
			)
		)
		(stroke
			(width 0)
			(type solid)
		)
		(fill yes)
		(layer "B.Cu")
		(net "GND")
	)
	(gr_poly
		(pts
			(arc
				(start 76.351638 -438.651396)
				(mid 76.14793 -438.651396)
				(end 76.351638 -438.651396)
			)
		)
		(stroke
			(width 0)
			(type solid)
		)
		(fill yes)
		(layer "B.Cu")
		(net "GND")
	)
	(gr_poly
		(pts
			(arc
				(start 76.351638 -437.49976)
				(mid 76.14793 -437.49976)
				(end 76.351638 -437.49976)
			)
		)
		(stroke
			(width 0)
			(type solid)
		)
		(fill yes)
		(layer "B.Cu")
		(net "GND")
	)
	(gr_poly
		(pts
			(arc
				(start 76.351638 -436.347362)
				(mid 76.14793 -436.347362)
				(end 76.351638 -436.347362)
			)
		)
		(stroke
			(width 0)
			(type solid)
		)
		(fill yes)
		(layer "B.Cu")
		(net "GND")
	)
	(gr_poly
		(pts
			(arc
				(start 76.351638 -435.0512)
				(mid 76.14793 -435.0512)
				(end 76.351638 -435.0512)
			)
		)
		(stroke
			(width 0)
			(type solid)
		)
		(fill yes)
		(layer "B.Cu")
		(net "GND")
	)
	(gr_poly
		(pts
			(arc
				(start 76.351638 -433.899564)
				(mid 76.14793 -433.899564)
				(end 76.351638 -433.899564)
			)
		)
		(stroke
			(width 0)
			(type solid)
		)
		(fill yes)
		(layer "B.Cu")
		(net "GND")
	)
	(gr_poly
		(pts
			(arc
				(start 76.351638 -432.747166)
				(mid 76.14793 -432.747166)
				(end 76.351638 -432.747166)
			)
		)
		(stroke
			(width 0)
			(type solid)
		)
		(fill yes)
		(layer "B.Cu")
		(net "GND")
	)
	(gr_poly
		(pts
			(arc
				(start 76.351638 -431.451258)
				(mid 76.14793 -431.451258)
				(end 76.351638 -431.451258)
			)
		)
		(stroke
			(width 0)
			(type solid)
		)
		(fill yes)
		(layer "B.Cu")
		(net "GND")
	)
	(gr_poly
		(pts
			(arc
				(start 76.351638 -430.299622)
				(mid 76.14793 -430.299622)
				(end 76.351638 -430.299622)
			)
		)
		(stroke
			(width 0)
			(type solid)
		)
		(fill yes)
		(layer "B.Cu")
		(net "GND")
	)
	(gr_poly
		(pts
			(arc
				(start 76.351638 -429.147224)
				(mid 76.14793 -429.147224)
				(end 76.351638 -429.147224)
			)
		)
		(stroke
			(width 0)
			(type solid)
		)
		(fill yes)
		(layer "B.Cu")
		(net "GND")
	)
	(gr_poly
		(pts
			(arc
				(start 76.351638 -427.851316)
				(mid 76.14793 -427.851316)
				(end 76.351638 -427.851316)
			)
		)
		(stroke
			(width 0)
			(type solid)
		)
		(fill yes)
		(layer "B.Cu")
		(net "GND")
	)
	(gr_poly
		(pts
			(arc
				(start 76.351638 -426.69968)
				(mid 76.14793 -426.69968)
				(end 76.351638 -426.69968)
			)
		)
		(stroke
			(width 0)
			(type solid)
		)
		(fill yes)
		(layer "B.Cu")
		(net "GND")
	)
	(gr_poly
		(pts
			(arc
				(start 76.351638 -425.547282)
				(mid 76.14793 -425.547282)
				(end 76.351638 -425.547282)
			)
		)
		(stroke
			(width 0)
			(type solid)
		)
		(fill yes)
		(layer "B.Cu")
		(net "GND")
	)
	(gr_poly
		(pts
			(arc
				(start 78.351634 -439.651394)
				(mid 78.147926 -439.651394)
				(end 78.351634 -439.651394)
			)
		)
		(stroke
			(width 0)
			(type solid)
		)
		(fill yes)
		(layer "B.Cu")
		(net "GND")
	)
	(gr_poly
		(pts
			(arc
				(start 78.351634 -438.499758)
				(mid 78.147926 -438.499758)
				(end 78.351634 -438.499758)
			)
		)
		(stroke
			(width 0)
			(type solid)
		)
		(fill yes)
		(layer "B.Cu")
		(net "GND")
	)
	(gr_poly
		(pts
			(arc
				(start 78.351634 -437.34736)
				(mid 78.147926 -437.34736)
				(end 78.351634 -437.34736)
			)
		)
		(stroke
			(width 0)
			(type solid)
		)
		(fill yes)
		(layer "B.Cu")
		(net "GND")
	)
	(gr_poly
		(pts
			(arc
				(start 78.351634 -436.051198)
				(mid 78.147926 -436.051198)
				(end 78.351634 -436.051198)
			)
		)
		(stroke
			(width 0)
			(type solid)
		)
		(fill yes)
		(layer "B.Cu")
		(net "GND")
	)
	(gr_poly
		(pts
			(arc
				(start 78.351634 -434.899562)
				(mid 78.147926 -434.899562)
				(end 78.351634 -434.899562)
			)
		)
		(stroke
			(width 0)
			(type solid)
		)
		(fill yes)
		(layer "B.Cu")
		(net "GND")
	)
	(gr_poly
		(pts
			(arc
				(start 78.351634 -433.747164)
				(mid 78.147926 -433.747164)
				(end 78.351634 -433.747164)
			)
		)
		(stroke
			(width 0)
			(type solid)
		)
		(fill yes)
		(layer "B.Cu")
		(net "GND")
	)
	(gr_poly
		(pts
			(arc
				(start 78.351634 -432.451256)
				(mid 78.147926 -432.451256)
				(end 78.351634 -432.451256)
			)
		)
		(stroke
			(width 0)
			(type solid)
		)
		(fill yes)
		(layer "B.Cu")
		(net "GND")
	)
	(gr_poly
		(pts
			(arc
				(start 78.351634 -431.29962)
				(mid 78.147926 -431.29962)
				(end 78.351634 -431.29962)
			)
		)
		(stroke
			(width 0)
			(type solid)
		)
		(fill yes)
		(layer "B.Cu")
		(net "GND")
	)
	(gr_poly
		(pts
			(arc
				(start 78.351634 -430.147222)
				(mid 78.147926 -430.147222)
				(end 78.351634 -430.147222)
			)
		)
		(stroke
			(width 0)
			(type solid)
		)
		(fill yes)
		(layer "B.Cu")
		(net "GND")
	)
	(gr_poly
		(pts
			(arc
				(start 78.351634 -428.851314)
				(mid 78.147926 -428.851314)
				(end 78.351634 -428.851314)
			)
		)
		(stroke
			(width 0)
			(type solid)
		)
		(fill yes)
		(layer "B.Cu")
		(net "GND")
	)
	(gr_poly
		(pts
			(arc
				(start 78.351634 -427.699678)
				(mid 78.147926 -427.699678)
				(end 78.351634 -427.699678)
			)
		)
		(stroke
			(width 0)
			(type solid)
		)
		(fill yes)
		(layer "B.Cu")
		(net "GND")
	)
	(gr_poly
		(pts
			(arc
				(start 78.351634 -426.54728)
				(mid 78.147926 -426.54728)
				(end 78.351634 -426.54728)
			)
		)
		(stroke
			(width 0)
			(type solid)
		)
		(fill yes)
		(layer "B.Cu")
		(net "GND")
	)
	(gr_poly
		(pts
			(arc
				(start 80.35163 -438.651396)
				(mid 80.147922 -438.651396)
				(end 80.35163 -438.651396)
			)
		)
		(stroke
			(width 0)
			(type solid)
		)
		(fill yes)
		(layer "B.Cu")
		(net "GND")
	)
	(gr_poly
		(pts
			(arc
				(start 80.35163 -437.49976)
				(mid 80.147922 -437.49976)
				(end 80.35163 -437.49976)
			)
		)
		(stroke
			(width 0)
			(type solid)
		)
		(fill yes)
		(layer "B.Cu")
		(net "GND")
	)
	(gr_poly
		(pts
			(arc
				(start 80.35163 -436.347362)
				(mid 80.147922 -436.347362)
				(end 80.35163 -436.347362)
			)
		)
		(stroke
			(width 0)
			(type solid)
		)
		(fill yes)
		(layer "B.Cu")
		(net "GND")
	)
	(gr_poly
		(pts
			(arc
				(start 80.35163 -435.0512)
				(mid 80.147922 -435.0512)
				(end 80.35163 -435.0512)
			)
		)
		(stroke
			(width 0)
			(type solid)
		)
		(fill yes)
		(layer "B.Cu")
		(net "GND")
	)
	(gr_poly
		(pts
			(arc
				(start 80.35163 -433.899564)
				(mid 80.147922 -433.899564)
				(end 80.35163 -433.899564)
			)
		)
		(stroke
			(width 0)
			(type solid)
		)
		(fill yes)
		(layer "B.Cu")
		(net "GND")
	)
	(gr_poly
		(pts
			(arc
				(start 80.35163 -432.747166)
				(mid 80.147922 -432.747166)
				(end 80.35163 -432.747166)
			)
		)
		(stroke
			(width 0)
			(type solid)
		)
		(fill yes)
		(layer "B.Cu")
		(net "GND")
	)
	(gr_poly
		(pts
			(arc
				(start 80.35163 -431.451258)
				(mid 80.147922 -431.451258)
				(end 80.35163 -431.451258)
			)
		)
		(stroke
			(width 0)
			(type solid)
		)
		(fill yes)
		(layer "B.Cu")
		(net "GND")
	)
	(gr_poly
		(pts
			(arc
				(start 80.35163 -430.299622)
				(mid 80.147922 -430.299622)
				(end 80.35163 -430.299622)
			)
		)
		(stroke
			(width 0)
			(type solid)
		)
		(fill yes)
		(layer "B.Cu")
		(net "GND")
	)
	(gr_poly
		(pts
			(arc
				(start 80.35163 -429.147224)
				(mid 80.147922 -429.147224)
				(end 80.35163 -429.147224)
			)
		)
		(stroke
			(width 0)
			(type solid)
		)
		(fill yes)
		(layer "B.Cu")
		(net "GND")
	)
	(gr_poly
		(pts
			(arc
				(start 80.35163 -427.851316)
				(mid 80.147922 -427.851316)
				(end 80.35163 -427.851316)
			)
		)
		(stroke
			(width 0)
			(type solid)
		)
		(fill yes)
		(layer "B.Cu")
		(net "GND")
	)
	(gr_poly
		(pts
			(arc
				(start 80.35163 -426.69968)
				(mid 80.147922 -426.69968)
				(end 80.35163 -426.69968)
			)
		)
		(stroke
			(width 0)
			(type solid)
		)
		(fill yes)
		(layer "B.Cu")
		(net "GND")
	)
	(gr_poly
		(pts
			(arc
				(start 80.35163 -425.547282)
				(mid 80.147922 -425.547282)
				(end 80.35163 -425.547282)
			)
		)
		(stroke
			(width 0)
			(type solid)
		)
		(fill yes)
		(layer "B.Cu")
		(net "GND")
	)
	(gr_poly
		(pts
			(arc
				(start 82.351626 -439.651394)
				(mid 82.147918 -439.651394)
				(end 82.351626 -439.651394)
			)
		)
		(stroke
			(width 0)
			(type solid)
		)
		(fill yes)
		(layer "B.Cu")
		(net "GND")
	)
	(gr_poly
		(pts
			(arc
				(start 82.351626 -438.499758)
				(mid 82.147918 -438.499758)
				(end 82.351626 -438.499758)
			)
		)
		(stroke
			(width 0)
			(type solid)
		)
		(fill yes)
		(layer "B.Cu")
		(net "GND")
	)
	(gr_poly
		(pts
			(arc
				(start 82.351626 -437.34736)
				(mid 82.147918 -437.34736)
				(end 82.351626 -437.34736)
			)
		)
		(stroke
			(width 0)
			(type solid)
		)
		(fill yes)
		(layer "B.Cu")
		(net "GND")
	)
	(gr_poly
		(pts
			(arc
				(start 82.351626 -436.051198)
				(mid 82.147918 -436.051198)
				(end 82.351626 -436.051198)
			)
		)
		(stroke
			(width 0)
			(type solid)
		)
		(fill yes)
		(layer "B.Cu")
		(net "GND")
	)
	(gr_poly
		(pts
			(arc
				(start 82.351626 -434.899562)
				(mid 82.147918 -434.899562)
				(end 82.351626 -434.899562)
			)
		)
		(stroke
			(width 0)
			(type solid)
		)
		(fill yes)
		(layer "B.Cu")
		(net "GND")
	)
	(gr_poly
		(pts
			(arc
				(start 82.351626 -433.747164)
				(mid 82.147918 -433.747164)
				(end 82.351626 -433.747164)
			)
		)
		(stroke
			(width 0)
			(type solid)
		)
		(fill yes)
		(layer "B.Cu")
		(net "GND")
	)
	(gr_poly
		(pts
			(arc
				(start 82.351626 -432.451256)
				(mid 82.147918 -432.451256)
				(end 82.351626 -432.451256)
			)
		)
		(stroke
			(width 0)
			(type solid)
		)
		(fill yes)
		(layer "B.Cu")
		(net "GND")
	)
	(gr_poly
		(pts
			(arc
				(start 82.351626 -431.29962)
				(mid 82.147918 -431.29962)
				(end 82.351626 -431.29962)
			)
		)
		(stroke
			(width 0)
			(type solid)
		)
		(fill yes)
		(layer "B.Cu")
		(net "GND")
	)
	(gr_poly
		(pts
			(arc
				(start 82.351626 -430.147222)
				(mid 82.147918 -430.147222)
				(end 82.351626 -430.147222)
			)
		)
		(stroke
			(width 0)
			(type solid)
		)
		(fill yes)
		(layer "B.Cu")
		(net "GND")
	)
	(gr_poly
		(pts
			(arc
				(start 82.351626 -428.851314)
				(mid 82.147918 -428.851314)
				(end 82.351626 -428.851314)
			)
		)
		(stroke
			(width 0)
			(type solid)
		)
		(fill yes)
		(layer "B.Cu")
		(net "GND")
	)
	(gr_poly
		(pts
			(arc
				(start 82.351626 -427.699678)
				(mid 82.147918 -427.699678)
				(end 82.351626 -427.699678)
			)
		)
		(stroke
			(width 0)
			(type solid)
		)
		(fill yes)
		(layer "B.Cu")
		(net "GND")
	)
	(gr_poly
		(pts
			(arc
				(start 82.351626 -426.54728)
				(mid 82.147918 -426.54728)
				(end 82.351626 -426.54728)
			)
		)
		(stroke
			(width 0)
			(type solid)
		)
		(fill yes)
		(layer "B.Cu")
		(net "GND")
	)
	(gr_poly
		(pts
			(arc
				(start 84.351622 -438.651396)
				(mid 84.147914 -438.651396)
				(end 84.351622 -438.651396)
			)
		)
		(stroke
			(width 0)
			(type solid)
		)
		(fill yes)
		(layer "B.Cu")
		(net "GND")
	)
	(gr_poly
		(pts
			(arc
				(start 84.351622 -437.49976)
				(mid 84.147914 -437.49976)
				(end 84.351622 -437.49976)
			)
		)
		(stroke
			(width 0)
			(type solid)
		)
		(fill yes)
		(layer "B.Cu")
		(net "GND")
	)
	(gr_poly
		(pts
			(arc
				(start 84.351622 -436.347362)
				(mid 84.147914 -436.347362)
				(end 84.351622 -436.347362)
			)
		)
		(stroke
			(width 0)
			(type solid)
		)
		(fill yes)
		(layer "B.Cu")
		(net "GND")
	)
	(gr_poly
		(pts
			(arc
				(start 84.351622 -435.0512)
				(mid 84.147914 -435.0512)
				(end 84.351622 -435.0512)
			)
		)
		(stroke
			(width 0)
			(type solid)
		)
		(fill yes)
		(layer "B.Cu")
		(net "GND")
	)
	(gr_poly
		(pts
			(arc
				(start 84.351622 -433.899564)
				(mid 84.147914 -433.899564)
				(end 84.351622 -433.899564)
			)
		)
		(stroke
			(width 0)
			(type solid)
		)
		(fill yes)
		(layer "B.Cu")
		(net "GND")
	)
	(gr_poly
		(pts
			(arc
				(start 84.351622 -432.747166)
				(mid 84.147914 -432.747166)
				(end 84.351622 -432.747166)
			)
		)
		(stroke
			(width 0)
			(type solid)
		)
		(fill yes)
		(layer "B.Cu")
		(net "GND")
	)
	(gr_poly
		(pts
			(arc
				(start 84.351622 -431.451258)
				(mid 84.147914 -431.451258)
				(end 84.351622 -431.451258)
			)
		)
		(stroke
			(width 0)
			(type solid)
		)
		(fill yes)
		(layer "B.Cu")
		(net "GND")
	)
	(gr_poly
		(pts
			(arc
				(start 84.351622 -430.299622)
				(mid 84.147914 -430.299622)
				(end 84.351622 -430.299622)
			)
		)
		(stroke
			(width 0)
			(type solid)
		)
		(fill yes)
		(layer "B.Cu")
		(net "GND")
	)
	(gr_poly
		(pts
			(arc
				(start 84.351622 -429.147224)
				(mid 84.147914 -429.147224)
				(end 84.351622 -429.147224)
			)
		)
		(stroke
			(width 0)
			(type solid)
		)
		(fill yes)
		(layer "B.Cu")
		(net "GND")
	)
	(gr_poly
		(pts
			(arc
				(start 84.351622 -427.851316)
				(mid 84.147914 -427.851316)
				(end 84.351622 -427.851316)
			)
		)
		(stroke
			(width 0)
			(type solid)
		)
		(fill yes)
		(layer "B.Cu")
		(net "GND")
	)
	(gr_poly
		(pts
			(arc
				(start 84.351622 -426.69968)
				(mid 84.147914 -426.69968)
				(end 84.351622 -426.69968)
			)
		)
		(stroke
			(width 0)
			(type solid)
		)
		(fill yes)
		(layer "B.Cu")
		(net "GND")
	)
	(gr_poly
		(pts
			(arc
				(start 84.351622 -425.547282)
				(mid 84.147914 -425.547282)
				(end 84.351622 -425.547282)
			)
		)
		(stroke
			(width 0)
			(type solid)
		)
		(fill yes)
		(layer "B.Cu")
		(net "GND")
	)
	(gr_poly
		(pts
			(arc
				(start 86.351618 -439.651394)
				(mid 86.14791 -439.651394)
				(end 86.351618 -439.651394)
			)
		)
		(stroke
			(width 0)
			(type solid)
		)
		(fill yes)
		(layer "B.Cu")
		(net "GND")
	)
	(gr_poly
		(pts
			(arc
				(start 86.351618 -438.499758)
				(mid 86.14791 -438.499758)
				(end 86.351618 -438.499758)
			)
		)
		(stroke
			(width 0)
			(type solid)
		)
		(fill yes)
		(layer "B.Cu")
		(net "GND")
	)
	(gr_poly
		(pts
			(arc
				(start 86.351618 -437.34736)
				(mid 86.14791 -437.34736)
				(end 86.351618 -437.34736)
			)
		)
		(stroke
			(width 0)
			(type solid)
		)
		(fill yes)
		(layer "B.Cu")
		(net "GND")
	)
	(gr_poly
		(pts
			(arc
				(start 86.351618 -436.051198)
				(mid 86.14791 -436.051198)
				(end 86.351618 -436.051198)
			)
		)
		(stroke
			(width 0)
			(type solid)
		)
		(fill yes)
		(layer "B.Cu")
		(net "GND")
	)
	(gr_poly
		(pts
			(arc
				(start 86.351618 -434.899562)
				(mid 86.14791 -434.899562)
				(end 86.351618 -434.899562)
			)
		)
		(stroke
			(width 0)
			(type solid)
		)
		(fill yes)
		(layer "B.Cu")
		(net "GND")
	)
	(gr_poly
		(pts
			(arc
				(start 86.351618 -433.747164)
				(mid 86.14791 -433.747164)
				(end 86.351618 -433.747164)
			)
		)
		(stroke
			(width 0)
			(type solid)
		)
		(fill yes)
		(layer "B.Cu")
		(net "GND")
	)
	(gr_poly
		(pts
			(arc
				(start 86.351618 -432.451256)
				(mid 86.14791 -432.451256)
				(end 86.351618 -432.451256)
			)
		)
		(stroke
			(width 0)
			(type solid)
		)
		(fill yes)
		(layer "B.Cu")
		(net "GND")
	)
	(gr_poly
		(pts
			(arc
				(start 86.351618 -431.29962)
				(mid 86.14791 -431.29962)
				(end 86.351618 -431.29962)
			)
		)
		(stroke
			(width 0)
			(type solid)
		)
		(fill yes)
		(layer "B.Cu")
		(net "GND")
	)
	(gr_poly
		(pts
			(arc
				(start 86.351618 -430.147222)
				(mid 86.14791 -430.147222)
				(end 86.351618 -430.147222)
			)
		)
		(stroke
			(width 0)
			(type solid)
		)
		(fill yes)
		(layer "B.Cu")
		(net "GND")
	)
	(gr_poly
		(pts
			(arc
				(start 86.351618 -428.851314)
				(mid 86.14791 -428.851314)
				(end 86.351618 -428.851314)
			)
		)
		(stroke
			(width 0)
			(type solid)
		)
		(fill yes)
		(layer "B.Cu")
		(net "GND")
	)
	(gr_poly
		(pts
			(arc
				(start 86.351618 -427.699678)
				(mid 86.14791 -427.699678)
				(end 86.351618 -427.699678)
			)
		)
		(stroke
			(width 0)
			(type solid)
		)
		(fill yes)
		(layer "B.Cu")
		(net "GND")
	)
	(gr_poly
		(pts
			(arc
				(start 86.351618 -426.54728)
				(mid 86.14791 -426.54728)
				(end 86.351618 -426.54728)
			)
		)
		(stroke
			(width 0)
			(type solid)
		)
		(fill yes)
		(layer "B.Cu")
		(net "GND")
	)
	(gr_poly
		(pts
			(arc
				(start 88.351614 -438.651396)
				(mid 88.147906 -438.651396)
				(end 88.351614 -438.651396)
			)
		)
		(stroke
			(width 0)
			(type solid)
		)
		(fill yes)
		(layer "B.Cu")
		(net "GND")
	)
	(gr_poly
		(pts
			(arc
				(start 88.351614 -437.49976)
				(mid 88.147906 -437.49976)
				(end 88.351614 -437.49976)
			)
		)
		(stroke
			(width 0)
			(type solid)
		)
		(fill yes)
		(layer "B.Cu")
		(net "GND")
	)
	(gr_poly
		(pts
			(arc
				(start 88.351614 -436.347362)
				(mid 88.147906 -436.347362)
				(end 88.351614 -436.347362)
			)
		)
		(stroke
			(width 0)
			(type solid)
		)
		(fill yes)
		(layer "B.Cu")
		(net "GND")
	)
	(gr_poly
		(pts
			(arc
				(start 88.351614 -435.0512)
				(mid 88.147906 -435.0512)
				(end 88.351614 -435.0512)
			)
		)
		(stroke
			(width 0)
			(type solid)
		)
		(fill yes)
		(layer "B.Cu")
		(net "GND")
	)
	(gr_poly
		(pts
			(arc
				(start 88.351614 -433.899564)
				(mid 88.147906 -433.899564)
				(end 88.351614 -433.899564)
			)
		)
		(stroke
			(width 0)
			(type solid)
		)
		(fill yes)
		(layer "B.Cu")
		(net "GND")
	)
	(gr_poly
		(pts
			(arc
				(start 88.351614 -432.747166)
				(mid 88.147906 -432.747166)
				(end 88.351614 -432.747166)
			)
		)
		(stroke
			(width 0)
			(type solid)
		)
		(fill yes)
		(layer "B.Cu")
		(net "GND")
	)
	(gr_poly
		(pts
			(arc
				(start 88.351614 -431.451258)
				(mid 88.147906 -431.451258)
				(end 88.351614 -431.451258)
			)
		)
		(stroke
			(width 0)
			(type solid)
		)
		(fill yes)
		(layer "B.Cu")
		(net "GND")
	)
	(gr_poly
		(pts
			(arc
				(start 88.351614 -430.299622)
				(mid 88.147906 -430.299622)
				(end 88.351614 -430.299622)
			)
		)
		(stroke
			(width 0)
			(type solid)
		)
		(fill yes)
		(layer "B.Cu")
		(net "GND")
	)
	(gr_poly
		(pts
			(arc
				(start 88.351614 -429.147224)
				(mid 88.147906 -429.147224)
				(end 88.351614 -429.147224)
			)
		)
		(stroke
			(width 0)
			(type solid)
		)
		(fill yes)
		(layer "B.Cu")
		(net "GND")
	)
	(gr_poly
		(pts
			(arc
				(start 88.351614 -427.851316)
				(mid 88.147906 -427.851316)
				(end 88.351614 -427.851316)
			)
		)
		(stroke
			(width 0)
			(type solid)
		)
		(fill yes)
		(layer "B.Cu")
		(net "GND")
	)
	(gr_poly
		(pts
			(arc
				(start 88.351614 -426.69968)
				(mid 88.147906 -426.69968)
				(end 88.351614 -426.69968)
			)
		)
		(stroke
			(width 0)
			(type solid)
		)
		(fill yes)
		(layer "B.Cu")
		(net "GND")
	)
	(gr_poly
		(pts
			(arc
				(start 88.351614 -425.547282)
				(mid 88.147906 -425.547282)
				(end 88.351614 -425.547282)
			)
		)
		(stroke
			(width 0)
			(type solid)
		)
		(fill yes)
		(layer "B.Cu")
		(net "GND")
	)
	(gr_poly
		(pts
			(arc
				(start 90.35161 -439.651394)
				(mid 90.147902 -439.651394)
				(end 90.35161 -439.651394)
			)
		)
		(stroke
			(width 0)
			(type solid)
		)
		(fill yes)
		(layer "B.Cu")
		(net "GND")
	)
	(gr_poly
		(pts
			(arc
				(start 90.35161 -438.499758)
				(mid 90.147902 -438.499758)
				(end 90.35161 -438.499758)
			)
		)
		(stroke
			(width 0)
			(type solid)
		)
		(fill yes)
		(layer "B.Cu")
		(net "GND")
	)
	(gr_poly
		(pts
			(arc
				(start 90.35161 -437.34736)
				(mid 90.147902 -437.34736)
				(end 90.35161 -437.34736)
			)
		)
		(stroke
			(width 0)
			(type solid)
		)
		(fill yes)
		(layer "B.Cu")
		(net "GND")
	)
	(gr_poly
		(pts
			(arc
				(start 90.35161 -436.051198)
				(mid 90.147902 -436.051198)
				(end 90.35161 -436.051198)
			)
		)
		(stroke
			(width 0)
			(type solid)
		)
		(fill yes)
		(layer "B.Cu")
		(net "GND")
	)
	(gr_poly
		(pts
			(arc
				(start 90.35161 -434.899562)
				(mid 90.147902 -434.899562)
				(end 90.35161 -434.899562)
			)
		)
		(stroke
			(width 0)
			(type solid)
		)
		(fill yes)
		(layer "B.Cu")
		(net "GND")
	)
	(gr_poly
		(pts
			(arc
				(start 90.35161 -433.747164)
				(mid 90.147902 -433.747164)
				(end 90.35161 -433.747164)
			)
		)
		(stroke
			(width 0)
			(type solid)
		)
		(fill yes)
		(layer "B.Cu")
		(net "GND")
	)
	(gr_poly
		(pts
			(arc
				(start 90.35161 -432.451256)
				(mid 90.147902 -432.451256)
				(end 90.35161 -432.451256)
			)
		)
		(stroke
			(width 0)
			(type solid)
		)
		(fill yes)
		(layer "B.Cu")
		(net "GND")
	)
	(gr_poly
		(pts
			(arc
				(start 90.35161 -431.29962)
				(mid 90.147902 -431.29962)
				(end 90.35161 -431.29962)
			)
		)
		(stroke
			(width 0)
			(type solid)
		)
		(fill yes)
		(layer "B.Cu")
		(net "GND")
	)
	(gr_poly
		(pts
			(arc
				(start 90.35161 -430.147222)
				(mid 90.147902 -430.147222)
				(end 90.35161 -430.147222)
			)
		)
		(stroke
			(width 0)
			(type solid)
		)
		(fill yes)
		(layer "B.Cu")
		(net "GND")
	)
	(gr_poly
		(pts
			(arc
				(start 90.35161 -428.851314)
				(mid 90.147902 -428.851314)
				(end 90.35161 -428.851314)
			)
		)
		(stroke
			(width 0)
			(type solid)
		)
		(fill yes)
		(layer "B.Cu")
		(net "GND")
	)
	(gr_poly
		(pts
			(arc
				(start 90.35161 -427.699678)
				(mid 90.147902 -427.699678)
				(end 90.35161 -427.699678)
			)
		)
		(stroke
			(width 0)
			(type solid)
		)
		(fill yes)
		(layer "B.Cu")
		(net "GND")
	)
	(gr_poly
		(pts
			(arc
				(start 90.35161 -426.54728)
				(mid 90.147902 -426.54728)
				(end 90.35161 -426.54728)
			)
		)
		(stroke
			(width 0)
			(type solid)
		)
		(fill yes)
		(layer "B.Cu")
		(net "GND")
	)
	(gr_poly
		(pts
			(arc
				(start 126.451614 -438.651396)
				(mid 126.247906 -438.651396)
				(end 126.451614 -438.651396)
			)
		)
		(stroke
			(width 0)
			(type solid)
		)
		(fill yes)
		(layer "B.Cu")
		(net "GND")
	)
	(gr_poly
		(pts
			(arc
				(start 126.451614 -437.49976)
				(mid 126.247906 -437.49976)
				(end 126.451614 -437.49976)
			)
		)
		(stroke
			(width 0)
			(type solid)
		)
		(fill yes)
		(layer "B.Cu")
		(net "GND")
	)
	(gr_poly
		(pts
			(arc
				(start 126.451614 -436.347362)
				(mid 126.247906 -436.347362)
				(end 126.451614 -436.347362)
			)
		)
		(stroke
			(width 0)
			(type solid)
		)
		(fill yes)
		(layer "B.Cu")
		(net "GND")
	)
	(gr_poly
		(pts
			(arc
				(start 126.451614 -435.0512)
				(mid 126.247906 -435.0512)
				(end 126.451614 -435.0512)
			)
		)
		(stroke
			(width 0)
			(type solid)
		)
		(fill yes)
		(layer "B.Cu")
		(net "GND")
	)
	(gr_poly
		(pts
			(arc
				(start 126.451614 -433.899564)
				(mid 126.247906 -433.899564)
				(end 126.451614 -433.899564)
			)
		)
		(stroke
			(width 0)
			(type solid)
		)
		(fill yes)
		(layer "B.Cu")
		(net "GND")
	)
	(gr_poly
		(pts
			(arc
				(start 126.451614 -432.747166)
				(mid 126.247906 -432.747166)
				(end 126.451614 -432.747166)
			)
		)
		(stroke
			(width 0)
			(type solid)
		)
		(fill yes)
		(layer "B.Cu")
		(net "GND")
	)
	(gr_poly
		(pts
			(arc
				(start 126.451614 -431.451258)
				(mid 126.247906 -431.451258)
				(end 126.451614 -431.451258)
			)
		)
		(stroke
			(width 0)
			(type solid)
		)
		(fill yes)
		(layer "B.Cu")
		(net "GND")
	)
	(gr_poly
		(pts
			(arc
				(start 126.451614 -430.299622)
				(mid 126.247906 -430.299622)
				(end 126.451614 -430.299622)
			)
		)
		(stroke
			(width 0)
			(type solid)
		)
		(fill yes)
		(layer "B.Cu")
		(net "GND")
	)
	(gr_poly
		(pts
			(arc
				(start 126.451614 -429.147224)
				(mid 126.247906 -429.147224)
				(end 126.451614 -429.147224)
			)
		)
		(stroke
			(width 0)
			(type solid)
		)
		(fill yes)
		(layer "B.Cu")
		(net "GND")
	)
	(gr_poly
		(pts
			(arc
				(start 126.451614 -427.851316)
				(mid 126.247906 -427.851316)
				(end 126.451614 -427.851316)
			)
		)
		(stroke
			(width 0)
			(type solid)
		)
		(fill yes)
		(layer "B.Cu")
		(net "GND")
	)
	(gr_poly
		(pts
			(arc
				(start 126.451614 -426.69968)
				(mid 126.247906 -426.69968)
				(end 126.451614 -426.69968)
			)
		)
		(stroke
			(width 0)
			(type solid)
		)
		(fill yes)
		(layer "B.Cu")
		(net "GND")
	)
	(gr_poly
		(pts
			(arc
				(start 126.451614 -425.547282)
				(mid 126.247906 -425.547282)
				(end 126.451614 -425.547282)
			)
		)
		(stroke
			(width 0)
			(type solid)
		)
		(fill yes)
		(layer "B.Cu")
		(net "GND")
	)
	(gr_poly
		(pts
			(arc
				(start 128.45161 -439.651394)
				(mid 128.247902 -439.651394)
				(end 128.45161 -439.651394)
			)
		)
		(stroke
			(width 0)
			(type solid)
		)
		(fill yes)
		(layer "B.Cu")
		(net "GND")
	)
	(gr_poly
		(pts
			(arc
				(start 128.45161 -438.499758)
				(mid 128.247902 -438.499758)
				(end 128.45161 -438.499758)
			)
		)
		(stroke
			(width 0)
			(type solid)
		)
		(fill yes)
		(layer "B.Cu")
		(net "GND")
	)
	(gr_poly
		(pts
			(arc
				(start 128.45161 -437.34736)
				(mid 128.247902 -437.34736)
				(end 128.45161 -437.34736)
			)
		)
		(stroke
			(width 0)
			(type solid)
		)
		(fill yes)
		(layer "B.Cu")
		(net "GND")
	)
	(gr_poly
		(pts
			(arc
				(start 128.45161 -436.051198)
				(mid 128.247902 -436.051198)
				(end 128.45161 -436.051198)
			)
		)
		(stroke
			(width 0)
			(type solid)
		)
		(fill yes)
		(layer "B.Cu")
		(net "GND")
	)
	(gr_poly
		(pts
			(arc
				(start 128.45161 -434.899562)
				(mid 128.247902 -434.899562)
				(end 128.45161 -434.899562)
			)
		)
		(stroke
			(width 0)
			(type solid)
		)
		(fill yes)
		(layer "B.Cu")
		(net "GND")
	)
	(gr_poly
		(pts
			(arc
				(start 128.45161 -433.747164)
				(mid 128.247902 -433.747164)
				(end 128.45161 -433.747164)
			)
		)
		(stroke
			(width 0)
			(type solid)
		)
		(fill yes)
		(layer "B.Cu")
		(net "GND")
	)
	(gr_poly
		(pts
			(arc
				(start 128.45161 -432.451256)
				(mid 128.247902 -432.451256)
				(end 128.45161 -432.451256)
			)
		)
		(stroke
			(width 0)
			(type solid)
		)
		(fill yes)
		(layer "B.Cu")
		(net "GND")
	)
	(gr_poly
		(pts
			(arc
				(start 128.45161 -431.29962)
				(mid 128.247902 -431.29962)
				(end 128.45161 -431.29962)
			)
		)
		(stroke
			(width 0)
			(type solid)
		)
		(fill yes)
		(layer "B.Cu")
		(net "GND")
	)
	(gr_poly
		(pts
			(arc
				(start 128.45161 -430.147222)
				(mid 128.247902 -430.147222)
				(end 128.45161 -430.147222)
			)
		)
		(stroke
			(width 0)
			(type solid)
		)
		(fill yes)
		(layer "B.Cu")
		(net "GND")
	)
	(gr_poly
		(pts
			(arc
				(start 128.45161 -428.851314)
				(mid 128.247902 -428.851314)
				(end 128.45161 -428.851314)
			)
		)
		(stroke
			(width 0)
			(type solid)
		)
		(fill yes)
		(layer "B.Cu")
		(net "GND")
	)
	(gr_poly
		(pts
			(arc
				(start 128.45161 -427.699678)
				(mid 128.247902 -427.699678)
				(end 128.45161 -427.699678)
			)
		)
		(stroke
			(width 0)
			(type solid)
		)
		(fill yes)
		(layer "B.Cu")
		(net "GND")
	)
	(gr_poly
		(pts
			(arc
				(start 128.45161 -426.54728)
				(mid 128.247902 -426.54728)
				(end 128.45161 -426.54728)
			)
		)
		(stroke
			(width 0)
			(type solid)
		)
		(fill yes)
		(layer "B.Cu")
		(net "GND")
	)
	(gr_poly
		(pts
			(arc
				(start 130.451606 -438.651396)
				(mid 130.247898 -438.651396)
				(end 130.451606 -438.651396)
			)
		)
		(stroke
			(width 0)
			(type solid)
		)
		(fill yes)
		(layer "B.Cu")
		(net "GND")
	)
	(gr_poly
		(pts
			(arc
				(start 130.451606 -437.49976)
				(mid 130.247898 -437.49976)
				(end 130.451606 -437.49976)
			)
		)
		(stroke
			(width 0)
			(type solid)
		)
		(fill yes)
		(layer "B.Cu")
		(net "GND")
	)
	(gr_poly
		(pts
			(arc
				(start 130.451606 -436.347362)
				(mid 130.247898 -436.347362)
				(end 130.451606 -436.347362)
			)
		)
		(stroke
			(width 0)
			(type solid)
		)
		(fill yes)
		(layer "B.Cu")
		(net "GND")
	)
	(gr_poly
		(pts
			(arc
				(start 130.451606 -435.0512)
				(mid 130.247898 -435.0512)
				(end 130.451606 -435.0512)
			)
		)
		(stroke
			(width 0)
			(type solid)
		)
		(fill yes)
		(layer "B.Cu")
		(net "GND")
	)
	(gr_poly
		(pts
			(arc
				(start 130.451606 -433.899564)
				(mid 130.247898 -433.899564)
				(end 130.451606 -433.899564)
			)
		)
		(stroke
			(width 0)
			(type solid)
		)
		(fill yes)
		(layer "B.Cu")
		(net "GND")
	)
	(gr_poly
		(pts
			(arc
				(start 130.451606 -432.747166)
				(mid 130.247898 -432.747166)
				(end 130.451606 -432.747166)
			)
		)
		(stroke
			(width 0)
			(type solid)
		)
		(fill yes)
		(layer "B.Cu")
		(net "GND")
	)
	(gr_poly
		(pts
			(arc
				(start 130.451606 -431.451258)
				(mid 130.247898 -431.451258)
				(end 130.451606 -431.451258)
			)
		)
		(stroke
			(width 0)
			(type solid)
		)
		(fill yes)
		(layer "B.Cu")
		(net "GND")
	)
	(gr_poly
		(pts
			(arc
				(start 130.451606 -430.299622)
				(mid 130.247898 -430.299622)
				(end 130.451606 -430.299622)
			)
		)
		(stroke
			(width 0)
			(type solid)
		)
		(fill yes)
		(layer "B.Cu")
		(net "GND")
	)
	(gr_poly
		(pts
			(arc
				(start 130.451606 -429.147224)
				(mid 130.247898 -429.147224)
				(end 130.451606 -429.147224)
			)
		)
		(stroke
			(width 0)
			(type solid)
		)
		(fill yes)
		(layer "B.Cu")
		(net "GND")
	)
	(gr_poly
		(pts
			(arc
				(start 130.451606 -427.851316)
				(mid 130.247898 -427.851316)
				(end 130.451606 -427.851316)
			)
		)
		(stroke
			(width 0)
			(type solid)
		)
		(fill yes)
		(layer "B.Cu")
		(net "GND")
	)
	(gr_poly
		(pts
			(arc
				(start 130.451606 -426.69968)
				(mid 130.247898 -426.69968)
				(end 130.451606 -426.69968)
			)
		)
		(stroke
			(width 0)
			(type solid)
		)
		(fill yes)
		(layer "B.Cu")
		(net "GND")
	)
	(gr_poly
		(pts
			(arc
				(start 130.451606 -425.547282)
				(mid 130.247898 -425.547282)
				(end 130.451606 -425.547282)
			)
		)
		(stroke
			(width 0)
			(type solid)
		)
		(fill yes)
		(layer "B.Cu")
		(net "GND")
	)
	(gr_poly
		(pts
			(arc
				(start 132.451602 -439.651394)
				(mid 132.247894 -439.651394)
				(end 132.451602 -439.651394)
			)
		)
		(stroke
			(width 0)
			(type solid)
		)
		(fill yes)
		(layer "B.Cu")
		(net "GND")
	)
	(gr_poly
		(pts
			(arc
				(start 132.451602 -438.499758)
				(mid 132.247894 -438.499758)
				(end 132.451602 -438.499758)
			)
		)
		(stroke
			(width 0)
			(type solid)
		)
		(fill yes)
		(layer "B.Cu")
		(net "GND")
	)
	(gr_poly
		(pts
			(arc
				(start 132.451602 -437.34736)
				(mid 132.247894 -437.34736)
				(end 132.451602 -437.34736)
			)
		)
		(stroke
			(width 0)
			(type solid)
		)
		(fill yes)
		(layer "B.Cu")
		(net "GND")
	)
	(gr_poly
		(pts
			(arc
				(start 132.451602 -436.051198)
				(mid 132.247894 -436.051198)
				(end 132.451602 -436.051198)
			)
		)
		(stroke
			(width 0)
			(type solid)
		)
		(fill yes)
		(layer "B.Cu")
		(net "GND")
	)
	(gr_poly
		(pts
			(arc
				(start 132.451602 -434.899562)
				(mid 132.247894 -434.899562)
				(end 132.451602 -434.899562)
			)
		)
		(stroke
			(width 0)
			(type solid)
		)
		(fill yes)
		(layer "B.Cu")
		(net "GND")
	)
	(gr_poly
		(pts
			(arc
				(start 132.451602 -433.747164)
				(mid 132.247894 -433.747164)
				(end 132.451602 -433.747164)
			)
		)
		(stroke
			(width 0)
			(type solid)
		)
		(fill yes)
		(layer "B.Cu")
		(net "GND")
	)
	(gr_poly
		(pts
			(arc
				(start 132.451602 -432.451256)
				(mid 132.247894 -432.451256)
				(end 132.451602 -432.451256)
			)
		)
		(stroke
			(width 0)
			(type solid)
		)
		(fill yes)
		(layer "B.Cu")
		(net "GND")
	)
	(gr_poly
		(pts
			(arc
				(start 132.451602 -431.29962)
				(mid 132.247894 -431.29962)
				(end 132.451602 -431.29962)
			)
		)
		(stroke
			(width 0)
			(type solid)
		)
		(fill yes)
		(layer "B.Cu")
		(net "GND")
	)
	(gr_poly
		(pts
			(arc
				(start 132.451602 -430.147222)
				(mid 132.247894 -430.147222)
				(end 132.451602 -430.147222)
			)
		)
		(stroke
			(width 0)
			(type solid)
		)
		(fill yes)
		(layer "B.Cu")
		(net "GND")
	)
	(gr_poly
		(pts
			(arc
				(start 132.451602 -428.851314)
				(mid 132.247894 -428.851314)
				(end 132.451602 -428.851314)
			)
		)
		(stroke
			(width 0)
			(type solid)
		)
		(fill yes)
		(layer "B.Cu")
		(net "GND")
	)
	(gr_poly
		(pts
			(arc
				(start 132.451602 -427.699678)
				(mid 132.247894 -427.699678)
				(end 132.451602 -427.699678)
			)
		)
		(stroke
			(width 0)
			(type solid)
		)
		(fill yes)
		(layer "B.Cu")
		(net "GND")
	)
	(gr_poly
		(pts
			(arc
				(start 132.451602 -426.54728)
				(mid 132.247894 -426.54728)
				(end 132.451602 -426.54728)
			)
		)
		(stroke
			(width 0)
			(type solid)
		)
		(fill yes)
		(layer "B.Cu")
		(net "GND")
	)
	(gr_poly
		(pts
			(arc
				(start 134.451598 -438.651396)
				(mid 134.24789 -438.651396)
				(end 134.451598 -438.651396)
			)
		)
		(stroke
			(width 0)
			(type solid)
		)
		(fill yes)
		(layer "B.Cu")
		(net "GND")
	)
	(gr_poly
		(pts
			(arc
				(start 134.451598 -437.49976)
				(mid 134.24789 -437.49976)
				(end 134.451598 -437.49976)
			)
		)
		(stroke
			(width 0)
			(type solid)
		)
		(fill yes)
		(layer "B.Cu")
		(net "GND")
	)
	(gr_poly
		(pts
			(arc
				(start 134.451598 -436.347362)
				(mid 134.24789 -436.347362)
				(end 134.451598 -436.347362)
			)
		)
		(stroke
			(width 0)
			(type solid)
		)
		(fill yes)
		(layer "B.Cu")
		(net "GND")
	)
	(gr_poly
		(pts
			(arc
				(start 134.451598 -435.0512)
				(mid 134.24789 -435.0512)
				(end 134.451598 -435.0512)
			)
		)
		(stroke
			(width 0)
			(type solid)
		)
		(fill yes)
		(layer "B.Cu")
		(net "GND")
	)
	(gr_poly
		(pts
			(arc
				(start 134.451598 -433.899564)
				(mid 134.24789 -433.899564)
				(end 134.451598 -433.899564)
			)
		)
		(stroke
			(width 0)
			(type solid)
		)
		(fill yes)
		(layer "B.Cu")
		(net "GND")
	)
	(gr_poly
		(pts
			(arc
				(start 134.451598 -432.747166)
				(mid 134.24789 -432.747166)
				(end 134.451598 -432.747166)
			)
		)
		(stroke
			(width 0)
			(type solid)
		)
		(fill yes)
		(layer "B.Cu")
		(net "GND")
	)
	(gr_poly
		(pts
			(arc
				(start 134.451598 -431.451258)
				(mid 134.24789 -431.451258)
				(end 134.451598 -431.451258)
			)
		)
		(stroke
			(width 0)
			(type solid)
		)
		(fill yes)
		(layer "B.Cu")
		(net "GND")
	)
	(gr_poly
		(pts
			(arc
				(start 134.451598 -430.299622)
				(mid 134.24789 -430.299622)
				(end 134.451598 -430.299622)
			)
		)
		(stroke
			(width 0)
			(type solid)
		)
		(fill yes)
		(layer "B.Cu")
		(net "GND")
	)
	(gr_poly
		(pts
			(arc
				(start 134.451598 -429.147224)
				(mid 134.24789 -429.147224)
				(end 134.451598 -429.147224)
			)
		)
		(stroke
			(width 0)
			(type solid)
		)
		(fill yes)
		(layer "B.Cu")
		(net "GND")
	)
	(gr_poly
		(pts
			(arc
				(start 134.451598 -427.851316)
				(mid 134.24789 -427.851316)
				(end 134.451598 -427.851316)
			)
		)
		(stroke
			(width 0)
			(type solid)
		)
		(fill yes)
		(layer "B.Cu")
		(net "GND")
	)
	(gr_poly
		(pts
			(arc
				(start 134.451598 -426.69968)
				(mid 134.24789 -426.69968)
				(end 134.451598 -426.69968)
			)
		)
		(stroke
			(width 0)
			(type solid)
		)
		(fill yes)
		(layer "B.Cu")
		(net "GND")
	)
	(gr_poly
		(pts
			(arc
				(start 134.451598 -425.547282)
				(mid 134.24789 -425.547282)
				(end 134.451598 -425.547282)
			)
		)
		(stroke
			(width 0)
			(type solid)
		)
		(fill yes)
		(layer "B.Cu")
		(net "GND")
	)
	(gr_poly
		(pts
			(arc
				(start 136.451594 -439.651394)
				(mid 136.247886 -439.651394)
				(end 136.451594 -439.651394)
			)
		)
		(stroke
			(width 0)
			(type solid)
		)
		(fill yes)
		(layer "B.Cu")
		(net "GND")
	)
	(gr_poly
		(pts
			(arc
				(start 136.451594 -438.499758)
				(mid 136.247886 -438.499758)
				(end 136.451594 -438.499758)
			)
		)
		(stroke
			(width 0)
			(type solid)
		)
		(fill yes)
		(layer "B.Cu")
		(net "GND")
	)
	(gr_poly
		(pts
			(arc
				(start 136.451594 -437.34736)
				(mid 136.247886 -437.34736)
				(end 136.451594 -437.34736)
			)
		)
		(stroke
			(width 0)
			(type solid)
		)
		(fill yes)
		(layer "B.Cu")
		(net "GND")
	)
	(gr_poly
		(pts
			(arc
				(start 136.451594 -436.051198)
				(mid 136.247886 -436.051198)
				(end 136.451594 -436.051198)
			)
		)
		(stroke
			(width 0)
			(type solid)
		)
		(fill yes)
		(layer "B.Cu")
		(net "GND")
	)
	(gr_poly
		(pts
			(arc
				(start 136.451594 -434.899562)
				(mid 136.247886 -434.899562)
				(end 136.451594 -434.899562)
			)
		)
		(stroke
			(width 0)
			(type solid)
		)
		(fill yes)
		(layer "B.Cu")
		(net "GND")
	)
	(gr_poly
		(pts
			(arc
				(start 136.451594 -433.747164)
				(mid 136.247886 -433.747164)
				(end 136.451594 -433.747164)
			)
		)
		(stroke
			(width 0)
			(type solid)
		)
		(fill yes)
		(layer "B.Cu")
		(net "GND")
	)
	(gr_poly
		(pts
			(arc
				(start 136.451594 -432.451256)
				(mid 136.247886 -432.451256)
				(end 136.451594 -432.451256)
			)
		)
		(stroke
			(width 0)
			(type solid)
		)
		(fill yes)
		(layer "B.Cu")
		(net "GND")
	)
	(gr_poly
		(pts
			(arc
				(start 136.451594 -431.29962)
				(mid 136.247886 -431.29962)
				(end 136.451594 -431.29962)
			)
		)
		(stroke
			(width 0)
			(type solid)
		)
		(fill yes)
		(layer "B.Cu")
		(net "GND")
	)
	(gr_poly
		(pts
			(arc
				(start 136.451594 -430.147222)
				(mid 136.247886 -430.147222)
				(end 136.451594 -430.147222)
			)
		)
		(stroke
			(width 0)
			(type solid)
		)
		(fill yes)
		(layer "B.Cu")
		(net "GND")
	)
	(gr_poly
		(pts
			(arc
				(start 136.451594 -428.851314)
				(mid 136.247886 -428.851314)
				(end 136.451594 -428.851314)
			)
		)
		(stroke
			(width 0)
			(type solid)
		)
		(fill yes)
		(layer "B.Cu")
		(net "GND")
	)
	(gr_poly
		(pts
			(arc
				(start 136.451594 -427.699678)
				(mid 136.247886 -427.699678)
				(end 136.451594 -427.699678)
			)
		)
		(stroke
			(width 0)
			(type solid)
		)
		(fill yes)
		(layer "B.Cu")
		(net "GND")
	)
	(gr_poly
		(pts
			(arc
				(start 136.451594 -426.54728)
				(mid 136.247886 -426.54728)
				(end 136.451594 -426.54728)
			)
		)
		(stroke
			(width 0)
			(type solid)
		)
		(fill yes)
		(layer "B.Cu")
		(net "GND")
	)
	(gr_poly
		(pts
			(xy 137.305034 -44.07916) (xy 137.305034 -42.66946) (xy 137.305034 -41.575228) (xy 136.948418 -41.218612)
			(xy 136.884918 -41.155112) (xy 136.034018 -41.155112) (xy 135.602218 -40.723312) (xy 135.602218 -39.958518)
			(xy 135.4963 -39.8526) (xy 135.025638 -39.8526) (xy 134.967218 -39.91102) (xy 134.967218 -42.746676)
			(xy 134.775194 -42.9387) (xy 133.92658 -42.9387) (xy 133.78434 -42.79646) (xy 133.78434 -41.22166)
			(xy 133.697472 -41.134792) (xy 132.255768 -41.134792) (xy 132.19557 -41.19499) (xy 132.19557 -42.08907)
			(xy 133.22808 -43.12158) (xy 134.24916 -44.14266) (xy 137.241534 -44.14266)
		)
		(stroke
			(width 0)
			(type solid)
		)
		(fill yes)
		(layer "B.Cu")
		(net "P1V2_CPU0_USB_DVDD12")
	)
	(gr_poly
		(pts
			(arc
				(start 138.45159 -438.651396)
				(mid 138.247882 -438.651396)
				(end 138.45159 -438.651396)
			)
		)
		(stroke
			(width 0)
			(type solid)
		)
		(fill yes)
		(layer "B.Cu")
		(net "GND")
	)
	(gr_poly
		(pts
			(arc
				(start 138.45159 -437.49976)
				(mid 138.247882 -437.49976)
				(end 138.45159 -437.49976)
			)
		)
		(stroke
			(width 0)
			(type solid)
		)
		(fill yes)
		(layer "B.Cu")
		(net "GND")
	)
	(gr_poly
		(pts
			(arc
				(start 138.45159 -436.347362)
				(mid 138.247882 -436.347362)
				(end 138.45159 -436.347362)
			)
		)
		(stroke
			(width 0)
			(type solid)
		)
		(fill yes)
		(layer "B.Cu")
		(net "GND")
	)
	(gr_poly
		(pts
			(arc
				(start 138.45159 -435.0512)
				(mid 138.247882 -435.0512)
				(end 138.45159 -435.0512)
			)
		)
		(stroke
			(width 0)
			(type solid)
		)
		(fill yes)
		(layer "B.Cu")
		(net "GND")
	)
	(gr_poly
		(pts
			(arc
				(start 138.45159 -433.899564)
				(mid 138.247882 -433.899564)
				(end 138.45159 -433.899564)
			)
		)
		(stroke
			(width 0)
			(type solid)
		)
		(fill yes)
		(layer "B.Cu")
		(net "GND")
	)
	(gr_poly
		(pts
			(arc
				(start 138.45159 -432.747166)
				(mid 138.247882 -432.747166)
				(end 138.45159 -432.747166)
			)
		)
		(stroke
			(width 0)
			(type solid)
		)
		(fill yes)
		(layer "B.Cu")
		(net "GND")
	)
	(gr_poly
		(pts
			(arc
				(start 138.45159 -431.451258)
				(mid 138.247882 -431.451258)
				(end 138.45159 -431.451258)
			)
		)
		(stroke
			(width 0)
			(type solid)
		)
		(fill yes)
		(layer "B.Cu")
		(net "GND")
	)
	(gr_poly
		(pts
			(arc
				(start 138.45159 -430.299622)
				(mid 138.247882 -430.299622)
				(end 138.45159 -430.299622)
			)
		)
		(stroke
			(width 0)
			(type solid)
		)
		(fill yes)
		(layer "B.Cu")
		(net "GND")
	)
	(gr_poly
		(pts
			(arc
				(start 138.45159 -429.147224)
				(mid 138.247882 -429.147224)
				(end 138.45159 -429.147224)
			)
		)
		(stroke
			(width 0)
			(type solid)
		)
		(fill yes)
		(layer "B.Cu")
		(net "GND")
	)
	(gr_poly
		(pts
			(arc
				(start 138.45159 -427.851316)
				(mid 138.247882 -427.851316)
				(end 138.45159 -427.851316)
			)
		)
		(stroke
			(width 0)
			(type solid)
		)
		(fill yes)
		(layer "B.Cu")
		(net "GND")
	)
	(gr_poly
		(pts
			(arc
				(start 138.45159 -426.69968)
				(mid 138.247882 -426.69968)
				(end 138.45159 -426.69968)
			)
		)
		(stroke
			(width 0)
			(type solid)
		)
		(fill yes)
		(layer "B.Cu")
		(net "GND")
	)
	(gr_poly
		(pts
			(arc
				(start 138.45159 -425.547282)
				(mid 138.247882 -425.547282)
				(end 138.45159 -425.547282)
			)
		)
		(stroke
			(width 0)
			(type solid)
		)
		(fill yes)
		(layer "B.Cu")
		(net "GND")
	)
	(gr_poly
		(pts
			(arc
				(start 140.451586 -439.651394)
				(mid 140.247878 -439.651394)
				(end 140.451586 -439.651394)
			)
		)
		(stroke
			(width 0)
			(type solid)
		)
		(fill yes)
		(layer "B.Cu")
		(net "GND")
	)
	(gr_poly
		(pts
			(arc
				(start 140.451586 -438.499758)
				(mid 140.247878 -438.499758)
				(end 140.451586 -438.499758)
			)
		)
		(stroke
			(width 0)
			(type solid)
		)
		(fill yes)
		(layer "B.Cu")
		(net "GND")
	)
	(gr_poly
		(pts
			(arc
				(start 140.451586 -437.34736)
				(mid 140.247878 -437.34736)
				(end 140.451586 -437.34736)
			)
		)
		(stroke
			(width 0)
			(type solid)
		)
		(fill yes)
		(layer "B.Cu")
		(net "GND")
	)
	(gr_poly
		(pts
			(arc
				(start 140.451586 -436.051198)
				(mid 140.247878 -436.051198)
				(end 140.451586 -436.051198)
			)
		)
		(stroke
			(width 0)
			(type solid)
		)
		(fill yes)
		(layer "B.Cu")
		(net "GND")
	)
	(gr_poly
		(pts
			(arc
				(start 140.451586 -434.899562)
				(mid 140.247878 -434.899562)
				(end 140.451586 -434.899562)
			)
		)
		(stroke
			(width 0)
			(type solid)
		)
		(fill yes)
		(layer "B.Cu")
		(net "GND")
	)
	(gr_poly
		(pts
			(arc
				(start 140.451586 -433.747164)
				(mid 140.247878 -433.747164)
				(end 140.451586 -433.747164)
			)
		)
		(stroke
			(width 0)
			(type solid)
		)
		(fill yes)
		(layer "B.Cu")
		(net "GND")
	)
	(gr_poly
		(pts
			(arc
				(start 140.451586 -432.451256)
				(mid 140.247878 -432.451256)
				(end 140.451586 -432.451256)
			)
		)
		(stroke
			(width 0)
			(type solid)
		)
		(fill yes)
		(layer "B.Cu")
		(net "GND")
	)
	(gr_poly
		(pts
			(arc
				(start 140.451586 -431.29962)
				(mid 140.247878 -431.29962)
				(end 140.451586 -431.29962)
			)
		)
		(stroke
			(width 0)
			(type solid)
		)
		(fill yes)
		(layer "B.Cu")
		(net "GND")
	)
	(gr_poly
		(pts
			(arc
				(start 140.451586 -430.147222)
				(mid 140.247878 -430.147222)
				(end 140.451586 -430.147222)
			)
		)
		(stroke
			(width 0)
			(type solid)
		)
		(fill yes)
		(layer "B.Cu")
		(net "GND")
	)
	(gr_poly
		(pts
			(arc
				(start 140.451586 -428.851314)
				(mid 140.247878 -428.851314)
				(end 140.451586 -428.851314)
			)
		)
		(stroke
			(width 0)
			(type solid)
		)
		(fill yes)
		(layer "B.Cu")
		(net "GND")
	)
	(gr_poly
		(pts
			(arc
				(start 140.451586 -427.699678)
				(mid 140.247878 -427.699678)
				(end 140.451586 -427.699678)
			)
		)
		(stroke
			(width 0)
			(type solid)
		)
		(fill yes)
		(layer "B.Cu")
		(net "GND")
	)
	(gr_poly
		(pts
			(arc
				(start 140.451586 -426.54728)
				(mid 140.247878 -426.54728)
				(end 140.451586 -426.54728)
			)
		)
		(stroke
			(width 0)
			(type solid)
		)
		(fill yes)
		(layer "B.Cu")
		(net "GND")
	)
	(gr_poly
		(pts
			(arc
				(start 143.45158 -438.651396)
				(mid 143.247872 -438.651396)
				(end 143.45158 -438.651396)
			)
		)
		(stroke
			(width 0)
			(type solid)
		)
		(fill yes)
		(layer "B.Cu")
		(net "GND")
	)
	(gr_poly
		(pts
			(arc
				(start 143.45158 -437.49976)
				(mid 143.247872 -437.49976)
				(end 143.45158 -437.49976)
			)
		)
		(stroke
			(width 0)
			(type solid)
		)
		(fill yes)
		(layer "B.Cu")
		(net "GND")
	)
	(gr_poly
		(pts
			(arc
				(start 143.45158 -436.347362)
				(mid 143.247872 -436.347362)
				(end 143.45158 -436.347362)
			)
		)
		(stroke
			(width 0)
			(type solid)
		)
		(fill yes)
		(layer "B.Cu")
		(net "GND")
	)
	(gr_poly
		(pts
			(arc
				(start 143.45158 -435.0512)
				(mid 143.247872 -435.0512)
				(end 143.45158 -435.0512)
			)
		)
		(stroke
			(width 0)
			(type solid)
		)
		(fill yes)
		(layer "B.Cu")
		(net "GND")
	)
	(gr_poly
		(pts
			(arc
				(start 143.45158 -433.899564)
				(mid 143.247872 -433.899564)
				(end 143.45158 -433.899564)
			)
		)
		(stroke
			(width 0)
			(type solid)
		)
		(fill yes)
		(layer "B.Cu")
		(net "GND")
	)
	(gr_poly
		(pts
			(arc
				(start 143.45158 -432.747166)
				(mid 143.247872 -432.747166)
				(end 143.45158 -432.747166)
			)
		)
		(stroke
			(width 0)
			(type solid)
		)
		(fill yes)
		(layer "B.Cu")
		(net "GND")
	)
	(gr_poly
		(pts
			(arc
				(start 143.45158 -431.451258)
				(mid 143.247872 -431.451258)
				(end 143.45158 -431.451258)
			)
		)
		(stroke
			(width 0)
			(type solid)
		)
		(fill yes)
		(layer "B.Cu")
		(net "GND")
	)
	(gr_poly
		(pts
			(arc
				(start 143.45158 -430.299622)
				(mid 143.247872 -430.299622)
				(end 143.45158 -430.299622)
			)
		)
		(stroke
			(width 0)
			(type solid)
		)
		(fill yes)
		(layer "B.Cu")
		(net "GND")
	)
	(gr_poly
		(pts
			(arc
				(start 143.45158 -429.147224)
				(mid 143.247872 -429.147224)
				(end 143.45158 -429.147224)
			)
		)
		(stroke
			(width 0)
			(type solid)
		)
		(fill yes)
		(layer "B.Cu")
		(net "GND")
	)
	(gr_poly
		(pts
			(arc
				(start 143.45158 -427.851316)
				(mid 143.247872 -427.851316)
				(end 143.45158 -427.851316)
			)
		)
		(stroke
			(width 0)
			(type solid)
		)
		(fill yes)
		(layer "B.Cu")
		(net "GND")
	)
	(gr_poly
		(pts
			(arc
				(start 143.45158 -426.69968)
				(mid 143.247872 -426.69968)
				(end 143.45158 -426.69968)
			)
		)
		(stroke
			(width 0)
			(type solid)
		)
		(fill yes)
		(layer "B.Cu")
		(net "GND")
	)
	(gr_poly
		(pts
			(arc
				(start 143.45158 -425.547282)
				(mid 143.247872 -425.547282)
				(end 143.45158 -425.547282)
			)
		)
		(stroke
			(width 0)
			(type solid)
		)
		(fill yes)
		(layer "B.Cu")
		(net "GND")
	)
	(gr_poly
		(pts
			(arc
				(start 145.451576 -439.651394)
				(mid 145.247868 -439.651394)
				(end 145.451576 -439.651394)
			)
		)
		(stroke
			(width 0)
			(type solid)
		)
		(fill yes)
		(layer "B.Cu")
		(net "GND")
	)
	(gr_poly
		(pts
			(arc
				(start 145.451576 -438.499758)
				(mid 145.247868 -438.499758)
				(end 145.451576 -438.499758)
			)
		)
		(stroke
			(width 0)
			(type solid)
		)
		(fill yes)
		(layer "B.Cu")
		(net "GND")
	)
	(gr_poly
		(pts
			(arc
				(start 145.451576 -437.34736)
				(mid 145.247868 -437.34736)
				(end 145.451576 -437.34736)
			)
		)
		(stroke
			(width 0)
			(type solid)
		)
		(fill yes)
		(layer "B.Cu")
		(net "GND")
	)
	(gr_poly
		(pts
			(arc
				(start 145.451576 -436.051198)
				(mid 145.247868 -436.051198)
				(end 145.451576 -436.051198)
			)
		)
		(stroke
			(width 0)
			(type solid)
		)
		(fill yes)
		(layer "B.Cu")
		(net "GND")
	)
	(gr_poly
		(pts
			(arc
				(start 145.451576 -434.899562)
				(mid 145.247868 -434.899562)
				(end 145.451576 -434.899562)
			)
		)
		(stroke
			(width 0)
			(type solid)
		)
		(fill yes)
		(layer "B.Cu")
		(net "GND")
	)
	(gr_poly
		(pts
			(arc
				(start 145.451576 -433.747164)
				(mid 145.247868 -433.747164)
				(end 145.451576 -433.747164)
			)
		)
		(stroke
			(width 0)
			(type solid)
		)
		(fill yes)
		(layer "B.Cu")
		(net "GND")
	)
	(gr_poly
		(pts
			(arc
				(start 145.451576 -432.451256)
				(mid 145.247868 -432.451256)
				(end 145.451576 -432.451256)
			)
		)
		(stroke
			(width 0)
			(type solid)
		)
		(fill yes)
		(layer "B.Cu")
		(net "GND")
	)
	(gr_poly
		(pts
			(arc
				(start 145.451576 -431.29962)
				(mid 145.247868 -431.29962)
				(end 145.451576 -431.29962)
			)
		)
		(stroke
			(width 0)
			(type solid)
		)
		(fill yes)
		(layer "B.Cu")
		(net "GND")
	)
	(gr_poly
		(pts
			(arc
				(start 145.451576 -430.147222)
				(mid 145.247868 -430.147222)
				(end 145.451576 -430.147222)
			)
		)
		(stroke
			(width 0)
			(type solid)
		)
		(fill yes)
		(layer "B.Cu")
		(net "GND")
	)
	(gr_poly
		(pts
			(arc
				(start 145.451576 -428.851314)
				(mid 145.247868 -428.851314)
				(end 145.451576 -428.851314)
			)
		)
		(stroke
			(width 0)
			(type solid)
		)
		(fill yes)
		(layer "B.Cu")
		(net "GND")
	)
	(gr_poly
		(pts
			(arc
				(start 145.451576 -427.699678)
				(mid 145.247868 -427.699678)
				(end 145.451576 -427.699678)
			)
		)
		(stroke
			(width 0)
			(type solid)
		)
		(fill yes)
		(layer "B.Cu")
		(net "GND")
	)
	(gr_poly
		(pts
			(arc
				(start 145.451576 -426.54728)
				(mid 145.247868 -426.54728)
				(end 145.451576 -426.54728)
			)
		)
		(stroke
			(width 0)
			(type solid)
		)
		(fill yes)
		(layer "B.Cu")
		(net "GND")
	)
	(gr_poly
		(pts
			(arc
				(start 147.451572 -438.651396)
				(mid 147.247864 -438.651396)
				(end 147.451572 -438.651396)
			)
		)
		(stroke
			(width 0)
			(type solid)
		)
		(fill yes)
		(layer "B.Cu")
		(net "GND")
	)
	(gr_poly
		(pts
			(arc
				(start 147.451572 -437.49976)
				(mid 147.247864 -437.49976)
				(end 147.451572 -437.49976)
			)
		)
		(stroke
			(width 0)
			(type solid)
		)
		(fill yes)
		(layer "B.Cu")
		(net "GND")
	)
	(gr_poly
		(pts
			(arc
				(start 147.451572 -436.347362)
				(mid 147.247864 -436.347362)
				(end 147.451572 -436.347362)
			)
		)
		(stroke
			(width 0)
			(type solid)
		)
		(fill yes)
		(layer "B.Cu")
		(net "GND")
	)
	(gr_poly
		(pts
			(arc
				(start 147.451572 -435.0512)
				(mid 147.247864 -435.0512)
				(end 147.451572 -435.0512)
			)
		)
		(stroke
			(width 0)
			(type solid)
		)
		(fill yes)
		(layer "B.Cu")
		(net "GND")
	)
	(gr_poly
		(pts
			(arc
				(start 147.451572 -433.899564)
				(mid 147.247864 -433.899564)
				(end 147.451572 -433.899564)
			)
		)
		(stroke
			(width 0)
			(type solid)
		)
		(fill yes)
		(layer "B.Cu")
		(net "GND")
	)
	(gr_poly
		(pts
			(arc
				(start 147.451572 -432.747166)
				(mid 147.247864 -432.747166)
				(end 147.451572 -432.747166)
			)
		)
		(stroke
			(width 0)
			(type solid)
		)
		(fill yes)
		(layer "B.Cu")
		(net "GND")
	)
	(gr_poly
		(pts
			(arc
				(start 147.451572 -431.451258)
				(mid 147.247864 -431.451258)
				(end 147.451572 -431.451258)
			)
		)
		(stroke
			(width 0)
			(type solid)
		)
		(fill yes)
		(layer "B.Cu")
		(net "GND")
	)
	(gr_poly
		(pts
			(arc
				(start 147.451572 -430.299622)
				(mid 147.247864 -430.299622)
				(end 147.451572 -430.299622)
			)
		)
		(stroke
			(width 0)
			(type solid)
		)
		(fill yes)
		(layer "B.Cu")
		(net "GND")
	)
	(gr_poly
		(pts
			(arc
				(start 147.451572 -429.147224)
				(mid 147.247864 -429.147224)
				(end 147.451572 -429.147224)
			)
		)
		(stroke
			(width 0)
			(type solid)
		)
		(fill yes)
		(layer "B.Cu")
		(net "GND")
	)
	(gr_poly
		(pts
			(arc
				(start 147.451572 -427.851316)
				(mid 147.247864 -427.851316)
				(end 147.451572 -427.851316)
			)
		)
		(stroke
			(width 0)
			(type solid)
		)
		(fill yes)
		(layer "B.Cu")
		(net "GND")
	)
	(gr_poly
		(pts
			(arc
				(start 147.451572 -426.69968)
				(mid 147.247864 -426.69968)
				(end 147.451572 -426.69968)
			)
		)
		(stroke
			(width 0)
			(type solid)
		)
		(fill yes)
		(layer "B.Cu")
		(net "GND")
	)
	(gr_poly
		(pts
			(arc
				(start 147.451572 -425.547282)
				(mid 147.247864 -425.547282)
				(end 147.451572 -425.547282)
			)
		)
		(stroke
			(width 0)
			(type solid)
		)
		(fill yes)
		(layer "B.Cu")
		(net "GND")
	)
	(gr_poly
		(pts
			(arc
				(start 149.451568 -439.651394)
				(mid 149.24786 -439.651394)
				(end 149.451568 -439.651394)
			)
		)
		(stroke
			(width 0)
			(type solid)
		)
		(fill yes)
		(layer "B.Cu")
		(net "GND")
	)
	(gr_poly
		(pts
			(arc
				(start 149.451568 -438.499758)
				(mid 149.24786 -438.499758)
				(end 149.451568 -438.499758)
			)
		)
		(stroke
			(width 0)
			(type solid)
		)
		(fill yes)
		(layer "B.Cu")
		(net "GND")
	)
	(gr_poly
		(pts
			(arc
				(start 149.451568 -437.34736)
				(mid 149.24786 -437.34736)
				(end 149.451568 -437.34736)
			)
		)
		(stroke
			(width 0)
			(type solid)
		)
		(fill yes)
		(layer "B.Cu")
		(net "GND")
	)
	(gr_poly
		(pts
			(arc
				(start 149.451568 -436.051198)
				(mid 149.24786 -436.051198)
				(end 149.451568 -436.051198)
			)
		)
		(stroke
			(width 0)
			(type solid)
		)
		(fill yes)
		(layer "B.Cu")
		(net "GND")
	)
	(gr_poly
		(pts
			(arc
				(start 149.451568 -434.899562)
				(mid 149.24786 -434.899562)
				(end 149.451568 -434.899562)
			)
		)
		(stroke
			(width 0)
			(type solid)
		)
		(fill yes)
		(layer "B.Cu")
		(net "GND")
	)
	(gr_poly
		(pts
			(arc
				(start 149.451568 -433.747164)
				(mid 149.24786 -433.747164)
				(end 149.451568 -433.747164)
			)
		)
		(stroke
			(width 0)
			(type solid)
		)
		(fill yes)
		(layer "B.Cu")
		(net "GND")
	)
	(gr_poly
		(pts
			(arc
				(start 149.451568 -432.451256)
				(mid 149.24786 -432.451256)
				(end 149.451568 -432.451256)
			)
		)
		(stroke
			(width 0)
			(type solid)
		)
		(fill yes)
		(layer "B.Cu")
		(net "GND")
	)
	(gr_poly
		(pts
			(arc
				(start 149.451568 -431.29962)
				(mid 149.24786 -431.29962)
				(end 149.451568 -431.29962)
			)
		)
		(stroke
			(width 0)
			(type solid)
		)
		(fill yes)
		(layer "B.Cu")
		(net "GND")
	)
	(gr_poly
		(pts
			(arc
				(start 149.451568 -430.147222)
				(mid 149.24786 -430.147222)
				(end 149.451568 -430.147222)
			)
		)
		(stroke
			(width 0)
			(type solid)
		)
		(fill yes)
		(layer "B.Cu")
		(net "GND")
	)
	(gr_poly
		(pts
			(arc
				(start 149.451568 -428.851314)
				(mid 149.24786 -428.851314)
				(end 149.451568 -428.851314)
			)
		)
		(stroke
			(width 0)
			(type solid)
		)
		(fill yes)
		(layer "B.Cu")
		(net "GND")
	)
	(gr_poly
		(pts
			(arc
				(start 149.451568 -427.699678)
				(mid 149.24786 -427.699678)
				(end 149.451568 -427.699678)
			)
		)
		(stroke
			(width 0)
			(type solid)
		)
		(fill yes)
		(layer "B.Cu")
		(net "GND")
	)
	(gr_poly
		(pts
			(arc
				(start 149.451568 -426.54728)
				(mid 149.24786 -426.54728)
				(end 149.451568 -426.54728)
			)
		)
		(stroke
			(width 0)
			(type solid)
		)
		(fill yes)
		(layer "B.Cu")
		(net "GND")
	)
	(gr_poly
		(pts
			(arc
				(start 151.451564 -438.651396)
				(mid 151.247856 -438.651396)
				(end 151.451564 -438.651396)
			)
		)
		(stroke
			(width 0)
			(type solid)
		)
		(fill yes)
		(layer "B.Cu")
		(net "GND")
	)
	(gr_poly
		(pts
			(arc
				(start 151.451564 -437.49976)
				(mid 151.247856 -437.49976)
				(end 151.451564 -437.49976)
			)
		)
		(stroke
			(width 0)
			(type solid)
		)
		(fill yes)
		(layer "B.Cu")
		(net "GND")
	)
	(gr_poly
		(pts
			(arc
				(start 151.451564 -436.347362)
				(mid 151.247856 -436.347362)
				(end 151.451564 -436.347362)
			)
		)
		(stroke
			(width 0)
			(type solid)
		)
		(fill yes)
		(layer "B.Cu")
		(net "GND")
	)
	(gr_poly
		(pts
			(arc
				(start 151.451564 -435.0512)
				(mid 151.247856 -435.0512)
				(end 151.451564 -435.0512)
			)
		)
		(stroke
			(width 0)
			(type solid)
		)
		(fill yes)
		(layer "B.Cu")
		(net "GND")
	)
	(gr_poly
		(pts
			(arc
				(start 151.451564 -433.899564)
				(mid 151.247856 -433.899564)
				(end 151.451564 -433.899564)
			)
		)
		(stroke
			(width 0)
			(type solid)
		)
		(fill yes)
		(layer "B.Cu")
		(net "GND")
	)
	(gr_poly
		(pts
			(arc
				(start 151.451564 -432.747166)
				(mid 151.247856 -432.747166)
				(end 151.451564 -432.747166)
			)
		)
		(stroke
			(width 0)
			(type solid)
		)
		(fill yes)
		(layer "B.Cu")
		(net "GND")
	)
	(gr_poly
		(pts
			(arc
				(start 151.451564 -431.451258)
				(mid 151.247856 -431.451258)
				(end 151.451564 -431.451258)
			)
		)
		(stroke
			(width 0)
			(type solid)
		)
		(fill yes)
		(layer "B.Cu")
		(net "GND")
	)
	(gr_poly
		(pts
			(arc
				(start 151.451564 -430.299622)
				(mid 151.247856 -430.299622)
				(end 151.451564 -430.299622)
			)
		)
		(stroke
			(width 0)
			(type solid)
		)
		(fill yes)
		(layer "B.Cu")
		(net "GND")
	)
	(gr_poly
		(pts
			(arc
				(start 151.451564 -429.147224)
				(mid 151.247856 -429.147224)
				(end 151.451564 -429.147224)
			)
		)
		(stroke
			(width 0)
			(type solid)
		)
		(fill yes)
		(layer "B.Cu")
		(net "GND")
	)
	(gr_poly
		(pts
			(arc
				(start 151.451564 -427.851316)
				(mid 151.247856 -427.851316)
				(end 151.451564 -427.851316)
			)
		)
		(stroke
			(width 0)
			(type solid)
		)
		(fill yes)
		(layer "B.Cu")
		(net "GND")
	)
	(gr_poly
		(pts
			(arc
				(start 151.451564 -426.69968)
				(mid 151.247856 -426.69968)
				(end 151.451564 -426.69968)
			)
		)
		(stroke
			(width 0)
			(type solid)
		)
		(fill yes)
		(layer "B.Cu")
		(net "GND")
	)
	(gr_poly
		(pts
			(arc
				(start 151.451564 -425.547282)
				(mid 151.247856 -425.547282)
				(end 151.451564 -425.547282)
			)
		)
		(stroke
			(width 0)
			(type solid)
		)
		(fill yes)
		(layer "B.Cu")
		(net "GND")
	)
	(gr_poly
		(pts
			(arc
				(start 153.45156 -439.651394)
				(mid 153.247852 -439.651394)
				(end 153.45156 -439.651394)
			)
		)
		(stroke
			(width 0)
			(type solid)
		)
		(fill yes)
		(layer "B.Cu")
		(net "GND")
	)
	(gr_poly
		(pts
			(arc
				(start 153.45156 -438.499758)
				(mid 153.247852 -438.499758)
				(end 153.45156 -438.499758)
			)
		)
		(stroke
			(width 0)
			(type solid)
		)
		(fill yes)
		(layer "B.Cu")
		(net "GND")
	)
	(gr_poly
		(pts
			(arc
				(start 153.45156 -437.34736)
				(mid 153.247852 -437.34736)
				(end 153.45156 -437.34736)
			)
		)
		(stroke
			(width 0)
			(type solid)
		)
		(fill yes)
		(layer "B.Cu")
		(net "GND")
	)
	(gr_poly
		(pts
			(arc
				(start 153.45156 -436.051198)
				(mid 153.247852 -436.051198)
				(end 153.45156 -436.051198)
			)
		)
		(stroke
			(width 0)
			(type solid)
		)
		(fill yes)
		(layer "B.Cu")
		(net "GND")
	)
	(gr_poly
		(pts
			(arc
				(start 153.45156 -434.899562)
				(mid 153.247852 -434.899562)
				(end 153.45156 -434.899562)
			)
		)
		(stroke
			(width 0)
			(type solid)
		)
		(fill yes)
		(layer "B.Cu")
		(net "GND")
	)
	(gr_poly
		(pts
			(arc
				(start 153.45156 -433.747164)
				(mid 153.247852 -433.747164)
				(end 153.45156 -433.747164)
			)
		)
		(stroke
			(width 0)
			(type solid)
		)
		(fill yes)
		(layer "B.Cu")
		(net "GND")
	)
	(gr_poly
		(pts
			(arc
				(start 153.45156 -432.451256)
				(mid 153.247852 -432.451256)
				(end 153.45156 -432.451256)
			)
		)
		(stroke
			(width 0)
			(type solid)
		)
		(fill yes)
		(layer "B.Cu")
		(net "GND")
	)
	(gr_poly
		(pts
			(arc
				(start 153.45156 -431.29962)
				(mid 153.247852 -431.29962)
				(end 153.45156 -431.29962)
			)
		)
		(stroke
			(width 0)
			(type solid)
		)
		(fill yes)
		(layer "B.Cu")
		(net "GND")
	)
	(gr_poly
		(pts
			(arc
				(start 153.45156 -430.147222)
				(mid 153.247852 -430.147222)
				(end 153.45156 -430.147222)
			)
		)
		(stroke
			(width 0)
			(type solid)
		)
		(fill yes)
		(layer "B.Cu")
		(net "GND")
	)
	(gr_poly
		(pts
			(arc
				(start 153.45156 -428.851314)
				(mid 153.247852 -428.851314)
				(end 153.45156 -428.851314)
			)
		)
		(stroke
			(width 0)
			(type solid)
		)
		(fill yes)
		(layer "B.Cu")
		(net "GND")
	)
	(gr_poly
		(pts
			(arc
				(start 153.45156 -427.699678)
				(mid 153.247852 -427.699678)
				(end 153.45156 -427.699678)
			)
		)
		(stroke
			(width 0)
			(type solid)
		)
		(fill yes)
		(layer "B.Cu")
		(net "GND")
	)
	(gr_poly
		(pts
			(arc
				(start 153.45156 -426.54728)
				(mid 153.247852 -426.54728)
				(end 153.45156 -426.54728)
			)
		)
		(stroke
			(width 0)
			(type solid)
		)
		(fill yes)
		(layer "B.Cu")
		(net "GND")
	)
	(gr_poly
		(pts
			(arc
				(start 155.451556 -438.651396)
				(mid 155.247848 -438.651396)
				(end 155.451556 -438.651396)
			)
		)
		(stroke
			(width 0)
			(type solid)
		)
		(fill yes)
		(layer "B.Cu")
		(net "GND")
	)
	(gr_poly
		(pts
			(arc
				(start 155.451556 -437.49976)
				(mid 155.247848 -437.49976)
				(end 155.451556 -437.49976)
			)
		)
		(stroke
			(width 0)
			(type solid)
		)
		(fill yes)
		(layer "B.Cu")
		(net "GND")
	)
	(gr_poly
		(pts
			(arc
				(start 155.451556 -436.347362)
				(mid 155.247848 -436.347362)
				(end 155.451556 -436.347362)
			)
		)
		(stroke
			(width 0)
			(type solid)
		)
		(fill yes)
		(layer "B.Cu")
		(net "GND")
	)
	(gr_poly
		(pts
			(arc
				(start 155.451556 -435.0512)
				(mid 155.247848 -435.0512)
				(end 155.451556 -435.0512)
			)
		)
		(stroke
			(width 0)
			(type solid)
		)
		(fill yes)
		(layer "B.Cu")
		(net "GND")
	)
	(gr_poly
		(pts
			(arc
				(start 155.451556 -433.899564)
				(mid 155.247848 -433.899564)
				(end 155.451556 -433.899564)
			)
		)
		(stroke
			(width 0)
			(type solid)
		)
		(fill yes)
		(layer "B.Cu")
		(net "GND")
	)
	(gr_poly
		(pts
			(arc
				(start 155.451556 -432.747166)
				(mid 155.247848 -432.747166)
				(end 155.451556 -432.747166)
			)
		)
		(stroke
			(width 0)
			(type solid)
		)
		(fill yes)
		(layer "B.Cu")
		(net "GND")
	)
	(gr_poly
		(pts
			(arc
				(start 155.451556 -431.451258)
				(mid 155.247848 -431.451258)
				(end 155.451556 -431.451258)
			)
		)
		(stroke
			(width 0)
			(type solid)
		)
		(fill yes)
		(layer "B.Cu")
		(net "GND")
	)
	(gr_poly
		(pts
			(arc
				(start 155.451556 -430.299622)
				(mid 155.247848 -430.299622)
				(end 155.451556 -430.299622)
			)
		)
		(stroke
			(width 0)
			(type solid)
		)
		(fill yes)
		(layer "B.Cu")
		(net "GND")
	)
	(gr_poly
		(pts
			(arc
				(start 155.451556 -429.147224)
				(mid 155.247848 -429.147224)
				(end 155.451556 -429.147224)
			)
		)
		(stroke
			(width 0)
			(type solid)
		)
		(fill yes)
		(layer "B.Cu")
		(net "GND")
	)
	(gr_poly
		(pts
			(arc
				(start 155.451556 -427.851316)
				(mid 155.247848 -427.851316)
				(end 155.451556 -427.851316)
			)
		)
		(stroke
			(width 0)
			(type solid)
		)
		(fill yes)
		(layer "B.Cu")
		(net "GND")
	)
	(gr_poly
		(pts
			(arc
				(start 155.451556 -426.69968)
				(mid 155.247848 -426.69968)
				(end 155.451556 -426.69968)
			)
		)
		(stroke
			(width 0)
			(type solid)
		)
		(fill yes)
		(layer "B.Cu")
		(net "GND")
	)
	(gr_poly
		(pts
			(arc
				(start 155.451556 -425.547282)
				(mid 155.247848 -425.547282)
				(end 155.451556 -425.547282)
			)
		)
		(stroke
			(width 0)
			(type solid)
		)
		(fill yes)
		(layer "B.Cu")
		(net "GND")
	)
	(gr_poly
		(pts
			(arc
				(start 157.451552 -439.651394)
				(mid 157.247844 -439.651394)
				(end 157.451552 -439.651394)
			)
		)
		(stroke
			(width 0)
			(type solid)
		)
		(fill yes)
		(layer "B.Cu")
		(net "GND")
	)
	(gr_poly
		(pts
			(arc
				(start 157.451552 -438.499758)
				(mid 157.247844 -438.499758)
				(end 157.451552 -438.499758)
			)
		)
		(stroke
			(width 0)
			(type solid)
		)
		(fill yes)
		(layer "B.Cu")
		(net "GND")
	)
	(gr_poly
		(pts
			(arc
				(start 157.451552 -437.34736)
				(mid 157.247844 -437.34736)
				(end 157.451552 -437.34736)
			)
		)
		(stroke
			(width 0)
			(type solid)
		)
		(fill yes)
		(layer "B.Cu")
		(net "GND")
	)
	(gr_poly
		(pts
			(arc
				(start 157.451552 -436.051198)
				(mid 157.247844 -436.051198)
				(end 157.451552 -436.051198)
			)
		)
		(stroke
			(width 0)
			(type solid)
		)
		(fill yes)
		(layer "B.Cu")
		(net "GND")
	)
	(gr_poly
		(pts
			(arc
				(start 157.451552 -434.899562)
				(mid 157.247844 -434.899562)
				(end 157.451552 -434.899562)
			)
		)
		(stroke
			(width 0)
			(type solid)
		)
		(fill yes)
		(layer "B.Cu")
		(net "GND")
	)
	(gr_poly
		(pts
			(arc
				(start 157.451552 -433.747164)
				(mid 157.247844 -433.747164)
				(end 157.451552 -433.747164)
			)
		)
		(stroke
			(width 0)
			(type solid)
		)
		(fill yes)
		(layer "B.Cu")
		(net "GND")
	)
	(gr_poly
		(pts
			(arc
				(start 157.451552 -432.451256)
				(mid 157.247844 -432.451256)
				(end 157.451552 -432.451256)
			)
		)
		(stroke
			(width 0)
			(type solid)
		)
		(fill yes)
		(layer "B.Cu")
		(net "GND")
	)
	(gr_poly
		(pts
			(arc
				(start 157.451552 -431.29962)
				(mid 157.247844 -431.29962)
				(end 157.451552 -431.29962)
			)
		)
		(stroke
			(width 0)
			(type solid)
		)
		(fill yes)
		(layer "B.Cu")
		(net "GND")
	)
	(gr_poly
		(pts
			(arc
				(start 157.451552 -430.147222)
				(mid 157.247844 -430.147222)
				(end 157.451552 -430.147222)
			)
		)
		(stroke
			(width 0)
			(type solid)
		)
		(fill yes)
		(layer "B.Cu")
		(net "GND")
	)
	(gr_poly
		(pts
			(arc
				(start 157.451552 -428.851314)
				(mid 157.247844 -428.851314)
				(end 157.451552 -428.851314)
			)
		)
		(stroke
			(width 0)
			(type solid)
		)
		(fill yes)
		(layer "B.Cu")
		(net "GND")
	)
	(gr_poly
		(pts
			(arc
				(start 157.451552 -427.699678)
				(mid 157.247844 -427.699678)
				(end 157.451552 -427.699678)
			)
		)
		(stroke
			(width 0)
			(type solid)
		)
		(fill yes)
		(layer "B.Cu")
		(net "GND")
	)
	(gr_poly
		(pts
			(arc
				(start 157.451552 -426.54728)
				(mid 157.247844 -426.54728)
				(end 157.451552 -426.54728)
			)
		)
		(stroke
			(width 0)
			(type solid)
		)
		(fill yes)
		(layer "B.Cu")
		(net "GND")
	)
	(gr_poly
		(pts
			(arc
				(start 315.351414 -438.651396)
				(mid 315.147706 -438.651396)
				(end 315.351414 -438.651396)
			)
		)
		(stroke
			(width 0)
			(type solid)
		)
		(fill yes)
		(layer "B.Cu")
		(net "GND")
	)
	(gr_poly
		(pts
			(arc
				(start 315.351414 -437.49976)
				(mid 315.147706 -437.49976)
				(end 315.351414 -437.49976)
			)
		)
		(stroke
			(width 0)
			(type solid)
		)
		(fill yes)
		(layer "B.Cu")
		(net "GND")
	)
	(gr_poly
		(pts
			(arc
				(start 315.351414 -436.347362)
				(mid 315.147706 -436.347362)
				(end 315.351414 -436.347362)
			)
		)
		(stroke
			(width 0)
			(type solid)
		)
		(fill yes)
		(layer "B.Cu")
		(net "GND")
	)
	(gr_poly
		(pts
			(arc
				(start 315.351414 -435.0512)
				(mid 315.147706 -435.0512)
				(end 315.351414 -435.0512)
			)
		)
		(stroke
			(width 0)
			(type solid)
		)
		(fill yes)
		(layer "B.Cu")
		(net "GND")
	)
	(gr_poly
		(pts
			(arc
				(start 315.351414 -433.899564)
				(mid 315.147706 -433.899564)
				(end 315.351414 -433.899564)
			)
		)
		(stroke
			(width 0)
			(type solid)
		)
		(fill yes)
		(layer "B.Cu")
		(net "GND")
	)
	(gr_poly
		(pts
			(arc
				(start 315.351414 -432.747166)
				(mid 315.147706 -432.747166)
				(end 315.351414 -432.747166)
			)
		)
		(stroke
			(width 0)
			(type solid)
		)
		(fill yes)
		(layer "B.Cu")
		(net "GND")
	)
	(gr_poly
		(pts
			(arc
				(start 315.351414 -431.451258)
				(mid 315.147706 -431.451258)
				(end 315.351414 -431.451258)
			)
		)
		(stroke
			(width 0)
			(type solid)
		)
		(fill yes)
		(layer "B.Cu")
		(net "GND")
	)
	(gr_poly
		(pts
			(arc
				(start 315.351414 -430.299622)
				(mid 315.147706 -430.299622)
				(end 315.351414 -430.299622)
			)
		)
		(stroke
			(width 0)
			(type solid)
		)
		(fill yes)
		(layer "B.Cu")
		(net "GND")
	)
	(gr_poly
		(pts
			(arc
				(start 315.351414 -429.147224)
				(mid 315.147706 -429.147224)
				(end 315.351414 -429.147224)
			)
		)
		(stroke
			(width 0)
			(type solid)
		)
		(fill yes)
		(layer "B.Cu")
		(net "GND")
	)
	(gr_poly
		(pts
			(arc
				(start 315.351414 -427.851316)
				(mid 315.147706 -427.851316)
				(end 315.351414 -427.851316)
			)
		)
		(stroke
			(width 0)
			(type solid)
		)
		(fill yes)
		(layer "B.Cu")
		(net "GND")
	)
	(gr_poly
		(pts
			(arc
				(start 315.351414 -426.69968)
				(mid 315.147706 -426.69968)
				(end 315.351414 -426.69968)
			)
		)
		(stroke
			(width 0)
			(type solid)
		)
		(fill yes)
		(layer "B.Cu")
		(net "GND")
	)
	(gr_poly
		(pts
			(arc
				(start 315.351414 -425.547282)
				(mid 315.147706 -425.547282)
				(end 315.351414 -425.547282)
			)
		)
		(stroke
			(width 0)
			(type solid)
		)
		(fill yes)
		(layer "B.Cu")
		(net "GND")
	)
	(gr_poly
		(pts
			(arc
				(start 317.35141 -439.651394)
				(mid 317.147702 -439.651394)
				(end 317.35141 -439.651394)
			)
		)
		(stroke
			(width 0)
			(type solid)
		)
		(fill yes)
		(layer "B.Cu")
		(net "GND")
	)
	(gr_poly
		(pts
			(arc
				(start 317.35141 -438.499758)
				(mid 317.147702 -438.499758)
				(end 317.35141 -438.499758)
			)
		)
		(stroke
			(width 0)
			(type solid)
		)
		(fill yes)
		(layer "B.Cu")
		(net "GND")
	)
	(gr_poly
		(pts
			(arc
				(start 317.35141 -437.34736)
				(mid 317.147702 -437.34736)
				(end 317.35141 -437.34736)
			)
		)
		(stroke
			(width 0)
			(type solid)
		)
		(fill yes)
		(layer "B.Cu")
		(net "GND")
	)
	(gr_poly
		(pts
			(arc
				(start 317.35141 -436.051198)
				(mid 317.147702 -436.051198)
				(end 317.35141 -436.051198)
			)
		)
		(stroke
			(width 0)
			(type solid)
		)
		(fill yes)
		(layer "B.Cu")
		(net "GND")
	)
	(gr_poly
		(pts
			(arc
				(start 317.35141 -434.899562)
				(mid 317.147702 -434.899562)
				(end 317.35141 -434.899562)
			)
		)
		(stroke
			(width 0)
			(type solid)
		)
		(fill yes)
		(layer "B.Cu")
		(net "GND")
	)
	(gr_poly
		(pts
			(arc
				(start 317.35141 -433.747164)
				(mid 317.147702 -433.747164)
				(end 317.35141 -433.747164)
			)
		)
		(stroke
			(width 0)
			(type solid)
		)
		(fill yes)
		(layer "B.Cu")
		(net "GND")
	)
	(gr_poly
		(pts
			(arc
				(start 317.35141 -432.451256)
				(mid 317.147702 -432.451256)
				(end 317.35141 -432.451256)
			)
		)
		(stroke
			(width 0)
			(type solid)
		)
		(fill yes)
		(layer "B.Cu")
		(net "GND")
	)
	(gr_poly
		(pts
			(arc
				(start 317.35141 -431.29962)
				(mid 317.147702 -431.29962)
				(end 317.35141 -431.29962)
			)
		)
		(stroke
			(width 0)
			(type solid)
		)
		(fill yes)
		(layer "B.Cu")
		(net "GND")
	)
	(gr_poly
		(pts
			(arc
				(start 317.35141 -430.147222)
				(mid 317.147702 -430.147222)
				(end 317.35141 -430.147222)
			)
		)
		(stroke
			(width 0)
			(type solid)
		)
		(fill yes)
		(layer "B.Cu")
		(net "GND")
	)
	(gr_poly
		(pts
			(arc
				(start 317.35141 -428.851314)
				(mid 317.147702 -428.851314)
				(end 317.35141 -428.851314)
			)
		)
		(stroke
			(width 0)
			(type solid)
		)
		(fill yes)
		(layer "B.Cu")
		(net "GND")
	)
	(gr_poly
		(pts
			(arc
				(start 317.35141 -427.699678)
				(mid 317.147702 -427.699678)
				(end 317.35141 -427.699678)
			)
		)
		(stroke
			(width 0)
			(type solid)
		)
		(fill yes)
		(layer "B.Cu")
		(net "GND")
	)
	(gr_poly
		(pts
			(arc
				(start 317.35141 -426.54728)
				(mid 317.147702 -426.54728)
				(end 317.35141 -426.54728)
			)
		)
		(stroke
			(width 0)
			(type solid)
		)
		(fill yes)
		(layer "B.Cu")
		(net "GND")
	)
	(gr_poly
		(pts
			(arc
				(start 319.351406 -438.651396)
				(mid 319.147698 -438.651396)
				(end 319.351406 -438.651396)
			)
		)
		(stroke
			(width 0)
			(type solid)
		)
		(fill yes)
		(layer "B.Cu")
		(net "GND")
	)
	(gr_poly
		(pts
			(arc
				(start 319.351406 -437.49976)
				(mid 319.147698 -437.49976)
				(end 319.351406 -437.49976)
			)
		)
		(stroke
			(width 0)
			(type solid)
		)
		(fill yes)
		(layer "B.Cu")
		(net "GND")
	)
	(gr_poly
		(pts
			(arc
				(start 319.351406 -436.347362)
				(mid 319.147698 -436.347362)
				(end 319.351406 -436.347362)
			)
		)
		(stroke
			(width 0)
			(type solid)
		)
		(fill yes)
		(layer "B.Cu")
		(net "GND")
	)
	(gr_poly
		(pts
			(arc
				(start 319.351406 -435.0512)
				(mid 319.147698 -435.0512)
				(end 319.351406 -435.0512)
			)
		)
		(stroke
			(width 0)
			(type solid)
		)
		(fill yes)
		(layer "B.Cu")
		(net "GND")
	)
	(gr_poly
		(pts
			(arc
				(start 319.351406 -433.899564)
				(mid 319.147698 -433.899564)
				(end 319.351406 -433.899564)
			)
		)
		(stroke
			(width 0)
			(type solid)
		)
		(fill yes)
		(layer "B.Cu")
		(net "GND")
	)
	(gr_poly
		(pts
			(arc
				(start 319.351406 -432.747166)
				(mid 319.147698 -432.747166)
				(end 319.351406 -432.747166)
			)
		)
		(stroke
			(width 0)
			(type solid)
		)
		(fill yes)
		(layer "B.Cu")
		(net "GND")
	)
	(gr_poly
		(pts
			(arc
				(start 319.351406 -431.451258)
				(mid 319.147698 -431.451258)
				(end 319.351406 -431.451258)
			)
		)
		(stroke
			(width 0)
			(type solid)
		)
		(fill yes)
		(layer "B.Cu")
		(net "GND")
	)
	(gr_poly
		(pts
			(arc
				(start 319.351406 -430.299622)
				(mid 319.147698 -430.299622)
				(end 319.351406 -430.299622)
			)
		)
		(stroke
			(width 0)
			(type solid)
		)
		(fill yes)
		(layer "B.Cu")
		(net "GND")
	)
	(gr_poly
		(pts
			(arc
				(start 319.351406 -429.147224)
				(mid 319.147698 -429.147224)
				(end 319.351406 -429.147224)
			)
		)
		(stroke
			(width 0)
			(type solid)
		)
		(fill yes)
		(layer "B.Cu")
		(net "GND")
	)
	(gr_poly
		(pts
			(arc
				(start 319.351406 -427.851316)
				(mid 319.147698 -427.851316)
				(end 319.351406 -427.851316)
			)
		)
		(stroke
			(width 0)
			(type solid)
		)
		(fill yes)
		(layer "B.Cu")
		(net "GND")
	)
	(gr_poly
		(pts
			(arc
				(start 319.351406 -426.69968)
				(mid 319.147698 -426.69968)
				(end 319.351406 -426.69968)
			)
		)
		(stroke
			(width 0)
			(type solid)
		)
		(fill yes)
		(layer "B.Cu")
		(net "GND")
	)
	(gr_poly
		(pts
			(arc
				(start 319.351406 -425.547282)
				(mid 319.147698 -425.547282)
				(end 319.351406 -425.547282)
			)
		)
		(stroke
			(width 0)
			(type solid)
		)
		(fill yes)
		(layer "B.Cu")
		(net "GND")
	)
	(gr_poly
		(pts
			(arc
				(start 321.351402 -439.651394)
				(mid 321.147694 -439.651394)
				(end 321.351402 -439.651394)
			)
		)
		(stroke
			(width 0)
			(type solid)
		)
		(fill yes)
		(layer "B.Cu")
		(net "GND")
	)
	(gr_poly
		(pts
			(arc
				(start 321.351402 -438.499758)
				(mid 321.147694 -438.499758)
				(end 321.351402 -438.499758)
			)
		)
		(stroke
			(width 0)
			(type solid)
		)
		(fill yes)
		(layer "B.Cu")
		(net "GND")
	)
	(gr_poly
		(pts
			(arc
				(start 321.351402 -437.34736)
				(mid 321.147694 -437.34736)
				(end 321.351402 -437.34736)
			)
		)
		(stroke
			(width 0)
			(type solid)
		)
		(fill yes)
		(layer "B.Cu")
		(net "GND")
	)
	(gr_poly
		(pts
			(arc
				(start 321.351402 -436.051198)
				(mid 321.147694 -436.051198)
				(end 321.351402 -436.051198)
			)
		)
		(stroke
			(width 0)
			(type solid)
		)
		(fill yes)
		(layer "B.Cu")
		(net "GND")
	)
	(gr_poly
		(pts
			(arc
				(start 321.351402 -434.899562)
				(mid 321.147694 -434.899562)
				(end 321.351402 -434.899562)
			)
		)
		(stroke
			(width 0)
			(type solid)
		)
		(fill yes)
		(layer "B.Cu")
		(net "GND")
	)
	(gr_poly
		(pts
			(arc
				(start 321.351402 -433.747164)
				(mid 321.147694 -433.747164)
				(end 321.351402 -433.747164)
			)
		)
		(stroke
			(width 0)
			(type solid)
		)
		(fill yes)
		(layer "B.Cu")
		(net "GND")
	)
	(gr_poly
		(pts
			(arc
				(start 321.351402 -432.451256)
				(mid 321.147694 -432.451256)
				(end 321.351402 -432.451256)
			)
		)
		(stroke
			(width 0)
			(type solid)
		)
		(fill yes)
		(layer "B.Cu")
		(net "GND")
	)
	(gr_poly
		(pts
			(arc
				(start 321.351402 -431.29962)
				(mid 321.147694 -431.29962)
				(end 321.351402 -431.29962)
			)
		)
		(stroke
			(width 0)
			(type solid)
		)
		(fill yes)
		(layer "B.Cu")
		(net "GND")
	)
	(gr_poly
		(pts
			(arc
				(start 321.351402 -430.147222)
				(mid 321.147694 -430.147222)
				(end 321.351402 -430.147222)
			)
		)
		(stroke
			(width 0)
			(type solid)
		)
		(fill yes)
		(layer "B.Cu")
		(net "GND")
	)
	(gr_poly
		(pts
			(arc
				(start 321.351402 -428.851314)
				(mid 321.147694 -428.851314)
				(end 321.351402 -428.851314)
			)
		)
		(stroke
			(width 0)
			(type solid)
		)
		(fill yes)
		(layer "B.Cu")
		(net "GND")
	)
	(gr_poly
		(pts
			(arc
				(start 321.351402 -427.699678)
				(mid 321.147694 -427.699678)
				(end 321.351402 -427.699678)
			)
		)
		(stroke
			(width 0)
			(type solid)
		)
		(fill yes)
		(layer "B.Cu")
		(net "GND")
	)
	(gr_poly
		(pts
			(arc
				(start 321.351402 -426.54728)
				(mid 321.147694 -426.54728)
				(end 321.351402 -426.54728)
			)
		)
		(stroke
			(width 0)
			(type solid)
		)
		(fill yes)
		(layer "B.Cu")
		(net "GND")
	)
	(gr_poly
		(pts
			(arc
				(start 323.351398 -438.651396)
				(mid 323.14769 -438.651396)
				(end 323.351398 -438.651396)
			)
		)
		(stroke
			(width 0)
			(type solid)
		)
		(fill yes)
		(layer "B.Cu")
		(net "GND")
	)
	(gr_poly
		(pts
			(arc
				(start 323.351398 -437.49976)
				(mid 323.14769 -437.49976)
				(end 323.351398 -437.49976)
			)
		)
		(stroke
			(width 0)
			(type solid)
		)
		(fill yes)
		(layer "B.Cu")
		(net "GND")
	)
	(gr_poly
		(pts
			(arc
				(start 323.351398 -436.347362)
				(mid 323.14769 -436.347362)
				(end 323.351398 -436.347362)
			)
		)
		(stroke
			(width 0)
			(type solid)
		)
		(fill yes)
		(layer "B.Cu")
		(net "GND")
	)
	(gr_poly
		(pts
			(arc
				(start 323.351398 -435.0512)
				(mid 323.14769 -435.0512)
				(end 323.351398 -435.0512)
			)
		)
		(stroke
			(width 0)
			(type solid)
		)
		(fill yes)
		(layer "B.Cu")
		(net "GND")
	)
	(gr_poly
		(pts
			(arc
				(start 323.351398 -433.899564)
				(mid 323.14769 -433.899564)
				(end 323.351398 -433.899564)
			)
		)
		(stroke
			(width 0)
			(type solid)
		)
		(fill yes)
		(layer "B.Cu")
		(net "GND")
	)
	(gr_poly
		(pts
			(arc
				(start 323.351398 -432.747166)
				(mid 323.14769 -432.747166)
				(end 323.351398 -432.747166)
			)
		)
		(stroke
			(width 0)
			(type solid)
		)
		(fill yes)
		(layer "B.Cu")
		(net "GND")
	)
	(gr_poly
		(pts
			(arc
				(start 323.351398 -431.451258)
				(mid 323.14769 -431.451258)
				(end 323.351398 -431.451258)
			)
		)
		(stroke
			(width 0)
			(type solid)
		)
		(fill yes)
		(layer "B.Cu")
		(net "GND")
	)
	(gr_poly
		(pts
			(arc
				(start 323.351398 -430.299622)
				(mid 323.14769 -430.299622)
				(end 323.351398 -430.299622)
			)
		)
		(stroke
			(width 0)
			(type solid)
		)
		(fill yes)
		(layer "B.Cu")
		(net "GND")
	)
	(gr_poly
		(pts
			(arc
				(start 323.351398 -429.147224)
				(mid 323.14769 -429.147224)
				(end 323.351398 -429.147224)
			)
		)
		(stroke
			(width 0)
			(type solid)
		)
		(fill yes)
		(layer "B.Cu")
		(net "GND")
	)
	(gr_poly
		(pts
			(arc
				(start 323.351398 -427.851316)
				(mid 323.14769 -427.851316)
				(end 323.351398 -427.851316)
			)
		)
		(stroke
			(width 0)
			(type solid)
		)
		(fill yes)
		(layer "B.Cu")
		(net "GND")
	)
	(gr_poly
		(pts
			(arc
				(start 323.351398 -426.69968)
				(mid 323.14769 -426.69968)
				(end 323.351398 -426.69968)
			)
		)
		(stroke
			(width 0)
			(type solid)
		)
		(fill yes)
		(layer "B.Cu")
		(net "GND")
	)
	(gr_poly
		(pts
			(arc
				(start 323.351398 -425.547282)
				(mid 323.14769 -425.547282)
				(end 323.351398 -425.547282)
			)
		)
		(stroke
			(width 0)
			(type solid)
		)
		(fill yes)
		(layer "B.Cu")
		(net "GND")
	)
	(gr_poly
		(pts
			(arc
				(start 325.351394 -439.651394)
				(mid 325.147686 -439.651394)
				(end 325.351394 -439.651394)
			)
		)
		(stroke
			(width 0)
			(type solid)
		)
		(fill yes)
		(layer "B.Cu")
		(net "GND")
	)
	(gr_poly
		(pts
			(arc
				(start 325.351394 -438.499758)
				(mid 325.147686 -438.499758)
				(end 325.351394 -438.499758)
			)
		)
		(stroke
			(width 0)
			(type solid)
		)
		(fill yes)
		(layer "B.Cu")
		(net "GND")
	)
	(gr_poly
		(pts
			(arc
				(start 325.351394 -437.34736)
				(mid 325.147686 -437.34736)
				(end 325.351394 -437.34736)
			)
		)
		(stroke
			(width 0)
			(type solid)
		)
		(fill yes)
		(layer "B.Cu")
		(net "GND")
	)
	(gr_poly
		(pts
			(arc
				(start 325.351394 -436.051198)
				(mid 325.147686 -436.051198)
				(end 325.351394 -436.051198)
			)
		)
		(stroke
			(width 0)
			(type solid)
		)
		(fill yes)
		(layer "B.Cu")
		(net "GND")
	)
	(gr_poly
		(pts
			(arc
				(start 325.351394 -434.899562)
				(mid 325.147686 -434.899562)
				(end 325.351394 -434.899562)
			)
		)
		(stroke
			(width 0)
			(type solid)
		)
		(fill yes)
		(layer "B.Cu")
		(net "GND")
	)
	(gr_poly
		(pts
			(arc
				(start 325.351394 -433.747164)
				(mid 325.147686 -433.747164)
				(end 325.351394 -433.747164)
			)
		)
		(stroke
			(width 0)
			(type solid)
		)
		(fill yes)
		(layer "B.Cu")
		(net "GND")
	)
	(gr_poly
		(pts
			(arc
				(start 325.351394 -432.451256)
				(mid 325.147686 -432.451256)
				(end 325.351394 -432.451256)
			)
		)
		(stroke
			(width 0)
			(type solid)
		)
		(fill yes)
		(layer "B.Cu")
		(net "GND")
	)
	(gr_poly
		(pts
			(arc
				(start 325.351394 -431.29962)
				(mid 325.147686 -431.29962)
				(end 325.351394 -431.29962)
			)
		)
		(stroke
			(width 0)
			(type solid)
		)
		(fill yes)
		(layer "B.Cu")
		(net "GND")
	)
	(gr_poly
		(pts
			(arc
				(start 325.351394 -430.147222)
				(mid 325.147686 -430.147222)
				(end 325.351394 -430.147222)
			)
		)
		(stroke
			(width 0)
			(type solid)
		)
		(fill yes)
		(layer "B.Cu")
		(net "GND")
	)
	(gr_poly
		(pts
			(arc
				(start 325.351394 -428.851314)
				(mid 325.147686 -428.851314)
				(end 325.351394 -428.851314)
			)
		)
		(stroke
			(width 0)
			(type solid)
		)
		(fill yes)
		(layer "B.Cu")
		(net "GND")
	)
	(gr_poly
		(pts
			(arc
				(start 325.351394 -427.699678)
				(mid 325.147686 -427.699678)
				(end 325.351394 -427.699678)
			)
		)
		(stroke
			(width 0)
			(type solid)
		)
		(fill yes)
		(layer "B.Cu")
		(net "GND")
	)
	(gr_poly
		(pts
			(arc
				(start 325.351394 -426.54728)
				(mid 325.147686 -426.54728)
				(end 325.351394 -426.54728)
			)
		)
		(stroke
			(width 0)
			(type solid)
		)
		(fill yes)
		(layer "B.Cu")
		(net "GND")
	)
	(gr_poly
		(pts
			(arc
				(start 327.35139 -438.651396)
				(mid 327.147682 -438.651396)
				(end 327.35139 -438.651396)
			)
		)
		(stroke
			(width 0)
			(type solid)
		)
		(fill yes)
		(layer "B.Cu")
		(net "GND")
	)
	(gr_poly
		(pts
			(arc
				(start 327.35139 -437.49976)
				(mid 327.147682 -437.49976)
				(end 327.35139 -437.49976)
			)
		)
		(stroke
			(width 0)
			(type solid)
		)
		(fill yes)
		(layer "B.Cu")
		(net "GND")
	)
	(gr_poly
		(pts
			(arc
				(start 327.35139 -436.347362)
				(mid 327.147682 -436.347362)
				(end 327.35139 -436.347362)
			)
		)
		(stroke
			(width 0)
			(type solid)
		)
		(fill yes)
		(layer "B.Cu")
		(net "GND")
	)
	(gr_poly
		(pts
			(arc
				(start 327.35139 -435.0512)
				(mid 327.147682 -435.0512)
				(end 327.35139 -435.0512)
			)
		)
		(stroke
			(width 0)
			(type solid)
		)
		(fill yes)
		(layer "B.Cu")
		(net "GND")
	)
	(gr_poly
		(pts
			(arc
				(start 327.35139 -433.899564)
				(mid 327.147682 -433.899564)
				(end 327.35139 -433.899564)
			)
		)
		(stroke
			(width 0)
			(type solid)
		)
		(fill yes)
		(layer "B.Cu")
		(net "GND")
	)
	(gr_poly
		(pts
			(arc
				(start 327.35139 -432.747166)
				(mid 327.147682 -432.747166)
				(end 327.35139 -432.747166)
			)
		)
		(stroke
			(width 0)
			(type solid)
		)
		(fill yes)
		(layer "B.Cu")
		(net "GND")
	)
	(gr_poly
		(pts
			(arc
				(start 327.35139 -431.451258)
				(mid 327.147682 -431.451258)
				(end 327.35139 -431.451258)
			)
		)
		(stroke
			(width 0)
			(type solid)
		)
		(fill yes)
		(layer "B.Cu")
		(net "GND")
	)
	(gr_poly
		(pts
			(arc
				(start 327.35139 -430.299622)
				(mid 327.147682 -430.299622)
				(end 327.35139 -430.299622)
			)
		)
		(stroke
			(width 0)
			(type solid)
		)
		(fill yes)
		(layer "B.Cu")
		(net "GND")
	)
	(gr_poly
		(pts
			(arc
				(start 327.35139 -429.147224)
				(mid 327.147682 -429.147224)
				(end 327.35139 -429.147224)
			)
		)
		(stroke
			(width 0)
			(type solid)
		)
		(fill yes)
		(layer "B.Cu")
		(net "GND")
	)
	(gr_poly
		(pts
			(arc
				(start 327.35139 -427.851316)
				(mid 327.147682 -427.851316)
				(end 327.35139 -427.851316)
			)
		)
		(stroke
			(width 0)
			(type solid)
		)
		(fill yes)
		(layer "B.Cu")
		(net "GND")
	)
	(gr_poly
		(pts
			(arc
				(start 327.35139 -426.69968)
				(mid 327.147682 -426.69968)
				(end 327.35139 -426.69968)
			)
		)
		(stroke
			(width 0)
			(type solid)
		)
		(fill yes)
		(layer "B.Cu")
		(net "GND")
	)
	(gr_poly
		(pts
			(arc
				(start 327.35139 -425.547282)
				(mid 327.147682 -425.547282)
				(end 327.35139 -425.547282)
			)
		)
		(stroke
			(width 0)
			(type solid)
		)
		(fill yes)
		(layer "B.Cu")
		(net "GND")
	)
	(gr_poly
		(pts
			(arc
				(start 329.351386 -439.651394)
				(mid 329.147678 -439.651394)
				(end 329.351386 -439.651394)
			)
		)
		(stroke
			(width 0)
			(type solid)
		)
		(fill yes)
		(layer "B.Cu")
		(net "GND")
	)
	(gr_poly
		(pts
			(arc
				(start 329.351386 -438.499758)
				(mid 329.147678 -438.499758)
				(end 329.351386 -438.499758)
			)
		)
		(stroke
			(width 0)
			(type solid)
		)
		(fill yes)
		(layer "B.Cu")
		(net "GND")
	)
	(gr_poly
		(pts
			(arc
				(start 329.351386 -437.34736)
				(mid 329.147678 -437.34736)
				(end 329.351386 -437.34736)
			)
		)
		(stroke
			(width 0)
			(type solid)
		)
		(fill yes)
		(layer "B.Cu")
		(net "GND")
	)
	(gr_poly
		(pts
			(arc
				(start 329.351386 -436.051198)
				(mid 329.147678 -436.051198)
				(end 329.351386 -436.051198)
			)
		)
		(stroke
			(width 0)
			(type solid)
		)
		(fill yes)
		(layer "B.Cu")
		(net "GND")
	)
	(gr_poly
		(pts
			(arc
				(start 329.351386 -434.899562)
				(mid 329.147678 -434.899562)
				(end 329.351386 -434.899562)
			)
		)
		(stroke
			(width 0)
			(type solid)
		)
		(fill yes)
		(layer "B.Cu")
		(net "GND")
	)
	(gr_poly
		(pts
			(arc
				(start 329.351386 -433.747164)
				(mid 329.147678 -433.747164)
				(end 329.351386 -433.747164)
			)
		)
		(stroke
			(width 0)
			(type solid)
		)
		(fill yes)
		(layer "B.Cu")
		(net "GND")
	)
	(gr_poly
		(pts
			(arc
				(start 329.351386 -432.451256)
				(mid 329.147678 -432.451256)
				(end 329.351386 -432.451256)
			)
		)
		(stroke
			(width 0)
			(type solid)
		)
		(fill yes)
		(layer "B.Cu")
		(net "GND")
	)
	(gr_poly
		(pts
			(arc
				(start 329.351386 -431.29962)
				(mid 329.147678 -431.29962)
				(end 329.351386 -431.29962)
			)
		)
		(stroke
			(width 0)
			(type solid)
		)
		(fill yes)
		(layer "B.Cu")
		(net "GND")
	)
	(gr_poly
		(pts
			(arc
				(start 329.351386 -430.147222)
				(mid 329.147678 -430.147222)
				(end 329.351386 -430.147222)
			)
		)
		(stroke
			(width 0)
			(type solid)
		)
		(fill yes)
		(layer "B.Cu")
		(net "GND")
	)
	(gr_poly
		(pts
			(arc
				(start 329.351386 -428.851314)
				(mid 329.147678 -428.851314)
				(end 329.351386 -428.851314)
			)
		)
		(stroke
			(width 0)
			(type solid)
		)
		(fill yes)
		(layer "B.Cu")
		(net "GND")
	)
	(gr_poly
		(pts
			(arc
				(start 329.351386 -427.699678)
				(mid 329.147678 -427.699678)
				(end 329.351386 -427.699678)
			)
		)
		(stroke
			(width 0)
			(type solid)
		)
		(fill yes)
		(layer "B.Cu")
		(net "GND")
	)
	(gr_poly
		(pts
			(arc
				(start 329.351386 -426.54728)
				(mid 329.147678 -426.54728)
				(end 329.351386 -426.54728)
			)
		)
		(stroke
			(width 0)
			(type solid)
		)
		(fill yes)
		(layer "B.Cu")
		(net "GND")
	)
	(gr_poly
		(pts
			(arc
				(start 332.35138 -438.651396)
				(mid 332.147672 -438.651396)
				(end 332.35138 -438.651396)
			)
		)
		(stroke
			(width 0)
			(type solid)
		)
		(fill yes)
		(layer "B.Cu")
		(net "GND")
	)
	(gr_poly
		(pts
			(arc
				(start 332.35138 -437.49976)
				(mid 332.147672 -437.49976)
				(end 332.35138 -437.49976)
			)
		)
		(stroke
			(width 0)
			(type solid)
		)
		(fill yes)
		(layer "B.Cu")
		(net "GND")
	)
	(gr_poly
		(pts
			(arc
				(start 332.35138 -436.347362)
				(mid 332.147672 -436.347362)
				(end 332.35138 -436.347362)
			)
		)
		(stroke
			(width 0)
			(type solid)
		)
		(fill yes)
		(layer "B.Cu")
		(net "GND")
	)
	(gr_poly
		(pts
			(arc
				(start 332.35138 -435.0512)
				(mid 332.147672 -435.0512)
				(end 332.35138 -435.0512)
			)
		)
		(stroke
			(width 0)
			(type solid)
		)
		(fill yes)
		(layer "B.Cu")
		(net "GND")
	)
	(gr_poly
		(pts
			(arc
				(start 332.35138 -433.899564)
				(mid 332.147672 -433.899564)
				(end 332.35138 -433.899564)
			)
		)
		(stroke
			(width 0)
			(type solid)
		)
		(fill yes)
		(layer "B.Cu")
		(net "GND")
	)
	(gr_poly
		(pts
			(arc
				(start 332.35138 -432.747166)
				(mid 332.147672 -432.747166)
				(end 332.35138 -432.747166)
			)
		)
		(stroke
			(width 0)
			(type solid)
		)
		(fill yes)
		(layer "B.Cu")
		(net "GND")
	)
	(gr_poly
		(pts
			(arc
				(start 332.35138 -431.451258)
				(mid 332.147672 -431.451258)
				(end 332.35138 -431.451258)
			)
		)
		(stroke
			(width 0)
			(type solid)
		)
		(fill yes)
		(layer "B.Cu")
		(net "GND")
	)
	(gr_poly
		(pts
			(arc
				(start 332.35138 -430.299622)
				(mid 332.147672 -430.299622)
				(end 332.35138 -430.299622)
			)
		)
		(stroke
			(width 0)
			(type solid)
		)
		(fill yes)
		(layer "B.Cu")
		(net "GND")
	)
	(gr_poly
		(pts
			(arc
				(start 332.35138 -429.147224)
				(mid 332.147672 -429.147224)
				(end 332.35138 -429.147224)
			)
		)
		(stroke
			(width 0)
			(type solid)
		)
		(fill yes)
		(layer "B.Cu")
		(net "GND")
	)
	(gr_poly
		(pts
			(arc
				(start 332.35138 -427.851316)
				(mid 332.147672 -427.851316)
				(end 332.35138 -427.851316)
			)
		)
		(stroke
			(width 0)
			(type solid)
		)
		(fill yes)
		(layer "B.Cu")
		(net "GND")
	)
	(gr_poly
		(pts
			(arc
				(start 332.35138 -426.69968)
				(mid 332.147672 -426.69968)
				(end 332.35138 -426.69968)
			)
		)
		(stroke
			(width 0)
			(type solid)
		)
		(fill yes)
		(layer "B.Cu")
		(net "GND")
	)
	(gr_poly
		(pts
			(arc
				(start 332.35138 -425.547282)
				(mid 332.147672 -425.547282)
				(end 332.35138 -425.547282)
			)
		)
		(stroke
			(width 0)
			(type solid)
		)
		(fill yes)
		(layer "B.Cu")
		(net "GND")
	)
	(gr_poly
		(pts
			(arc
				(start 334.351376 -439.651394)
				(mid 334.147668 -439.651394)
				(end 334.351376 -439.651394)
			)
		)
		(stroke
			(width 0)
			(type solid)
		)
		(fill yes)
		(layer "B.Cu")
		(net "GND")
	)
	(gr_poly
		(pts
			(arc
				(start 334.351376 -438.499758)
				(mid 334.147668 -438.499758)
				(end 334.351376 -438.499758)
			)
		)
		(stroke
			(width 0)
			(type solid)
		)
		(fill yes)
		(layer "B.Cu")
		(net "GND")
	)
	(gr_poly
		(pts
			(arc
				(start 334.351376 -437.34736)
				(mid 334.147668 -437.34736)
				(end 334.351376 -437.34736)
			)
		)
		(stroke
			(width 0)
			(type solid)
		)
		(fill yes)
		(layer "B.Cu")
		(net "GND")
	)
	(gr_poly
		(pts
			(arc
				(start 334.351376 -436.051198)
				(mid 334.147668 -436.051198)
				(end 334.351376 -436.051198)
			)
		)
		(stroke
			(width 0)
			(type solid)
		)
		(fill yes)
		(layer "B.Cu")
		(net "GND")
	)
	(gr_poly
		(pts
			(arc
				(start 334.351376 -434.899562)
				(mid 334.147668 -434.899562)
				(end 334.351376 -434.899562)
			)
		)
		(stroke
			(width 0)
			(type solid)
		)
		(fill yes)
		(layer "B.Cu")
		(net "GND")
	)
	(gr_poly
		(pts
			(arc
				(start 334.351376 -433.747164)
				(mid 334.147668 -433.747164)
				(end 334.351376 -433.747164)
			)
		)
		(stroke
			(width 0)
			(type solid)
		)
		(fill yes)
		(layer "B.Cu")
		(net "GND")
	)
	(gr_poly
		(pts
			(arc
				(start 334.351376 -432.451256)
				(mid 334.147668 -432.451256)
				(end 334.351376 -432.451256)
			)
		)
		(stroke
			(width 0)
			(type solid)
		)
		(fill yes)
		(layer "B.Cu")
		(net "GND")
	)
	(gr_poly
		(pts
			(arc
				(start 334.351376 -431.29962)
				(mid 334.147668 -431.29962)
				(end 334.351376 -431.29962)
			)
		)
		(stroke
			(width 0)
			(type solid)
		)
		(fill yes)
		(layer "B.Cu")
		(net "GND")
	)
	(gr_poly
		(pts
			(arc
				(start 334.351376 -430.147222)
				(mid 334.147668 -430.147222)
				(end 334.351376 -430.147222)
			)
		)
		(stroke
			(width 0)
			(type solid)
		)
		(fill yes)
		(layer "B.Cu")
		(net "GND")
	)
	(gr_poly
		(pts
			(arc
				(start 334.351376 -428.851314)
				(mid 334.147668 -428.851314)
				(end 334.351376 -428.851314)
			)
		)
		(stroke
			(width 0)
			(type solid)
		)
		(fill yes)
		(layer "B.Cu")
		(net "GND")
	)
	(gr_poly
		(pts
			(arc
				(start 334.351376 -427.699678)
				(mid 334.147668 -427.699678)
				(end 334.351376 -427.699678)
			)
		)
		(stroke
			(width 0)
			(type solid)
		)
		(fill yes)
		(layer "B.Cu")
		(net "GND")
	)
	(gr_poly
		(pts
			(arc
				(start 334.351376 -426.54728)
				(mid 334.147668 -426.54728)
				(end 334.351376 -426.54728)
			)
		)
		(stroke
			(width 0)
			(type solid)
		)
		(fill yes)
		(layer "B.Cu")
		(net "GND")
	)
	(gr_poly
		(pts
			(arc
				(start 336.351372 -438.651396)
				(mid 336.147664 -438.651396)
				(end 336.351372 -438.651396)
			)
		)
		(stroke
			(width 0)
			(type solid)
		)
		(fill yes)
		(layer "B.Cu")
		(net "GND")
	)
	(gr_poly
		(pts
			(arc
				(start 336.351372 -437.49976)
				(mid 336.147664 -437.49976)
				(end 336.351372 -437.49976)
			)
		)
		(stroke
			(width 0)
			(type solid)
		)
		(fill yes)
		(layer "B.Cu")
		(net "GND")
	)
	(gr_poly
		(pts
			(arc
				(start 336.351372 -436.347362)
				(mid 336.147664 -436.347362)
				(end 336.351372 -436.347362)
			)
		)
		(stroke
			(width 0)
			(type solid)
		)
		(fill yes)
		(layer "B.Cu")
		(net "GND")
	)
	(gr_poly
		(pts
			(arc
				(start 336.351372 -435.0512)
				(mid 336.147664 -435.0512)
				(end 336.351372 -435.0512)
			)
		)
		(stroke
			(width 0)
			(type solid)
		)
		(fill yes)
		(layer "B.Cu")
		(net "GND")
	)
	(gr_poly
		(pts
			(arc
				(start 336.351372 -433.899564)
				(mid 336.147664 -433.899564)
				(end 336.351372 -433.899564)
			)
		)
		(stroke
			(width 0)
			(type solid)
		)
		(fill yes)
		(layer "B.Cu")
		(net "GND")
	)
	(gr_poly
		(pts
			(arc
				(start 336.351372 -432.747166)
				(mid 336.147664 -432.747166)
				(end 336.351372 -432.747166)
			)
		)
		(stroke
			(width 0)
			(type solid)
		)
		(fill yes)
		(layer "B.Cu")
		(net "GND")
	)
	(gr_poly
		(pts
			(arc
				(start 336.351372 -431.451258)
				(mid 336.147664 -431.451258)
				(end 336.351372 -431.451258)
			)
		)
		(stroke
			(width 0)
			(type solid)
		)
		(fill yes)
		(layer "B.Cu")
		(net "GND")
	)
	(gr_poly
		(pts
			(arc
				(start 336.351372 -430.299622)
				(mid 336.147664 -430.299622)
				(end 336.351372 -430.299622)
			)
		)
		(stroke
			(width 0)
			(type solid)
		)
		(fill yes)
		(layer "B.Cu")
		(net "GND")
	)
	(gr_poly
		(pts
			(arc
				(start 336.351372 -429.147224)
				(mid 336.147664 -429.147224)
				(end 336.351372 -429.147224)
			)
		)
		(stroke
			(width 0)
			(type solid)
		)
		(fill yes)
		(layer "B.Cu")
		(net "GND")
	)
	(gr_poly
		(pts
			(arc
				(start 336.351372 -427.851316)
				(mid 336.147664 -427.851316)
				(end 336.351372 -427.851316)
			)
		)
		(stroke
			(width 0)
			(type solid)
		)
		(fill yes)
		(layer "B.Cu")
		(net "GND")
	)
	(gr_poly
		(pts
			(arc
				(start 336.351372 -426.69968)
				(mid 336.147664 -426.69968)
				(end 336.351372 -426.69968)
			)
		)
		(stroke
			(width 0)
			(type solid)
		)
		(fill yes)
		(layer "B.Cu")
		(net "GND")
	)
	(gr_poly
		(pts
			(arc
				(start 336.351372 -425.547282)
				(mid 336.147664 -425.547282)
				(end 336.351372 -425.547282)
			)
		)
		(stroke
			(width 0)
			(type solid)
		)
		(fill yes)
		(layer "B.Cu")
		(net "GND")
	)
	(gr_poly
		(pts
			(arc
				(start 338.351368 -439.651394)
				(mid 338.14766 -439.651394)
				(end 338.351368 -439.651394)
			)
		)
		(stroke
			(width 0)
			(type solid)
		)
		(fill yes)
		(layer "B.Cu")
		(net "GND")
	)
	(gr_poly
		(pts
			(arc
				(start 338.351368 -438.499758)
				(mid 338.14766 -438.499758)
				(end 338.351368 -438.499758)
			)
		)
		(stroke
			(width 0)
			(type solid)
		)
		(fill yes)
		(layer "B.Cu")
		(net "GND")
	)
	(gr_poly
		(pts
			(arc
				(start 338.351368 -437.34736)
				(mid 338.14766 -437.34736)
				(end 338.351368 -437.34736)
			)
		)
		(stroke
			(width 0)
			(type solid)
		)
		(fill yes)
		(layer "B.Cu")
		(net "GND")
	)
	(gr_poly
		(pts
			(arc
				(start 338.351368 -436.051198)
				(mid 338.14766 -436.051198)
				(end 338.351368 -436.051198)
			)
		)
		(stroke
			(width 0)
			(type solid)
		)
		(fill yes)
		(layer "B.Cu")
		(net "GND")
	)
	(gr_poly
		(pts
			(arc
				(start 338.351368 -434.899562)
				(mid 338.14766 -434.899562)
				(end 338.351368 -434.899562)
			)
		)
		(stroke
			(width 0)
			(type solid)
		)
		(fill yes)
		(layer "B.Cu")
		(net "GND")
	)
	(gr_poly
		(pts
			(arc
				(start 338.351368 -433.747164)
				(mid 338.14766 -433.747164)
				(end 338.351368 -433.747164)
			)
		)
		(stroke
			(width 0)
			(type solid)
		)
		(fill yes)
		(layer "B.Cu")
		(net "GND")
	)
	(gr_poly
		(pts
			(arc
				(start 338.351368 -432.451256)
				(mid 338.14766 -432.451256)
				(end 338.351368 -432.451256)
			)
		)
		(stroke
			(width 0)
			(type solid)
		)
		(fill yes)
		(layer "B.Cu")
		(net "GND")
	)
	(gr_poly
		(pts
			(arc
				(start 338.351368 -431.29962)
				(mid 338.14766 -431.29962)
				(end 338.351368 -431.29962)
			)
		)
		(stroke
			(width 0)
			(type solid)
		)
		(fill yes)
		(layer "B.Cu")
		(net "GND")
	)
	(gr_poly
		(pts
			(arc
				(start 338.351368 -430.147222)
				(mid 338.14766 -430.147222)
				(end 338.351368 -430.147222)
			)
		)
		(stroke
			(width 0)
			(type solid)
		)
		(fill yes)
		(layer "B.Cu")
		(net "GND")
	)
	(gr_poly
		(pts
			(arc
				(start 338.351368 -428.851314)
				(mid 338.14766 -428.851314)
				(end 338.351368 -428.851314)
			)
		)
		(stroke
			(width 0)
			(type solid)
		)
		(fill yes)
		(layer "B.Cu")
		(net "GND")
	)
	(gr_poly
		(pts
			(arc
				(start 338.351368 -427.699678)
				(mid 338.14766 -427.699678)
				(end 338.351368 -427.699678)
			)
		)
		(stroke
			(width 0)
			(type solid)
		)
		(fill yes)
		(layer "B.Cu")
		(net "GND")
	)
	(gr_poly
		(pts
			(arc
				(start 338.351368 -426.54728)
				(mid 338.14766 -426.54728)
				(end 338.351368 -426.54728)
			)
		)
		(stroke
			(width 0)
			(type solid)
		)
		(fill yes)
		(layer "B.Cu")
		(net "GND")
	)
	(gr_poly
		(pts
			(arc
				(start 340.351364 -438.651396)
				(mid 340.147656 -438.651396)
				(end 340.351364 -438.651396)
			)
		)
		(stroke
			(width 0)
			(type solid)
		)
		(fill yes)
		(layer "B.Cu")
		(net "GND")
	)
	(gr_poly
		(pts
			(arc
				(start 340.351364 -437.49976)
				(mid 340.147656 -437.49976)
				(end 340.351364 -437.49976)
			)
		)
		(stroke
			(width 0)
			(type solid)
		)
		(fill yes)
		(layer "B.Cu")
		(net "GND")
	)
	(gr_poly
		(pts
			(arc
				(start 340.351364 -436.347362)
				(mid 340.147656 -436.347362)
				(end 340.351364 -436.347362)
			)
		)
		(stroke
			(width 0)
			(type solid)
		)
		(fill yes)
		(layer "B.Cu")
		(net "GND")
	)
	(gr_poly
		(pts
			(arc
				(start 340.351364 -435.0512)
				(mid 340.147656 -435.0512)
				(end 340.351364 -435.0512)
			)
		)
		(stroke
			(width 0)
			(type solid)
		)
		(fill yes)
		(layer "B.Cu")
		(net "GND")
	)
	(gr_poly
		(pts
			(arc
				(start 340.351364 -433.899564)
				(mid 340.147656 -433.899564)
				(end 340.351364 -433.899564)
			)
		)
		(stroke
			(width 0)
			(type solid)
		)
		(fill yes)
		(layer "B.Cu")
		(net "GND")
	)
	(gr_poly
		(pts
			(arc
				(start 340.351364 -432.747166)
				(mid 340.147656 -432.747166)
				(end 340.351364 -432.747166)
			)
		)
		(stroke
			(width 0)
			(type solid)
		)
		(fill yes)
		(layer "B.Cu")
		(net "GND")
	)
	(gr_poly
		(pts
			(arc
				(start 340.351364 -431.451258)
				(mid 340.147656 -431.451258)
				(end 340.351364 -431.451258)
			)
		)
		(stroke
			(width 0)
			(type solid)
		)
		(fill yes)
		(layer "B.Cu")
		(net "GND")
	)
	(gr_poly
		(pts
			(arc
				(start 340.351364 -430.299622)
				(mid 340.147656 -430.299622)
				(end 340.351364 -430.299622)
			)
		)
		(stroke
			(width 0)
			(type solid)
		)
		(fill yes)
		(layer "B.Cu")
		(net "GND")
	)
	(gr_poly
		(pts
			(arc
				(start 340.351364 -429.147224)
				(mid 340.147656 -429.147224)
				(end 340.351364 -429.147224)
			)
		)
		(stroke
			(width 0)
			(type solid)
		)
		(fill yes)
		(layer "B.Cu")
		(net "GND")
	)
	(gr_poly
		(pts
			(arc
				(start 340.351364 -427.851316)
				(mid 340.147656 -427.851316)
				(end 340.351364 -427.851316)
			)
		)
		(stroke
			(width 0)
			(type solid)
		)
		(fill yes)
		(layer "B.Cu")
		(net "GND")
	)
	(gr_poly
		(pts
			(arc
				(start 340.351364 -426.69968)
				(mid 340.147656 -426.69968)
				(end 340.351364 -426.69968)
			)
		)
		(stroke
			(width 0)
			(type solid)
		)
		(fill yes)
		(layer "B.Cu")
		(net "GND")
	)
	(gr_poly
		(pts
			(arc
				(start 340.351364 -425.547282)
				(mid 340.147656 -425.547282)
				(end 340.351364 -425.547282)
			)
		)
		(stroke
			(width 0)
			(type solid)
		)
		(fill yes)
		(layer "B.Cu")
		(net "GND")
	)
	(gr_poly
		(pts
			(arc
				(start 342.35136 -439.651394)
				(mid 342.147652 -439.651394)
				(end 342.35136 -439.651394)
			)
		)
		(stroke
			(width 0)
			(type solid)
		)
		(fill yes)
		(layer "B.Cu")
		(net "GND")
	)
	(gr_poly
		(pts
			(arc
				(start 342.35136 -438.499758)
				(mid 342.147652 -438.499758)
				(end 342.35136 -438.499758)
			)
		)
		(stroke
			(width 0)
			(type solid)
		)
		(fill yes)
		(layer "B.Cu")
		(net "GND")
	)
	(gr_poly
		(pts
			(arc
				(start 342.35136 -437.34736)
				(mid 342.147652 -437.34736)
				(end 342.35136 -437.34736)
			)
		)
		(stroke
			(width 0)
			(type solid)
		)
		(fill yes)
		(layer "B.Cu")
		(net "GND")
	)
	(gr_poly
		(pts
			(arc
				(start 342.35136 -436.051198)
				(mid 342.147652 -436.051198)
				(end 342.35136 -436.051198)
			)
		)
		(stroke
			(width 0)
			(type solid)
		)
		(fill yes)
		(layer "B.Cu")
		(net "GND")
	)
	(gr_poly
		(pts
			(arc
				(start 342.35136 -434.899562)
				(mid 342.147652 -434.899562)
				(end 342.35136 -434.899562)
			)
		)
		(stroke
			(width 0)
			(type solid)
		)
		(fill yes)
		(layer "B.Cu")
		(net "GND")
	)
	(gr_poly
		(pts
			(arc
				(start 342.35136 -433.747164)
				(mid 342.147652 -433.747164)
				(end 342.35136 -433.747164)
			)
		)
		(stroke
			(width 0)
			(type solid)
		)
		(fill yes)
		(layer "B.Cu")
		(net "GND")
	)
	(gr_poly
		(pts
			(arc
				(start 342.35136 -432.451256)
				(mid 342.147652 -432.451256)
				(end 342.35136 -432.451256)
			)
		)
		(stroke
			(width 0)
			(type solid)
		)
		(fill yes)
		(layer "B.Cu")
		(net "GND")
	)
	(gr_poly
		(pts
			(arc
				(start 342.35136 -431.29962)
				(mid 342.147652 -431.29962)
				(end 342.35136 -431.29962)
			)
		)
		(stroke
			(width 0)
			(type solid)
		)
		(fill yes)
		(layer "B.Cu")
		(net "GND")
	)
	(gr_poly
		(pts
			(arc
				(start 342.35136 -430.147222)
				(mid 342.147652 -430.147222)
				(end 342.35136 -430.147222)
			)
		)
		(stroke
			(width 0)
			(type solid)
		)
		(fill yes)
		(layer "B.Cu")
		(net "GND")
	)
	(gr_poly
		(pts
			(arc
				(start 342.35136 -428.851314)
				(mid 342.147652 -428.851314)
				(end 342.35136 -428.851314)
			)
		)
		(stroke
			(width 0)
			(type solid)
		)
		(fill yes)
		(layer "B.Cu")
		(net "GND")
	)
	(gr_poly
		(pts
			(arc
				(start 342.35136 -427.699678)
				(mid 342.147652 -427.699678)
				(end 342.35136 -427.699678)
			)
		)
		(stroke
			(width 0)
			(type solid)
		)
		(fill yes)
		(layer "B.Cu")
		(net "GND")
	)
	(gr_poly
		(pts
			(arc
				(start 342.35136 -426.54728)
				(mid 342.147652 -426.54728)
				(end 342.35136 -426.54728)
			)
		)
		(stroke
			(width 0)
			(type solid)
		)
		(fill yes)
		(layer "B.Cu")
		(net "GND")
	)
	(gr_poly
		(pts
			(arc
				(start 344.351356 -438.651396)
				(mid 344.147648 -438.651396)
				(end 344.351356 -438.651396)
			)
		)
		(stroke
			(width 0)
			(type solid)
		)
		(fill yes)
		(layer "B.Cu")
		(net "GND")
	)
	(gr_poly
		(pts
			(arc
				(start 344.351356 -437.49976)
				(mid 344.147648 -437.49976)
				(end 344.351356 -437.49976)
			)
		)
		(stroke
			(width 0)
			(type solid)
		)
		(fill yes)
		(layer "B.Cu")
		(net "GND")
	)
	(gr_poly
		(pts
			(arc
				(start 344.351356 -436.347362)
				(mid 344.147648 -436.347362)
				(end 344.351356 -436.347362)
			)
		)
		(stroke
			(width 0)
			(type solid)
		)
		(fill yes)
		(layer "B.Cu")
		(net "GND")
	)
	(gr_poly
		(pts
			(arc
				(start 344.351356 -435.0512)
				(mid 344.147648 -435.0512)
				(end 344.351356 -435.0512)
			)
		)
		(stroke
			(width 0)
			(type solid)
		)
		(fill yes)
		(layer "B.Cu")
		(net "GND")
	)
	(gr_poly
		(pts
			(arc
				(start 344.351356 -433.899564)
				(mid 344.147648 -433.899564)
				(end 344.351356 -433.899564)
			)
		)
		(stroke
			(width 0)
			(type solid)
		)
		(fill yes)
		(layer "B.Cu")
		(net "GND")
	)
	(gr_poly
		(pts
			(arc
				(start 344.351356 -432.747166)
				(mid 344.147648 -432.747166)
				(end 344.351356 -432.747166)
			)
		)
		(stroke
			(width 0)
			(type solid)
		)
		(fill yes)
		(layer "B.Cu")
		(net "GND")
	)
	(gr_poly
		(pts
			(arc
				(start 344.351356 -431.451258)
				(mid 344.147648 -431.451258)
				(end 344.351356 -431.451258)
			)
		)
		(stroke
			(width 0)
			(type solid)
		)
		(fill yes)
		(layer "B.Cu")
		(net "GND")
	)
	(gr_poly
		(pts
			(arc
				(start 344.351356 -430.299622)
				(mid 344.147648 -430.299622)
				(end 344.351356 -430.299622)
			)
		)
		(stroke
			(width 0)
			(type solid)
		)
		(fill yes)
		(layer "B.Cu")
		(net "GND")
	)
	(gr_poly
		(pts
			(arc
				(start 344.351356 -429.147224)
				(mid 344.147648 -429.147224)
				(end 344.351356 -429.147224)
			)
		)
		(stroke
			(width 0)
			(type solid)
		)
		(fill yes)
		(layer "B.Cu")
		(net "GND")
	)
	(gr_poly
		(pts
			(arc
				(start 344.351356 -427.851316)
				(mid 344.147648 -427.851316)
				(end 344.351356 -427.851316)
			)
		)
		(stroke
			(width 0)
			(type solid)
		)
		(fill yes)
		(layer "B.Cu")
		(net "GND")
	)
	(gr_poly
		(pts
			(arc
				(start 344.351356 -426.69968)
				(mid 344.147648 -426.69968)
				(end 344.351356 -426.69968)
			)
		)
		(stroke
			(width 0)
			(type solid)
		)
		(fill yes)
		(layer "B.Cu")
		(net "GND")
	)
	(gr_poly
		(pts
			(arc
				(start 344.351356 -425.547282)
				(mid 344.147648 -425.547282)
				(end 344.351356 -425.547282)
			)
		)
		(stroke
			(width 0)
			(type solid)
		)
		(fill yes)
		(layer "B.Cu")
		(net "GND")
	)
	(gr_poly
		(pts
			(arc
				(start 346.351352 -439.651394)
				(mid 346.147644 -439.651394)
				(end 346.351352 -439.651394)
			)
		)
		(stroke
			(width 0)
			(type solid)
		)
		(fill yes)
		(layer "B.Cu")
		(net "GND")
	)
	(gr_poly
		(pts
			(arc
				(start 346.351352 -438.499758)
				(mid 346.147644 -438.499758)
				(end 346.351352 -438.499758)
			)
		)
		(stroke
			(width 0)
			(type solid)
		)
		(fill yes)
		(layer "B.Cu")
		(net "GND")
	)
	(gr_poly
		(pts
			(arc
				(start 346.351352 -437.34736)
				(mid 346.147644 -437.34736)
				(end 346.351352 -437.34736)
			)
		)
		(stroke
			(width 0)
			(type solid)
		)
		(fill yes)
		(layer "B.Cu")
		(net "GND")
	)
	(gr_poly
		(pts
			(arc
				(start 346.351352 -436.051198)
				(mid 346.147644 -436.051198)
				(end 346.351352 -436.051198)
			)
		)
		(stroke
			(width 0)
			(type solid)
		)
		(fill yes)
		(layer "B.Cu")
		(net "GND")
	)
	(gr_poly
		(pts
			(arc
				(start 346.351352 -434.899562)
				(mid 346.147644 -434.899562)
				(end 346.351352 -434.899562)
			)
		)
		(stroke
			(width 0)
			(type solid)
		)
		(fill yes)
		(layer "B.Cu")
		(net "GND")
	)
	(gr_poly
		(pts
			(arc
				(start 346.351352 -433.747164)
				(mid 346.147644 -433.747164)
				(end 346.351352 -433.747164)
			)
		)
		(stroke
			(width 0)
			(type solid)
		)
		(fill yes)
		(layer "B.Cu")
		(net "GND")
	)
	(gr_poly
		(pts
			(arc
				(start 346.351352 -432.451256)
				(mid 346.147644 -432.451256)
				(end 346.351352 -432.451256)
			)
		)
		(stroke
			(width 0)
			(type solid)
		)
		(fill yes)
		(layer "B.Cu")
		(net "GND")
	)
	(gr_poly
		(pts
			(arc
				(start 346.351352 -431.29962)
				(mid 346.147644 -431.29962)
				(end 346.351352 -431.29962)
			)
		)
		(stroke
			(width 0)
			(type solid)
		)
		(fill yes)
		(layer "B.Cu")
		(net "GND")
	)
	(gr_poly
		(pts
			(arc
				(start 346.351352 -430.147222)
				(mid 346.147644 -430.147222)
				(end 346.351352 -430.147222)
			)
		)
		(stroke
			(width 0)
			(type solid)
		)
		(fill yes)
		(layer "B.Cu")
		(net "GND")
	)
	(gr_poly
		(pts
			(arc
				(start 346.351352 -428.851314)
				(mid 346.147644 -428.851314)
				(end 346.351352 -428.851314)
			)
		)
		(stroke
			(width 0)
			(type solid)
		)
		(fill yes)
		(layer "B.Cu")
		(net "GND")
	)
	(gr_poly
		(pts
			(arc
				(start 346.351352 -427.699678)
				(mid 346.147644 -427.699678)
				(end 346.351352 -427.699678)
			)
		)
		(stroke
			(width 0)
			(type solid)
		)
		(fill yes)
		(layer "B.Cu")
		(net "GND")
	)
	(gr_poly
		(pts
			(arc
				(start 346.351352 -426.54728)
				(mid 346.147644 -426.54728)
				(end 346.351352 -426.54728)
			)
		)
		(stroke
			(width 0)
			(type solid)
		)
		(fill yes)
		(layer "B.Cu")
		(net "GND")
	)
	(gr_poly
		(pts
			(arc
				(start 382.451356 -438.651396)
				(mid 382.247648 -438.651396)
				(end 382.451356 -438.651396)
			)
		)
		(stroke
			(width 0)
			(type solid)
		)
		(fill yes)
		(layer "B.Cu")
		(net "GND")
	)
	(gr_poly
		(pts
			(arc
				(start 382.451356 -437.49976)
				(mid 382.247648 -437.49976)
				(end 382.451356 -437.49976)
			)
		)
		(stroke
			(width 0)
			(type solid)
		)
		(fill yes)
		(layer "B.Cu")
		(net "GND")
	)
	(gr_poly
		(pts
			(arc
				(start 382.451356 -436.347362)
				(mid 382.247648 -436.347362)
				(end 382.451356 -436.347362)
			)
		)
		(stroke
			(width 0)
			(type solid)
		)
		(fill yes)
		(layer "B.Cu")
		(net "GND")
	)
	(gr_poly
		(pts
			(arc
				(start 382.451356 -435.0512)
				(mid 382.247648 -435.0512)
				(end 382.451356 -435.0512)
			)
		)
		(stroke
			(width 0)
			(type solid)
		)
		(fill yes)
		(layer "B.Cu")
		(net "GND")
	)
	(gr_poly
		(pts
			(arc
				(start 382.451356 -433.899564)
				(mid 382.247648 -433.899564)
				(end 382.451356 -433.899564)
			)
		)
		(stroke
			(width 0)
			(type solid)
		)
		(fill yes)
		(layer "B.Cu")
		(net "GND")
	)
	(gr_poly
		(pts
			(arc
				(start 382.451356 -432.747166)
				(mid 382.247648 -432.747166)
				(end 382.451356 -432.747166)
			)
		)
		(stroke
			(width 0)
			(type solid)
		)
		(fill yes)
		(layer "B.Cu")
		(net "GND")
	)
	(gr_poly
		(pts
			(arc
				(start 382.451356 -431.451258)
				(mid 382.247648 -431.451258)
				(end 382.451356 -431.451258)
			)
		)
		(stroke
			(width 0)
			(type solid)
		)
		(fill yes)
		(layer "B.Cu")
		(net "GND")
	)
	(gr_poly
		(pts
			(arc
				(start 382.451356 -430.299622)
				(mid 382.247648 -430.299622)
				(end 382.451356 -430.299622)
			)
		)
		(stroke
			(width 0)
			(type solid)
		)
		(fill yes)
		(layer "B.Cu")
		(net "GND")
	)
	(gr_poly
		(pts
			(arc
				(start 382.451356 -429.147224)
				(mid 382.247648 -429.147224)
				(end 382.451356 -429.147224)
			)
		)
		(stroke
			(width 0)
			(type solid)
		)
		(fill yes)
		(layer "B.Cu")
		(net "GND")
	)
	(gr_poly
		(pts
			(arc
				(start 382.451356 -427.851316)
				(mid 382.247648 -427.851316)
				(end 382.451356 -427.851316)
			)
		)
		(stroke
			(width 0)
			(type solid)
		)
		(fill yes)
		(layer "B.Cu")
		(net "GND")
	)
	(gr_poly
		(pts
			(arc
				(start 382.451356 -426.69968)
				(mid 382.247648 -426.69968)
				(end 382.451356 -426.69968)
			)
		)
		(stroke
			(width 0)
			(type solid)
		)
		(fill yes)
		(layer "B.Cu")
		(net "GND")
	)
	(gr_poly
		(pts
			(arc
				(start 382.451356 -425.547282)
				(mid 382.247648 -425.547282)
				(end 382.451356 -425.547282)
			)
		)
		(stroke
			(width 0)
			(type solid)
		)
		(fill yes)
		(layer "B.Cu")
		(net "GND")
	)
	(gr_poly
		(pts
			(arc
				(start 384.451352 -439.651394)
				(mid 384.247644 -439.651394)
				(end 384.451352 -439.651394)
			)
		)
		(stroke
			(width 0)
			(type solid)
		)
		(fill yes)
		(layer "B.Cu")
		(net "GND")
	)
	(gr_poly
		(pts
			(arc
				(start 384.451352 -438.499758)
				(mid 384.247644 -438.499758)
				(end 384.451352 -438.499758)
			)
		)
		(stroke
			(width 0)
			(type solid)
		)
		(fill yes)
		(layer "B.Cu")
		(net "GND")
	)
	(gr_poly
		(pts
			(arc
				(start 384.451352 -437.34736)
				(mid 384.247644 -437.34736)
				(end 384.451352 -437.34736)
			)
		)
		(stroke
			(width 0)
			(type solid)
		)
		(fill yes)
		(layer "B.Cu")
		(net "GND")
	)
	(gr_poly
		(pts
			(arc
				(start 384.451352 -436.051198)
				(mid 384.247644 -436.051198)
				(end 384.451352 -436.051198)
			)
		)
		(stroke
			(width 0)
			(type solid)
		)
		(fill yes)
		(layer "B.Cu")
		(net "GND")
	)
	(gr_poly
		(pts
			(arc
				(start 384.451352 -434.899562)
				(mid 384.247644 -434.899562)
				(end 384.451352 -434.899562)
			)
		)
		(stroke
			(width 0)
			(type solid)
		)
		(fill yes)
		(layer "B.Cu")
		(net "GND")
	)
	(gr_poly
		(pts
			(arc
				(start 384.451352 -433.747164)
				(mid 384.247644 -433.747164)
				(end 384.451352 -433.747164)
			)
		)
		(stroke
			(width 0)
			(type solid)
		)
		(fill yes)
		(layer "B.Cu")
		(net "GND")
	)
	(gr_poly
		(pts
			(arc
				(start 384.451352 -432.451256)
				(mid 384.247644 -432.451256)
				(end 384.451352 -432.451256)
			)
		)
		(stroke
			(width 0)
			(type solid)
		)
		(fill yes)
		(layer "B.Cu")
		(net "GND")
	)
	(gr_poly
		(pts
			(arc
				(start 384.451352 -431.29962)
				(mid 384.247644 -431.29962)
				(end 384.451352 -431.29962)
			)
		)
		(stroke
			(width 0)
			(type solid)
		)
		(fill yes)
		(layer "B.Cu")
		(net "GND")
	)
	(gr_poly
		(pts
			(arc
				(start 384.451352 -430.147222)
				(mid 384.247644 -430.147222)
				(end 384.451352 -430.147222)
			)
		)
		(stroke
			(width 0)
			(type solid)
		)
		(fill yes)
		(layer "B.Cu")
		(net "GND")
	)
	(gr_poly
		(pts
			(arc
				(start 384.451352 -428.851314)
				(mid 384.247644 -428.851314)
				(end 384.451352 -428.851314)
			)
		)
		(stroke
			(width 0)
			(type solid)
		)
		(fill yes)
		(layer "B.Cu")
		(net "GND")
	)
	(gr_poly
		(pts
			(arc
				(start 384.451352 -427.699678)
				(mid 384.247644 -427.699678)
				(end 384.451352 -427.699678)
			)
		)
		(stroke
			(width 0)
			(type solid)
		)
		(fill yes)
		(layer "B.Cu")
		(net "GND")
	)
	(gr_poly
		(pts
			(arc
				(start 384.451352 -426.54728)
				(mid 384.247644 -426.54728)
				(end 384.451352 -426.54728)
			)
		)
		(stroke
			(width 0)
			(type solid)
		)
		(fill yes)
		(layer "B.Cu")
		(net "GND")
	)
	(gr_poly
		(pts
			(arc
				(start 386.451348 -438.651396)
				(mid 386.24764 -438.651396)
				(end 386.451348 -438.651396)
			)
		)
		(stroke
			(width 0)
			(type solid)
		)
		(fill yes)
		(layer "B.Cu")
		(net "GND")
	)
	(gr_poly
		(pts
			(arc
				(start 386.451348 -437.49976)
				(mid 386.24764 -437.49976)
				(end 386.451348 -437.49976)
			)
		)
		(stroke
			(width 0)
			(type solid)
		)
		(fill yes)
		(layer "B.Cu")
		(net "GND")
	)
	(gr_poly
		(pts
			(arc
				(start 386.451348 -436.347362)
				(mid 386.24764 -436.347362)
				(end 386.451348 -436.347362)
			)
		)
		(stroke
			(width 0)
			(type solid)
		)
		(fill yes)
		(layer "B.Cu")
		(net "GND")
	)
	(gr_poly
		(pts
			(arc
				(start 386.451348 -435.0512)
				(mid 386.24764 -435.0512)
				(end 386.451348 -435.0512)
			)
		)
		(stroke
			(width 0)
			(type solid)
		)
		(fill yes)
		(layer "B.Cu")
		(net "GND")
	)
	(gr_poly
		(pts
			(arc
				(start 386.451348 -433.899564)
				(mid 386.24764 -433.899564)
				(end 386.451348 -433.899564)
			)
		)
		(stroke
			(width 0)
			(type solid)
		)
		(fill yes)
		(layer "B.Cu")
		(net "GND")
	)
	(gr_poly
		(pts
			(arc
				(start 386.451348 -432.747166)
				(mid 386.24764 -432.747166)
				(end 386.451348 -432.747166)
			)
		)
		(stroke
			(width 0)
			(type solid)
		)
		(fill yes)
		(layer "B.Cu")
		(net "GND")
	)
	(gr_poly
		(pts
			(arc
				(start 386.451348 -431.451258)
				(mid 386.24764 -431.451258)
				(end 386.451348 -431.451258)
			)
		)
		(stroke
			(width 0)
			(type solid)
		)
		(fill yes)
		(layer "B.Cu")
		(net "GND")
	)
	(gr_poly
		(pts
			(arc
				(start 386.451348 -430.299622)
				(mid 386.24764 -430.299622)
				(end 386.451348 -430.299622)
			)
		)
		(stroke
			(width 0)
			(type solid)
		)
		(fill yes)
		(layer "B.Cu")
		(net "GND")
	)
	(gr_poly
		(pts
			(arc
				(start 386.451348 -429.147224)
				(mid 386.24764 -429.147224)
				(end 386.451348 -429.147224)
			)
		)
		(stroke
			(width 0)
			(type solid)
		)
		(fill yes)
		(layer "B.Cu")
		(net "GND")
	)
	(gr_poly
		(pts
			(arc
				(start 386.451348 -427.851316)
				(mid 386.24764 -427.851316)
				(end 386.451348 -427.851316)
			)
		)
		(stroke
			(width 0)
			(type solid)
		)
		(fill yes)
		(layer "B.Cu")
		(net "GND")
	)
	(gr_poly
		(pts
			(arc
				(start 386.451348 -426.69968)
				(mid 386.24764 -426.69968)
				(end 386.451348 -426.69968)
			)
		)
		(stroke
			(width 0)
			(type solid)
		)
		(fill yes)
		(layer "B.Cu")
		(net "GND")
	)
	(gr_poly
		(pts
			(arc
				(start 386.451348 -425.547282)
				(mid 386.24764 -425.547282)
				(end 386.451348 -425.547282)
			)
		)
		(stroke
			(width 0)
			(type solid)
		)
		(fill yes)
		(layer "B.Cu")
		(net "GND")
	)
	(gr_poly
		(pts
			(arc
				(start 388.451344 -439.651394)
				(mid 388.247636 -439.651394)
				(end 388.451344 -439.651394)
			)
		)
		(stroke
			(width 0)
			(type solid)
		)
		(fill yes)
		(layer "B.Cu")
		(net "GND")
	)
	(gr_poly
		(pts
			(arc
				(start 388.451344 -438.499758)
				(mid 388.247636 -438.499758)
				(end 388.451344 -438.499758)
			)
		)
		(stroke
			(width 0)
			(type solid)
		)
		(fill yes)
		(layer "B.Cu")
		(net "GND")
	)
	(gr_poly
		(pts
			(arc
				(start 388.451344 -437.34736)
				(mid 388.247636 -437.34736)
				(end 388.451344 -437.34736)
			)
		)
		(stroke
			(width 0)
			(type solid)
		)
		(fill yes)
		(layer "B.Cu")
		(net "GND")
	)
	(gr_poly
		(pts
			(arc
				(start 388.451344 -436.051198)
				(mid 388.247636 -436.051198)
				(end 388.451344 -436.051198)
			)
		)
		(stroke
			(width 0)
			(type solid)
		)
		(fill yes)
		(layer "B.Cu")
		(net "GND")
	)
	(gr_poly
		(pts
			(arc
				(start 388.451344 -434.899562)
				(mid 388.247636 -434.899562)
				(end 388.451344 -434.899562)
			)
		)
		(stroke
			(width 0)
			(type solid)
		)
		(fill yes)
		(layer "B.Cu")
		(net "GND")
	)
	(gr_poly
		(pts
			(arc
				(start 388.451344 -433.747164)
				(mid 388.247636 -433.747164)
				(end 388.451344 -433.747164)
			)
		)
		(stroke
			(width 0)
			(type solid)
		)
		(fill yes)
		(layer "B.Cu")
		(net "GND")
	)
	(gr_poly
		(pts
			(arc
				(start 388.451344 -432.451256)
				(mid 388.247636 -432.451256)
				(end 388.451344 -432.451256)
			)
		)
		(stroke
			(width 0)
			(type solid)
		)
		(fill yes)
		(layer "B.Cu")
		(net "GND")
	)
	(gr_poly
		(pts
			(arc
				(start 388.451344 -431.29962)
				(mid 388.247636 -431.29962)
				(end 388.451344 -431.29962)
			)
		)
		(stroke
			(width 0)
			(type solid)
		)
		(fill yes)
		(layer "B.Cu")
		(net "GND")
	)
	(gr_poly
		(pts
			(arc
				(start 388.451344 -430.147222)
				(mid 388.247636 -430.147222)
				(end 388.451344 -430.147222)
			)
		)
		(stroke
			(width 0)
			(type solid)
		)
		(fill yes)
		(layer "B.Cu")
		(net "GND")
	)
	(gr_poly
		(pts
			(arc
				(start 388.451344 -428.851314)
				(mid 388.247636 -428.851314)
				(end 388.451344 -428.851314)
			)
		)
		(stroke
			(width 0)
			(type solid)
		)
		(fill yes)
		(layer "B.Cu")
		(net "GND")
	)
	(gr_poly
		(pts
			(arc
				(start 388.451344 -427.699678)
				(mid 388.247636 -427.699678)
				(end 388.451344 -427.699678)
			)
		)
		(stroke
			(width 0)
			(type solid)
		)
		(fill yes)
		(layer "B.Cu")
		(net "GND")
	)
	(gr_poly
		(pts
			(arc
				(start 388.451344 -426.54728)
				(mid 388.247636 -426.54728)
				(end 388.451344 -426.54728)
			)
		)
		(stroke
			(width 0)
			(type solid)
		)
		(fill yes)
		(layer "B.Cu")
		(net "GND")
	)
	(gr_poly
		(pts
			(arc
				(start 390.45134 -438.651396)
				(mid 390.247632 -438.651396)
				(end 390.45134 -438.651396)
			)
		)
		(stroke
			(width 0)
			(type solid)
		)
		(fill yes)
		(layer "B.Cu")
		(net "GND")
	)
	(gr_poly
		(pts
			(arc
				(start 390.45134 -437.49976)
				(mid 390.247632 -437.49976)
				(end 390.45134 -437.49976)
			)
		)
		(stroke
			(width 0)
			(type solid)
		)
		(fill yes)
		(layer "B.Cu")
		(net "GND")
	)
	(gr_poly
		(pts
			(arc
				(start 390.45134 -436.347362)
				(mid 390.247632 -436.347362)
				(end 390.45134 -436.347362)
			)
		)
		(stroke
			(width 0)
			(type solid)
		)
		(fill yes)
		(layer "B.Cu")
		(net "GND")
	)
	(gr_poly
		(pts
			(arc
				(start 390.45134 -435.0512)
				(mid 390.247632 -435.0512)
				(end 390.45134 -435.0512)
			)
		)
		(stroke
			(width 0)
			(type solid)
		)
		(fill yes)
		(layer "B.Cu")
		(net "GND")
	)
	(gr_poly
		(pts
			(arc
				(start 390.45134 -433.899564)
				(mid 390.247632 -433.899564)
				(end 390.45134 -433.899564)
			)
		)
		(stroke
			(width 0)
			(type solid)
		)
		(fill yes)
		(layer "B.Cu")
		(net "GND")
	)
	(gr_poly
		(pts
			(arc
				(start 390.45134 -432.747166)
				(mid 390.247632 -432.747166)
				(end 390.45134 -432.747166)
			)
		)
		(stroke
			(width 0)
			(type solid)
		)
		(fill yes)
		(layer "B.Cu")
		(net "GND")
	)
	(gr_poly
		(pts
			(arc
				(start 390.45134 -431.451258)
				(mid 390.247632 -431.451258)
				(end 390.45134 -431.451258)
			)
		)
		(stroke
			(width 0)
			(type solid)
		)
		(fill yes)
		(layer "B.Cu")
		(net "GND")
	)
	(gr_poly
		(pts
			(arc
				(start 390.45134 -430.299622)
				(mid 390.247632 -430.299622)
				(end 390.45134 -430.299622)
			)
		)
		(stroke
			(width 0)
			(type solid)
		)
		(fill yes)
		(layer "B.Cu")
		(net "GND")
	)
	(gr_poly
		(pts
			(arc
				(start 390.45134 -429.147224)
				(mid 390.247632 -429.147224)
				(end 390.45134 -429.147224)
			)
		)
		(stroke
			(width 0)
			(type solid)
		)
		(fill yes)
		(layer "B.Cu")
		(net "GND")
	)
	(gr_poly
		(pts
			(arc
				(start 390.45134 -427.851316)
				(mid 390.247632 -427.851316)
				(end 390.45134 -427.851316)
			)
		)
		(stroke
			(width 0)
			(type solid)
		)
		(fill yes)
		(layer "B.Cu")
		(net "GND")
	)
	(gr_poly
		(pts
			(arc
				(start 390.45134 -426.69968)
				(mid 390.247632 -426.69968)
				(end 390.45134 -426.69968)
			)
		)
		(stroke
			(width 0)
			(type solid)
		)
		(fill yes)
		(layer "B.Cu")
		(net "GND")
	)
	(gr_poly
		(pts
			(arc
				(start 390.45134 -425.547282)
				(mid 390.247632 -425.547282)
				(end 390.45134 -425.547282)
			)
		)
		(stroke
			(width 0)
			(type solid)
		)
		(fill yes)
		(layer "B.Cu")
		(net "GND")
	)
	(gr_poly
		(pts
			(arc
				(start 392.451336 -439.651394)
				(mid 392.247628 -439.651394)
				(end 392.451336 -439.651394)
			)
		)
		(stroke
			(width 0)
			(type solid)
		)
		(fill yes)
		(layer "B.Cu")
		(net "GND")
	)
	(gr_poly
		(pts
			(arc
				(start 392.451336 -438.499758)
				(mid 392.247628 -438.499758)
				(end 392.451336 -438.499758)
			)
		)
		(stroke
			(width 0)
			(type solid)
		)
		(fill yes)
		(layer "B.Cu")
		(net "GND")
	)
	(gr_poly
		(pts
			(arc
				(start 392.451336 -437.34736)
				(mid 392.247628 -437.34736)
				(end 392.451336 -437.34736)
			)
		)
		(stroke
			(width 0)
			(type solid)
		)
		(fill yes)
		(layer "B.Cu")
		(net "GND")
	)
	(gr_poly
		(pts
			(arc
				(start 392.451336 -436.051198)
				(mid 392.247628 -436.051198)
				(end 392.451336 -436.051198)
			)
		)
		(stroke
			(width 0)
			(type solid)
		)
		(fill yes)
		(layer "B.Cu")
		(net "GND")
	)
	(gr_poly
		(pts
			(arc
				(start 392.451336 -434.899562)
				(mid 392.247628 -434.899562)
				(end 392.451336 -434.899562)
			)
		)
		(stroke
			(width 0)
			(type solid)
		)
		(fill yes)
		(layer "B.Cu")
		(net "GND")
	)
	(gr_poly
		(pts
			(arc
				(start 392.451336 -433.747164)
				(mid 392.247628 -433.747164)
				(end 392.451336 -433.747164)
			)
		)
		(stroke
			(width 0)
			(type solid)
		)
		(fill yes)
		(layer "B.Cu")
		(net "GND")
	)
	(gr_poly
		(pts
			(arc
				(start 392.451336 -432.451256)
				(mid 392.247628 -432.451256)
				(end 392.451336 -432.451256)
			)
		)
		(stroke
			(width 0)
			(type solid)
		)
		(fill yes)
		(layer "B.Cu")
		(net "GND")
	)
	(gr_poly
		(pts
			(arc
				(start 392.451336 -431.29962)
				(mid 392.247628 -431.29962)
				(end 392.451336 -431.29962)
			)
		)
		(stroke
			(width 0)
			(type solid)
		)
		(fill yes)
		(layer "B.Cu")
		(net "GND")
	)
	(gr_poly
		(pts
			(arc
				(start 392.451336 -430.147222)
				(mid 392.247628 -430.147222)
				(end 392.451336 -430.147222)
			)
		)
		(stroke
			(width 0)
			(type solid)
		)
		(fill yes)
		(layer "B.Cu")
		(net "GND")
	)
	(gr_poly
		(pts
			(arc
				(start 392.451336 -428.851314)
				(mid 392.247628 -428.851314)
				(end 392.451336 -428.851314)
			)
		)
		(stroke
			(width 0)
			(type solid)
		)
		(fill yes)
		(layer "B.Cu")
		(net "GND")
	)
	(gr_poly
		(pts
			(arc
				(start 392.451336 -427.699678)
				(mid 392.247628 -427.699678)
				(end 392.451336 -427.699678)
			)
		)
		(stroke
			(width 0)
			(type solid)
		)
		(fill yes)
		(layer "B.Cu")
		(net "GND")
	)
	(gr_poly
		(pts
			(arc
				(start 392.451336 -426.54728)
				(mid 392.247628 -426.54728)
				(end 392.451336 -426.54728)
			)
		)
		(stroke
			(width 0)
			(type solid)
		)
		(fill yes)
		(layer "B.Cu")
		(net "GND")
	)
	(gr_poly
		(pts
			(arc
				(start 394.451332 -438.651396)
				(mid 394.247624 -438.651396)
				(end 394.451332 -438.651396)
			)
		)
		(stroke
			(width 0)
			(type solid)
		)
		(fill yes)
		(layer "B.Cu")
		(net "GND")
	)
	(gr_poly
		(pts
			(arc
				(start 394.451332 -437.49976)
				(mid 394.247624 -437.49976)
				(end 394.451332 -437.49976)
			)
		)
		(stroke
			(width 0)
			(type solid)
		)
		(fill yes)
		(layer "B.Cu")
		(net "GND")
	)
	(gr_poly
		(pts
			(arc
				(start 394.451332 -436.347362)
				(mid 394.247624 -436.347362)
				(end 394.451332 -436.347362)
			)
		)
		(stroke
			(width 0)
			(type solid)
		)
		(fill yes)
		(layer "B.Cu")
		(net "GND")
	)
	(gr_poly
		(pts
			(arc
				(start 394.451332 -435.0512)
				(mid 394.247624 -435.0512)
				(end 394.451332 -435.0512)
			)
		)
		(stroke
			(width 0)
			(type solid)
		)
		(fill yes)
		(layer "B.Cu")
		(net "GND")
	)
	(gr_poly
		(pts
			(arc
				(start 394.451332 -433.899564)
				(mid 394.247624 -433.899564)
				(end 394.451332 -433.899564)
			)
		)
		(stroke
			(width 0)
			(type solid)
		)
		(fill yes)
		(layer "B.Cu")
		(net "GND")
	)
	(gr_poly
		(pts
			(arc
				(start 394.451332 -432.747166)
				(mid 394.247624 -432.747166)
				(end 394.451332 -432.747166)
			)
		)
		(stroke
			(width 0)
			(type solid)
		)
		(fill yes)
		(layer "B.Cu")
		(net "GND")
	)
	(gr_poly
		(pts
			(arc
				(start 394.451332 -431.451258)
				(mid 394.247624 -431.451258)
				(end 394.451332 -431.451258)
			)
		)
		(stroke
			(width 0)
			(type solid)
		)
		(fill yes)
		(layer "B.Cu")
		(net "GND")
	)
	(gr_poly
		(pts
			(arc
				(start 394.451332 -430.299622)
				(mid 394.247624 -430.299622)
				(end 394.451332 -430.299622)
			)
		)
		(stroke
			(width 0)
			(type solid)
		)
		(fill yes)
		(layer "B.Cu")
		(net "GND")
	)
	(gr_poly
		(pts
			(arc
				(start 394.451332 -429.147224)
				(mid 394.247624 -429.147224)
				(end 394.451332 -429.147224)
			)
		)
		(stroke
			(width 0)
			(type solid)
		)
		(fill yes)
		(layer "B.Cu")
		(net "GND")
	)
	(gr_poly
		(pts
			(arc
				(start 394.451332 -427.851316)
				(mid 394.247624 -427.851316)
				(end 394.451332 -427.851316)
			)
		)
		(stroke
			(width 0)
			(type solid)
		)
		(fill yes)
		(layer "B.Cu")
		(net "GND")
	)
	(gr_poly
		(pts
			(arc
				(start 394.451332 -426.69968)
				(mid 394.247624 -426.69968)
				(end 394.451332 -426.69968)
			)
		)
		(stroke
			(width 0)
			(type solid)
		)
		(fill yes)
		(layer "B.Cu")
		(net "GND")
	)
	(gr_poly
		(pts
			(arc
				(start 394.451332 -425.547282)
				(mid 394.247624 -425.547282)
				(end 394.451332 -425.547282)
			)
		)
		(stroke
			(width 0)
			(type solid)
		)
		(fill yes)
		(layer "B.Cu")
		(net "GND")
	)
	(gr_poly
		(pts
			(arc
				(start 396.451328 -439.651394)
				(mid 396.24762 -439.651394)
				(end 396.451328 -439.651394)
			)
		)
		(stroke
			(width 0)
			(type solid)
		)
		(fill yes)
		(layer "B.Cu")
		(net "GND")
	)
	(gr_poly
		(pts
			(arc
				(start 396.451328 -438.499758)
				(mid 396.24762 -438.499758)
				(end 396.451328 -438.499758)
			)
		)
		(stroke
			(width 0)
			(type solid)
		)
		(fill yes)
		(layer "B.Cu")
		(net "GND")
	)
	(gr_poly
		(pts
			(arc
				(start 396.451328 -437.34736)
				(mid 396.24762 -437.34736)
				(end 396.451328 -437.34736)
			)
		)
		(stroke
			(width 0)
			(type solid)
		)
		(fill yes)
		(layer "B.Cu")
		(net "GND")
	)
	(gr_poly
		(pts
			(arc
				(start 396.451328 -436.051198)
				(mid 396.24762 -436.051198)
				(end 396.451328 -436.051198)
			)
		)
		(stroke
			(width 0)
			(type solid)
		)
		(fill yes)
		(layer "B.Cu")
		(net "GND")
	)
	(gr_poly
		(pts
			(arc
				(start 396.451328 -434.899562)
				(mid 396.24762 -434.899562)
				(end 396.451328 -434.899562)
			)
		)
		(stroke
			(width 0)
			(type solid)
		)
		(fill yes)
		(layer "B.Cu")
		(net "GND")
	)
	(gr_poly
		(pts
			(arc
				(start 396.451328 -433.747164)
				(mid 396.24762 -433.747164)
				(end 396.451328 -433.747164)
			)
		)
		(stroke
			(width 0)
			(type solid)
		)
		(fill yes)
		(layer "B.Cu")
		(net "GND")
	)
	(gr_poly
		(pts
			(arc
				(start 396.451328 -432.451256)
				(mid 396.24762 -432.451256)
				(end 396.451328 -432.451256)
			)
		)
		(stroke
			(width 0)
			(type solid)
		)
		(fill yes)
		(layer "B.Cu")
		(net "GND")
	)
	(gr_poly
		(pts
			(arc
				(start 396.451328 -431.29962)
				(mid 396.24762 -431.29962)
				(end 396.451328 -431.29962)
			)
		)
		(stroke
			(width 0)
			(type solid)
		)
		(fill yes)
		(layer "B.Cu")
		(net "GND")
	)
	(gr_poly
		(pts
			(arc
				(start 396.451328 -430.147222)
				(mid 396.24762 -430.147222)
				(end 396.451328 -430.147222)
			)
		)
		(stroke
			(width 0)
			(type solid)
		)
		(fill yes)
		(layer "B.Cu")
		(net "GND")
	)
	(gr_poly
		(pts
			(arc
				(start 396.451328 -428.851314)
				(mid 396.24762 -428.851314)
				(end 396.451328 -428.851314)
			)
		)
		(stroke
			(width 0)
			(type solid)
		)
		(fill yes)
		(layer "B.Cu")
		(net "GND")
	)
	(gr_poly
		(pts
			(arc
				(start 396.451328 -427.699678)
				(mid 396.24762 -427.699678)
				(end 396.451328 -427.699678)
			)
		)
		(stroke
			(width 0)
			(type solid)
		)
		(fill yes)
		(layer "B.Cu")
		(net "GND")
	)
	(gr_poly
		(pts
			(arc
				(start 396.451328 -426.54728)
				(mid 396.24762 -426.54728)
				(end 396.451328 -426.54728)
			)
		)
		(stroke
			(width 0)
			(type solid)
		)
		(fill yes)
		(layer "B.Cu")
		(net "GND")
	)
	(gr_poly
		(pts
			(arc
				(start 399.451576 -438.651396)
				(mid 399.247868 -438.651396)
				(end 399.451576 -438.651396)
			)
		)
		(stroke
			(width 0)
			(type solid)
		)
		(fill yes)
		(layer "B.Cu")
		(net "GND")
	)
	(gr_poly
		(pts
			(arc
				(start 399.451576 -437.49976)
				(mid 399.247868 -437.49976)
				(end 399.451576 -437.49976)
			)
		)
		(stroke
			(width 0)
			(type solid)
		)
		(fill yes)
		(layer "B.Cu")
		(net "GND")
	)
	(gr_poly
		(pts
			(arc
				(start 399.451576 -436.347362)
				(mid 399.247868 -436.347362)
				(end 399.451576 -436.347362)
			)
		)
		(stroke
			(width 0)
			(type solid)
		)
		(fill yes)
		(layer "B.Cu")
		(net "GND")
	)
	(gr_poly
		(pts
			(arc
				(start 399.451576 -435.0512)
				(mid 399.247868 -435.0512)
				(end 399.451576 -435.0512)
			)
		)
		(stroke
			(width 0)
			(type solid)
		)
		(fill yes)
		(layer "B.Cu")
		(net "GND")
	)
	(gr_poly
		(pts
			(arc
				(start 399.451576 -433.899564)
				(mid 399.247868 -433.899564)
				(end 399.451576 -433.899564)
			)
		)
		(stroke
			(width 0)
			(type solid)
		)
		(fill yes)
		(layer "B.Cu")
		(net "GND")
	)
	(gr_poly
		(pts
			(arc
				(start 399.451576 -432.747166)
				(mid 399.247868 -432.747166)
				(end 399.451576 -432.747166)
			)
		)
		(stroke
			(width 0)
			(type solid)
		)
		(fill yes)
		(layer "B.Cu")
		(net "GND")
	)
	(gr_poly
		(pts
			(arc
				(start 399.451576 -431.451258)
				(mid 399.247868 -431.451258)
				(end 399.451576 -431.451258)
			)
		)
		(stroke
			(width 0)
			(type solid)
		)
		(fill yes)
		(layer "B.Cu")
		(net "GND")
	)
	(gr_poly
		(pts
			(arc
				(start 399.451576 -430.299622)
				(mid 399.247868 -430.299622)
				(end 399.451576 -430.299622)
			)
		)
		(stroke
			(width 0)
			(type solid)
		)
		(fill yes)
		(layer "B.Cu")
		(net "GND")
	)
	(gr_poly
		(pts
			(arc
				(start 399.451576 -429.147224)
				(mid 399.247868 -429.147224)
				(end 399.451576 -429.147224)
			)
		)
		(stroke
			(width 0)
			(type solid)
		)
		(fill yes)
		(layer "B.Cu")
		(net "GND")
	)
	(gr_poly
		(pts
			(arc
				(start 399.451576 -427.851316)
				(mid 399.247868 -427.851316)
				(end 399.451576 -427.851316)
			)
		)
		(stroke
			(width 0)
			(type solid)
		)
		(fill yes)
		(layer "B.Cu")
		(net "GND")
	)
	(gr_poly
		(pts
			(arc
				(start 399.451576 -426.69968)
				(mid 399.247868 -426.69968)
				(end 399.451576 -426.69968)
			)
		)
		(stroke
			(width 0)
			(type solid)
		)
		(fill yes)
		(layer "B.Cu")
		(net "GND")
	)
	(gr_poly
		(pts
			(arc
				(start 399.451576 -425.547282)
				(mid 399.247868 -425.547282)
				(end 399.451576 -425.547282)
			)
		)
		(stroke
			(width 0)
			(type solid)
		)
		(fill yes)
		(layer "B.Cu")
		(net "GND")
	)
	(gr_poly
		(pts
			(arc
				(start 401.451572 -439.651394)
				(mid 401.247864 -439.651394)
				(end 401.451572 -439.651394)
			)
		)
		(stroke
			(width 0)
			(type solid)
		)
		(fill yes)
		(layer "B.Cu")
		(net "GND")
	)
	(gr_poly
		(pts
			(arc
				(start 401.451572 -438.499758)
				(mid 401.247864 -438.499758)
				(end 401.451572 -438.499758)
			)
		)
		(stroke
			(width 0)
			(type solid)
		)
		(fill yes)
		(layer "B.Cu")
		(net "GND")
	)
	(gr_poly
		(pts
			(arc
				(start 401.451572 -437.34736)
				(mid 401.247864 -437.34736)
				(end 401.451572 -437.34736)
			)
		)
		(stroke
			(width 0)
			(type solid)
		)
		(fill yes)
		(layer "B.Cu")
		(net "GND")
	)
	(gr_poly
		(pts
			(arc
				(start 401.451572 -436.051198)
				(mid 401.247864 -436.051198)
				(end 401.451572 -436.051198)
			)
		)
		(stroke
			(width 0)
			(type solid)
		)
		(fill yes)
		(layer "B.Cu")
		(net "GND")
	)
	(gr_poly
		(pts
			(arc
				(start 401.451572 -434.899562)
				(mid 401.247864 -434.899562)
				(end 401.451572 -434.899562)
			)
		)
		(stroke
			(width 0)
			(type solid)
		)
		(fill yes)
		(layer "B.Cu")
		(net "GND")
	)
	(gr_poly
		(pts
			(arc
				(start 401.451572 -433.747164)
				(mid 401.247864 -433.747164)
				(end 401.451572 -433.747164)
			)
		)
		(stroke
			(width 0)
			(type solid)
		)
		(fill yes)
		(layer "B.Cu")
		(net "GND")
	)
	(gr_poly
		(pts
			(arc
				(start 401.451572 -432.451256)
				(mid 401.247864 -432.451256)
				(end 401.451572 -432.451256)
			)
		)
		(stroke
			(width 0)
			(type solid)
		)
		(fill yes)
		(layer "B.Cu")
		(net "GND")
	)
	(gr_poly
		(pts
			(arc
				(start 401.451572 -431.29962)
				(mid 401.247864 -431.29962)
				(end 401.451572 -431.29962)
			)
		)
		(stroke
			(width 0)
			(type solid)
		)
		(fill yes)
		(layer "B.Cu")
		(net "GND")
	)
	(gr_poly
		(pts
			(arc
				(start 401.451572 -430.147222)
				(mid 401.247864 -430.147222)
				(end 401.451572 -430.147222)
			)
		)
		(stroke
			(width 0)
			(type solid)
		)
		(fill yes)
		(layer "B.Cu")
		(net "GND")
	)
	(gr_poly
		(pts
			(arc
				(start 401.451572 -428.851314)
				(mid 401.247864 -428.851314)
				(end 401.451572 -428.851314)
			)
		)
		(stroke
			(width 0)
			(type solid)
		)
		(fill yes)
		(layer "B.Cu")
		(net "GND")
	)
	(gr_poly
		(pts
			(arc
				(start 401.451572 -427.699678)
				(mid 401.247864 -427.699678)
				(end 401.451572 -427.699678)
			)
		)
		(stroke
			(width 0)
			(type solid)
		)
		(fill yes)
		(layer "B.Cu")
		(net "GND")
	)
	(gr_poly
		(pts
			(arc
				(start 401.451572 -426.54728)
				(mid 401.247864 -426.54728)
				(end 401.451572 -426.54728)
			)
		)
		(stroke
			(width 0)
			(type solid)
		)
		(fill yes)
		(layer "B.Cu")
		(net "GND")
	)
	(gr_poly
		(pts
			(arc
				(start 403.451568 -438.651396)
				(mid 403.24786 -438.651396)
				(end 403.451568 -438.651396)
			)
		)
		(stroke
			(width 0)
			(type solid)
		)
		(fill yes)
		(layer "B.Cu")
		(net "GND")
	)
	(gr_poly
		(pts
			(arc
				(start 403.451568 -437.49976)
				(mid 403.24786 -437.49976)
				(end 403.451568 -437.49976)
			)
		)
		(stroke
			(width 0)
			(type solid)
		)
		(fill yes)
		(layer "B.Cu")
		(net "GND")
	)
	(gr_poly
		(pts
			(arc
				(start 403.451568 -436.347362)
				(mid 403.24786 -436.347362)
				(end 403.451568 -436.347362)
			)
		)
		(stroke
			(width 0)
			(type solid)
		)
		(fill yes)
		(layer "B.Cu")
		(net "GND")
	)
	(gr_poly
		(pts
			(arc
				(start 403.451568 -435.0512)
				(mid 403.24786 -435.0512)
				(end 403.451568 -435.0512)
			)
		)
		(stroke
			(width 0)
			(type solid)
		)
		(fill yes)
		(layer "B.Cu")
		(net "GND")
	)
	(gr_poly
		(pts
			(arc
				(start 403.451568 -433.899564)
				(mid 403.24786 -433.899564)
				(end 403.451568 -433.899564)
			)
		)
		(stroke
			(width 0)
			(type solid)
		)
		(fill yes)
		(layer "B.Cu")
		(net "GND")
	)
	(gr_poly
		(pts
			(arc
				(start 403.451568 -432.747166)
				(mid 403.24786 -432.747166)
				(end 403.451568 -432.747166)
			)
		)
		(stroke
			(width 0)
			(type solid)
		)
		(fill yes)
		(layer "B.Cu")
		(net "GND")
	)
	(gr_poly
		(pts
			(arc
				(start 403.451568 -431.451258)
				(mid 403.24786 -431.451258)
				(end 403.451568 -431.451258)
			)
		)
		(stroke
			(width 0)
			(type solid)
		)
		(fill yes)
		(layer "B.Cu")
		(net "GND")
	)
	(gr_poly
		(pts
			(arc
				(start 403.451568 -430.299622)
				(mid 403.24786 -430.299622)
				(end 403.451568 -430.299622)
			)
		)
		(stroke
			(width 0)
			(type solid)
		)
		(fill yes)
		(layer "B.Cu")
		(net "GND")
	)
	(gr_poly
		(pts
			(arc
				(start 403.451568 -429.147224)
				(mid 403.24786 -429.147224)
				(end 403.451568 -429.147224)
			)
		)
		(stroke
			(width 0)
			(type solid)
		)
		(fill yes)
		(layer "B.Cu")
		(net "GND")
	)
	(gr_poly
		(pts
			(arc
				(start 403.451568 -427.851316)
				(mid 403.24786 -427.851316)
				(end 403.451568 -427.851316)
			)
		)
		(stroke
			(width 0)
			(type solid)
		)
		(fill yes)
		(layer "B.Cu")
		(net "GND")
	)
	(gr_poly
		(pts
			(arc
				(start 403.451568 -426.69968)
				(mid 403.24786 -426.69968)
				(end 403.451568 -426.69968)
			)
		)
		(stroke
			(width 0)
			(type solid)
		)
		(fill yes)
		(layer "B.Cu")
		(net "GND")
	)
	(gr_poly
		(pts
			(arc
				(start 403.451568 -425.547282)
				(mid 403.24786 -425.547282)
				(end 403.451568 -425.547282)
			)
		)
		(stroke
			(width 0)
			(type solid)
		)
		(fill yes)
		(layer "B.Cu")
		(net "GND")
	)
	(gr_poly
		(pts
			(arc
				(start 405.451564 -439.651394)
				(mid 405.247856 -439.651394)
				(end 405.451564 -439.651394)
			)
		)
		(stroke
			(width 0)
			(type solid)
		)
		(fill yes)
		(layer "B.Cu")
		(net "GND")
	)
	(gr_poly
		(pts
			(arc
				(start 405.451564 -438.499758)
				(mid 405.247856 -438.499758)
				(end 405.451564 -438.499758)
			)
		)
		(stroke
			(width 0)
			(type solid)
		)
		(fill yes)
		(layer "B.Cu")
		(net "GND")
	)
	(gr_poly
		(pts
			(arc
				(start 405.451564 -437.34736)
				(mid 405.247856 -437.34736)
				(end 405.451564 -437.34736)
			)
		)
		(stroke
			(width 0)
			(type solid)
		)
		(fill yes)
		(layer "B.Cu")
		(net "GND")
	)
	(gr_poly
		(pts
			(arc
				(start 405.451564 -436.051198)
				(mid 405.247856 -436.051198)
				(end 405.451564 -436.051198)
			)
		)
		(stroke
			(width 0)
			(type solid)
		)
		(fill yes)
		(layer "B.Cu")
		(net "GND")
	)
	(gr_poly
		(pts
			(arc
				(start 405.451564 -434.899562)
				(mid 405.247856 -434.899562)
				(end 405.451564 -434.899562)
			)
		)
		(stroke
			(width 0)
			(type solid)
		)
		(fill yes)
		(layer "B.Cu")
		(net "GND")
	)
	(gr_poly
		(pts
			(arc
				(start 405.451564 -433.747164)
				(mid 405.247856 -433.747164)
				(end 405.451564 -433.747164)
			)
		)
		(stroke
			(width 0)
			(type solid)
		)
		(fill yes)
		(layer "B.Cu")
		(net "GND")
	)
	(gr_poly
		(pts
			(arc
				(start 405.451564 -432.451256)
				(mid 405.247856 -432.451256)
				(end 405.451564 -432.451256)
			)
		)
		(stroke
			(width 0)
			(type solid)
		)
		(fill yes)
		(layer "B.Cu")
		(net "GND")
	)
	(gr_poly
		(pts
			(arc
				(start 405.451564 -431.29962)
				(mid 405.247856 -431.29962)
				(end 405.451564 -431.29962)
			)
		)
		(stroke
			(width 0)
			(type solid)
		)
		(fill yes)
		(layer "B.Cu")
		(net "GND")
	)
	(gr_poly
		(pts
			(arc
				(start 405.451564 -430.147222)
				(mid 405.247856 -430.147222)
				(end 405.451564 -430.147222)
			)
		)
		(stroke
			(width 0)
			(type solid)
		)
		(fill yes)
		(layer "B.Cu")
		(net "GND")
	)
	(gr_poly
		(pts
			(arc
				(start 405.451564 -428.851314)
				(mid 405.247856 -428.851314)
				(end 405.451564 -428.851314)
			)
		)
		(stroke
			(width 0)
			(type solid)
		)
		(fill yes)
		(layer "B.Cu")
		(net "GND")
	)
	(gr_poly
		(pts
			(arc
				(start 405.451564 -427.699678)
				(mid 405.247856 -427.699678)
				(end 405.451564 -427.699678)
			)
		)
		(stroke
			(width 0)
			(type solid)
		)
		(fill yes)
		(layer "B.Cu")
		(net "GND")
	)
	(gr_poly
		(pts
			(arc
				(start 405.451564 -426.54728)
				(mid 405.247856 -426.54728)
				(end 405.451564 -426.54728)
			)
		)
		(stroke
			(width 0)
			(type solid)
		)
		(fill yes)
		(layer "B.Cu")
		(net "GND")
	)
	(gr_poly
		(pts
			(arc
				(start 407.45156 -438.651396)
				(mid 407.247852 -438.651396)
				(end 407.45156 -438.651396)
			)
		)
		(stroke
			(width 0)
			(type solid)
		)
		(fill yes)
		(layer "B.Cu")
		(net "GND")
	)
	(gr_poly
		(pts
			(arc
				(start 407.45156 -437.49976)
				(mid 407.247852 -437.49976)
				(end 407.45156 -437.49976)
			)
		)
		(stroke
			(width 0)
			(type solid)
		)
		(fill yes)
		(layer "B.Cu")
		(net "GND")
	)
	(gr_poly
		(pts
			(arc
				(start 407.45156 -436.347362)
				(mid 407.247852 -436.347362)
				(end 407.45156 -436.347362)
			)
		)
		(stroke
			(width 0)
			(type solid)
		)
		(fill yes)
		(layer "B.Cu")
		(net "GND")
	)
	(gr_poly
		(pts
			(arc
				(start 407.45156 -435.0512)
				(mid 407.247852 -435.0512)
				(end 407.45156 -435.0512)
			)
		)
		(stroke
			(width 0)
			(type solid)
		)
		(fill yes)
		(layer "B.Cu")
		(net "GND")
	)
	(gr_poly
		(pts
			(arc
				(start 407.45156 -433.899564)
				(mid 407.247852 -433.899564)
				(end 407.45156 -433.899564)
			)
		)
		(stroke
			(width 0)
			(type solid)
		)
		(fill yes)
		(layer "B.Cu")
		(net "GND")
	)
	(gr_poly
		(pts
			(arc
				(start 407.45156 -432.747166)
				(mid 407.247852 -432.747166)
				(end 407.45156 -432.747166)
			)
		)
		(stroke
			(width 0)
			(type solid)
		)
		(fill yes)
		(layer "B.Cu")
		(net "GND")
	)
	(gr_poly
		(pts
			(arc
				(start 407.45156 -431.451258)
				(mid 407.247852 -431.451258)
				(end 407.45156 -431.451258)
			)
		)
		(stroke
			(width 0)
			(type solid)
		)
		(fill yes)
		(layer "B.Cu")
		(net "GND")
	)
	(gr_poly
		(pts
			(arc
				(start 407.45156 -430.299622)
				(mid 407.247852 -430.299622)
				(end 407.45156 -430.299622)
			)
		)
		(stroke
			(width 0)
			(type solid)
		)
		(fill yes)
		(layer "B.Cu")
		(net "GND")
	)
	(gr_poly
		(pts
			(arc
				(start 407.45156 -429.147224)
				(mid 407.247852 -429.147224)
				(end 407.45156 -429.147224)
			)
		)
		(stroke
			(width 0)
			(type solid)
		)
		(fill yes)
		(layer "B.Cu")
		(net "GND")
	)
	(gr_poly
		(pts
			(arc
				(start 407.45156 -427.851316)
				(mid 407.247852 -427.851316)
				(end 407.45156 -427.851316)
			)
		)
		(stroke
			(width 0)
			(type solid)
		)
		(fill yes)
		(layer "B.Cu")
		(net "GND")
	)
	(gr_poly
		(pts
			(arc
				(start 407.45156 -426.69968)
				(mid 407.247852 -426.69968)
				(end 407.45156 -426.69968)
			)
		)
		(stroke
			(width 0)
			(type solid)
		)
		(fill yes)
		(layer "B.Cu")
		(net "GND")
	)
	(gr_poly
		(pts
			(arc
				(start 407.45156 -425.547282)
				(mid 407.247852 -425.547282)
				(end 407.45156 -425.547282)
			)
		)
		(stroke
			(width 0)
			(type solid)
		)
		(fill yes)
		(layer "B.Cu")
		(net "GND")
	)
	(gr_poly
		(pts
			(arc
				(start 409.451556 -439.651394)
				(mid 409.247848 -439.651394)
				(end 409.451556 -439.651394)
			)
		)
		(stroke
			(width 0)
			(type solid)
		)
		(fill yes)
		(layer "B.Cu")
		(net "GND")
	)
	(gr_poly
		(pts
			(arc
				(start 409.451556 -438.499758)
				(mid 409.247848 -438.499758)
				(end 409.451556 -438.499758)
			)
		)
		(stroke
			(width 0)
			(type solid)
		)
		(fill yes)
		(layer "B.Cu")
		(net "GND")
	)
	(gr_poly
		(pts
			(arc
				(start 409.451556 -437.34736)
				(mid 409.247848 -437.34736)
				(end 409.451556 -437.34736)
			)
		)
		(stroke
			(width 0)
			(type solid)
		)
		(fill yes)
		(layer "B.Cu")
		(net "GND")
	)
	(gr_poly
		(pts
			(arc
				(start 409.451556 -436.051198)
				(mid 409.247848 -436.051198)
				(end 409.451556 -436.051198)
			)
		)
		(stroke
			(width 0)
			(type solid)
		)
		(fill yes)
		(layer "B.Cu")
		(net "GND")
	)
	(gr_poly
		(pts
			(arc
				(start 409.451556 -434.899562)
				(mid 409.247848 -434.899562)
				(end 409.451556 -434.899562)
			)
		)
		(stroke
			(width 0)
			(type solid)
		)
		(fill yes)
		(layer "B.Cu")
		(net "GND")
	)
	(gr_poly
		(pts
			(arc
				(start 409.451556 -433.747164)
				(mid 409.247848 -433.747164)
				(end 409.451556 -433.747164)
			)
		)
		(stroke
			(width 0)
			(type solid)
		)
		(fill yes)
		(layer "B.Cu")
		(net "GND")
	)
	(gr_poly
		(pts
			(arc
				(start 409.451556 -432.451256)
				(mid 409.247848 -432.451256)
				(end 409.451556 -432.451256)
			)
		)
		(stroke
			(width 0)
			(type solid)
		)
		(fill yes)
		(layer "B.Cu")
		(net "GND")
	)
	(gr_poly
		(pts
			(arc
				(start 409.451556 -431.29962)
				(mid 409.247848 -431.29962)
				(end 409.451556 -431.29962)
			)
		)
		(stroke
			(width 0)
			(type solid)
		)
		(fill yes)
		(layer "B.Cu")
		(net "GND")
	)
	(gr_poly
		(pts
			(arc
				(start 409.451556 -430.147222)
				(mid 409.247848 -430.147222)
				(end 409.451556 -430.147222)
			)
		)
		(stroke
			(width 0)
			(type solid)
		)
		(fill yes)
		(layer "B.Cu")
		(net "GND")
	)
	(gr_poly
		(pts
			(arc
				(start 409.451556 -428.851314)
				(mid 409.247848 -428.851314)
				(end 409.451556 -428.851314)
			)
		)
		(stroke
			(width 0)
			(type solid)
		)
		(fill yes)
		(layer "B.Cu")
		(net "GND")
	)
	(gr_poly
		(pts
			(arc
				(start 409.451556 -427.699678)
				(mid 409.247848 -427.699678)
				(end 409.451556 -427.699678)
			)
		)
		(stroke
			(width 0)
			(type solid)
		)
		(fill yes)
		(layer "B.Cu")
		(net "GND")
	)
	(gr_poly
		(pts
			(arc
				(start 409.451556 -426.54728)
				(mid 409.247848 -426.54728)
				(end 409.451556 -426.54728)
			)
		)
		(stroke
			(width 0)
			(type solid)
		)
		(fill yes)
		(layer "B.Cu")
		(net "GND")
	)
	(gr_poly
		(pts
			(arc
				(start 411.451552 -438.651396)
				(mid 411.247844 -438.651396)
				(end 411.451552 -438.651396)
			)
		)
		(stroke
			(width 0)
			(type solid)
		)
		(fill yes)
		(layer "B.Cu")
		(net "GND")
	)
	(gr_poly
		(pts
			(arc
				(start 411.451552 -437.49976)
				(mid 411.247844 -437.49976)
				(end 411.451552 -437.49976)
			)
		)
		(stroke
			(width 0)
			(type solid)
		)
		(fill yes)
		(layer "B.Cu")
		(net "GND")
	)
	(gr_poly
		(pts
			(arc
				(start 411.451552 -436.347362)
				(mid 411.247844 -436.347362)
				(end 411.451552 -436.347362)
			)
		)
		(stroke
			(width 0)
			(type solid)
		)
		(fill yes)
		(layer "B.Cu")
		(net "GND")
	)
	(gr_poly
		(pts
			(arc
				(start 411.451552 -435.0512)
				(mid 411.247844 -435.0512)
				(end 411.451552 -435.0512)
			)
		)
		(stroke
			(width 0)
			(type solid)
		)
		(fill yes)
		(layer "B.Cu")
		(net "GND")
	)
	(gr_poly
		(pts
			(arc
				(start 411.451552 -433.899564)
				(mid 411.247844 -433.899564)
				(end 411.451552 -433.899564)
			)
		)
		(stroke
			(width 0)
			(type solid)
		)
		(fill yes)
		(layer "B.Cu")
		(net "GND")
	)
	(gr_poly
		(pts
			(arc
				(start 411.451552 -432.747166)
				(mid 411.247844 -432.747166)
				(end 411.451552 -432.747166)
			)
		)
		(stroke
			(width 0)
			(type solid)
		)
		(fill yes)
		(layer "B.Cu")
		(net "GND")
	)
	(gr_poly
		(pts
			(arc
				(start 411.451552 -431.451258)
				(mid 411.247844 -431.451258)
				(end 411.451552 -431.451258)
			)
		)
		(stroke
			(width 0)
			(type solid)
		)
		(fill yes)
		(layer "B.Cu")
		(net "GND")
	)
	(gr_poly
		(pts
			(arc
				(start 411.451552 -430.299622)
				(mid 411.247844 -430.299622)
				(end 411.451552 -430.299622)
			)
		)
		(stroke
			(width 0)
			(type solid)
		)
		(fill yes)
		(layer "B.Cu")
		(net "GND")
	)
	(gr_poly
		(pts
			(arc
				(start 411.451552 -429.147224)
				(mid 411.247844 -429.147224)
				(end 411.451552 -429.147224)
			)
		)
		(stroke
			(width 0)
			(type solid)
		)
		(fill yes)
		(layer "B.Cu")
		(net "GND")
	)
	(gr_poly
		(pts
			(arc
				(start 411.451552 -427.851316)
				(mid 411.247844 -427.851316)
				(end 411.451552 -427.851316)
			)
		)
		(stroke
			(width 0)
			(type solid)
		)
		(fill yes)
		(layer "B.Cu")
		(net "GND")
	)
	(gr_poly
		(pts
			(arc
				(start 411.451552 -426.69968)
				(mid 411.247844 -426.69968)
				(end 411.451552 -426.69968)
			)
		)
		(stroke
			(width 0)
			(type solid)
		)
		(fill yes)
		(layer "B.Cu")
		(net "GND")
	)
	(gr_poly
		(pts
			(arc
				(start 411.451552 -425.547282)
				(mid 411.247844 -425.547282)
				(end 411.451552 -425.547282)
			)
		)
		(stroke
			(width 0)
			(type solid)
		)
		(fill yes)
		(layer "B.Cu")
		(net "GND")
	)
	(gr_poly
		(pts
			(arc
				(start 413.451548 -439.651394)
				(mid 413.24784 -439.651394)
				(end 413.451548 -439.651394)
			)
		)
		(stroke
			(width 0)
			(type solid)
		)
		(fill yes)
		(layer "B.Cu")
		(net "GND")
	)
	(gr_poly
		(pts
			(arc
				(start 413.451548 -438.499758)
				(mid 413.24784 -438.499758)
				(end 413.451548 -438.499758)
			)
		)
		(stroke
			(width 0)
			(type solid)
		)
		(fill yes)
		(layer "B.Cu")
		(net "GND")
	)
	(gr_poly
		(pts
			(arc
				(start 413.451548 -437.34736)
				(mid 413.24784 -437.34736)
				(end 413.451548 -437.34736)
			)
		)
		(stroke
			(width 0)
			(type solid)
		)
		(fill yes)
		(layer "B.Cu")
		(net "GND")
	)
	(gr_poly
		(pts
			(arc
				(start 413.451548 -436.051198)
				(mid 413.24784 -436.051198)
				(end 413.451548 -436.051198)
			)
		)
		(stroke
			(width 0)
			(type solid)
		)
		(fill yes)
		(layer "B.Cu")
		(net "GND")
	)
	(gr_poly
		(pts
			(arc
				(start 413.451548 -434.899562)
				(mid 413.24784 -434.899562)
				(end 413.451548 -434.899562)
			)
		)
		(stroke
			(width 0)
			(type solid)
		)
		(fill yes)
		(layer "B.Cu")
		(net "GND")
	)
	(gr_poly
		(pts
			(arc
				(start 413.451548 -433.747164)
				(mid 413.24784 -433.747164)
				(end 413.451548 -433.747164)
			)
		)
		(stroke
			(width 0)
			(type solid)
		)
		(fill yes)
		(layer "B.Cu")
		(net "GND")
	)
	(gr_poly
		(pts
			(arc
				(start 413.451548 -432.451256)
				(mid 413.24784 -432.451256)
				(end 413.451548 -432.451256)
			)
		)
		(stroke
			(width 0)
			(type solid)
		)
		(fill yes)
		(layer "B.Cu")
		(net "GND")
	)
	(gr_poly
		(pts
			(arc
				(start 413.451548 -431.29962)
				(mid 413.24784 -431.29962)
				(end 413.451548 -431.29962)
			)
		)
		(stroke
			(width 0)
			(type solid)
		)
		(fill yes)
		(layer "B.Cu")
		(net "GND")
	)
	(gr_poly
		(pts
			(arc
				(start 413.451548 -430.147222)
				(mid 413.24784 -430.147222)
				(end 413.451548 -430.147222)
			)
		)
		(stroke
			(width 0)
			(type solid)
		)
		(fill yes)
		(layer "B.Cu")
		(net "GND")
	)
	(gr_poly
		(pts
			(arc
				(start 413.451548 -428.851314)
				(mid 413.24784 -428.851314)
				(end 413.451548 -428.851314)
			)
		)
		(stroke
			(width 0)
			(type solid)
		)
		(fill yes)
		(layer "B.Cu")
		(net "GND")
	)
	(gr_poly
		(pts
			(arc
				(start 413.451548 -427.699678)
				(mid 413.24784 -427.699678)
				(end 413.451548 -427.699678)
			)
		)
		(stroke
			(width 0)
			(type solid)
		)
		(fill yes)
		(layer "B.Cu")
		(net "GND")
	)
	(gr_poly
		(pts
			(arc
				(start 413.451548 -426.54728)
				(mid 413.24784 -426.54728)
				(end 413.451548 -426.54728)
			)
		)
		(stroke
			(width 0)
			(type solid)
		)
		(fill yes)
		(layer "B.Cu")
		(net "GND")
	)
	(gr_poly
		(pts
			(arc
				(start 47.921418 -393.902438)
				(mid 47.711614 -393.902438)
				(end 47.921418 -393.902438)
			)
		)
		(stroke
			(width 0)
			(type solid)
		)
		(fill yes)
		(layer "B.Cu")
		(net "GND")
	)
	(gr_poly
		(pts
			(arc
				(start 49.121314 -393.902438)
				(mid 48.91151 -393.902438)
				(end 49.121314 -393.902438)
			)
		)
		(stroke
			(width 0)
			(type solid)
		)
		(fill yes)
		(layer "B.Cu")
		(net "GND")
	)
	(gr_poly
		(pts
			(arc
				(start 50.321464 -393.927838)
				(mid 50.11166 -393.927838)
				(end 50.321464 -393.927838)
			)
		)
		(stroke
			(width 0)
			(type solid)
		)
		(fill yes)
		(layer "B.Cu")
		(net "GND")
	)
	(gr_poly
		(pts
			(arc
				(start 51.52136 -393.877038)
				(mid 51.311556 -393.877038)
				(end 51.52136 -393.877038)
			)
		)
		(stroke
			(width 0)
			(type solid)
		)
		(fill yes)
		(layer "B.Cu")
		(net "GND")
	)
	(gr_poly
		(pts
			(arc
				(start 52.72151 -393.927838)
				(mid 52.511706 -393.927838)
				(end 52.72151 -393.927838)
			)
		)
		(stroke
			(width 0)
			(type solid)
		)
		(fill yes)
		(layer "B.Cu")
		(net "GND")
	)
	(gr_poly
		(pts
			(arc
				(start 53.921406 -393.927838)
				(mid 53.711602 -393.927838)
				(end 53.921406 -393.927838)
			)
		)
		(stroke
			(width 0)
			(type solid)
		)
		(fill yes)
		(layer "B.Cu")
		(net "GND")
	)
	(gr_poly
		(pts
			(arc
				(start 55.121556 -393.877038)
				(mid 54.911752 -393.877038)
				(end 55.121556 -393.877038)
			)
		)
		(stroke
			(width 0)
			(type solid)
		)
		(fill yes)
		(layer "B.Cu")
		(net "GND")
	)
	(gr_poly
		(pts
			(arc
				(start 56.321452 -393.902438)
				(mid 56.111648 -393.902438)
				(end 56.321452 -393.902438)
			)
		)
		(stroke
			(width 0)
			(type solid)
		)
		(fill yes)
		(layer "B.Cu")
		(net "GND")
	)
	(gr_poly
		(pts
			(arc
				(start 57.521602 -393.927838)
				(mid 57.311798 -393.927838)
				(end 57.521602 -393.927838)
			)
		)
		(stroke
			(width 0)
			(type solid)
		)
		(fill yes)
		(layer "B.Cu")
		(net "GND")
	)
	(gr_poly
		(pts
			(arc
				(start 58.721498 -393.927838)
				(mid 58.511694 -393.927838)
				(end 58.721498 -393.927838)
			)
		)
		(stroke
			(width 0)
			(type solid)
		)
		(fill yes)
		(layer "B.Cu")
		(net "GND")
	)
	(gr_poly
		(pts
			(arc
				(start 59.921648 -393.927838)
				(mid 59.711844 -393.927838)
				(end 59.921648 -393.927838)
			)
		)
		(stroke
			(width 0)
			(type solid)
		)
		(fill yes)
		(layer "B.Cu")
		(net "GND")
	)
	(gr_poly
		(pts
			(arc
				(start 61.121544 -393.927838)
				(mid 60.91174 -393.927838)
				(end 61.121544 -393.927838)
			)
		)
		(stroke
			(width 0)
			(type solid)
		)
		(fill yes)
		(layer "B.Cu")
		(net "GND")
	)
	(gr_poly
		(pts
			(arc
				(start 62.32144 -393.877038)
				(mid 62.111636 -393.877038)
				(end 62.32144 -393.877038)
			)
		)
		(stroke
			(width 0)
			(type solid)
		)
		(fill yes)
		(layer "B.Cu")
		(net "GND")
	)
	(gr_poly
		(pts
			(arc
				(start 63.521336 -393.927838)
				(mid 63.311532 -393.927838)
				(end 63.521336 -393.927838)
			)
		)
		(stroke
			(width 0)
			(type solid)
		)
		(fill yes)
		(layer "B.Cu")
		(net "GND")
	)
	(gr_poly
		(pts
			(arc
				(start 64.721486 -393.927838)
				(mid 64.511682 -393.927838)
				(end 64.721486 -393.927838)
			)
		)
		(stroke
			(width 0)
			(type solid)
		)
		(fill yes)
		(layer "B.Cu")
		(net "GND")
	)
	(gr_poly
		(pts
			(arc
				(start 65.921382 -393.902438)
				(mid 65.711578 -393.902438)
				(end 65.921382 -393.902438)
			)
		)
		(stroke
			(width 0)
			(type solid)
		)
		(fill yes)
		(layer "B.Cu")
		(net "GND")
	)
	(gr_poly
		(pts
			(arc
				(start 80.449166 -393.902438)
				(mid 80.239362 -393.902438)
				(end 80.449166 -393.902438)
			)
		)
		(stroke
			(width 0)
			(type solid)
		)
		(fill yes)
		(layer "B.Cu")
		(net "GND")
	)
	(gr_poly
		(pts
			(xy 81.193894 -9.24306)
			(arc
				(start 81.193894 -3.638804)
				(mid 81.182847 -3.607429)
				(end 81.154778 -3.589528)
			)
			(xy 81.041494 -3.56235) (xy 81.00949 -3.577336)
			(arc
				(start 81.001616 -3.593084)
				(mid 80.87562 -3.782127)
				(end 80.707992 -3.935476)
			)
			(arc
				(start 80.707992 -3.935476)
				(mid 80.692292 -3.953586)
				(end 80.686656 -3.976878)
			)
			(arc
				(start 80.686656 -9.050274)
				(mid 80.690557 -9.069797)
				(end 80.701642 -9.086342)
			)
			(xy 80.920336 -9.30529) (xy 81.131664 -9.30529)
		)
		(stroke
			(width 0)
			(type solid)
		)
		(fill yes)
		(layer "B.Cu")
		(net "GND")
	)
	(gr_poly
		(pts
			(arc
				(start 81.649062 -393.902438)
				(mid 81.439258 -393.902438)
				(end 81.649062 -393.902438)
			)
		)
		(stroke
			(width 0)
			(type solid)
		)
		(fill yes)
		(layer "B.Cu")
		(net "GND")
	)
	(gr_poly
		(pts
			(arc
				(start 82.849212 -393.927838)
				(mid 82.639408 -393.927838)
				(end 82.849212 -393.927838)
			)
		)
		(stroke
			(width 0)
			(type solid)
		)
		(fill yes)
		(layer "B.Cu")
		(net "GND")
	)
	(gr_poly
		(pts
			(arc
				(start 84.049108 -393.877038)
				(mid 83.839304 -393.877038)
				(end 84.049108 -393.877038)
			)
		)
		(stroke
			(width 0)
			(type solid)
		)
		(fill yes)
		(layer "B.Cu")
		(net "GND")
	)
	(gr_poly
		(pts
			(arc
				(start 85.249258 -393.927838)
				(mid 85.039454 -393.927838)
				(end 85.249258 -393.927838)
			)
		)
		(stroke
			(width 0)
			(type solid)
		)
		(fill yes)
		(layer "B.Cu")
		(net "GND")
	)
	(gr_poly
		(pts
			(arc
				(start 86.449154 -393.927838)
				(mid 86.23935 -393.927838)
				(end 86.449154 -393.927838)
			)
		)
		(stroke
			(width 0)
			(type solid)
		)
		(fill yes)
		(layer "B.Cu")
		(net "GND")
	)
	(gr_poly
		(pts
			(arc
				(start 87.649304 -393.877038)
				(mid 87.4395 -393.877038)
				(end 87.649304 -393.877038)
			)
		)
		(stroke
			(width 0)
			(type solid)
		)
		(fill yes)
		(layer "B.Cu")
		(net "GND")
	)
	(gr_poly
		(pts
			(arc
				(start 88.8492 -393.902438)
				(mid 88.639396 -393.902438)
				(end 88.8492 -393.902438)
			)
		)
		(stroke
			(width 0)
			(type solid)
		)
		(fill yes)
		(layer "B.Cu")
		(net "GND")
	)
	(gr_poly
		(pts
			(arc
				(start 90.04935 -393.927838)
				(mid 89.839546 -393.927838)
				(end 90.04935 -393.927838)
			)
		)
		(stroke
			(width 0)
			(type solid)
		)
		(fill yes)
		(layer "B.Cu")
		(net "GND")
	)
	(gr_poly
		(pts
			(arc
				(start 91.249246 -393.927838)
				(mid 91.039442 -393.927838)
				(end 91.249246 -393.927838)
			)
		)
		(stroke
			(width 0)
			(type solid)
		)
		(fill yes)
		(layer "B.Cu")
		(net "GND")
	)
	(gr_poly
		(pts
			(arc
				(start 92.449396 -393.927838)
				(mid 92.239592 -393.927838)
				(end 92.449396 -393.927838)
			)
		)
		(stroke
			(width 0)
			(type solid)
		)
		(fill yes)
		(layer "B.Cu")
		(net "GND")
	)
	(gr_poly
		(pts
			(arc
				(start 93.649292 -393.927838)
				(mid 93.439488 -393.927838)
				(end 93.649292 -393.927838)
			)
		)
		(stroke
			(width 0)
			(type solid)
		)
		(fill yes)
		(layer "B.Cu")
		(net "GND")
	)
	(gr_poly
		(pts
			(arc
				(start 94.849188 -393.877038)
				(mid 94.639384 -393.877038)
				(end 94.849188 -393.877038)
			)
		)
		(stroke
			(width 0)
			(type solid)
		)
		(fill yes)
		(layer "B.Cu")
		(net "GND")
	)
	(gr_poly
		(pts
			(arc
				(start 96.049084 -393.927838)
				(mid 95.83928 -393.927838)
				(end 96.049084 -393.927838)
			)
		)
		(stroke
			(width 0)
			(type solid)
		)
		(fill yes)
		(layer "B.Cu")
		(net "GND")
	)
	(gr_poly
		(pts
			(arc
				(start 97.249234 -393.927838)
				(mid 97.03943 -393.927838)
				(end 97.249234 -393.927838)
			)
		)
		(stroke
			(width 0)
			(type solid)
		)
		(fill yes)
		(layer "B.Cu")
		(net "GND")
	)
	(gr_poly
		(pts
			(arc
				(start 98.44913 -393.902438)
				(mid 98.239326 -393.902438)
				(end 98.44913 -393.902438)
			)
		)
		(stroke
			(width 0)
			(type solid)
		)
		(fill yes)
		(layer "B.Cu")
		(net "GND")
	)
	(gr_poly
		(pts
			(arc
				(start 115.02136 -393.902438)
				(mid 114.811556 -393.902438)
				(end 115.02136 -393.902438)
			)
		)
		(stroke
			(width 0)
			(type solid)
		)
		(fill yes)
		(layer "B.Cu")
		(net "GND")
	)
	(gr_poly
		(pts
			(arc
				(start 116.221256 -393.902438)
				(mid 116.011452 -393.902438)
				(end 116.221256 -393.902438)
			)
		)
		(stroke
			(width 0)
			(type solid)
		)
		(fill yes)
		(layer "B.Cu")
		(net "GND")
	)
	(gr_poly
		(pts
			(arc
				(start 117.421406 -393.927838)
				(mid 117.211602 -393.927838)
				(end 117.421406 -393.927838)
			)
		)
		(stroke
			(width 0)
			(type solid)
		)
		(fill yes)
		(layer "B.Cu")
		(net "GND")
	)
	(gr_poly
		(pts
			(arc
				(start 118.621302 -393.877038)
				(mid 118.411498 -393.877038)
				(end 118.621302 -393.877038)
			)
		)
		(stroke
			(width 0)
			(type solid)
		)
		(fill yes)
		(layer "B.Cu")
		(net "GND")
	)
	(gr_poly
		(pts
			(arc
				(start 119.821452 -393.927838)
				(mid 119.611648 -393.927838)
				(end 119.821452 -393.927838)
			)
		)
		(stroke
			(width 0)
			(type solid)
		)
		(fill yes)
		(layer "B.Cu")
		(net "GND")
	)
	(gr_poly
		(pts
			(arc
				(start 121.021348 -393.927838)
				(mid 120.811544 -393.927838)
				(end 121.021348 -393.927838)
			)
		)
		(stroke
			(width 0)
			(type solid)
		)
		(fill yes)
		(layer "B.Cu")
		(net "GND")
	)
	(gr_poly
		(pts
			(arc
				(start 122.221498 -393.877038)
				(mid 122.011694 -393.877038)
				(end 122.221498 -393.877038)
			)
		)
		(stroke
			(width 0)
			(type solid)
		)
		(fill yes)
		(layer "B.Cu")
		(net "GND")
	)
	(gr_poly
		(pts
			(arc
				(start 123.421394 -393.902438)
				(mid 123.21159 -393.902438)
				(end 123.421394 -393.902438)
			)
		)
		(stroke
			(width 0)
			(type solid)
		)
		(fill yes)
		(layer "B.Cu")
		(net "GND")
	)
	(gr_poly
		(pts
			(arc
				(start 124.621544 -393.927838)
				(mid 124.41174 -393.927838)
				(end 124.621544 -393.927838)
			)
		)
		(stroke
			(width 0)
			(type solid)
		)
		(fill yes)
		(layer "B.Cu")
		(net "GND")
	)
	(gr_poly
		(pts
			(arc
				(start 125.82144 -393.927838)
				(mid 125.611636 -393.927838)
				(end 125.82144 -393.927838)
			)
		)
		(stroke
			(width 0)
			(type solid)
		)
		(fill yes)
		(layer "B.Cu")
		(net "GND")
	)
	(gr_poly
		(pts
			(arc
				(start 127.02159 -393.927838)
				(mid 126.811786 -393.927838)
				(end 127.02159 -393.927838)
			)
		)
		(stroke
			(width 0)
			(type solid)
		)
		(fill yes)
		(layer "B.Cu")
		(net "GND")
	)
	(gr_poly
		(pts
			(arc
				(start 128.221486 -393.927838)
				(mid 128.011682 -393.927838)
				(end 128.221486 -393.927838)
			)
		)
		(stroke
			(width 0)
			(type solid)
		)
		(fill yes)
		(layer "B.Cu")
		(net "GND")
	)
	(gr_poly
		(pts
			(arc
				(start 129.421382 -393.877038)
				(mid 129.211578 -393.877038)
				(end 129.421382 -393.877038)
			)
		)
		(stroke
			(width 0)
			(type solid)
		)
		(fill yes)
		(layer "B.Cu")
		(net "GND")
	)
	(gr_poly
		(pts
			(arc
				(start 130.621278 -393.927838)
				(mid 130.411474 -393.927838)
				(end 130.621278 -393.927838)
			)
		)
		(stroke
			(width 0)
			(type solid)
		)
		(fill yes)
		(layer "B.Cu")
		(net "GND")
	)
	(gr_poly
		(pts
			(arc
				(start 131.821428 -393.927838)
				(mid 131.611624 -393.927838)
				(end 131.821428 -393.927838)
			)
		)
		(stroke
			(width 0)
			(type solid)
		)
		(fill yes)
		(layer "B.Cu")
		(net "GND")
	)
	(gr_poly
		(pts
			(arc
				(start 133.021324 -393.902438)
				(mid 132.81152 -393.902438)
				(end 133.021324 -393.902438)
			)
		)
		(stroke
			(width 0)
			(type solid)
		)
		(fill yes)
		(layer "B.Cu")
		(net "GND")
	)
	(gr_poly
		(pts
			(arc
				(start 147.549108 -393.902438)
				(mid 147.339304 -393.902438)
				(end 147.549108 -393.902438)
			)
		)
		(stroke
			(width 0)
			(type solid)
		)
		(fill yes)
		(layer "B.Cu")
		(net "GND")
	)
	(gr_poly
		(pts
			(arc
				(start 148.749004 -393.902438)
				(mid 148.5392 -393.902438)
				(end 148.749004 -393.902438)
			)
		)
		(stroke
			(width 0)
			(type solid)
		)
		(fill yes)
		(layer "B.Cu")
		(net "GND")
	)
	(gr_poly
		(pts
			(arc
				(start 149.949154 -393.927838)
				(mid 149.73935 -393.927838)
				(end 149.949154 -393.927838)
			)
		)
		(stroke
			(width 0)
			(type solid)
		)
		(fill yes)
		(layer "B.Cu")
		(net "GND")
	)
	(gr_poly
		(pts
			(arc
				(start 151.14905 -393.877038)
				(mid 150.939246 -393.877038)
				(end 151.14905 -393.877038)
			)
		)
		(stroke
			(width 0)
			(type solid)
		)
		(fill yes)
		(layer "B.Cu")
		(net "GND")
	)
	(gr_poly
		(pts
			(arc
				(start 152.3492 -393.927838)
				(mid 152.139396 -393.927838)
				(end 152.3492 -393.927838)
			)
		)
		(stroke
			(width 0)
			(type solid)
		)
		(fill yes)
		(layer "B.Cu")
		(net "GND")
	)
	(gr_poly
		(pts
			(arc
				(start 153.549096 -393.927838)
				(mid 153.339292 -393.927838)
				(end 153.549096 -393.927838)
			)
		)
		(stroke
			(width 0)
			(type solid)
		)
		(fill yes)
		(layer "B.Cu")
		(net "GND")
	)
	(gr_poly
		(pts
			(arc
				(start 154.749246 -393.877038)
				(mid 154.539442 -393.877038)
				(end 154.749246 -393.877038)
			)
		)
		(stroke
			(width 0)
			(type solid)
		)
		(fill yes)
		(layer "B.Cu")
		(net "GND")
	)
	(gr_poly
		(pts
			(arc
				(start 155.949142 -393.902438)
				(mid 155.739338 -393.902438)
				(end 155.949142 -393.902438)
			)
		)
		(stroke
			(width 0)
			(type solid)
		)
		(fill yes)
		(layer "B.Cu")
		(net "GND")
	)
	(gr_poly
		(pts
			(arc
				(start 157.149292 -393.927838)
				(mid 156.939488 -393.927838)
				(end 157.149292 -393.927838)
			)
		)
		(stroke
			(width 0)
			(type solid)
		)
		(fill yes)
		(layer "B.Cu")
		(net "GND")
	)
	(gr_poly
		(pts
			(arc
				(start 158.349188 -393.927838)
				(mid 158.139384 -393.927838)
				(end 158.349188 -393.927838)
			)
		)
		(stroke
			(width 0)
			(type solid)
		)
		(fill yes)
		(layer "B.Cu")
		(net "GND")
	)
	(gr_poly
		(pts
			(arc
				(start 159.549338 -393.927838)
				(mid 159.339534 -393.927838)
				(end 159.549338 -393.927838)
			)
		)
		(stroke
			(width 0)
			(type solid)
		)
		(fill yes)
		(layer "B.Cu")
		(net "GND")
	)
	(gr_poly
		(pts
			(arc
				(start 160.749234 -393.927838)
				(mid 160.53943 -393.927838)
				(end 160.749234 -393.927838)
			)
		)
		(stroke
			(width 0)
			(type solid)
		)
		(fill yes)
		(layer "B.Cu")
		(net "GND")
	)
	(gr_poly
		(pts
			(arc
				(start 161.94913 -393.877038)
				(mid 161.739326 -393.877038)
				(end 161.94913 -393.877038)
			)
		)
		(stroke
			(width 0)
			(type solid)
		)
		(fill yes)
		(layer "B.Cu")
		(net "GND")
	)
	(gr_poly
		(pts
			(arc
				(start 163.149026 -393.927838)
				(mid 162.939222 -393.927838)
				(end 163.149026 -393.927838)
			)
		)
		(stroke
			(width 0)
			(type solid)
		)
		(fill yes)
		(layer "B.Cu")
		(net "GND")
	)
	(gr_poly
		(pts
			(arc
				(start 164.349176 -393.927838)
				(mid 164.139372 -393.927838)
				(end 164.349176 -393.927838)
			)
		)
		(stroke
			(width 0)
			(type solid)
		)
		(fill yes)
		(layer "B.Cu")
		(net "GND")
	)
	(gr_poly
		(pts
			(arc
				(start 165.549072 -393.902438)
				(mid 165.339268 -393.902438)
				(end 165.549072 -393.902438)
			)
		)
		(stroke
			(width 0)
			(type solid)
		)
		(fill yes)
		(layer "B.Cu")
		(net "GND")
	)
	(gr_poly
		(pts
			(arc
				(start 303.92116 -402.284438)
				(mid 303.711356 -402.284438)
				(end 303.92116 -402.284438)
			)
		)
		(stroke
			(width 0)
			(type solid)
		)
		(fill yes)
		(layer "B.Cu")
		(net "GND")
	)
	(gr_poly
		(pts
			(arc
				(start 305.121056 -402.284438)
				(mid 304.911252 -402.284438)
				(end 305.121056 -402.284438)
			)
		)
		(stroke
			(width 0)
			(type solid)
		)
		(fill yes)
		(layer "B.Cu")
		(net "GND")
	)
	(gr_poly
		(pts
			(arc
				(start 306.321206 -402.309838)
				(mid 306.111402 -402.309838)
				(end 306.321206 -402.309838)
			)
		)
		(stroke
			(width 0)
			(type solid)
		)
		(fill yes)
		(layer "B.Cu")
		(net "GND")
	)
	(gr_poly
		(pts
			(arc
				(start 319.521078 -402.309838)
				(mid 319.311274 -402.309838)
				(end 319.521078 -402.309838)
			)
		)
		(stroke
			(width 0)
			(type solid)
		)
		(fill yes)
		(layer "B.Cu")
		(net "GND")
	)
	(gr_poly
		(pts
			(arc
				(start 320.721228 -402.309838)
				(mid 320.511424 -402.309838)
				(end 320.721228 -402.309838)
			)
		)
		(stroke
			(width 0)
			(type solid)
		)
		(fill yes)
		(layer "B.Cu")
		(net "GND")
	)
	(gr_poly
		(pts
			(arc
				(start 321.921124 -402.284438)
				(mid 321.71132 -402.284438)
				(end 321.921124 -402.284438)
			)
		)
		(stroke
			(width 0)
			(type solid)
		)
		(fill yes)
		(layer "B.Cu")
		(net "GND")
	)
	(gr_poly
		(pts
			(arc
				(start 336.448908 -402.284438)
				(mid 336.239104 -402.284438)
				(end 336.448908 -402.284438)
			)
		)
		(stroke
			(width 0)
			(type solid)
		)
		(fill yes)
		(layer "B.Cu")
		(net "GND")
	)
	(gr_poly
		(pts
			(arc
				(start 337.648804 -402.284438)
				(mid 337.439 -402.284438)
				(end 337.648804 -402.284438)
			)
		)
		(stroke
			(width 0)
			(type solid)
		)
		(fill yes)
		(layer "B.Cu")
		(net "GND")
	)
	(gr_poly
		(pts
			(arc
				(start 338.848954 -402.309838)
				(mid 338.63915 -402.309838)
				(end 338.848954 -402.309838)
			)
		)
		(stroke
			(width 0)
			(type solid)
		)
		(fill yes)
		(layer "B.Cu")
		(net "GND")
	)
	(gr_poly
		(pts
			(arc
				(start 340.04885 -402.259038)
				(mid 339.839046 -402.259038)
				(end 340.04885 -402.259038)
			)
		)
		(stroke
			(width 0)
			(type solid)
		)
		(fill yes)
		(layer "B.Cu")
		(net "GND")
	)
	(gr_poly
		(pts
			(arc
				(start 341.249 -402.309838)
				(mid 341.039196 -402.309838)
				(end 341.249 -402.309838)
			)
		)
		(stroke
			(width 0)
			(type solid)
		)
		(fill yes)
		(layer "B.Cu")
		(net "GND")
	)
	(gr_poly
		(pts
			(arc
				(start 342.448896 -402.309838)
				(mid 342.239092 -402.309838)
				(end 342.448896 -402.309838)
			)
		)
		(stroke
			(width 0)
			(type solid)
		)
		(fill yes)
		(layer "B.Cu")
		(net "GND")
	)
	(gr_poly
		(pts
			(arc
				(start 343.649046 -402.259038)
				(mid 343.439242 -402.259038)
				(end 343.649046 -402.259038)
			)
		)
		(stroke
			(width 0)
			(type solid)
		)
		(fill yes)
		(layer "B.Cu")
		(net "GND")
	)
	(gr_poly
		(pts
			(arc
				(start 344.848942 -402.284438)
				(mid 344.639138 -402.284438)
				(end 344.848942 -402.284438)
			)
		)
		(stroke
			(width 0)
			(type solid)
		)
		(fill yes)
		(layer "B.Cu")
		(net "GND")
	)
	(gr_poly
		(pts
			(arc
				(start 346.049092 -402.309838)
				(mid 345.839288 -402.309838)
				(end 346.049092 -402.309838)
			)
		)
		(stroke
			(width 0)
			(type solid)
		)
		(fill yes)
		(layer "B.Cu")
		(net "GND")
	)
	(gr_poly
		(pts
			(arc
				(start 347.248988 -402.309838)
				(mid 347.039184 -402.309838)
				(end 347.248988 -402.309838)
			)
		)
		(stroke
			(width 0)
			(type solid)
		)
		(fill yes)
		(layer "B.Cu")
		(net "GND")
	)
	(gr_poly
		(pts
			(arc
				(start 348.449138 -402.309838)
				(mid 348.239334 -402.309838)
				(end 348.449138 -402.309838)
			)
		)
		(stroke
			(width 0)
			(type solid)
		)
		(fill yes)
		(layer "B.Cu")
		(net "GND")
	)
	(gr_poly
		(pts
			(arc
				(start 349.649034 -402.309838)
				(mid 349.43923 -402.309838)
				(end 349.649034 -402.309838)
			)
		)
		(stroke
			(width 0)
			(type solid)
		)
		(fill yes)
		(layer "B.Cu")
		(net "GND")
	)
	(gr_poly
		(pts
			(arc
				(start 350.84893 -402.259038)
				(mid 350.639126 -402.259038)
				(end 350.84893 -402.259038)
			)
		)
		(stroke
			(width 0)
			(type solid)
		)
		(fill yes)
		(layer "B.Cu")
		(net "GND")
	)
	(gr_poly
		(pts
			(arc
				(start 352.048826 -402.309838)
				(mid 351.839022 -402.309838)
				(end 352.048826 -402.309838)
			)
		)
		(stroke
			(width 0)
			(type solid)
		)
		(fill yes)
		(layer "B.Cu")
		(net "GND")
	)
	(gr_poly
		(pts
			(arc
				(start 353.248976 -402.309838)
				(mid 353.039172 -402.309838)
				(end 353.248976 -402.309838)
			)
		)
		(stroke
			(width 0)
			(type solid)
		)
		(fill yes)
		(layer "B.Cu")
		(net "GND")
	)
	(gr_poly
		(pts
			(arc
				(start 354.448872 -402.284438)
				(mid 354.239068 -402.284438)
				(end 354.448872 -402.284438)
			)
		)
		(stroke
			(width 0)
			(type solid)
		)
		(fill yes)
		(layer "B.Cu")
		(net "GND")
	)
	(gr_poly
		(pts
			(arc
				(start 371.021356 -402.284438)
				(mid 370.811552 -402.284438)
				(end 371.021356 -402.284438)
			)
		)
		(stroke
			(width 0)
			(type solid)
		)
		(fill yes)
		(layer "B.Cu")
		(net "GND")
	)
	(gr_poly
		(pts
			(arc
				(start 372.221252 -402.284438)
				(mid 372.011448 -402.284438)
				(end 372.221252 -402.284438)
			)
		)
		(stroke
			(width 0)
			(type solid)
		)
		(fill yes)
		(layer "B.Cu")
		(net "GND")
	)
	(gr_poly
		(pts
			(arc
				(start 373.421402 -402.309838)
				(mid 373.211598 -402.309838)
				(end 373.421402 -402.309838)
			)
		)
		(stroke
			(width 0)
			(type solid)
		)
		(fill yes)
		(layer "B.Cu")
		(net "GND")
	)
	(gr_poly
		(pts
			(arc
				(start 374.621298 -402.259038)
				(mid 374.411494 -402.259038)
				(end 374.621298 -402.259038)
			)
		)
		(stroke
			(width 0)
			(type solid)
		)
		(fill yes)
		(layer "B.Cu")
		(net "GND")
	)
	(gr_poly
		(pts
			(arc
				(start 375.821448 -402.309838)
				(mid 375.611644 -402.309838)
				(end 375.821448 -402.309838)
			)
		)
		(stroke
			(width 0)
			(type solid)
		)
		(fill yes)
		(layer "B.Cu")
		(net "GND")
	)
	(gr_poly
		(pts
			(arc
				(start 377.021344 -402.309838)
				(mid 376.81154 -402.309838)
				(end 377.021344 -402.309838)
			)
		)
		(stroke
			(width 0)
			(type solid)
		)
		(fill yes)
		(layer "B.Cu")
		(net "GND")
	)
	(gr_poly
		(pts
			(arc
				(start 378.221494 -402.259038)
				(mid 378.01169 -402.259038)
				(end 378.221494 -402.259038)
			)
		)
		(stroke
			(width 0)
			(type solid)
		)
		(fill yes)
		(layer "B.Cu")
		(net "GND")
	)
	(gr_poly
		(pts
			(arc
				(start 379.42139 -402.284438)
				(mid 379.211586 -402.284438)
				(end 379.42139 -402.284438)
			)
		)
		(stroke
			(width 0)
			(type solid)
		)
		(fill yes)
		(layer "B.Cu")
		(net "GND")
	)
	(gr_poly
		(pts
			(arc
				(start 380.62154 -402.309838)
				(mid 380.411736 -402.309838)
				(end 380.62154 -402.309838)
			)
		)
		(stroke
			(width 0)
			(type solid)
		)
		(fill yes)
		(layer "B.Cu")
		(net "GND")
	)
	(gr_poly
		(pts
			(arc
				(start 381.821436 -402.309838)
				(mid 381.611632 -402.309838)
				(end 381.821436 -402.309838)
			)
		)
		(stroke
			(width 0)
			(type solid)
		)
		(fill yes)
		(layer "B.Cu")
		(net "GND")
	)
	(gr_poly
		(pts
			(arc
				(start 383.021586 -402.309838)
				(mid 382.811782 -402.309838)
				(end 383.021586 -402.309838)
			)
		)
		(stroke
			(width 0)
			(type solid)
		)
		(fill yes)
		(layer "B.Cu")
		(net "GND")
	)
	(gr_poly
		(pts
			(arc
				(start 384.221482 -402.309838)
				(mid 384.011678 -402.309838)
				(end 384.221482 -402.309838)
			)
		)
		(stroke
			(width 0)
			(type solid)
		)
		(fill yes)
		(layer "B.Cu")
		(net "GND")
	)
	(gr_poly
		(pts
			(arc
				(start 385.421378 -402.259038)
				(mid 385.211574 -402.259038)
				(end 385.421378 -402.259038)
			)
		)
		(stroke
			(width 0)
			(type solid)
		)
		(fill yes)
		(layer "B.Cu")
		(net "GND")
	)
	(gr_poly
		(pts
			(arc
				(start 386.621274 -402.309838)
				(mid 386.41147 -402.309838)
				(end 386.621274 -402.309838)
			)
		)
		(stroke
			(width 0)
			(type solid)
		)
		(fill yes)
		(layer "B.Cu")
		(net "GND")
	)
	(gr_poly
		(pts
			(arc
				(start 387.821424 -402.309838)
				(mid 387.61162 -402.309838)
				(end 387.821424 -402.309838)
			)
		)
		(stroke
			(width 0)
			(type solid)
		)
		(fill yes)
		(layer "B.Cu")
		(net "GND")
	)
	(gr_poly
		(pts
			(arc
				(start 389.02132 -402.284438)
				(mid 388.811516 -402.284438)
				(end 389.02132 -402.284438)
			)
		)
		(stroke
			(width 0)
			(type solid)
		)
		(fill yes)
		(layer "B.Cu")
		(net "GND")
	)
	(gr_poly
		(pts
			(arc
				(start 403.549104 -402.284438)
				(mid 403.3393 -402.284438)
				(end 403.549104 -402.284438)
			)
		)
		(stroke
			(width 0)
			(type solid)
		)
		(fill yes)
		(layer "B.Cu")
		(net "GND")
	)
	(gr_poly
		(pts
			(arc
				(start 404.749 -402.284438)
				(mid 404.539196 -402.284438)
				(end 404.749 -402.284438)
			)
		)
		(stroke
			(width 0)
			(type solid)
		)
		(fill yes)
		(layer "B.Cu")
		(net "GND")
	)
	(gr_poly
		(pts
			(arc
				(start 405.94915 -402.309838)
				(mid 405.739346 -402.309838)
				(end 405.94915 -402.309838)
			)
		)
		(stroke
			(width 0)
			(type solid)
		)
		(fill yes)
		(layer "B.Cu")
		(net "GND")
	)
	(gr_poly
		(pts
			(arc
				(start 407.149046 -402.259038)
				(mid 406.939242 -402.259038)
				(end 407.149046 -402.259038)
			)
		)
		(stroke
			(width 0)
			(type solid)
		)
		(fill yes)
		(layer "B.Cu")
		(net "GND")
	)
	(gr_poly
		(pts
			(arc
				(start 408.349196 -402.309838)
				(mid 408.139392 -402.309838)
				(end 408.349196 -402.309838)
			)
		)
		(stroke
			(width 0)
			(type solid)
		)
		(fill yes)
		(layer "B.Cu")
		(net "GND")
	)
	(gr_poly
		(pts
			(arc
				(start 409.549092 -402.309838)
				(mid 409.339288 -402.309838)
				(end 409.549092 -402.309838)
			)
		)
		(stroke
			(width 0)
			(type solid)
		)
		(fill yes)
		(layer "B.Cu")
		(net "GND")
	)
	(gr_poly
		(pts
			(arc
				(start 410.749242 -402.259038)
				(mid 410.539438 -402.259038)
				(end 410.749242 -402.259038)
			)
		)
		(stroke
			(width 0)
			(type solid)
		)
		(fill yes)
		(layer "B.Cu")
		(net "GND")
	)
	(gr_poly
		(pts
			(arc
				(start 411.949138 -402.284438)
				(mid 411.739334 -402.284438)
				(end 411.949138 -402.284438)
			)
		)
		(stroke
			(width 0)
			(type solid)
		)
		(fill yes)
		(layer "B.Cu")
		(net "GND")
	)
	(gr_poly
		(pts
			(arc
				(start 413.149288 -402.309838)
				(mid 412.939484 -402.309838)
				(end 413.149288 -402.309838)
			)
		)
		(stroke
			(width 0)
			(type solid)
		)
		(fill yes)
		(layer "B.Cu")
		(net "GND")
	)
	(gr_poly
		(pts
			(arc
				(start 414.349184 -402.309838)
				(mid 414.13938 -402.309838)
				(end 414.349184 -402.309838)
			)
		)
		(stroke
			(width 0)
			(type solid)
		)
		(fill yes)
		(layer "B.Cu")
		(net "GND")
	)
	(gr_poly
		(pts
			(arc
				(start 415.549334 -402.309838)
				(mid 415.33953 -402.309838)
				(end 415.549334 -402.309838)
			)
		)
		(stroke
			(width 0)
			(type solid)
		)
		(fill yes)
		(layer "B.Cu")
		(net "GND")
	)
	(gr_poly
		(pts
			(arc
				(start 416.74923 -402.309838)
				(mid 416.539426 -402.309838)
				(end 416.74923 -402.309838)
			)
		)
		(stroke
			(width 0)
			(type solid)
		)
		(fill yes)
		(layer "B.Cu")
		(net "GND")
	)
	(gr_poly
		(pts
			(arc
				(start 417.949126 -402.259038)
				(mid 417.739322 -402.259038)
				(end 417.949126 -402.259038)
			)
		)
		(stroke
			(width 0)
			(type solid)
		)
		(fill yes)
		(layer "B.Cu")
		(net "GND")
	)
	(gr_poly
		(pts
			(arc
				(start 419.149022 -402.309838)
				(mid 418.939218 -402.309838)
				(end 419.149022 -402.309838)
			)
		)
		(stroke
			(width 0)
			(type solid)
		)
		(fill yes)
		(layer "B.Cu")
		(net "GND")
	)
	(gr_poly
		(pts
			(arc
				(start 420.349172 -402.309838)
				(mid 420.139368 -402.309838)
				(end 420.349172 -402.309838)
			)
		)
		(stroke
			(width 0)
			(type solid)
		)
		(fill yes)
		(layer "B.Cu")
		(net "GND")
	)
	(gr_poly
		(pts
			(xy 421.371014 -363.703108) (xy 421.371014 -362.913168) (xy 421.362378 -362.904532) (xy 421.362378 -362.242354)
			(xy 421.312848 -362.192824) (xy 421.055292 -362.192824) (xy 420.914322 -362.192824) (xy 420.76243 -362.040932)
			(xy 420.76243 -360.407204) (xy 420.628826 -360.2736) (xy 420.387272 -360.032046) (xy 420.387272 -359.497376)
			(xy 420.284402 -359.394506) (xy 419.893242 -359.394506) (xy 419.819328 -359.46842) (xy 419.819328 -360.246422)
			(xy 419.79215 -360.2736) (xy 417.027614 -360.2736) (xy 416.84702 -360.454194) (xy 416.84702 -363.743494)
			(xy 416.952938 -363.849412) (xy 420.049198 -363.849412) (xy 420.920164 -363.849412) (xy 421.22471 -363.849412)
		)
		(stroke
			(width 0)
			(type solid)
		)
		(fill yes)
		(layer "B.Cu")
		(net "GND")
	)
	(gr_poly
		(pts
			(arc
				(start 421.549068 -402.284438)
				(mid 421.339264 -402.284438)
				(end 421.549068 -402.284438)
			)
		)
		(stroke
			(width 0)
			(type solid)
		)
		(fill yes)
		(layer "B.Cu")
		(net "GND")
	)
	(gr_poly
		(pts
			(xy 65.340738 -164.587428)
			(arc
				(start 65.341754 -164.568124)
				(mid 65.452954 -164.318898)
				(end 65.70218 -164.207698)
			)
			(xy 65.721484 -164.206682) (xy 65.84569 -164.082222) (xy 69.108066 -164.082222) (xy 69.254878 -163.93541)
			(xy 69.254878 -163.04641) (xy 68.99148 -162.783012) (xy 68.542154 -162.783012) (xy 63.944754 -162.783012)
			(xy 63.690754 -163.037012) (xy 63.690754 -164.713412) (xy 63.741554 -164.764212) (xy 65.163954 -164.764212)
		)
		(stroke
			(width 0)
			(type solid)
		)
		(fill yes)
		(layer "B.Cu")
		(net "GND")
	)
	(gr_poly
		(pts
			(xy 184.8866 -363.938058) (xy 184.8866 -358.462326) (xy 184.8866 -356.725474) (xy 184.8866 -355.658674)
			(xy 184.8866 -355.455474) (xy 184.785 -355.353874) (xy 183.515 -355.353874) (xy 183.4388 -355.430074)
			(xy 183.4388 -355.709474) (xy 183.075072 -356.073202) (xy 182.853076 -356.073202) (xy 182.413402 -356.073202)
			(xy 182.105046 -356.381558) (xy 180.157882 -356.381558) (xy 179.97424 -356.5652) (xy 179.97424 -357.750872)
			(xy 179.97424 -358.28478) (xy 180.245512 -358.556052) (xy 182.871364 -358.556052) (xy 183.010556 -358.695244)
			(xy 183.010556 -363.6137) (xy 183.010556 -363.909864) (xy 183.15559 -364.054898) (xy 183.451754 -364.054898)
			(xy 184.76976 -364.054898)
		)
		(stroke
			(width 0)
			(type solid)
		)
		(fill yes)
		(layer "B.Cu")
		(net "GND")
	)
	(gr_poly
		(pts
			(xy 193.2178 -356.725474) (xy 193.2178 -355.709474) (xy 193.2178 -355.455474) (xy 193.1416 -355.379274)
			(xy 191.8716 -355.379274) (xy 191.8208 -355.430074) (xy 191.8208 -355.684074) (xy 191.7192 -355.785674)
			(xy 191.406272 -356.098602) (xy 191.179704 -356.098602) (xy 190.74003 -356.098602) (xy 190.431674 -356.406958)
			(xy 188.409326 -356.406958) (xy 188.104272 -356.101904) (xy 188.079888 -356.07752) (xy 187.37834 -356.07752)
			(xy 187.25642 -356.19944) (xy 187.25642 -356.524052) (xy 187.596272 -356.863904) (xy 187.887356 -357.154988)
			(xy 188.289184 -357.154988) (xy 188.410088 -357.154988) (xy 189.519814 -357.154988) (xy 191.165226 -357.154988)
			(xy 192.788286 -357.154988)
		)
		(stroke
			(width 0)
			(type solid)
		)
		(fill yes)
		(layer "B.Cu")
		(net "GND")
	)
	(gr_poly
		(pts
			(arc
				(start 215.679782 -165.386258)
				(mid 215.439498 -165.386258)
				(end 215.679782 -165.386258)
			)
		)
		(stroke
			(width 0)
			(type solid)
		)
		(fill yes)
		(layer "B.Cu")
		(net "GND")
	)
	(gr_poly
		(pts
			(xy 425.610782 -359.157524) (xy 425.610782 -357.586788) (xy 425.610782 -356.918768) (xy 425.610782 -356.54488)
			(xy 425.610782 -355.47808) (xy 425.610782 -355.27488) (xy 425.509182 -355.17328) (xy 424.239182 -355.17328)
			(xy 424.162982 -355.24948) (xy 424.162982 -355.52888) (xy 423.799254 -355.892608) (xy 423.799254 -355.895402)
			(xy 423.646854 -356.047802) (xy 422.98239 -356.047802) (xy 422.829228 -356.200964) (xy 420.853108 -356.200964)
			(xy 420.664132 -356.011988) (xy 420.189152 -356.011988) (xy 420.054532 -356.146608) (xy 420.054532 -356.431342)
			(xy 420.054532 -357.108506) (xy 420.054532 -358.412542) (xy 420.849552 -359.207562) (xy 422.153588 -359.207562)
			(xy 425.560744 -359.207562)
		)
		(stroke
			(width 0)
			(type solid)
		)
		(fill yes)
		(layer "B.Cu")
		(net "GND")
	)
	(gr_poly
		(pts
			(xy 433.941982 -356.54488) (xy 433.941982 -355.52888) (xy 433.941982 -355.27488) (xy 433.865782 -355.19868)
			(xy 432.595782 -355.19868) (xy 432.544982 -355.24948) (xy 432.544982 -355.50348) (xy 432.443382 -355.60508)
			(xy 432.130454 -355.918008) (xy 431.903886 -355.918008) (xy 431.464212 -355.918008) (xy 431.155856 -356.226364)
			(xy 429.133508 -356.226364) (xy 428.828454 -355.92131) (xy 428.791624 -355.88448) (xy 428.05096 -355.88448)
			(xy 427.99508 -355.94036) (xy 427.99508 -356.357936) (xy 428.320454 -356.68331) (xy 428.611538 -356.974394)
			(xy 429.013366 -356.974394) (xy 429.13427 -356.974394) (xy 430.243996 -356.974394) (xy 431.889408 -356.974394)
			(xy 433.512468 -356.974394)
		)
		(stroke
			(width 0)
			(type solid)
		)
		(fill yes)
		(layer "B.Cu")
		(net "GND")
	)
	(gr_poly
		(pts
			(arc
				(start 47.364904 -412.570168)
				(mid 47.105824 -412.570168)
				(end 47.364904 -412.570168)
			)
		)
		(stroke
			(width 0)
			(type solid)
		)
		(fill yes)
		(layer "B.Cu")
		(net "GND")
	)
	(gr_poly
		(pts
			(arc
				(start 47.726092 -413.204152)
				(mid 47.467012 -413.204152)
				(end 47.726092 -413.204152)
			)
		)
		(stroke
			(width 0)
			(type solid)
		)
		(fill yes)
		(layer "B.Cu")
		(net "GND")
	)
	(gr_poly
		(pts
			(arc
				(start 48.984916 -413.204152)
				(mid 48.725836 -413.204152)
				(end 48.984916 -413.204152)
			)
		)
		(stroke
			(width 0)
			(type solid)
		)
		(fill yes)
		(layer "B.Cu")
		(net "GND")
	)
	(gr_poly
		(pts
			(arc
				(start 49.346104 -412.570168)
				(mid 49.087024 -412.570168)
				(end 49.346104 -412.570168)
			)
		)
		(stroke
			(width 0)
			(type solid)
		)
		(fill yes)
		(layer "B.Cu")
		(net "GND")
	)
	(gr_poly
		(pts
			(arc
				(start 89.777062 -308.48554)
				(mid 89.517982 -308.48554)
				(end 89.777062 -308.48554)
			)
		)
		(stroke
			(width 0)
			(type solid)
		)
		(fill yes)
		(layer "B.Cu")
		(net "GND")
	)
	(gr_poly
		(pts
			(arc
				(start 94.61754 -215.737948)
				(mid 94.35846 -215.737948)
				(end 94.61754 -215.737948)
			)
		)
		(stroke
			(width 0)
			(type solid)
		)
		(fill yes)
		(layer "B.Cu")
		(net "GND")
	)
	(gr_poly
		(pts
			(arc
				(start 94.61754 -213.451948)
				(mid 94.35846 -213.451948)
				(end 94.61754 -213.451948)
			)
		)
		(stroke
			(width 0)
			(type solid)
		)
		(fill yes)
		(layer "B.Cu")
		(net "GND")
	)
	(gr_poly
		(pts
			(arc
				(start 94.61754 -212.816948)
				(mid 94.35846 -212.816948)
				(end 94.61754 -212.816948)
			)
		)
		(stroke
			(width 0)
			(type solid)
		)
		(fill yes)
		(layer "B.Cu")
		(net "GND")
	)
	(gr_poly
		(pts
			(arc
				(start 94.61754 -210.530948)
				(mid 94.35846 -210.530948)
				(end 94.61754 -210.530948)
			)
		)
		(stroke
			(width 0)
			(type solid)
		)
		(fill yes)
		(layer "B.Cu")
		(net "GND")
	)
	(gr_poly
		(pts
			(arc
				(start 94.61754 -209.895948)
				(mid 94.35846 -209.895948)
				(end 94.61754 -209.895948)
			)
		)
		(stroke
			(width 0)
			(type solid)
		)
		(fill yes)
		(layer "B.Cu")
		(net "GND")
	)
	(gr_poly
		(pts
			(arc
				(start 94.61754 -207.482948)
				(mid 94.35846 -207.482948)
				(end 94.61754 -207.482948)
			)
		)
		(stroke
			(width 0)
			(type solid)
		)
		(fill yes)
		(layer "B.Cu")
		(net "GND")
	)
	(gr_poly
		(pts
			(arc
				(start 96.020382 -310.457596)
				(mid 95.761302 -310.457596)
				(end 96.020382 -310.457596)
			)
		)
		(stroke
			(width 0)
			(type solid)
		)
		(fill yes)
		(layer "B.Cu")
		(net "GND")
	)
	(gr_poly
		(pts
			(arc
				(start 97.792286 -208.244948)
				(mid 97.533206 -208.244948)
				(end 97.792286 -208.244948)
			)
		)
		(stroke
			(width 0)
			(type solid)
		)
		(fill yes)
		(layer "B.Cu")
		(net "GND")
	)
	(gr_poly
		(pts
			(arc
				(start 97.79254 -205.958948)
				(mid 97.53346 -205.958948)
				(end 97.79254 -205.958948)
			)
		)
		(stroke
			(width 0)
			(type solid)
		)
		(fill yes)
		(layer "B.Cu")
		(net "GND")
	)
	(gr_poly
		(pts
			(xy 139.0777 -44.12488) (xy 139.0777 -42.61612) (xy 139.00658 -42.545) (xy 138.86942 -42.545) (xy 138.52652 -42.2021)
			(xy 138.52652 -36.356544) (xy 138.487912 -36.317936) (xy 137.930382 -36.317936) (xy 137.84072 -36.228274)
			(xy 137.84072 -35.96894) (xy 137.69594 -35.82416) (xy 137.41146 -35.82416) (xy 137.24636 -35.98926)
			(xy 137.24636 -37.23386) (xy 136.964928 -37.515292) (xy 136.205722 -37.515292) (xy 136.167114 -37.5539)
			(xy 136.167114 -39.106094) (xy 136.358884 -39.297864) (xy 136.798304 -39.297864) (xy 137.680954 -40.180514)
			(xy 137.680954 -42.66946) (xy 137.680954 -44.07916) (xy 137.744454 -44.14266) (xy 139.020804 -44.14266)
			(xy 139.05992 -44.14266)
		)
		(stroke
			(width 0)
			(type solid)
		)
		(fill yes)
		(layer "B.Cu")
		(net "P1V2_AUX")
	)
	(gr_poly
		(pts
			(arc
				(start 181.537102 -54.152546)
				(mid 181.278022 -54.152546)
				(end 181.537102 -54.152546)
			)
		)
		(stroke
			(width 0)
			(type solid)
		)
		(fill yes)
		(layer "B.Cu")
		(net "GND")
	)
	(gr_poly
		(pts
			(arc
				(start 181.537102 -51.14671)
				(mid 181.278022 -51.14671)
				(end 181.537102 -51.14671)
			)
		)
		(stroke
			(width 0)
			(type solid)
		)
		(fill yes)
		(layer "B.Cu")
		(net "GND")
	)
	(gr_poly
		(pts
			(arc
				(start 181.537102 -49.878742)
				(mid 181.278022 -49.878742)
				(end 181.537102 -49.878742)
			)
		)
		(stroke
			(width 0)
			(type solid)
		)
		(fill yes)
		(layer "B.Cu")
		(net "GND")
	)
	(gr_poly
		(pts
			(arc
				(start 181.537102 -48.22571)
				(mid 181.278022 -48.22571)
				(end 181.537102 -48.22571)
			)
		)
		(stroke
			(width 0)
			(type solid)
		)
		(fill yes)
		(layer "B.Cu")
		(net "GND")
	)
	(gr_poly
		(pts
			(arc
				(start 181.537102 -46.957742)
				(mid 181.278022 -46.957742)
				(end 181.537102 -46.957742)
			)
		)
		(stroke
			(width 0)
			(type solid)
		)
		(fill yes)
		(layer "B.Cu")
		(net "GND")
	)
	(gr_poly
		(pts
			(arc
				(start 181.537102 -45.17771)
				(mid 181.278022 -45.17771)
				(end 181.537102 -45.17771)
			)
		)
		(stroke
			(width 0)
			(type solid)
		)
		(fill yes)
		(layer "B.Cu")
		(net "GND")
	)
	(gr_poly
		(pts
			(arc
				(start 181.537102 -43.909742)
				(mid 181.278022 -43.909742)
				(end 181.537102 -43.909742)
			)
		)
		(stroke
			(width 0)
			(type solid)
		)
		(fill yes)
		(layer "B.Cu")
		(net "GND")
	)
	(gr_poly
		(pts
			(arc
				(start 182.80507 -54.152546)
				(mid 182.54599 -54.152546)
				(end 182.80507 -54.152546)
			)
		)
		(stroke
			(width 0)
			(type solid)
		)
		(fill yes)
		(layer "B.Cu")
		(net "GND")
	)
	(gr_poly
		(pts
			(arc
				(start 182.80507 -51.14671)
				(mid 182.54599 -51.14671)
				(end 182.80507 -51.14671)
			)
		)
		(stroke
			(width 0)
			(type solid)
		)
		(fill yes)
		(layer "B.Cu")
		(net "GND")
	)
	(gr_poly
		(pts
			(arc
				(start 182.80507 -49.878742)
				(mid 182.54599 -49.878742)
				(end 182.80507 -49.878742)
			)
		)
		(stroke
			(width 0)
			(type solid)
		)
		(fill yes)
		(layer "B.Cu")
		(net "GND")
	)
	(gr_poly
		(pts
			(arc
				(start 182.80507 -48.22571)
				(mid 182.54599 -48.22571)
				(end 182.80507 -48.22571)
			)
		)
		(stroke
			(width 0)
			(type solid)
		)
		(fill yes)
		(layer "B.Cu")
		(net "GND")
	)
	(gr_poly
		(pts
			(arc
				(start 182.80507 -46.957742)
				(mid 182.54599 -46.957742)
				(end 182.80507 -46.957742)
			)
		)
		(stroke
			(width 0)
			(type solid)
		)
		(fill yes)
		(layer "B.Cu")
		(net "GND")
	)
	(gr_poly
		(pts
			(arc
				(start 182.80507 -45.17771)
				(mid 182.54599 -45.17771)
				(end 182.80507 -45.17771)
			)
		)
		(stroke
			(width 0)
			(type solid)
		)
		(fill yes)
		(layer "B.Cu")
		(net "GND")
	)
	(gr_poly
		(pts
			(arc
				(start 182.80507 -43.909742)
				(mid 182.54599 -43.909742)
				(end 182.80507 -43.909742)
			)
		)
		(stroke
			(width 0)
			(type solid)
		)
		(fill yes)
		(layer "B.Cu")
		(net "GND")
	)
	(gr_poly
		(pts
			(arc
				(start 256.056638 -214.441024)
				(mid 255.797558 -214.441024)
				(end 256.056638 -214.441024)
			)
		)
		(stroke
			(width 0)
			(type solid)
		)
		(fill yes)
		(layer "B.Cu")
		(net "GND")
	)
	(gr_poly
		(pts
			(arc
				(start 256.056638 -212.307424)
				(mid 255.797558 -212.307424)
				(end 256.056638 -212.307424)
			)
		)
		(stroke
			(width 0)
			(type solid)
		)
		(fill yes)
		(layer "B.Cu")
		(net "GND")
	)
	(gr_poly
		(pts
			(arc
				(start 256.056638 -211.672424)
				(mid 255.797558 -211.672424)
				(end 256.056638 -211.672424)
			)
		)
		(stroke
			(width 0)
			(type solid)
		)
		(fill yes)
		(layer "B.Cu")
		(net "GND")
	)
	(gr_poly
		(pts
			(arc
				(start 256.056638 -209.487008)
				(mid 255.797558 -209.487008)
				(end 256.056638 -209.487008)
			)
		)
		(stroke
			(width 0)
			(type solid)
		)
		(fill yes)
		(layer "B.Cu")
		(net "GND")
	)
	(gr_poly
		(pts
			(arc
				(start 256.056638 -208.852008)
				(mid 255.797558 -208.852008)
				(end 256.056638 -208.852008)
			)
		)
		(stroke
			(width 0)
			(type solid)
		)
		(fill yes)
		(layer "B.Cu")
		(net "GND")
	)
	(gr_poly
		(pts
			(arc
				(start 256.056638 -206.718408)
				(mid 255.797558 -206.718408)
				(end 256.056638 -206.718408)
			)
		)
		(stroke
			(width 0)
			(type solid)
		)
		(fill yes)
		(layer "B.Cu")
		(net "GND")
	)
	(gr_poly
		(pts
			(arc
				(start 256.056638 -206.083408)
				(mid 255.797558 -206.083408)
				(end 256.056638 -206.083408)
			)
		)
		(stroke
			(width 0)
			(type solid)
		)
		(fill yes)
		(layer "B.Cu")
		(net "GND")
	)
	(gr_poly
		(pts
			(arc
				(start 256.056638 -203.932536)
				(mid 255.797558 -203.932536)
				(end 256.056638 -203.932536)
			)
		)
		(stroke
			(width 0)
			(type solid)
		)
		(fill yes)
		(layer "B.Cu")
		(net "GND")
	)
	(gr_poly
		(pts
			(arc
				(start 256.056638 -203.297536)
				(mid 255.797558 -203.297536)
				(end 256.056638 -203.297536)
			)
		)
		(stroke
			(width 0)
			(type solid)
		)
		(fill yes)
		(layer "B.Cu")
		(net "GND")
	)
	(gr_poly
		(pts
			(arc
				(start 256.056638 -201.163936)
				(mid 255.797558 -201.163936)
				(end 256.056638 -201.163936)
			)
		)
		(stroke
			(width 0)
			(type solid)
		)
		(fill yes)
		(layer "B.Cu")
		(net "GND")
	)
	(gr_poly
		(pts
			(arc
				(start 256.056638 -200.528936)
				(mid 255.797558 -200.528936)
				(end 256.056638 -200.528936)
			)
		)
		(stroke
			(width 0)
			(type solid)
		)
		(fill yes)
		(layer "B.Cu")
		(net "GND")
	)
	(gr_poly
		(pts
			(arc
				(start 256.056638 -198.34352)
				(mid 255.797558 -198.34352)
				(end 256.056638 -198.34352)
			)
		)
		(stroke
			(width 0)
			(type solid)
		)
		(fill yes)
		(layer "B.Cu")
		(net "GND")
	)
	(gr_poly
		(pts
			(arc
				(start 256.056638 -197.70852)
				(mid 255.797558 -197.70852)
				(end 256.056638 -197.70852)
			)
		)
		(stroke
			(width 0)
			(type solid)
		)
		(fill yes)
		(layer "B.Cu")
		(net "GND")
	)
	(gr_poly
		(pts
			(arc
				(start 256.056638 -195.57492)
				(mid 255.797558 -195.57492)
				(end 256.056638 -195.57492)
			)
		)
		(stroke
			(width 0)
			(type solid)
		)
		(fill yes)
		(layer "B.Cu")
		(net "GND")
	)
	(gr_poly
		(pts
			(arc
				(start 256.056638 -194.93992)
				(mid 255.797558 -194.93992)
				(end 256.056638 -194.93992)
			)
		)
		(stroke
			(width 0)
			(type solid)
		)
		(fill yes)
		(layer "B.Cu")
		(net "GND")
	)
	(gr_poly
		(pts
			(arc
				(start 256.086102 -192.789048)
				(mid 255.827022 -192.789048)
				(end 256.086102 -192.789048)
			)
		)
		(stroke
			(width 0)
			(type solid)
		)
		(fill yes)
		(layer "B.Cu")
		(net "GND")
	)
	(gr_poly
		(pts
			(arc
				(start 260.604762 -195.254626)
				(mid 260.345682 -195.254626)
				(end 260.604762 -195.254626)
			)
		)
		(stroke
			(width 0)
			(type solid)
		)
		(fill yes)
		(layer "B.Cu")
		(net "GND")
	)
	(gr_poly
		(pts
			(arc
				(start 260.604762 -192.740026)
				(mid 260.345682 -192.740026)
				(end 260.604762 -192.740026)
			)
		)
		(stroke
			(width 0)
			(type solid)
		)
		(fill yes)
		(layer "B.Cu")
		(net "GND")
	)
	(gr_poly
		(pts
			(arc
				(start 284.056074 -374.165114)
				(mid 283.80055 -374.165114)
				(end 284.056074 -374.165114)
			)
		)
		(stroke
			(width 0)
			(type solid)
		)
		(fill yes)
		(layer "B.Cu")
		(net "GND")
	)
	(gr_poly
		(pts
			(arc
				(start 284.086046 -372.86057)
				(mid 283.830522 -372.86057)
				(end 284.086046 -372.86057)
			)
		)
		(stroke
			(width 0)
			(type solid)
		)
		(fill yes)
		(layer "B.Cu")
		(net "GND")
	)
	(gr_poly
		(pts
			(arc
				(start 367.284762 -409.321)
				(mid 367.029238 -409.321)
				(end 367.284762 -409.321)
			)
		)
		(stroke
			(width 0)
			(type solid)
		)
		(fill yes)
		(layer "B.Cu")
		(net "GND")
	)
	(gr_poly
		(pts
			(arc
				(start 368.046762 -406.654)
				(mid 367.791238 -406.654)
				(end 368.046762 -406.654)
			)
		)
		(stroke
			(width 0)
			(type solid)
		)
		(fill yes)
		(layer "B.Cu")
		(net "GND")
	)
	(gr_poly
		(pts
			(arc
				(start 75.30465 -411.936184)
				(mid 75.026774 -411.936184)
				(end 75.30465 -411.936184)
			)
		)
		(stroke
			(width 0)
			(type solid)
		)
		(fill yes)
		(layer "B.Cu")
		(net "GND")
	)
	(gr_poly
		(pts
			(arc
				(start 76.563474 -411.936184)
				(mid 76.285598 -411.936184)
				(end 76.563474 -411.936184)
			)
		)
		(stroke
			(width 0)
			(type solid)
		)
		(fill yes)
		(layer "B.Cu")
		(net "GND")
	)
	(gr_poly
		(pts
			(arc
				(start 78.36789 -411.936184)
				(mid 78.090014 -411.936184)
				(end 78.36789 -411.936184)
			)
		)
		(stroke
			(width 0)
			(type solid)
		)
		(fill yes)
		(layer "B.Cu")
		(net "GND")
	)
	(gr_poly
		(pts
			(arc
				(start 79.626714 -411.936184)
				(mid 79.348838 -411.936184)
				(end 79.626714 -411.936184)
			)
		)
		(stroke
			(width 0)
			(type solid)
		)
		(fill yes)
		(layer "B.Cu")
		(net "GND")
	)
	(gr_poly
		(pts
			(arc
				(start 81.43113 -411.936184)
				(mid 81.153254 -411.936184)
				(end 81.43113 -411.936184)
			)
		)
		(stroke
			(width 0)
			(type solid)
		)
		(fill yes)
		(layer "B.Cu")
		(net "GND")
	)
	(gr_poly
		(pts
			(arc
				(start 82.689954 -411.936184)
				(mid 82.412078 -411.936184)
				(end 82.689954 -411.936184)
			)
		)
		(stroke
			(width 0)
			(type solid)
		)
		(fill yes)
		(layer "B.Cu")
		(net "GND")
	)
	(gr_poly
		(pts
			(arc
				(start 84.49437 -411.936184)
				(mid 84.216494 -411.936184)
				(end 84.49437 -411.936184)
			)
		)
		(stroke
			(width 0)
			(type solid)
		)
		(fill yes)
		(layer "B.Cu")
		(net "GND")
	)
	(gr_poly
		(pts
			(arc
				(start 85.753194 -411.936184)
				(mid 85.475318 -411.936184)
				(end 85.753194 -411.936184)
			)
		)
		(stroke
			(width 0)
			(type solid)
		)
		(fill yes)
		(layer "B.Cu")
		(net "GND")
	)
	(gr_poly
		(pts
			(arc
				(start 87.55761 -411.936184)
				(mid 87.279734 -411.936184)
				(end 87.55761 -411.936184)
			)
		)
		(stroke
			(width 0)
			(type solid)
		)
		(fill yes)
		(layer "B.Cu")
		(net "GND")
	)
	(gr_poly
		(pts
			(arc
				(start 88.816434 -411.936184)
				(mid 88.538558 -411.936184)
				(end 88.816434 -411.936184)
			)
		)
		(stroke
			(width 0)
			(type solid)
		)
		(fill yes)
		(layer "B.Cu")
		(net "GND")
	)
	(gr_poly
		(pts
			(arc
				(start 90.62085 -411.936184)
				(mid 90.342974 -411.936184)
				(end 90.62085 -411.936184)
			)
		)
		(stroke
			(width 0)
			(type solid)
		)
		(fill yes)
		(layer "B.Cu")
		(net "GND")
	)
	(gr_poly
		(pts
			(arc
				(start 91.879674 -411.936184)
				(mid 91.601798 -411.936184)
				(end 91.879674 -411.936184)
			)
		)
		(stroke
			(width 0)
			(type solid)
		)
		(fill yes)
		(layer "B.Cu")
		(net "GND")
	)
	(gr_poly
		(pts
			(arc
				(start 93.68409 -411.936184)
				(mid 93.406214 -411.936184)
				(end 93.68409 -411.936184)
			)
		)
		(stroke
			(width 0)
			(type solid)
		)
		(fill yes)
		(layer "B.Cu")
		(net "GND")
	)
	(gr_poly
		(pts
			(arc
				(start 94.942914 -411.936184)
				(mid 94.665038 -411.936184)
				(end 94.942914 -411.936184)
			)
		)
		(stroke
			(width 0)
			(type solid)
		)
		(fill yes)
		(layer "B.Cu")
		(net "GND")
	)
	(gr_poly
		(pts
			(xy 129.4511 -41.762172) (xy 129.4511 -40.93464) (xy 129.13868 -40.62222) (xy 128.763522 -40.62222)
			(xy 128.684528 -40.543226) (xy 128.684528 -38.83787) (xy 128.642364 -38.795706) (xy 128.084834 -38.795706)
			(xy 127.88011 -39.00043) (xy 125.55093 -39.00043) (xy 123.4059 -36.8554) (xy 121.031 -36.8554) (xy 120.6246 -36.449)
			(xy 115.062 -36.449) (xy 114.937286 -36.573714) (xy 114.937286 -37.666676) (xy 115.000786 -37.730176)
			(xy 115.02771 -37.7571) (xy 116.3955 -37.7571) (xy 120.1547 -37.7571) (xy 122.2248 -39.8272) (xy 125.683772 -39.8272)
			(xy 126.405894 -40.549322) (xy 126.405894 -41.571672) (xy 126.469394 -41.635172) (xy 127.642874 -41.635172)
			(xy 127.828294 -41.820592) (xy 129.39268 -41.820592)
		)
		(stroke
			(width 0)
			(type solid)
		)
		(fill yes)
		(layer "B.Cu")
		(net "P1V2_AUX")
	)
	(gr_poly
		(pts
			(xy 142.24 -35.55492) (xy 142.24 -34.91484) (xy 142.13586 -34.8107) (xy 141.48816 -34.8107) (xy 141.34592 -34.66846)
			(xy 141.34592 -34.180272) (xy 141.34592 -32.770572) (xy 141.28242 -32.707072) (xy 140.00607 -32.707072)
			(xy 139.94257 -32.770572) (xy 139.94257 -33.52165) (xy 139.810998 -33.653222) (xy 138.943842 -33.653222)
			(xy 138.905234 -33.69183) (xy 138.905234 -34.24936) (xy 138.612372 -34.542222) (xy 137.497058 -34.542222)
			(xy 137.32256 -34.71672) (xy 137.32256 -35.01644) (xy 137.483342 -35.177222) (xy 139.828016 -35.177222)
			(xy 140.046202 -35.177222) (xy 140.14196 -35.27298) (xy 140.14196 -35.48634) (xy 140.340842 -35.685222)
			(xy 140.90777 -35.685222) (xy 141.190218 -35.685222) (xy 142.109698 -35.685222)
		)
		(stroke
			(width 0)
			(type solid)
		)
		(fill yes)
		(layer "B.Cu")
		(net "P3V3_AUX_CPU0_USB_AVDD33")
	)
	(gr_poly
		(pts
			(xy 441.762388 -20.70227) (xy 441.762388 -19.732244) (xy 441.762388 -15.26413) (xy 442.468 -14.558264)
			(xy 442.468 -10.135108) (xy 442.111384 -9.778492)
			(arc
				(start 437.829706 -9.778492)
				(mid 437.810183 -9.782393)
				(end 437.793638 -9.793478)
			)
			(arc
				(start 437.24703 -10.340086)
				(mid 437.235919 -10.35662)
				(end 437.232044 -10.376154)
			)
			(arc
				(start 437.232044 -12.83589)
				(mid 437.235945 -12.855413)
				(end 437.24703 -12.871958)
			)
			(xy 437.675528 -13.300456) (xy 439.375042 -13.300456) (xy 439.536078 -13.13942) (xy 440.369198 -13.13942)
			(xy 440.533028 -13.30325) (xy 440.533028 -14.39672) (xy 440.533028 -19.749262) (xy 440.533028 -20.813268)
			(xy 440.736736 -21.016976) (xy 441.447682 -21.016976)
		)
		(stroke
			(width 0)
			(type solid)
		)
		(fill yes)
		(layer "B.Cu")
		(net "P12V_OCP_SFF_R")
	)
	(gr_poly
		(pts
			(arc
				(start 33.65246 -168.899332)
				(mid 33.332928 -168.899332)
				(end 33.65246 -168.899332)
			)
		)
		(stroke
			(width 0)
			(type solid)
		)
		(fill yes)
		(layer "B.Cu")
		(net "GND")
	)
	(gr_poly
		(pts
			(arc
				(start 35.686492 -174.391828)
				(mid 35.36696 -174.391828)
				(end 35.686492 -174.391828)
			)
		)
		(stroke
			(width 0)
			(type solid)
		)
		(fill yes)
		(layer "B.Cu")
		(net "GND")
	)
	(gr_poly
		(pts
			(arc
				(start 44.051474 -173.237144)
				(mid 43.731942 -173.237144)
				(end 44.051474 -173.237144)
			)
		)
		(stroke
			(width 0)
			(type solid)
		)
		(fill yes)
		(layer "B.Cu")
		(net "GND")
	)
	(gr_poly
		(pts
			(arc
				(start 44.177712 -168.899332)
				(mid 43.85818 -168.899332)
				(end 44.177712 -168.899332)
			)
		)
		(stroke
			(width 0)
			(type solid)
		)
		(fill yes)
		(layer "B.Cu")
		(net "GND")
	)
	(gr_poly
		(pts
			(arc
				(start 348.329758 -391.342372)
				(mid 348.349252 -391.338588)
				(end 348.365826 -391.32764)
			)
			(arc
				(start 348.575884 -391.117328)
				(mid 348.586946 -391.100911)
				(end 348.59087 -391.081514)
			)
			(arc
				(start 348.59087 -387.810502)
				(mid 348.586969 -387.790979)
				(end 348.575884 -387.774434)
			)
			(xy 348.568264 -387.767068)
			(arc
				(start 342.312244 -387.767068)
				(mid 342.292887 -387.770901)
				(end 342.27643 -387.7818)
			)
			(arc
				(start 342.25357 -387.80466)
				(mid 342.242508 -387.821077)
				(end 342.238584 -387.840474)
			)
			(arc
				(start 342.238584 -391.287508)
				(mid 342.242485 -391.307031)
				(end 342.25357 -391.323576)
			)
			(arc
				(start 342.257634 -391.32764)
				(mid 342.274197 -391.338614)
				(end 342.293702 -391.342372)
			)
		)
		(stroke
			(width 0)
			(type solid)
		)
		(fill yes)
		(layer "B.Cu")
		(net "GND")
	)
	(gr_poly
		(pts
			(xy 439.975498 -22.57044) (xy 439.975498 -15.23365) (xy 440.203844 -15.005304) (xy 440.251596 -14.957552)
			(xy 440.251596 -13.418312) (xy 440.22772 -13.394436) (xy 439.795412 -13.394436) (xy 439.60796 -13.581888)
			(xy 437.45912 -13.581888) (xy 436.881524 -13.004292) (xy 436.881524 -9.994392) (xy 436.718964 -9.831832)
			(xy 435.835044 -9.831832) (xy 435.657244 -10.009632) (xy 435.657244 -13.464032) (xy 435.657244 -13.634212)
			(xy 435.76748 -13.744448) (xy 436.531004 -13.744448) (xy 438.296558 -15.510002) (xy 438.296558 -17.330674)
			(xy 438.63768 -17.671796) (xy 438.63768 -18.99666) (xy 438.418986 -19.215354) (xy 436.714138 -19.215354)
			(xy 436.665878 -19.263614) (xy 436.665878 -21.430742) (xy 436.665878 -22.316694) (xy 437.120538 -22.771354)
			(xy 439.774584 -22.771354)
		)
		(stroke
			(width 0)
			(type solid)
		)
		(fill yes)
		(layer "B.Cu")
		(net "GND")
	)
	(gr_poly
		(pts
			(arc
				(start 92.361512 -157.713172)
				(mid 92.381035 -157.709271)
				(end 92.39758 -157.698186)
			)
			(arc
				(start 92.888308 -157.207458)
				(mid 92.899419 -157.190924)
				(end 92.903294 -157.17139)
			)
			(arc
				(start 92.903294 -154.783028)
				(mid 92.899393 -154.763505)
				(end 92.888308 -154.74696)
			)
			(arc
				(start 89.72296 -151.581612)
				(mid 89.706426 -151.570501)
				(end 89.686892 -151.566626)
			)
			(arc
				(start 83.423252 -151.566626)
				(mid 83.387331 -151.581505)
				(end 83.372452 -151.617426)
			)
			(arc
				(start 83.372452 -157.508448)
				(mid 83.376353 -157.527971)
				(end 83.387438 -157.544516)
			)
			(arc
				(start 83.541108 -157.698186)
				(mid 83.557642 -157.709297)
				(end 83.577176 -157.713172)
			)
		)
		(stroke
			(width 0)
			(type solid)
		)
		(fill yes)
		(layer "B.Cu")
		(net "P12V_AUX")
	)
	(gr_poly
		(pts
			(xy 252.187202 -274.039584)
			(arc
				(start 252.838458 -273.388328)
				(mid 252.849569 -273.371794)
				(end 252.853444 -273.35226)
			)
			(arc
				(start 252.853444 -269.376906)
				(mid 252.849543 -269.357383)
				(end 252.838458 -269.340838)
			)
			(arc
				(start 252.338078 -268.840458)
				(mid 252.321544 -268.829347)
				(end 252.30201 -268.825472)
			)
			(arc
				(start 249.545094 -268.825472)
				(mid 249.525571 -268.829373)
				(end 249.509026 -268.840458)
			)
			(arc
				(start 249.008646 -269.340838)
				(mid 248.997535 -269.357372)
				(end 248.99366 -269.376906)
			)
			(arc
				(start 248.99366 -273.598894)
				(mid 248.997561 -273.618417)
				(end 249.008646 -273.634962)
			)
			(arc
				(start 249.399044 -274.02536)
				(mid 249.415578 -274.036471)
				(end 249.435112 -274.040346)
			)
			(xy 252.187202 -274.040346)
		)
		(stroke
			(width 0)
			(type solid)
		)
		(fill yes)
		(layer "B.Cu")
		(net "P12V_AUX")
	)
	(gr_poly
		(pts
			(arc
				(start 15.030958 -17.61236)
				(mid 14.665198 -17.61236)
				(end 15.030958 -17.61236)
			)
		)
		(stroke
			(width 0)
			(type solid)
		)
		(fill yes)
		(layer "B.Cu")
		(net "GND")
	)
	(gr_poly
		(pts
			(arc
				(start 15.516098 -18.247106)
				(mid 15.150338 -18.247106)
				(end 15.516098 -18.247106)
			)
		)
		(stroke
			(width 0)
			(type solid)
		)
		(fill yes)
		(layer "B.Cu")
		(net "GND")
	)
	(gr_poly
		(pts
			(arc
				(start 15.516098 -16.979138)
				(mid 15.150338 -16.979138)
				(end 15.516098 -16.979138)
			)
		)
		(stroke
			(width 0)
			(type solid)
		)
		(fill yes)
		(layer "B.Cu")
		(net "GND")
	)
	(gr_poly
		(pts
			(arc
				(start 16.781018 -18.247106)
				(mid 16.415258 -18.247106)
				(end 16.781018 -18.247106)
			)
		)
		(stroke
			(width 0)
			(type solid)
		)
		(fill yes)
		(layer "B.Cu")
		(net "GND")
	)
	(gr_poly
		(pts
			(arc
				(start 16.781018 -16.979138)
				(mid 16.415258 -16.979138)
				(end 16.781018 -16.979138)
			)
		)
		(stroke
			(width 0)
			(type solid)
		)
		(fill yes)
		(layer "B.Cu")
		(net "GND")
	)
	(gr_poly
		(pts
			(arc
				(start 17.266158 -17.61236)
				(mid 16.900398 -17.61236)
				(end 17.266158 -17.61236)
			)
		)
		(stroke
			(width 0)
			(type solid)
		)
		(fill yes)
		(layer "B.Cu")
		(net "GND")
	)
	(gr_poly
		(pts
			(arc
				(start 17.823942 -19.137122)
				(mid 17.458182 -19.137122)
				(end 17.823942 -19.137122)
			)
		)
		(stroke
			(width 0)
			(type solid)
		)
		(fill yes)
		(layer "B.Cu")
		(net "GND")
	)
	(gr_poly
		(pts
			(arc
				(start 18.309082 -19.771868)
				(mid 17.943322 -19.771868)
				(end 18.309082 -19.771868)
			)
		)
		(stroke
			(width 0)
			(type solid)
		)
		(fill yes)
		(layer "B.Cu")
		(net "GND")
	)
	(gr_poly
		(pts
			(arc
				(start 18.309082 -18.5039)
				(mid 17.943322 -18.5039)
				(end 18.309082 -18.5039)
			)
		)
		(stroke
			(width 0)
			(type solid)
		)
		(fill yes)
		(layer "B.Cu")
		(net "GND")
	)
	(gr_poly
		(pts
			(arc
				(start 18.492978 -6.598158)
				(mid 18.127218 -6.598158)
				(end 18.492978 -6.598158)
			)
		)
		(stroke
			(width 0)
			(type solid)
		)
		(fill yes)
		(layer "B.Cu")
		(net "GND")
	)
	(gr_poly
		(pts
			(arc
				(start 19.000978 -6.091174)
				(mid 18.635218 -6.091174)
				(end 19.000978 -6.091174)
			)
		)
		(stroke
			(width 0)
			(type solid)
		)
		(fill yes)
		(layer "B.Cu")
		(net "GND")
	)
	(gr_poly
		(pts
			(arc
				(start 19.574002 -19.771868)
				(mid 19.208242 -19.771868)
				(end 19.574002 -19.771868)
			)
		)
		(stroke
			(width 0)
			(type solid)
		)
		(fill yes)
		(layer "B.Cu")
		(net "GND")
	)
	(gr_poly
		(pts
			(arc
				(start 19.574002 -18.5039)
				(mid 19.208242 -18.5039)
				(end 19.574002 -18.5039)
			)
		)
		(stroke
			(width 0)
			(type solid)
		)
		(fill yes)
		(layer "B.Cu")
		(net "GND")
	)
	(gr_poly
		(pts
			(arc
				(start 20.059142 -19.137122)
				(mid 19.693382 -19.137122)
				(end 20.059142 -19.137122)
			)
		)
		(stroke
			(width 0)
			(type solid)
		)
		(fill yes)
		(layer "B.Cu")
		(net "GND")
	)
	(gr_poly
		(pts
			(arc
				(start 20.259802 -6.091174)
				(mid 19.894042 -6.091174)
				(end 20.259802 -6.091174)
			)
		)
		(stroke
			(width 0)
			(type solid)
		)
		(fill yes)
		(layer "B.Cu")
		(net "GND")
	)
	(gr_poly
		(pts
			(arc
				(start 20.297648 -4.963414)
				(mid 19.931888 -4.963414)
				(end 20.297648 -4.963414)
			)
		)
		(stroke
			(width 0)
			(type solid)
		)
		(fill yes)
		(layer "B.Cu")
		(net "GND")
	)
	(gr_poly
		(pts
			(arc
				(start 20.618958 -17.61236)
				(mid 20.253198 -17.61236)
				(end 20.618958 -17.61236)
			)
		)
		(stroke
			(width 0)
			(type solid)
		)
		(fill yes)
		(layer "B.Cu")
		(net "GND")
	)
	(gr_poly
		(pts
			(arc
				(start 20.767802 -6.598158)
				(mid 20.402042 -6.598158)
				(end 20.767802 -6.598158)
			)
		)
		(stroke
			(width 0)
			(type solid)
		)
		(fill yes)
		(layer "B.Cu")
		(net "GND")
	)
	(gr_poly
		(pts
			(arc
				(start 20.797266 -5.597398)
				(mid 20.431506 -5.597398)
				(end 20.797266 -5.597398)
			)
		)
		(stroke
			(width 0)
			(type solid)
		)
		(fill yes)
		(layer "B.Cu")
		(net "GND")
	)
	(gr_poly
		(pts
			(arc
				(start 20.797266 -4.32943)
				(mid 20.431506 -4.32943)
				(end 20.797266 -4.32943)
			)
		)
		(stroke
			(width 0)
			(type solid)
		)
		(fill yes)
		(layer "B.Cu")
		(net "GND")
	)
	(gr_poly
		(pts
			(arc
				(start 21.104098 -18.247106)
				(mid 20.738338 -18.247106)
				(end 21.104098 -18.247106)
			)
		)
		(stroke
			(width 0)
			(type solid)
		)
		(fill yes)
		(layer "B.Cu")
		(net "GND")
	)
	(gr_poly
		(pts
			(arc
				(start 21.104098 -16.979138)
				(mid 20.738338 -16.979138)
				(end 21.104098 -16.979138)
			)
		)
		(stroke
			(width 0)
			(type solid)
		)
		(fill yes)
		(layer "B.Cu")
		(net "GND")
	)
	(gr_poly
		(pts
			(arc
				(start 22.062186 -5.597398)
				(mid 21.696426 -5.597398)
				(end 22.062186 -5.597398)
			)
		)
		(stroke
			(width 0)
			(type solid)
		)
		(fill yes)
		(layer "B.Cu")
		(net "GND")
	)
	(gr_poly
		(pts
			(arc
				(start 22.062186 -4.32943)
				(mid 21.696426 -4.32943)
				(end 22.062186 -4.32943)
			)
		)
		(stroke
			(width 0)
			(type solid)
		)
		(fill yes)
		(layer "B.Cu")
		(net "GND")
	)
	(gr_poly
		(pts
			(arc
				(start 22.09292 -6.598158)
				(mid 21.72716 -6.598158)
				(end 22.09292 -6.598158)
			)
		)
		(stroke
			(width 0)
			(type solid)
		)
		(fill yes)
		(layer "B.Cu")
		(net "GND")
	)
	(gr_poly
		(pts
			(arc
				(start 22.369018 -18.247106)
				(mid 22.003258 -18.247106)
				(end 22.369018 -18.247106)
			)
		)
		(stroke
			(width 0)
			(type solid)
		)
		(fill yes)
		(layer "B.Cu")
		(net "GND")
	)
	(gr_poly
		(pts
			(arc
				(start 22.369018 -16.979138)
				(mid 22.003258 -16.979138)
				(end 22.369018 -16.979138)
			)
		)
		(stroke
			(width 0)
			(type solid)
		)
		(fill yes)
		(layer "B.Cu")
		(net "GND")
	)
	(gr_poly
		(pts
			(arc
				(start 22.572472 -4.963414)
				(mid 22.206712 -4.963414)
				(end 22.572472 -4.963414)
			)
		)
		(stroke
			(width 0)
			(type solid)
		)
		(fill yes)
		(layer "B.Cu")
		(net "GND")
	)
	(gr_poly
		(pts
			(arc
				(start 22.60092 -6.091174)
				(mid 22.23516 -6.091174)
				(end 22.60092 -6.091174)
			)
		)
		(stroke
			(width 0)
			(type solid)
		)
		(fill yes)
		(layer "B.Cu")
		(net "GND")
	)
	(gr_poly
		(pts
			(arc
				(start 22.854158 -17.61236)
				(mid 22.488398 -17.61236)
				(end 22.854158 -17.61236)
			)
		)
		(stroke
			(width 0)
			(type solid)
		)
		(fill yes)
		(layer "B.Cu")
		(net "GND")
	)
	(gr_poly
		(pts
			(arc
				(start 23.412958 -19.13636)
				(mid 23.047198 -19.13636)
				(end 23.412958 -19.13636)
			)
		)
		(stroke
			(width 0)
			(type solid)
		)
		(fill yes)
		(layer "B.Cu")
		(net "GND")
	)
	(gr_poly
		(pts
			(arc
				(start 23.859744 -6.091174)
				(mid 23.493984 -6.091174)
				(end 23.859744 -6.091174)
			)
		)
		(stroke
			(width 0)
			(type solid)
		)
		(fill yes)
		(layer "B.Cu")
		(net "GND")
	)
	(gr_poly
		(pts
			(arc
				(start 23.89759 -4.963414)
				(mid 23.53183 -4.963414)
				(end 23.89759 -4.963414)
			)
		)
		(stroke
			(width 0)
			(type solid)
		)
		(fill yes)
		(layer "B.Cu")
		(net "GND")
	)
	(gr_poly
		(pts
			(arc
				(start 23.898098 -19.771106)
				(mid 23.532338 -19.771106)
				(end 23.898098 -19.771106)
			)
		)
		(stroke
			(width 0)
			(type solid)
		)
		(fill yes)
		(layer "B.Cu")
		(net "GND")
	)
	(gr_poly
		(pts
			(arc
				(start 23.898098 -18.503138)
				(mid 23.532338 -18.503138)
				(end 23.898098 -18.503138)
			)
		)
		(stroke
			(width 0)
			(type solid)
		)
		(fill yes)
		(layer "B.Cu")
		(net "GND")
	)
	(gr_poly
		(pts
			(arc
				(start 24.367744 -6.598158)
				(mid 24.001984 -6.598158)
				(end 24.367744 -6.598158)
			)
		)
		(stroke
			(width 0)
			(type solid)
		)
		(fill yes)
		(layer "B.Cu")
		(net "GND")
	)
	(gr_poly
		(pts
			(arc
				(start 24.397462 -5.597398)
				(mid 24.031702 -5.597398)
				(end 24.397462 -5.597398)
			)
		)
		(stroke
			(width 0)
			(type solid)
		)
		(fill yes)
		(layer "B.Cu")
		(net "GND")
	)
	(gr_poly
		(pts
			(arc
				(start 24.397462 -4.32943)
				(mid 24.031702 -4.32943)
				(end 24.397462 -4.32943)
			)
		)
		(stroke
			(width 0)
			(type solid)
		)
		(fill yes)
		(layer "B.Cu")
		(net "GND")
	)
	(gr_poly
		(pts
			(arc
				(start 25.163018 -19.771106)
				(mid 24.797258 -19.771106)
				(end 25.163018 -19.771106)
			)
		)
		(stroke
			(width 0)
			(type solid)
		)
		(fill yes)
		(layer "B.Cu")
		(net "GND")
	)
	(gr_poly
		(pts
			(arc
				(start 25.163018 -18.503138)
				(mid 24.797258 -18.503138)
				(end 25.163018 -18.503138)
			)
		)
		(stroke
			(width 0)
			(type solid)
		)
		(fill yes)
		(layer "B.Cu")
		(net "GND")
	)
	(gr_poly
		(pts
			(arc
				(start 25.648158 -19.13636)
				(mid 25.282398 -19.13636)
				(end 25.648158 -19.13636)
			)
		)
		(stroke
			(width 0)
			(type solid)
		)
		(fill yes)
		(layer "B.Cu")
		(net "GND")
	)
	(gr_poly
		(pts
			(arc
				(start 25.662382 -5.597398)
				(mid 25.296622 -5.597398)
				(end 25.662382 -5.597398)
			)
		)
		(stroke
			(width 0)
			(type solid)
		)
		(fill yes)
		(layer "B.Cu")
		(net "GND")
	)
	(gr_poly
		(pts
			(arc
				(start 25.662382 -4.32943)
				(mid 25.296622 -4.32943)
				(end 25.662382 -4.32943)
			)
		)
		(stroke
			(width 0)
			(type solid)
		)
		(fill yes)
		(layer "B.Cu")
		(net "GND")
	)
	(gr_poly
		(pts
			(arc
				(start 25.692862 -6.598158)
				(mid 25.327102 -6.598158)
				(end 25.692862 -6.598158)
			)
		)
		(stroke
			(width 0)
			(type solid)
		)
		(fill yes)
		(layer "B.Cu")
		(net "GND")
	)
	(gr_poly
		(pts
			(arc
				(start 26.172414 -4.963414)
				(mid 25.806654 -4.963414)
				(end 26.172414 -4.963414)
			)
		)
		(stroke
			(width 0)
			(type solid)
		)
		(fill yes)
		(layer "B.Cu")
		(net "GND")
	)
	(gr_poly
		(pts
			(arc
				(start 26.200862 -6.091174)
				(mid 25.835102 -6.091174)
				(end 26.200862 -6.091174)
			)
		)
		(stroke
			(width 0)
			(type solid)
		)
		(fill yes)
		(layer "B.Cu")
		(net "GND")
	)
	(gr_poly
		(pts
			(arc
				(start 26.206958 -17.61236)
				(mid 25.841198 -17.61236)
				(end 26.206958 -17.61236)
			)
		)
		(stroke
			(width 0)
			(type solid)
		)
		(fill yes)
		(layer "B.Cu")
		(net "GND")
	)
	(gr_poly
		(pts
			(arc
				(start 26.692098 -18.247106)
				(mid 26.326338 -18.247106)
				(end 26.692098 -18.247106)
			)
		)
		(stroke
			(width 0)
			(type solid)
		)
		(fill yes)
		(layer "B.Cu")
		(net "GND")
	)
	(gr_poly
		(pts
			(arc
				(start 26.692098 -16.979138)
				(mid 26.326338 -16.979138)
				(end 26.692098 -16.979138)
			)
		)
		(stroke
			(width 0)
			(type solid)
		)
		(fill yes)
		(layer "B.Cu")
		(net "GND")
	)
	(gr_poly
		(pts
			(arc
				(start 27.459686 -6.091174)
				(mid 27.093926 -6.091174)
				(end 27.459686 -6.091174)
			)
		)
		(stroke
			(width 0)
			(type solid)
		)
		(fill yes)
		(layer "B.Cu")
		(net "GND")
	)
	(gr_poly
		(pts
			(arc
				(start 27.497532 -4.963414)
				(mid 27.131772 -4.963414)
				(end 27.497532 -4.963414)
			)
		)
		(stroke
			(width 0)
			(type solid)
		)
		(fill yes)
		(layer "B.Cu")
		(net "GND")
	)
	(gr_poly
		(pts
			(arc
				(start 27.957018 -18.247106)
				(mid 27.591258 -18.247106)
				(end 27.957018 -18.247106)
			)
		)
		(stroke
			(width 0)
			(type solid)
		)
		(fill yes)
		(layer "B.Cu")
		(net "GND")
	)
	(gr_poly
		(pts
			(arc
				(start 27.957018 -16.979138)
				(mid 27.591258 -16.979138)
				(end 27.957018 -16.979138)
			)
		)
		(stroke
			(width 0)
			(type solid)
		)
		(fill yes)
		(layer "B.Cu")
		(net "GND")
	)
	(gr_poly
		(pts
			(arc
				(start 27.967686 -6.598158)
				(mid 27.601926 -6.598158)
				(end 27.967686 -6.598158)
			)
		)
		(stroke
			(width 0)
			(type solid)
		)
		(fill yes)
		(layer "B.Cu")
		(net "GND")
	)
	(gr_poly
		(pts
			(arc
				(start 27.997404 -5.597398)
				(mid 27.631644 -5.597398)
				(end 27.997404 -5.597398)
			)
		)
		(stroke
			(width 0)
			(type solid)
		)
		(fill yes)
		(layer "B.Cu")
		(net "GND")
	)
	(gr_poly
		(pts
			(arc
				(start 27.997404 -4.32943)
				(mid 27.631644 -4.32943)
				(end 27.997404 -4.32943)
			)
		)
		(stroke
			(width 0)
			(type solid)
		)
		(fill yes)
		(layer "B.Cu")
		(net "GND")
	)
	(gr_poly
		(pts
			(arc
				(start 28.442158 -17.61236)
				(mid 28.076398 -17.61236)
				(end 28.442158 -17.61236)
			)
		)
		(stroke
			(width 0)
			(type solid)
		)
		(fill yes)
		(layer "B.Cu")
		(net "GND")
	)
	(gr_poly
		(pts
			(arc
				(start 29.000958 -19.13636)
				(mid 28.635198 -19.13636)
				(end 29.000958 -19.13636)
			)
		)
		(stroke
			(width 0)
			(type solid)
		)
		(fill yes)
		(layer "B.Cu")
		(net "GND")
	)
	(gr_poly
		(pts
			(arc
				(start 29.262324 -5.597398)
				(mid 28.896564 -5.597398)
				(end 29.262324 -5.597398)
			)
		)
		(stroke
			(width 0)
			(type solid)
		)
		(fill yes)
		(layer "B.Cu")
		(net "GND")
	)
	(gr_poly
		(pts
			(arc
				(start 29.262324 -4.32943)
				(mid 28.896564 -4.32943)
				(end 29.262324 -4.32943)
			)
		)
		(stroke
			(width 0)
			(type solid)
		)
		(fill yes)
		(layer "B.Cu")
		(net "GND")
	)
	(gr_poly
		(pts
			(arc
				(start 29.293058 -6.598158)
				(mid 28.927298 -6.598158)
				(end 29.293058 -6.598158)
			)
		)
		(stroke
			(width 0)
			(type solid)
		)
		(fill yes)
		(layer "B.Cu")
		(net "GND")
	)
	(gr_poly
		(pts
			(arc
				(start 29.486098 -19.771106)
				(mid 29.120338 -19.771106)
				(end 29.486098 -19.771106)
			)
		)
		(stroke
			(width 0)
			(type solid)
		)
		(fill yes)
		(layer "B.Cu")
		(net "GND")
	)
	(gr_poly
		(pts
			(arc
				(start 29.486098 -18.503138)
				(mid 29.120338 -18.503138)
				(end 29.486098 -18.503138)
			)
		)
		(stroke
			(width 0)
			(type solid)
		)
		(fill yes)
		(layer "B.Cu")
		(net "GND")
	)
	(gr_poly
		(pts
			(arc
				(start 29.772356 -4.963414)
				(mid 29.406596 -4.963414)
				(end 29.772356 -4.963414)
			)
		)
		(stroke
			(width 0)
			(type solid)
		)
		(fill yes)
		(layer "B.Cu")
		(net "GND")
	)
	(gr_poly
		(pts
			(arc
				(start 29.801058 -6.091174)
				(mid 29.435298 -6.091174)
				(end 29.801058 -6.091174)
			)
		)
		(stroke
			(width 0)
			(type solid)
		)
		(fill yes)
		(layer "B.Cu")
		(net "GND")
	)
	(gr_poly
		(pts
			(arc
				(start 30.751018 -19.771106)
				(mid 30.385258 -19.771106)
				(end 30.751018 -19.771106)
			)
		)
		(stroke
			(width 0)
			(type solid)
		)
		(fill yes)
		(layer "B.Cu")
		(net "GND")
	)
	(gr_poly
		(pts
			(arc
				(start 30.751018 -18.503138)
				(mid 30.385258 -18.503138)
				(end 30.751018 -18.503138)
			)
		)
		(stroke
			(width 0)
			(type solid)
		)
		(fill yes)
		(layer "B.Cu")
		(net "GND")
	)
	(gr_poly
		(pts
			(arc
				(start 31.059882 -6.091174)
				(mid 30.694122 -6.091174)
				(end 31.059882 -6.091174)
			)
		)
		(stroke
			(width 0)
			(type solid)
		)
		(fill yes)
		(layer "B.Cu")
		(net "GND")
	)
	(gr_poly
		(pts
			(arc
				(start 31.097728 -4.963414)
				(mid 30.731968 -4.963414)
				(end 31.097728 -4.963414)
			)
		)
		(stroke
			(width 0)
			(type solid)
		)
		(fill yes)
		(layer "B.Cu")
		(net "GND")
	)
	(gr_poly
		(pts
			(arc
				(start 31.236158 -19.13636)
				(mid 30.870398 -19.13636)
				(end 31.236158 -19.13636)
			)
		)
		(stroke
			(width 0)
			(type solid)
		)
		(fill yes)
		(layer "B.Cu")
		(net "GND")
	)
	(gr_poly
		(pts
			(arc
				(start 31.567882 -6.598158)
				(mid 31.202122 -6.598158)
				(end 31.567882 -6.598158)
			)
		)
		(stroke
			(width 0)
			(type solid)
		)
		(fill yes)
		(layer "B.Cu")
		(net "GND")
	)
	(gr_poly
		(pts
			(arc
				(start 31.598362 -5.597398)
				(mid 31.232602 -5.597398)
				(end 31.598362 -5.597398)
			)
		)
		(stroke
			(width 0)
			(type solid)
		)
		(fill yes)
		(layer "B.Cu")
		(net "GND")
	)
	(gr_poly
		(pts
			(arc
				(start 31.598362 -4.32943)
				(mid 31.232602 -4.32943)
				(end 31.598362 -4.32943)
			)
		)
		(stroke
			(width 0)
			(type solid)
		)
		(fill yes)
		(layer "B.Cu")
		(net "GND")
	)
	(gr_poly
		(pts
			(arc
				(start 31.794958 -17.613122)
				(mid 31.429198 -17.613122)
				(end 31.794958 -17.613122)
			)
		)
		(stroke
			(width 0)
			(type solid)
		)
		(fill yes)
		(layer "B.Cu")
		(net "GND")
	)
	(gr_poly
		(pts
			(arc
				(start 32.280098 -18.247868)
				(mid 31.914338 -18.247868)
				(end 32.280098 -18.247868)
			)
		)
		(stroke
			(width 0)
			(type solid)
		)
		(fill yes)
		(layer "B.Cu")
		(net "GND")
	)
	(gr_poly
		(pts
			(arc
				(start 32.280098 -16.9799)
				(mid 31.914338 -16.9799)
				(end 32.280098 -16.9799)
			)
		)
		(stroke
			(width 0)
			(type solid)
		)
		(fill yes)
		(layer "B.Cu")
		(net "GND")
	)
	(gr_poly
		(pts
			(arc
				(start 32.863282 -5.597398)
				(mid 32.497522 -5.597398)
				(end 32.863282 -5.597398)
			)
		)
		(stroke
			(width 0)
			(type solid)
		)
		(fill yes)
		(layer "B.Cu")
		(net "GND")
	)
	(gr_poly
		(pts
			(arc
				(start 32.863282 -4.32943)
				(mid 32.497522 -4.32943)
				(end 32.863282 -4.32943)
			)
		)
		(stroke
			(width 0)
			(type solid)
		)
		(fill yes)
		(layer "B.Cu")
		(net "GND")
	)
	(gr_poly
		(pts
			(arc
				(start 33.372552 -4.963414)
				(mid 33.006792 -4.963414)
				(end 33.372552 -4.963414)
			)
		)
		(stroke
			(width 0)
			(type solid)
		)
		(fill yes)
		(layer "B.Cu")
		(net "GND")
	)
	(gr_poly
		(pts
			(arc
				(start 33.545018 -18.247868)
				(mid 33.179258 -18.247868)
				(end 33.545018 -18.247868)
			)
		)
		(stroke
			(width 0)
			(type solid)
		)
		(fill yes)
		(layer "B.Cu")
		(net "GND")
	)
	(gr_poly
		(pts
			(arc
				(start 33.545018 -16.9799)
				(mid 33.179258 -16.9799)
				(end 33.545018 -16.9799)
			)
		)
		(stroke
			(width 0)
			(type solid)
		)
		(fill yes)
		(layer "B.Cu")
		(net "GND")
	)
	(gr_poly
		(pts
			(arc
				(start 34.030158 -17.613122)
				(mid 33.664398 -17.613122)
				(end 34.030158 -17.613122)
			)
		)
		(stroke
			(width 0)
			(type solid)
		)
		(fill yes)
		(layer "B.Cu")
		(net "GND")
	)
	(gr_poly
		(pts
			(arc
				(start 34.588958 -19.13636)
				(mid 34.223198 -19.13636)
				(end 34.588958 -19.13636)
			)
		)
		(stroke
			(width 0)
			(type solid)
		)
		(fill yes)
		(layer "B.Cu")
		(net "GND")
	)
	(gr_poly
		(pts
			(arc
				(start 35.074098 -19.771106)
				(mid 34.708338 -19.771106)
				(end 35.074098 -19.771106)
			)
		)
		(stroke
			(width 0)
			(type solid)
		)
		(fill yes)
		(layer "B.Cu")
		(net "GND")
	)
	(gr_poly
		(pts
			(arc
				(start 35.074098 -18.503138)
				(mid 34.708338 -18.503138)
				(end 35.074098 -18.503138)
			)
		)
		(stroke
			(width 0)
			(type solid)
		)
		(fill yes)
		(layer "B.Cu")
		(net "GND")
	)
	(gr_poly
		(pts
			(arc
				(start 36.339018 -19.771106)
				(mid 35.973258 -19.771106)
				(end 36.339018 -19.771106)
			)
		)
		(stroke
			(width 0)
			(type solid)
		)
		(fill yes)
		(layer "B.Cu")
		(net "GND")
	)
	(gr_poly
		(pts
			(arc
				(start 36.339018 -18.503138)
				(mid 35.973258 -18.503138)
				(end 36.339018 -18.503138)
			)
		)
		(stroke
			(width 0)
			(type solid)
		)
		(fill yes)
		(layer "B.Cu")
		(net "GND")
	)
	(gr_poly
		(pts
			(arc
				(start 36.824158 -19.13636)
				(mid 36.458398 -19.13636)
				(end 36.824158 -19.13636)
			)
		)
		(stroke
			(width 0)
			(type solid)
		)
		(fill yes)
		(layer "B.Cu")
		(net "GND")
	)
	(gr_poly
		(pts
			(arc
				(start 37.381942 -17.613122)
				(mid 37.016182 -17.613122)
				(end 37.381942 -17.613122)
			)
		)
		(stroke
			(width 0)
			(type solid)
		)
		(fill yes)
		(layer "B.Cu")
		(net "GND")
	)
	(gr_poly
		(pts
			(arc
				(start 37.867082 -18.247868)
				(mid 37.501322 -18.247868)
				(end 37.867082 -18.247868)
			)
		)
		(stroke
			(width 0)
			(type solid)
		)
		(fill yes)
		(layer "B.Cu")
		(net "GND")
	)
	(gr_poly
		(pts
			(arc
				(start 37.867082 -16.9799)
				(mid 37.501322 -16.9799)
				(end 37.867082 -16.9799)
			)
		)
		(stroke
			(width 0)
			(type solid)
		)
		(fill yes)
		(layer "B.Cu")
		(net "GND")
	)
	(gr_poly
		(pts
			(arc
				(start 38.403022 -6.598158)
				(mid 38.037262 -6.598158)
				(end 38.403022 -6.598158)
			)
		)
		(stroke
			(width 0)
			(type solid)
		)
		(fill yes)
		(layer "B.Cu")
		(net "GND")
	)
	(gr_poly
		(pts
			(arc
				(start 38.911022 -6.091174)
				(mid 38.545262 -6.091174)
				(end 38.911022 -6.091174)
			)
		)
		(stroke
			(width 0)
			(type solid)
		)
		(fill yes)
		(layer "B.Cu")
		(net "GND")
	)
	(gr_poly
		(pts
			(arc
				(start 39.132002 -18.247868)
				(mid 38.766242 -18.247868)
				(end 39.132002 -18.247868)
			)
		)
		(stroke
			(width 0)
			(type solid)
		)
		(fill yes)
		(layer "B.Cu")
		(net "GND")
	)
	(gr_poly
		(pts
			(arc
				(start 39.132002 -16.9799)
				(mid 38.766242 -16.9799)
				(end 39.132002 -16.9799)
			)
		)
		(stroke
			(width 0)
			(type solid)
		)
		(fill yes)
		(layer "B.Cu")
		(net "GND")
	)
	(gr_poly
		(pts
			(arc
				(start 39.617142 -17.613122)
				(mid 39.251382 -17.613122)
				(end 39.617142 -17.613122)
			)
		)
		(stroke
			(width 0)
			(type solid)
		)
		(fill yes)
		(layer "B.Cu")
		(net "GND")
	)
	(gr_poly
		(pts
			(arc
				(start 40.169846 -6.091174)
				(mid 39.804086 -6.091174)
				(end 40.169846 -6.091174)
			)
		)
		(stroke
			(width 0)
			(type solid)
		)
		(fill yes)
		(layer "B.Cu")
		(net "GND")
	)
	(gr_poly
		(pts
			(arc
				(start 40.207692 -4.963414)
				(mid 39.841932 -4.963414)
				(end 40.207692 -4.963414)
			)
		)
		(stroke
			(width 0)
			(type solid)
		)
		(fill yes)
		(layer "B.Cu")
		(net "GND")
	)
	(gr_poly
		(pts
			(arc
				(start 40.482774 -19.13636)
				(mid 40.117014 -19.13636)
				(end 40.482774 -19.13636)
			)
		)
		(stroke
			(width 0)
			(type solid)
		)
		(fill yes)
		(layer "B.Cu")
		(net "GND")
	)
	(gr_poly
		(pts
			(arc
				(start 40.677846 -6.598158)
				(mid 40.312086 -6.598158)
				(end 40.677846 -6.598158)
			)
		)
		(stroke
			(width 0)
			(type solid)
		)
		(fill yes)
		(layer "B.Cu")
		(net "GND")
	)
	(gr_poly
		(pts
			(arc
				(start 40.70731 -5.597398)
				(mid 40.34155 -5.597398)
				(end 40.70731 -5.597398)
			)
		)
		(stroke
			(width 0)
			(type solid)
		)
		(fill yes)
		(layer "B.Cu")
		(net "GND")
	)
	(gr_poly
		(pts
			(arc
				(start 40.70731 -4.32943)
				(mid 40.34155 -4.32943)
				(end 40.70731 -4.32943)
			)
		)
		(stroke
			(width 0)
			(type solid)
		)
		(fill yes)
		(layer "B.Cu")
		(net "GND")
	)
	(gr_poly
		(pts
			(arc
				(start 40.967914 -19.771106)
				(mid 40.602154 -19.771106)
				(end 40.967914 -19.771106)
			)
		)
		(stroke
			(width 0)
			(type solid)
		)
		(fill yes)
		(layer "B.Cu")
		(net "GND")
	)
	(gr_poly
		(pts
			(arc
				(start 40.967914 -18.503138)
				(mid 40.602154 -18.503138)
				(end 40.967914 -18.503138)
			)
		)
		(stroke
			(width 0)
			(type solid)
		)
		(fill yes)
		(layer "B.Cu")
		(net "GND")
	)
	(gr_poly
		(pts
			(arc
				(start 41.97223 -5.597398)
				(mid 41.60647 -5.597398)
				(end 41.97223 -5.597398)
			)
		)
		(stroke
			(width 0)
			(type solid)
		)
		(fill yes)
		(layer "B.Cu")
		(net "GND")
	)
	(gr_poly
		(pts
			(arc
				(start 41.97223 -4.32943)
				(mid 41.60647 -4.32943)
				(end 41.97223 -4.32943)
			)
		)
		(stroke
			(width 0)
			(type solid)
		)
		(fill yes)
		(layer "B.Cu")
		(net "GND")
	)
	(gr_poly
		(pts
			(arc
				(start 42.002964 -6.598158)
				(mid 41.637204 -6.598158)
				(end 42.002964 -6.598158)
			)
		)
		(stroke
			(width 0)
			(type solid)
		)
		(fill yes)
		(layer "B.Cu")
		(net "GND")
	)
	(gr_poly
		(pts
			(arc
				(start 42.232834 -19.771106)
				(mid 41.867074 -19.771106)
				(end 42.232834 -19.771106)
			)
		)
		(stroke
			(width 0)
			(type solid)
		)
		(fill yes)
		(layer "B.Cu")
		(net "GND")
	)
	(gr_poly
		(pts
			(arc
				(start 42.232834 -18.503138)
				(mid 41.867074 -18.503138)
				(end 42.232834 -18.503138)
			)
		)
		(stroke
			(width 0)
			(type solid)
		)
		(fill yes)
		(layer "B.Cu")
		(net "GND")
	)
	(gr_poly
		(pts
			(arc
				(start 42.482516 -4.963414)
				(mid 42.116756 -4.963414)
				(end 42.482516 -4.963414)
			)
		)
		(stroke
			(width 0)
			(type solid)
		)
		(fill yes)
		(layer "B.Cu")
		(net "GND")
	)
	(gr_poly
		(pts
			(arc
				(start 42.510964 -6.091174)
				(mid 42.145204 -6.091174)
				(end 42.510964 -6.091174)
			)
		)
		(stroke
			(width 0)
			(type solid)
		)
		(fill yes)
		(layer "B.Cu")
		(net "GND")
	)
	(gr_poly
		(pts
			(arc
				(start 42.717974 -19.13636)
				(mid 42.352214 -19.13636)
				(end 42.717974 -19.13636)
			)
		)
		(stroke
			(width 0)
			(type solid)
		)
		(fill yes)
		(layer "B.Cu")
		(net "GND")
	)
	(gr_poly
		(pts
			(arc
				(start 43.276774 -17.61236)
				(mid 42.911014 -17.61236)
				(end 43.276774 -17.61236)
			)
		)
		(stroke
			(width 0)
			(type solid)
		)
		(fill yes)
		(layer "B.Cu")
		(net "GND")
	)
	(gr_poly
		(pts
			(arc
				(start 43.761914 -18.247106)
				(mid 43.396154 -18.247106)
				(end 43.761914 -18.247106)
			)
		)
		(stroke
			(width 0)
			(type solid)
		)
		(fill yes)
		(layer "B.Cu")
		(net "GND")
	)
	(gr_poly
		(pts
			(arc
				(start 43.761914 -16.979138)
				(mid 43.396154 -16.979138)
				(end 43.761914 -16.979138)
			)
		)
		(stroke
			(width 0)
			(type solid)
		)
		(fill yes)
		(layer "B.Cu")
		(net "GND")
	)
	(gr_poly
		(pts
			(arc
				(start 43.769788 -6.091174)
				(mid 43.404028 -6.091174)
				(end 43.769788 -6.091174)
			)
		)
		(stroke
			(width 0)
			(type solid)
		)
		(fill yes)
		(layer "B.Cu")
		(net "GND")
	)
	(gr_poly
		(pts
			(arc
				(start 43.807634 -4.963414)
				(mid 43.441874 -4.963414)
				(end 43.807634 -4.963414)
			)
		)
		(stroke
			(width 0)
			(type solid)
		)
		(fill yes)
		(layer "B.Cu")
		(net "GND")
	)
	(gr_poly
		(pts
			(arc
				(start 44.277788 -6.598158)
				(mid 43.912028 -6.598158)
				(end 44.277788 -6.598158)
			)
		)
		(stroke
			(width 0)
			(type solid)
		)
		(fill yes)
		(layer "B.Cu")
		(net "GND")
	)
	(gr_poly
		(pts
			(arc
				(start 44.307506 -5.597398)
				(mid 43.941746 -5.597398)
				(end 44.307506 -5.597398)
			)
		)
		(stroke
			(width 0)
			(type solid)
		)
		(fill yes)
		(layer "B.Cu")
		(net "GND")
	)
	(gr_poly
		(pts
			(arc
				(start 44.307506 -4.32943)
				(mid 43.941746 -4.32943)
				(end 44.307506 -4.32943)
			)
		)
		(stroke
			(width 0)
			(type solid)
		)
		(fill yes)
		(layer "B.Cu")
		(net "GND")
	)
	(gr_poly
		(pts
			(arc
				(start 45.026834 -18.247106)
				(mid 44.661074 -18.247106)
				(end 45.026834 -18.247106)
			)
		)
		(stroke
			(width 0)
			(type solid)
		)
		(fill yes)
		(layer "B.Cu")
		(net "GND")
	)
	(gr_poly
		(pts
			(arc
				(start 45.026834 -16.979138)
				(mid 44.661074 -16.979138)
				(end 45.026834 -16.979138)
			)
		)
		(stroke
			(width 0)
			(type solid)
		)
		(fill yes)
		(layer "B.Cu")
		(net "GND")
	)
	(gr_poly
		(pts
			(arc
				(start 45.511974 -17.61236)
				(mid 45.146214 -17.61236)
				(end 45.511974 -17.61236)
			)
		)
		(stroke
			(width 0)
			(type solid)
		)
		(fill yes)
		(layer "B.Cu")
		(net "GND")
	)
	(gr_poly
		(pts
			(arc
				(start 45.572426 -5.597398)
				(mid 45.206666 -5.597398)
				(end 45.572426 -5.597398)
			)
		)
		(stroke
			(width 0)
			(type solid)
		)
		(fill yes)
		(layer "B.Cu")
		(net "GND")
	)
	(gr_poly
		(pts
			(arc
				(start 45.572426 -4.32943)
				(mid 45.206666 -4.32943)
				(end 45.572426 -4.32943)
			)
		)
		(stroke
			(width 0)
			(type solid)
		)
		(fill yes)
		(layer "B.Cu")
		(net "GND")
	)
	(gr_poly
		(pts
			(arc
				(start 46.069758 -19.137122)
				(mid 45.703998 -19.137122)
				(end 46.069758 -19.137122)
			)
		)
		(stroke
			(width 0)
			(type solid)
		)
		(fill yes)
		(layer "B.Cu")
		(net "GND")
	)
	(gr_poly
		(pts
			(arc
				(start 46.082458 -4.963414)
				(mid 45.716698 -4.963414)
				(end 46.082458 -4.963414)
			)
		)
		(stroke
			(width 0)
			(type solid)
		)
		(fill yes)
		(layer "B.Cu")
		(net "GND")
	)
	(gr_poly
		(pts
			(arc
				(start 46.554898 -19.771868)
				(mid 46.189138 -19.771868)
				(end 46.554898 -19.771868)
			)
		)
		(stroke
			(width 0)
			(type solid)
		)
		(fill yes)
		(layer "B.Cu")
		(net "GND")
	)
	(gr_poly
		(pts
			(arc
				(start 46.554898 -18.5039)
				(mid 46.189138 -18.5039)
				(end 46.554898 -18.5039)
			)
		)
		(stroke
			(width 0)
			(type solid)
		)
		(fill yes)
		(layer "B.Cu")
		(net "GND")
	)
	(gr_poly
		(pts
			(arc
				(start 47.819818 -19.771868)
				(mid 47.454058 -19.771868)
				(end 47.819818 -19.771868)
			)
		)
		(stroke
			(width 0)
			(type solid)
		)
		(fill yes)
		(layer "B.Cu")
		(net "GND")
	)
	(gr_poly
		(pts
			(arc
				(start 47.819818 -18.5039)
				(mid 47.454058 -18.5039)
				(end 47.819818 -18.5039)
			)
		)
		(stroke
			(width 0)
			(type solid)
		)
		(fill yes)
		(layer "B.Cu")
		(net "GND")
	)
	(gr_poly
		(pts
			(arc
				(start 48.304958 -19.137122)
				(mid 47.939198 -19.137122)
				(end 48.304958 -19.137122)
			)
		)
		(stroke
			(width 0)
			(type solid)
		)
		(fill yes)
		(layer "B.Cu")
		(net "GND")
	)
	(gr_poly
		(pts
			(arc
				(start 48.864774 -17.61236)
				(mid 48.499014 -17.61236)
				(end 48.864774 -17.61236)
			)
		)
		(stroke
			(width 0)
			(type solid)
		)
		(fill yes)
		(layer "B.Cu")
		(net "GND")
	)
	(gr_poly
		(pts
			(arc
				(start 49.349914 -18.247106)
				(mid 48.984154 -18.247106)
				(end 49.349914 -18.247106)
			)
		)
		(stroke
			(width 0)
			(type solid)
		)
		(fill yes)
		(layer "B.Cu")
		(net "GND")
	)
	(gr_poly
		(pts
			(arc
				(start 49.349914 -16.979138)
				(mid 48.984154 -16.979138)
				(end 49.349914 -16.979138)
			)
		)
		(stroke
			(width 0)
			(type solid)
		)
		(fill yes)
		(layer "B.Cu")
		(net "GND")
	)
	(gr_poly
		(pts
			(arc
				(start 49.613058 -6.598158)
				(mid 49.247298 -6.598158)
				(end 49.613058 -6.598158)
			)
		)
		(stroke
			(width 0)
			(type solid)
		)
		(fill yes)
		(layer "B.Cu")
		(net "GND")
	)
	(gr_poly
		(pts
			(arc
				(start 50.121058 -6.091174)
				(mid 49.755298 -6.091174)
				(end 50.121058 -6.091174)
			)
		)
		(stroke
			(width 0)
			(type solid)
		)
		(fill yes)
		(layer "B.Cu")
		(net "GND")
	)
	(gr_poly
		(pts
			(arc
				(start 50.614834 -18.247106)
				(mid 50.249074 -18.247106)
				(end 50.614834 -18.247106)
			)
		)
		(stroke
			(width 0)
			(type solid)
		)
		(fill yes)
		(layer "B.Cu")
		(net "GND")
	)
	(gr_poly
		(pts
			(arc
				(start 50.614834 -16.979138)
				(mid 50.249074 -16.979138)
				(end 50.614834 -16.979138)
			)
		)
		(stroke
			(width 0)
			(type solid)
		)
		(fill yes)
		(layer "B.Cu")
		(net "GND")
	)
	(gr_poly
		(pts
			(arc
				(start 51.099974 -17.61236)
				(mid 50.734214 -17.61236)
				(end 51.099974 -17.61236)
			)
		)
		(stroke
			(width 0)
			(type solid)
		)
		(fill yes)
		(layer "B.Cu")
		(net "GND")
	)
	(gr_poly
		(pts
			(arc
				(start 51.379882 -6.091174)
				(mid 51.014122 -6.091174)
				(end 51.379882 -6.091174)
			)
		)
		(stroke
			(width 0)
			(type solid)
		)
		(fill yes)
		(layer "B.Cu")
		(net "GND")
	)
	(gr_poly
		(pts
			(arc
				(start 51.417728 -4.963414)
				(mid 51.051968 -4.963414)
				(end 51.417728 -4.963414)
			)
		)
		(stroke
			(width 0)
			(type solid)
		)
		(fill yes)
		(layer "B.Cu")
		(net "GND")
	)
	(gr_poly
		(pts
			(arc
				(start 51.69281 -19.13636)
				(mid 51.32705 -19.13636)
				(end 51.69281 -19.13636)
			)
		)
		(stroke
			(width 0)
			(type solid)
		)
		(fill yes)
		(layer "B.Cu")
		(net "GND")
	)
	(gr_poly
		(pts
			(arc
				(start 51.887882 -6.598158)
				(mid 51.522122 -6.598158)
				(end 51.887882 -6.598158)
			)
		)
		(stroke
			(width 0)
			(type solid)
		)
		(fill yes)
		(layer "B.Cu")
		(net "GND")
	)
	(gr_poly
		(pts
			(arc
				(start 51.917346 -5.597398)
				(mid 51.551586 -5.597398)
				(end 51.917346 -5.597398)
			)
		)
		(stroke
			(width 0)
			(type solid)
		)
		(fill yes)
		(layer "B.Cu")
		(net "GND")
	)
	(gr_poly
		(pts
			(arc
				(start 51.917346 -4.32943)
				(mid 51.551586 -4.32943)
				(end 51.917346 -4.32943)
			)
		)
		(stroke
			(width 0)
			(type solid)
		)
		(fill yes)
		(layer "B.Cu")
		(net "GND")
	)
	(gr_poly
		(pts
			(arc
				(start 52.17795 -19.771106)
				(mid 51.81219 -19.771106)
				(end 52.17795 -19.771106)
			)
		)
		(stroke
			(width 0)
			(type solid)
		)
		(fill yes)
		(layer "B.Cu")
		(net "GND")
	)
	(gr_poly
		(pts
			(arc
				(start 52.17795 -18.503138)
				(mid 51.81219 -18.503138)
				(end 52.17795 -18.503138)
			)
		)
		(stroke
			(width 0)
			(type solid)
		)
		(fill yes)
		(layer "B.Cu")
		(net "GND")
	)
	(gr_poly
		(pts
			(arc
				(start 53.182266 -5.597398)
				(mid 52.816506 -5.597398)
				(end 53.182266 -5.597398)
			)
		)
		(stroke
			(width 0)
			(type solid)
		)
		(fill yes)
		(layer "B.Cu")
		(net "GND")
	)
	(gr_poly
		(pts
			(arc
				(start 53.182266 -4.32943)
				(mid 52.816506 -4.32943)
				(end 53.182266 -4.32943)
			)
		)
		(stroke
			(width 0)
			(type solid)
		)
		(fill yes)
		(layer "B.Cu")
		(net "GND")
	)
	(gr_poly
		(pts
			(arc
				(start 53.213 -6.598158)
				(mid 52.84724 -6.598158)
				(end 53.213 -6.598158)
			)
		)
		(stroke
			(width 0)
			(type solid)
		)
		(fill yes)
		(layer "B.Cu")
		(net "GND")
	)
	(gr_poly
		(pts
			(arc
				(start 53.44287 -19.771106)
				(mid 53.07711 -19.771106)
				(end 53.44287 -19.771106)
			)
		)
		(stroke
			(width 0)
			(type solid)
		)
		(fill yes)
		(layer "B.Cu")
		(net "GND")
	)
	(gr_poly
		(pts
			(arc
				(start 53.44287 -18.503138)
				(mid 53.07711 -18.503138)
				(end 53.44287 -18.503138)
			)
		)
		(stroke
			(width 0)
			(type solid)
		)
		(fill yes)
		(layer "B.Cu")
		(net "GND")
	)
	(gr_poly
		(pts
			(arc
				(start 53.692552 -4.963414)
				(mid 53.326792 -4.963414)
				(end 53.692552 -4.963414)
			)
		)
		(stroke
			(width 0)
			(type solid)
		)
		(fill yes)
		(layer "B.Cu")
		(net "GND")
	)
	(gr_poly
		(pts
			(arc
				(start 53.721 -6.091174)
				(mid 53.35524 -6.091174)
				(end 53.721 -6.091174)
			)
		)
		(stroke
			(width 0)
			(type solid)
		)
		(fill yes)
		(layer "B.Cu")
		(net "GND")
	)
	(gr_poly
		(pts
			(arc
				(start 53.92801 -19.13636)
				(mid 53.56225 -19.13636)
				(end 53.92801 -19.13636)
			)
		)
		(stroke
			(width 0)
			(type solid)
		)
		(fill yes)
		(layer "B.Cu")
		(net "GND")
	)
	(gr_poly
		(pts
			(arc
				(start 54.485794 -17.613122)
				(mid 54.120034 -17.613122)
				(end 54.485794 -17.613122)
			)
		)
		(stroke
			(width 0)
			(type solid)
		)
		(fill yes)
		(layer "B.Cu")
		(net "GND")
	)
	(gr_poly
		(pts
			(arc
				(start 54.970934 -18.247868)
				(mid 54.605174 -18.247868)
				(end 54.970934 -18.247868)
			)
		)
		(stroke
			(width 0)
			(type solid)
		)
		(fill yes)
		(layer "B.Cu")
		(net "GND")
	)
	(gr_poly
		(pts
			(arc
				(start 54.970934 -16.9799)
				(mid 54.605174 -16.9799)
				(end 54.970934 -16.9799)
			)
		)
		(stroke
			(width 0)
			(type solid)
		)
		(fill yes)
		(layer "B.Cu")
		(net "GND")
	)
	(gr_poly
		(pts
			(arc
				(start 54.979824 -6.091174)
				(mid 54.614064 -6.091174)
				(end 54.979824 -6.091174)
			)
		)
		(stroke
			(width 0)
			(type solid)
		)
		(fill yes)
		(layer "B.Cu")
		(net "GND")
	)
	(gr_poly
		(pts
			(arc
				(start 55.01767 -4.963414)
				(mid 54.65191 -4.963414)
				(end 55.01767 -4.963414)
			)
		)
		(stroke
			(width 0)
			(type solid)
		)
		(fill yes)
		(layer "B.Cu")
		(net "GND")
	)
	(gr_poly
		(pts
			(arc
				(start 55.487824 -6.598158)
				(mid 55.122064 -6.598158)
				(end 55.487824 -6.598158)
			)
		)
		(stroke
			(width 0)
			(type solid)
		)
		(fill yes)
		(layer "B.Cu")
		(net "GND")
	)
	(gr_poly
		(pts
			(arc
				(start 55.517542 -5.597398)
				(mid 55.151782 -5.597398)
				(end 55.517542 -5.597398)
			)
		)
		(stroke
			(width 0)
			(type solid)
		)
		(fill yes)
		(layer "B.Cu")
		(net "GND")
	)
	(gr_poly
		(pts
			(arc
				(start 55.517542 -4.32943)
				(mid 55.151782 -4.32943)
				(end 55.517542 -4.32943)
			)
		)
		(stroke
			(width 0)
			(type solid)
		)
		(fill yes)
		(layer "B.Cu")
		(net "GND")
	)
	(gr_poly
		(pts
			(arc
				(start 56.235854 -18.247868)
				(mid 55.870094 -18.247868)
				(end 56.235854 -18.247868)
			)
		)
		(stroke
			(width 0)
			(type solid)
		)
		(fill yes)
		(layer "B.Cu")
		(net "GND")
	)
	(gr_poly
		(pts
			(arc
				(start 56.235854 -16.9799)
				(mid 55.870094 -16.9799)
				(end 56.235854 -16.9799)
			)
		)
		(stroke
			(width 0)
			(type solid)
		)
		(fill yes)
		(layer "B.Cu")
		(net "GND")
	)
	(gr_poly
		(pts
			(arc
				(start 56.720994 -17.613122)
				(mid 56.355234 -17.613122)
				(end 56.720994 -17.613122)
			)
		)
		(stroke
			(width 0)
			(type solid)
		)
		(fill yes)
		(layer "B.Cu")
		(net "GND")
	)
	(gr_poly
		(pts
			(arc
				(start 56.782462 -5.597398)
				(mid 56.416702 -5.597398)
				(end 56.782462 -5.597398)
			)
		)
		(stroke
			(width 0)
			(type solid)
		)
		(fill yes)
		(layer "B.Cu")
		(net "GND")
	)
	(gr_poly
		(pts
			(arc
				(start 56.782462 -4.32943)
				(mid 56.416702 -4.32943)
				(end 56.782462 -4.32943)
			)
		)
		(stroke
			(width 0)
			(type solid)
		)
		(fill yes)
		(layer "B.Cu")
		(net "GND")
	)
	(gr_poly
		(pts
			(arc
				(start 57.28081 -19.13636)
				(mid 56.91505 -19.13636)
				(end 57.28081 -19.13636)
			)
		)
		(stroke
			(width 0)
			(type solid)
		)
		(fill yes)
		(layer "B.Cu")
		(net "GND")
	)
	(gr_poly
		(pts
			(arc
				(start 57.292494 -4.963414)
				(mid 56.926734 -4.963414)
				(end 57.292494 -4.963414)
			)
		)
		(stroke
			(width 0)
			(type solid)
		)
		(fill yes)
		(layer "B.Cu")
		(net "GND")
	)
	(gr_poly
		(pts
			(arc
				(start 57.76595 -19.771106)
				(mid 57.40019 -19.771106)
				(end 57.76595 -19.771106)
			)
		)
		(stroke
			(width 0)
			(type solid)
		)
		(fill yes)
		(layer "B.Cu")
		(net "GND")
	)
	(gr_poly
		(pts
			(arc
				(start 57.76595 -18.503138)
				(mid 57.40019 -18.503138)
				(end 57.76595 -18.503138)
			)
		)
		(stroke
			(width 0)
			(type solid)
		)
		(fill yes)
		(layer "B.Cu")
		(net "GND")
	)
	(gr_poly
		(pts
			(arc
				(start 59.03087 -19.771106)
				(mid 58.66511 -19.771106)
				(end 59.03087 -19.771106)
			)
		)
		(stroke
			(width 0)
			(type solid)
		)
		(fill yes)
		(layer "B.Cu")
		(net "GND")
	)
	(gr_poly
		(pts
			(arc
				(start 59.03087 -18.503138)
				(mid 58.66511 -18.503138)
				(end 59.03087 -18.503138)
			)
		)
		(stroke
			(width 0)
			(type solid)
		)
		(fill yes)
		(layer "B.Cu")
		(net "GND")
	)
	(gr_poly
		(pts
			(arc
				(start 59.51601 -19.13636)
				(mid 59.15025 -19.13636)
				(end 59.51601 -19.13636)
			)
		)
		(stroke
			(width 0)
			(type solid)
		)
		(fill yes)
		(layer "B.Cu")
		(net "GND")
	)
	(gr_poly
		(pts
			(arc
				(start 131.73329 -10.733278)
				(mid 131.36753 -10.733278)
				(end 131.73329 -10.733278)
			)
		)
		(stroke
			(width 0)
			(type solid)
		)
		(fill yes)
		(layer "B.Cu")
		(net "GND")
	)
	(gr_poly
		(pts
			(arc
				(start 133.533134 -10.733278)
				(mid 133.167374 -10.733278)
				(end 133.533134 -10.733278)
			)
		)
		(stroke
			(width 0)
			(type solid)
		)
		(fill yes)
		(layer "B.Cu")
		(net "GND")
	)
	(gr_poly
		(pts
			(arc
				(start 221.012004 -191.399414)
				(mid 220.646244 -191.399414)
				(end 221.012004 -191.399414)
			)
		)
		(stroke
			(width 0)
			(type solid)
		)
		(fill yes)
		(layer "B.Cu")
		(net "GND")
	)
	(gr_poly
		(pts
			(arc
				(start 221.921324 -191.376554)
				(mid 221.555564 -191.376554)
				(end 221.921324 -191.376554)
			)
		)
		(stroke
			(width 0)
			(type solid)
		)
		(fill yes)
		(layer "B.Cu")
		(net "GND")
	)
	(gr_poly
		(pts
			(arc
				(start 389.530844 -17.61236)
				(mid 389.165084 -17.61236)
				(end 389.530844 -17.61236)
			)
		)
		(stroke
			(width 0)
			(type solid)
		)
		(fill yes)
		(layer "B.Cu")
		(net "GND")
	)
	(gr_poly
		(pts
			(arc
				(start 390.015984 -18.247106)
				(mid 389.650224 -18.247106)
				(end 390.015984 -18.247106)
			)
		)
		(stroke
			(width 0)
			(type solid)
		)
		(fill yes)
		(layer "B.Cu")
		(net "GND")
	)
	(gr_poly
		(pts
			(arc
				(start 390.015984 -16.979138)
				(mid 389.650224 -16.979138)
				(end 390.015984 -16.979138)
			)
		)
		(stroke
			(width 0)
			(type solid)
		)
		(fill yes)
		(layer "B.Cu")
		(net "GND")
	)
	(gr_poly
		(pts
			(arc
				(start 391.280904 -18.247106)
				(mid 390.915144 -18.247106)
				(end 391.280904 -18.247106)
			)
		)
		(stroke
			(width 0)
			(type solid)
		)
		(fill yes)
		(layer "B.Cu")
		(net "GND")
	)
	(gr_poly
		(pts
			(arc
				(start 391.280904 -16.979138)
				(mid 390.915144 -16.979138)
				(end 391.280904 -16.979138)
			)
		)
		(stroke
			(width 0)
			(type solid)
		)
		(fill yes)
		(layer "B.Cu")
		(net "GND")
	)
	(gr_poly
		(pts
			(arc
				(start 391.766044 -17.61236)
				(mid 391.400284 -17.61236)
				(end 391.766044 -17.61236)
			)
		)
		(stroke
			(width 0)
			(type solid)
		)
		(fill yes)
		(layer "B.Cu")
		(net "GND")
	)
	(gr_poly
		(pts
			(arc
				(start 392.323828 -19.137122)
				(mid 391.958068 -19.137122)
				(end 392.323828 -19.137122)
			)
		)
		(stroke
			(width 0)
			(type solid)
		)
		(fill yes)
		(layer "B.Cu")
		(net "GND")
	)
	(gr_poly
		(pts
			(arc
				(start 392.808968 -19.771868)
				(mid 392.443208 -19.771868)
				(end 392.808968 -19.771868)
			)
		)
		(stroke
			(width 0)
			(type solid)
		)
		(fill yes)
		(layer "B.Cu")
		(net "GND")
	)
	(gr_poly
		(pts
			(arc
				(start 392.808968 -18.5039)
				(mid 392.443208 -18.5039)
				(end 392.808968 -18.5039)
			)
		)
		(stroke
			(width 0)
			(type solid)
		)
		(fill yes)
		(layer "B.Cu")
		(net "GND")
	)
	(gr_poly
		(pts
			(arc
				(start 392.992864 -6.598158)
				(mid 392.627104 -6.598158)
				(end 392.992864 -6.598158)
			)
		)
		(stroke
			(width 0)
			(type solid)
		)
		(fill yes)
		(layer "B.Cu")
		(net "GND")
	)
	(gr_poly
		(pts
			(arc
				(start 393.500864 -6.091174)
				(mid 393.135104 -6.091174)
				(end 393.500864 -6.091174)
			)
		)
		(stroke
			(width 0)
			(type solid)
		)
		(fill yes)
		(layer "B.Cu")
		(net "GND")
	)
	(gr_poly
		(pts
			(arc
				(start 394.073888 -19.771868)
				(mid 393.708128 -19.771868)
				(end 394.073888 -19.771868)
			)
		)
		(stroke
			(width 0)
			(type solid)
		)
		(fill yes)
		(layer "B.Cu")
		(net "GND")
	)
	(gr_poly
		(pts
			(arc
				(start 394.073888 -18.5039)
				(mid 393.708128 -18.5039)
				(end 394.073888 -18.5039)
			)
		)
		(stroke
			(width 0)
			(type solid)
		)
		(fill yes)
		(layer "B.Cu")
		(net "GND")
	)
	(gr_poly
		(pts
			(arc
				(start 394.559028 -19.137122)
				(mid 394.193268 -19.137122)
				(end 394.559028 -19.137122)
			)
		)
		(stroke
			(width 0)
			(type solid)
		)
		(fill yes)
		(layer "B.Cu")
		(net "GND")
	)
	(gr_poly
		(pts
			(arc
				(start 394.759688 -6.091174)
				(mid 394.393928 -6.091174)
				(end 394.759688 -6.091174)
			)
		)
		(stroke
			(width 0)
			(type solid)
		)
		(fill yes)
		(layer "B.Cu")
		(net "GND")
	)
	(gr_poly
		(pts
			(arc
				(start 394.797534 -4.963414)
				(mid 394.431774 -4.963414)
				(end 394.797534 -4.963414)
			)
		)
		(stroke
			(width 0)
			(type solid)
		)
		(fill yes)
		(layer "B.Cu")
		(net "GND")
	)
	(gr_poly
		(pts
			(arc
				(start 395.118844 -17.61236)
				(mid 394.753084 -17.61236)
				(end 395.118844 -17.61236)
			)
		)
		(stroke
			(width 0)
			(type solid)
		)
		(fill yes)
		(layer "B.Cu")
		(net "GND")
	)
	(gr_poly
		(pts
			(arc
				(start 395.267688 -6.598158)
				(mid 394.901928 -6.598158)
				(end 395.267688 -6.598158)
			)
		)
		(stroke
			(width 0)
			(type solid)
		)
		(fill yes)
		(layer "B.Cu")
		(net "GND")
	)
	(gr_poly
		(pts
			(arc
				(start 395.297152 -5.597398)
				(mid 394.931392 -5.597398)
				(end 395.297152 -5.597398)
			)
		)
		(stroke
			(width 0)
			(type solid)
		)
		(fill yes)
		(layer "B.Cu")
		(net "GND")
	)
	(gr_poly
		(pts
			(arc
				(start 395.297152 -4.32943)
				(mid 394.931392 -4.32943)
				(end 395.297152 -4.32943)
			)
		)
		(stroke
			(width 0)
			(type solid)
		)
		(fill yes)
		(layer "B.Cu")
		(net "GND")
	)
	(gr_poly
		(pts
			(arc
				(start 395.603984 -18.247106)
				(mid 395.238224 -18.247106)
				(end 395.603984 -18.247106)
			)
		)
		(stroke
			(width 0)
			(type solid)
		)
		(fill yes)
		(layer "B.Cu")
		(net "GND")
	)
	(gr_poly
		(pts
			(arc
				(start 395.603984 -16.979138)
				(mid 395.238224 -16.979138)
				(end 395.603984 -16.979138)
			)
		)
		(stroke
			(width 0)
			(type solid)
		)
		(fill yes)
		(layer "B.Cu")
		(net "GND")
	)
	(gr_poly
		(pts
			(arc
				(start 396.562072 -5.597398)
				(mid 396.196312 -5.597398)
				(end 396.562072 -5.597398)
			)
		)
		(stroke
			(width 0)
			(type solid)
		)
		(fill yes)
		(layer "B.Cu")
		(net "GND")
	)
	(gr_poly
		(pts
			(arc
				(start 396.562072 -4.32943)
				(mid 396.196312 -4.32943)
				(end 396.562072 -4.32943)
			)
		)
		(stroke
			(width 0)
			(type solid)
		)
		(fill yes)
		(layer "B.Cu")
		(net "GND")
	)
	(gr_poly
		(pts
			(arc
				(start 396.592806 -6.598158)
				(mid 396.227046 -6.598158)
				(end 396.592806 -6.598158)
			)
		)
		(stroke
			(width 0)
			(type solid)
		)
		(fill yes)
		(layer "B.Cu")
		(net "GND")
	)
	(gr_poly
		(pts
			(arc
				(start 396.868904 -18.247106)
				(mid 396.503144 -18.247106)
				(end 396.868904 -18.247106)
			)
		)
		(stroke
			(width 0)
			(type solid)
		)
		(fill yes)
		(layer "B.Cu")
		(net "GND")
	)
	(gr_poly
		(pts
			(arc
				(start 396.868904 -16.979138)
				(mid 396.503144 -16.979138)
				(end 396.868904 -16.979138)
			)
		)
		(stroke
			(width 0)
			(type solid)
		)
		(fill yes)
		(layer "B.Cu")
		(net "GND")
	)
	(gr_poly
		(pts
			(arc
				(start 397.072358 -4.963414)
				(mid 396.706598 -4.963414)
				(end 397.072358 -4.963414)
			)
		)
		(stroke
			(width 0)
			(type solid)
		)
		(fill yes)
		(layer "B.Cu")
		(net "GND")
	)
	(gr_poly
		(pts
			(arc
				(start 397.100806 -6.091174)
				(mid 396.735046 -6.091174)
				(end 397.100806 -6.091174)
			)
		)
		(stroke
			(width 0)
			(type solid)
		)
		(fill yes)
		(layer "B.Cu")
		(net "GND")
	)
	(gr_poly
		(pts
			(arc
				(start 397.354044 -17.61236)
				(mid 396.988284 -17.61236)
				(end 397.354044 -17.61236)
			)
		)
		(stroke
			(width 0)
			(type solid)
		)
		(fill yes)
		(layer "B.Cu")
		(net "GND")
	)
	(gr_poly
		(pts
			(arc
				(start 397.912844 -19.13636)
				(mid 397.547084 -19.13636)
				(end 397.912844 -19.13636)
			)
		)
		(stroke
			(width 0)
			(type solid)
		)
		(fill yes)
		(layer "B.Cu")
		(net "GND")
	)
	(gr_poly
		(pts
			(arc
				(start 398.35963 -6.091174)
				(mid 397.99387 -6.091174)
				(end 398.35963 -6.091174)
			)
		)
		(stroke
			(width 0)
			(type solid)
		)
		(fill yes)
		(layer "B.Cu")
		(net "GND")
	)
	(gr_poly
		(pts
			(arc
				(start 398.397476 -4.963414)
				(mid 398.031716 -4.963414)
				(end 398.397476 -4.963414)
			)
		)
		(stroke
			(width 0)
			(type solid)
		)
		(fill yes)
		(layer "B.Cu")
		(net "GND")
	)
	(gr_poly
		(pts
			(arc
				(start 398.397984 -19.771106)
				(mid 398.032224 -19.771106)
				(end 398.397984 -19.771106)
			)
		)
		(stroke
			(width 0)
			(type solid)
		)
		(fill yes)
		(layer "B.Cu")
		(net "GND")
	)
	(gr_poly
		(pts
			(arc
				(start 398.397984 -18.503138)
				(mid 398.032224 -18.503138)
				(end 398.397984 -18.503138)
			)
		)
		(stroke
			(width 0)
			(type solid)
		)
		(fill yes)
		(layer "B.Cu")
		(net "GND")
	)
	(gr_poly
		(pts
			(arc
				(start 398.86763 -6.598158)
				(mid 398.50187 -6.598158)
				(end 398.86763 -6.598158)
			)
		)
		(stroke
			(width 0)
			(type solid)
		)
		(fill yes)
		(layer "B.Cu")
		(net "GND")
	)
	(gr_poly
		(pts
			(arc
				(start 398.897348 -5.597398)
				(mid 398.531588 -5.597398)
				(end 398.897348 -5.597398)
			)
		)
		(stroke
			(width 0)
			(type solid)
		)
		(fill yes)
		(layer "B.Cu")
		(net "GND")
	)
	(gr_poly
		(pts
			(arc
				(start 398.897348 -4.32943)
				(mid 398.531588 -4.32943)
				(end 398.897348 -4.32943)
			)
		)
		(stroke
			(width 0)
			(type solid)
		)
		(fill yes)
		(layer "B.Cu")
		(net "GND")
	)
	(gr_poly
		(pts
			(arc
				(start 399.662904 -19.771106)
				(mid 399.297144 -19.771106)
				(end 399.662904 -19.771106)
			)
		)
		(stroke
			(width 0)
			(type solid)
		)
		(fill yes)
		(layer "B.Cu")
		(net "GND")
	)
	(gr_poly
		(pts
			(arc
				(start 399.662904 -18.503138)
				(mid 399.297144 -18.503138)
				(end 399.662904 -18.503138)
			)
		)
		(stroke
			(width 0)
			(type solid)
		)
		(fill yes)
		(layer "B.Cu")
		(net "GND")
	)
	(gr_poly
		(pts
			(arc
				(start 400.148044 -19.13636)
				(mid 399.782284 -19.13636)
				(end 400.148044 -19.13636)
			)
		)
		(stroke
			(width 0)
			(type solid)
		)
		(fill yes)
		(layer "B.Cu")
		(net "GND")
	)
	(gr_poly
		(pts
			(arc
				(start 400.162268 -5.597398)
				(mid 399.796508 -5.597398)
				(end 400.162268 -5.597398)
			)
		)
		(stroke
			(width 0)
			(type solid)
		)
		(fill yes)
		(layer "B.Cu")
		(net "GND")
	)
	(gr_poly
		(pts
			(arc
				(start 400.162268 -4.32943)
				(mid 399.796508 -4.32943)
				(end 400.162268 -4.32943)
			)
		)
		(stroke
			(width 0)
			(type solid)
		)
		(fill yes)
		(layer "B.Cu")
		(net "GND")
	)
	(gr_poly
		(pts
			(arc
				(start 400.192748 -6.598158)
				(mid 399.826988 -6.598158)
				(end 400.192748 -6.598158)
			)
		)
		(stroke
			(width 0)
			(type solid)
		)
		(fill yes)
		(layer "B.Cu")
		(net "GND")
	)
	(gr_poly
		(pts
			(arc
				(start 400.6723 -4.963414)
				(mid 400.30654 -4.963414)
				(end 400.6723 -4.963414)
			)
		)
		(stroke
			(width 0)
			(type solid)
		)
		(fill yes)
		(layer "B.Cu")
		(net "GND")
	)
	(gr_poly
		(pts
			(arc
				(start 400.700748 -6.091174)
				(mid 400.334988 -6.091174)
				(end 400.700748 -6.091174)
			)
		)
		(stroke
			(width 0)
			(type solid)
		)
		(fill yes)
		(layer "B.Cu")
		(net "GND")
	)
	(gr_poly
		(pts
			(arc
				(start 400.706844 -17.61236)
				(mid 400.341084 -17.61236)
				(end 400.706844 -17.61236)
			)
		)
		(stroke
			(width 0)
			(type solid)
		)
		(fill yes)
		(layer "B.Cu")
		(net "GND")
	)
	(gr_poly
		(pts
			(arc
				(start 401.191984 -18.247106)
				(mid 400.826224 -18.247106)
				(end 401.191984 -18.247106)
			)
		)
		(stroke
			(width 0)
			(type solid)
		)
		(fill yes)
		(layer "B.Cu")
		(net "GND")
	)
	(gr_poly
		(pts
			(arc
				(start 401.191984 -16.979138)
				(mid 400.826224 -16.979138)
				(end 401.191984 -16.979138)
			)
		)
		(stroke
			(width 0)
			(type solid)
		)
		(fill yes)
		(layer "B.Cu")
		(net "GND")
	)
	(gr_poly
		(pts
			(arc
				(start 401.959572 -6.091174)
				(mid 401.593812 -6.091174)
				(end 401.959572 -6.091174)
			)
		)
		(stroke
			(width 0)
			(type solid)
		)
		(fill yes)
		(layer "B.Cu")
		(net "GND")
	)
	(gr_poly
		(pts
			(arc
				(start 401.997418 -4.963414)
				(mid 401.631658 -4.963414)
				(end 401.997418 -4.963414)
			)
		)
		(stroke
			(width 0)
			(type solid)
		)
		(fill yes)
		(layer "B.Cu")
		(net "GND")
	)
	(gr_poly
		(pts
			(arc
				(start 402.456904 -18.247106)
				(mid 402.091144 -18.247106)
				(end 402.456904 -18.247106)
			)
		)
		(stroke
			(width 0)
			(type solid)
		)
		(fill yes)
		(layer "B.Cu")
		(net "GND")
	)
	(gr_poly
		(pts
			(arc
				(start 402.456904 -16.979138)
				(mid 402.091144 -16.979138)
				(end 402.456904 -16.979138)
			)
		)
		(stroke
			(width 0)
			(type solid)
		)
		(fill yes)
		(layer "B.Cu")
		(net "GND")
	)
	(gr_poly
		(pts
			(arc
				(start 402.467572 -6.598158)
				(mid 402.101812 -6.598158)
				(end 402.467572 -6.598158)
			)
		)
		(stroke
			(width 0)
			(type solid)
		)
		(fill yes)
		(layer "B.Cu")
		(net "GND")
	)
	(gr_poly
		(pts
			(arc
				(start 402.49729 -5.597398)
				(mid 402.13153 -5.597398)
				(end 402.49729 -5.597398)
			)
		)
		(stroke
			(width 0)
			(type solid)
		)
		(fill yes)
		(layer "B.Cu")
		(net "GND")
	)
	(gr_poly
		(pts
			(arc
				(start 402.49729 -4.32943)
				(mid 402.13153 -4.32943)
				(end 402.49729 -4.32943)
			)
		)
		(stroke
			(width 0)
			(type solid)
		)
		(fill yes)
		(layer "B.Cu")
		(net "GND")
	)
	(gr_poly
		(pts
			(arc
				(start 402.942044 -17.61236)
				(mid 402.576284 -17.61236)
				(end 402.942044 -17.61236)
			)
		)
		(stroke
			(width 0)
			(type solid)
		)
		(fill yes)
		(layer "B.Cu")
		(net "GND")
	)
	(gr_poly
		(pts
			(arc
				(start 403.500844 -19.13636)
				(mid 403.135084 -19.13636)
				(end 403.500844 -19.13636)
			)
		)
		(stroke
			(width 0)
			(type solid)
		)
		(fill yes)
		(layer "B.Cu")
		(net "GND")
	)
	(gr_poly
		(pts
			(arc
				(start 403.76221 -5.597398)
				(mid 403.39645 -5.597398)
				(end 403.76221 -5.597398)
			)
		)
		(stroke
			(width 0)
			(type solid)
		)
		(fill yes)
		(layer "B.Cu")
		(net "GND")
	)
	(gr_poly
		(pts
			(arc
				(start 403.76221 -4.32943)
				(mid 403.39645 -4.32943)
				(end 403.76221 -4.32943)
			)
		)
		(stroke
			(width 0)
			(type solid)
		)
		(fill yes)
		(layer "B.Cu")
		(net "GND")
	)
	(gr_poly
		(pts
			(arc
				(start 403.792944 -6.598158)
				(mid 403.427184 -6.598158)
				(end 403.792944 -6.598158)
			)
		)
		(stroke
			(width 0)
			(type solid)
		)
		(fill yes)
		(layer "B.Cu")
		(net "GND")
	)
	(gr_poly
		(pts
			(arc
				(start 403.985984 -19.771106)
				(mid 403.620224 -19.771106)
				(end 403.985984 -19.771106)
			)
		)
		(stroke
			(width 0)
			(type solid)
		)
		(fill yes)
		(layer "B.Cu")
		(net "GND")
	)
	(gr_poly
		(pts
			(arc
				(start 403.985984 -18.503138)
				(mid 403.620224 -18.503138)
				(end 403.985984 -18.503138)
			)
		)
		(stroke
			(width 0)
			(type solid)
		)
		(fill yes)
		(layer "B.Cu")
		(net "GND")
	)
	(gr_poly
		(pts
			(arc
				(start 404.272242 -4.963414)
				(mid 403.906482 -4.963414)
				(end 404.272242 -4.963414)
			)
		)
		(stroke
			(width 0)
			(type solid)
		)
		(fill yes)
		(layer "B.Cu")
		(net "GND")
	)
	(gr_poly
		(pts
			(arc
				(start 404.300944 -6.091174)
				(mid 403.935184 -6.091174)
				(end 404.300944 -6.091174)
			)
		)
		(stroke
			(width 0)
			(type solid)
		)
		(fill yes)
		(layer "B.Cu")
		(net "GND")
	)
	(gr_poly
		(pts
			(arc
				(start 405.250904 -19.771106)
				(mid 404.885144 -19.771106)
				(end 405.250904 -19.771106)
			)
		)
		(stroke
			(width 0)
			(type solid)
		)
		(fill yes)
		(layer "B.Cu")
		(net "GND")
	)
	(gr_poly
		(pts
			(arc
				(start 405.250904 -18.503138)
				(mid 404.885144 -18.503138)
				(end 405.250904 -18.503138)
			)
		)
		(stroke
			(width 0)
			(type solid)
		)
		(fill yes)
		(layer "B.Cu")
		(net "GND")
	)
	(gr_poly
		(pts
			(arc
				(start 405.559768 -6.091174)
				(mid 405.194008 -6.091174)
				(end 405.559768 -6.091174)
			)
		)
		(stroke
			(width 0)
			(type solid)
		)
		(fill yes)
		(layer "B.Cu")
		(net "GND")
	)
	(gr_poly
		(pts
			(arc
				(start 405.597614 -4.963414)
				(mid 405.231854 -4.963414)
				(end 405.597614 -4.963414)
			)
		)
		(stroke
			(width 0)
			(type solid)
		)
		(fill yes)
		(layer "B.Cu")
		(net "GND")
	)
	(gr_poly
		(pts
			(arc
				(start 405.736044 -19.13636)
				(mid 405.370284 -19.13636)
				(end 405.736044 -19.13636)
			)
		)
		(stroke
			(width 0)
			(type solid)
		)
		(fill yes)
		(layer "B.Cu")
		(net "GND")
	)
	(gr_poly
		(pts
			(arc
				(start 406.067768 -6.598158)
				(mid 405.702008 -6.598158)
				(end 406.067768 -6.598158)
			)
		)
		(stroke
			(width 0)
			(type solid)
		)
		(fill yes)
		(layer "B.Cu")
		(net "GND")
	)
	(gr_poly
		(pts
			(arc
				(start 406.098248 -5.597398)
				(mid 405.732488 -5.597398)
				(end 406.098248 -5.597398)
			)
		)
		(stroke
			(width 0)
			(type solid)
		)
		(fill yes)
		(layer "B.Cu")
		(net "GND")
	)
	(gr_poly
		(pts
			(arc
				(start 406.098248 -4.32943)
				(mid 405.732488 -4.32943)
				(end 406.098248 -4.32943)
			)
		)
		(stroke
			(width 0)
			(type solid)
		)
		(fill yes)
		(layer "B.Cu")
		(net "GND")
	)
	(gr_poly
		(pts
			(arc
				(start 406.294844 -17.613122)
				(mid 405.929084 -17.613122)
				(end 406.294844 -17.613122)
			)
		)
		(stroke
			(width 0)
			(type solid)
		)
		(fill yes)
		(layer "B.Cu")
		(net "GND")
	)
	(gr_poly
		(pts
			(arc
				(start 406.779984 -18.247868)
				(mid 406.414224 -18.247868)
				(end 406.779984 -18.247868)
			)
		)
		(stroke
			(width 0)
			(type solid)
		)
		(fill yes)
		(layer "B.Cu")
		(net "GND")
	)
	(gr_poly
		(pts
			(arc
				(start 406.779984 -16.9799)
				(mid 406.414224 -16.9799)
				(end 406.779984 -16.9799)
			)
		)
		(stroke
			(width 0)
			(type solid)
		)
		(fill yes)
		(layer "B.Cu")
		(net "GND")
	)
	(gr_poly
		(pts
			(arc
				(start 407.363168 -5.597398)
				(mid 406.997408 -5.597398)
				(end 407.363168 -5.597398)
			)
		)
		(stroke
			(width 0)
			(type solid)
		)
		(fill yes)
		(layer "B.Cu")
		(net "GND")
	)
	(gr_poly
		(pts
			(arc
				(start 407.363168 -4.32943)
				(mid 406.997408 -4.32943)
				(end 407.363168 -4.32943)
			)
		)
		(stroke
			(width 0)
			(type solid)
		)
		(fill yes)
		(layer "B.Cu")
		(net "GND")
	)
	(gr_poly
		(pts
			(arc
				(start 407.872438 -4.963414)
				(mid 407.506678 -4.963414)
				(end 407.872438 -4.963414)
			)
		)
		(stroke
			(width 0)
			(type solid)
		)
		(fill yes)
		(layer "B.Cu")
		(net "GND")
	)
	(gr_poly
		(pts
			(arc
				(start 408.044904 -18.247868)
				(mid 407.679144 -18.247868)
				(end 408.044904 -18.247868)
			)
		)
		(stroke
			(width 0)
			(type solid)
		)
		(fill yes)
		(layer "B.Cu")
		(net "GND")
	)
	(gr_poly
		(pts
			(arc
				(start 408.044904 -16.9799)
				(mid 407.679144 -16.9799)
				(end 408.044904 -16.9799)
			)
		)
		(stroke
			(width 0)
			(type solid)
		)
		(fill yes)
		(layer "B.Cu")
		(net "GND")
	)
	(gr_poly
		(pts
			(arc
				(start 408.530044 -17.613122)
				(mid 408.164284 -17.613122)
				(end 408.530044 -17.613122)
			)
		)
		(stroke
			(width 0)
			(type solid)
		)
		(fill yes)
		(layer "B.Cu")
		(net "GND")
	)
	(gr_poly
		(pts
			(arc
				(start 409.088844 -19.13636)
				(mid 408.723084 -19.13636)
				(end 409.088844 -19.13636)
			)
		)
		(stroke
			(width 0)
			(type solid)
		)
		(fill yes)
		(layer "B.Cu")
		(net "GND")
	)
	(gr_poly
		(pts
			(arc
				(start 409.573984 -19.771106)
				(mid 409.208224 -19.771106)
				(end 409.573984 -19.771106)
			)
		)
		(stroke
			(width 0)
			(type solid)
		)
		(fill yes)
		(layer "B.Cu")
		(net "GND")
	)
	(gr_poly
		(pts
			(arc
				(start 409.573984 -18.503138)
				(mid 409.208224 -18.503138)
				(end 409.573984 -18.503138)
			)
		)
		(stroke
			(width 0)
			(type solid)
		)
		(fill yes)
		(layer "B.Cu")
		(net "GND")
	)
	(gr_poly
		(pts
			(arc
				(start 410.838904 -19.771106)
				(mid 410.473144 -19.771106)
				(end 410.838904 -19.771106)
			)
		)
		(stroke
			(width 0)
			(type solid)
		)
		(fill yes)
		(layer "B.Cu")
		(net "GND")
	)
	(gr_poly
		(pts
			(arc
				(start 410.838904 -18.503138)
				(mid 410.473144 -18.503138)
				(end 410.838904 -18.503138)
			)
		)
		(stroke
			(width 0)
			(type solid)
		)
		(fill yes)
		(layer "B.Cu")
		(net "GND")
	)
	(gr_poly
		(pts
			(arc
				(start 411.324044 -19.13636)
				(mid 410.958284 -19.13636)
				(end 411.324044 -19.13636)
			)
		)
		(stroke
			(width 0)
			(type solid)
		)
		(fill yes)
		(layer "B.Cu")
		(net "GND")
	)
	(gr_poly
		(pts
			(arc
				(start 411.881828 -17.613122)
				(mid 411.516068 -17.613122)
				(end 411.881828 -17.613122)
			)
		)
		(stroke
			(width 0)
			(type solid)
		)
		(fill yes)
		(layer "B.Cu")
		(net "GND")
	)
	(gr_poly
		(pts
			(arc
				(start 412.366968 -18.247868)
				(mid 412.001208 -18.247868)
				(end 412.366968 -18.247868)
			)
		)
		(stroke
			(width 0)
			(type solid)
		)
		(fill yes)
		(layer "B.Cu")
		(net "GND")
	)
	(gr_poly
		(pts
			(arc
				(start 412.366968 -16.9799)
				(mid 412.001208 -16.9799)
				(end 412.366968 -16.9799)
			)
		)
		(stroke
			(width 0)
			(type solid)
		)
		(fill yes)
		(layer "B.Cu")
		(net "GND")
	)
	(gr_poly
		(pts
			(arc
				(start 412.902908 -6.598158)
				(mid 412.537148 -6.598158)
				(end 412.902908 -6.598158)
			)
		)
		(stroke
			(width 0)
			(type solid)
		)
		(fill yes)
		(layer "B.Cu")
		(net "GND")
	)
	(gr_poly
		(pts
			(arc
				(start 413.410908 -6.091174)
				(mid 413.045148 -6.091174)
				(end 413.410908 -6.091174)
			)
		)
		(stroke
			(width 0)
			(type solid)
		)
		(fill yes)
		(layer "B.Cu")
		(net "GND")
	)
	(gr_poly
		(pts
			(arc
				(start 413.631888 -18.247868)
				(mid 413.266128 -18.247868)
				(end 413.631888 -18.247868)
			)
		)
		(stroke
			(width 0)
			(type solid)
		)
		(fill yes)
		(layer "B.Cu")
		(net "GND")
	)
	(gr_poly
		(pts
			(arc
				(start 413.631888 -16.9799)
				(mid 413.266128 -16.9799)
				(end 413.631888 -16.9799)
			)
		)
		(stroke
			(width 0)
			(type solid)
		)
		(fill yes)
		(layer "B.Cu")
		(net "GND")
	)
	(gr_poly
		(pts
			(arc
				(start 414.117028 -17.613122)
				(mid 413.751268 -17.613122)
				(end 414.117028 -17.613122)
			)
		)
		(stroke
			(width 0)
			(type solid)
		)
		(fill yes)
		(layer "B.Cu")
		(net "GND")
	)
	(gr_poly
		(pts
			(arc
				(start 414.669732 -6.091174)
				(mid 414.303972 -6.091174)
				(end 414.669732 -6.091174)
			)
		)
		(stroke
			(width 0)
			(type solid)
		)
		(fill yes)
		(layer "B.Cu")
		(net "GND")
	)
	(gr_poly
		(pts
			(arc
				(start 414.707578 -4.963414)
				(mid 414.341818 -4.963414)
				(end 414.707578 -4.963414)
			)
		)
		(stroke
			(width 0)
			(type solid)
		)
		(fill yes)
		(layer "B.Cu")
		(net "GND")
	)
	(gr_poly
		(pts
			(arc
				(start 414.98266 -19.13636)
				(mid 414.6169 -19.13636)
				(end 414.98266 -19.13636)
			)
		)
		(stroke
			(width 0)
			(type solid)
		)
		(fill yes)
		(layer "B.Cu")
		(net "GND")
	)
	(gr_poly
		(pts
			(arc
				(start 415.177732 -6.598158)
				(mid 414.811972 -6.598158)
				(end 415.177732 -6.598158)
			)
		)
		(stroke
			(width 0)
			(type solid)
		)
		(fill yes)
		(layer "B.Cu")
		(net "GND")
	)
	(gr_poly
		(pts
			(arc
				(start 415.207196 -5.597398)
				(mid 414.841436 -5.597398)
				(end 415.207196 -5.597398)
			)
		)
		(stroke
			(width 0)
			(type solid)
		)
		(fill yes)
		(layer "B.Cu")
		(net "GND")
	)
	(gr_poly
		(pts
			(arc
				(start 415.207196 -4.32943)
				(mid 414.841436 -4.32943)
				(end 415.207196 -4.32943)
			)
		)
		(stroke
			(width 0)
			(type solid)
		)
		(fill yes)
		(layer "B.Cu")
		(net "GND")
	)
	(gr_poly
		(pts
			(arc
				(start 415.4678 -19.771106)
				(mid 415.10204 -19.771106)
				(end 415.4678 -19.771106)
			)
		)
		(stroke
			(width 0)
			(type solid)
		)
		(fill yes)
		(layer "B.Cu")
		(net "GND")
	)
	(gr_poly
		(pts
			(arc
				(start 415.4678 -18.503138)
				(mid 415.10204 -18.503138)
				(end 415.4678 -18.503138)
			)
		)
		(stroke
			(width 0)
			(type solid)
		)
		(fill yes)
		(layer "B.Cu")
		(net "GND")
	)
	(gr_poly
		(pts
			(arc
				(start 416.472116 -5.597398)
				(mid 416.106356 -5.597398)
				(end 416.472116 -5.597398)
			)
		)
		(stroke
			(width 0)
			(type solid)
		)
		(fill yes)
		(layer "B.Cu")
		(net "GND")
	)
	(gr_poly
		(pts
			(arc
				(start 416.472116 -4.32943)
				(mid 416.106356 -4.32943)
				(end 416.472116 -4.32943)
			)
		)
		(stroke
			(width 0)
			(type solid)
		)
		(fill yes)
		(layer "B.Cu")
		(net "GND")
	)
	(gr_poly
		(pts
			(arc
				(start 416.50285 -6.598158)
				(mid 416.13709 -6.598158)
				(end 416.50285 -6.598158)
			)
		)
		(stroke
			(width 0)
			(type solid)
		)
		(fill yes)
		(layer "B.Cu")
		(net "GND")
	)
	(gr_poly
		(pts
			(arc
				(start 416.73272 -19.771106)
				(mid 416.36696 -19.771106)
				(end 416.73272 -19.771106)
			)
		)
		(stroke
			(width 0)
			(type solid)
		)
		(fill yes)
		(layer "B.Cu")
		(net "GND")
	)
	(gr_poly
		(pts
			(arc
				(start 416.73272 -18.503138)
				(mid 416.36696 -18.503138)
				(end 416.73272 -18.503138)
			)
		)
		(stroke
			(width 0)
			(type solid)
		)
		(fill yes)
		(layer "B.Cu")
		(net "GND")
	)
	(gr_poly
		(pts
			(arc
				(start 416.982402 -4.963414)
				(mid 416.616642 -4.963414)
				(end 416.982402 -4.963414)
			)
		)
		(stroke
			(width 0)
			(type solid)
		)
		(fill yes)
		(layer "B.Cu")
		(net "GND")
	)
	(gr_poly
		(pts
			(arc
				(start 417.01085 -6.091174)
				(mid 416.64509 -6.091174)
				(end 417.01085 -6.091174)
			)
		)
		(stroke
			(width 0)
			(type solid)
		)
		(fill yes)
		(layer "B.Cu")
		(net "GND")
	)
	(gr_poly
		(pts
			(arc
				(start 417.21786 -19.13636)
				(mid 416.8521 -19.13636)
				(end 417.21786 -19.13636)
			)
		)
		(stroke
			(width 0)
			(type solid)
		)
		(fill yes)
		(layer "B.Cu")
		(net "GND")
	)
	(gr_poly
		(pts
			(arc
				(start 417.77666 -17.61236)
				(mid 417.4109 -17.61236)
				(end 417.77666 -17.61236)
			)
		)
		(stroke
			(width 0)
			(type solid)
		)
		(fill yes)
		(layer "B.Cu")
		(net "GND")
	)
	(gr_poly
		(pts
			(arc
				(start 418.2618 -18.247106)
				(mid 417.89604 -18.247106)
				(end 418.2618 -18.247106)
			)
		)
		(stroke
			(width 0)
			(type solid)
		)
		(fill yes)
		(layer "B.Cu")
		(net "GND")
	)
	(gr_poly
		(pts
			(arc
				(start 418.2618 -16.979138)
				(mid 417.89604 -16.979138)
				(end 418.2618 -16.979138)
			)
		)
		(stroke
			(width 0)
			(type solid)
		)
		(fill yes)
		(layer "B.Cu")
		(net "GND")
	)
	(gr_poly
		(pts
			(arc
				(start 418.269674 -6.091174)
				(mid 417.903914 -6.091174)
				(end 418.269674 -6.091174)
			)
		)
		(stroke
			(width 0)
			(type solid)
		)
		(fill yes)
		(layer "B.Cu")
		(net "GND")
	)
	(gr_poly
		(pts
			(arc
				(start 418.30752 -4.963414)
				(mid 417.94176 -4.963414)
				(end 418.30752 -4.963414)
			)
		)
		(stroke
			(width 0)
			(type solid)
		)
		(fill yes)
		(layer "B.Cu")
		(net "GND")
	)
	(gr_poly
		(pts
			(arc
				(start 418.777674 -6.598158)
				(mid 418.411914 -6.598158)
				(end 418.777674 -6.598158)
			)
		)
		(stroke
			(width 0)
			(type solid)
		)
		(fill yes)
		(layer "B.Cu")
		(net "GND")
	)
	(gr_poly
		(pts
			(arc
				(start 418.807392 -5.597398)
				(mid 418.441632 -5.597398)
				(end 418.807392 -5.597398)
			)
		)
		(stroke
			(width 0)
			(type solid)
		)
		(fill yes)
		(layer "B.Cu")
		(net "GND")
	)
	(gr_poly
		(pts
			(arc
				(start 418.807392 -4.32943)
				(mid 418.441632 -4.32943)
				(end 418.807392 -4.32943)
			)
		)
		(stroke
			(width 0)
			(type solid)
		)
		(fill yes)
		(layer "B.Cu")
		(net "GND")
	)
	(gr_poly
		(pts
			(arc
				(start 419.52672 -16.979138)
				(mid 419.16096 -16.979138)
				(end 419.52672 -16.979138)
			)
		)
		(stroke
			(width 0)
			(type solid)
		)
		(fill yes)
		(layer "B.Cu")
		(net "GND")
	)
	(gr_poly
		(pts
			(arc
				(start 420.072312 -5.597398)
				(mid 419.706552 -5.597398)
				(end 420.072312 -5.597398)
			)
		)
		(stroke
			(width 0)
			(type solid)
		)
		(fill yes)
		(layer "B.Cu")
		(net "GND")
	)
	(gr_poly
		(pts
			(arc
				(start 420.072312 -4.32943)
				(mid 419.706552 -4.32943)
				(end 420.072312 -4.32943)
			)
		)
		(stroke
			(width 0)
			(type solid)
		)
		(fill yes)
		(layer "B.Cu")
		(net "GND")
	)
	(gr_poly
		(pts
			(arc
				(start 420.582344 -4.963414)
				(mid 420.216584 -4.963414)
				(end 420.582344 -4.963414)
			)
		)
		(stroke
			(width 0)
			(type solid)
		)
		(fill yes)
		(layer "B.Cu")
		(net "GND")
	)
	(gr_poly
		(pts
			(arc
				(start 421.054784 -19.771868)
				(mid 420.689024 -19.771868)
				(end 421.054784 -19.771868)
			)
		)
		(stroke
			(width 0)
			(type solid)
		)
		(fill yes)
		(layer "B.Cu")
		(net "GND")
	)
	(gr_poly
		(pts
			(arc
				(start 422.319704 -19.771868)
				(mid 421.953944 -19.771868)
				(end 422.319704 -19.771868)
			)
		)
		(stroke
			(width 0)
			(type solid)
		)
		(fill yes)
		(layer "B.Cu")
		(net "GND")
	)
	(gr_poly
		(pts
			(arc
				(start 423.8498 -16.979138)
				(mid 423.48404 -16.979138)
				(end 423.8498 -16.979138)
			)
		)
		(stroke
			(width 0)
			(type solid)
		)
		(fill yes)
		(layer "B.Cu")
		(net "GND")
	)
	(gr_poly
		(pts
			(arc
				(start 424.112944 -6.598158)
				(mid 423.747184 -6.598158)
				(end 424.112944 -6.598158)
			)
		)
		(stroke
			(width 0)
			(type solid)
		)
		(fill yes)
		(layer "B.Cu")
		(net "GND")
	)
	(gr_poly
		(pts
			(arc
				(start 424.620944 -6.091174)
				(mid 424.255184 -6.091174)
				(end 424.620944 -6.091174)
			)
		)
		(stroke
			(width 0)
			(type solid)
		)
		(fill yes)
		(layer "B.Cu")
		(net "GND")
	)
	(gr_poly
		(pts
			(arc
				(start 425.11472 -18.247106)
				(mid 424.74896 -18.247106)
				(end 425.11472 -18.247106)
			)
		)
		(stroke
			(width 0)
			(type solid)
		)
		(fill yes)
		(layer "B.Cu")
		(net "GND")
	)
	(gr_poly
		(pts
			(arc
				(start 425.11472 -16.979138)
				(mid 424.74896 -16.979138)
				(end 425.11472 -16.979138)
			)
		)
		(stroke
			(width 0)
			(type solid)
		)
		(fill yes)
		(layer "B.Cu")
		(net "GND")
	)
	(gr_poly
		(pts
			(arc
				(start 425.59986 -17.61236)
				(mid 425.2341 -17.61236)
				(end 425.59986 -17.61236)
			)
		)
		(stroke
			(width 0)
			(type solid)
		)
		(fill yes)
		(layer "B.Cu")
		(net "GND")
	)
	(gr_poly
		(pts
			(arc
				(start 425.879768 -6.091174)
				(mid 425.514008 -6.091174)
				(end 425.879768 -6.091174)
			)
		)
		(stroke
			(width 0)
			(type solid)
		)
		(fill yes)
		(layer "B.Cu")
		(net "GND")
	)
	(gr_poly
		(pts
			(arc
				(start 425.917614 -4.963414)
				(mid 425.551854 -4.963414)
				(end 425.917614 -4.963414)
			)
		)
		(stroke
			(width 0)
			(type solid)
		)
		(fill yes)
		(layer "B.Cu")
		(net "GND")
	)
	(gr_poly
		(pts
			(arc
				(start 426.192696 -19.13636)
				(mid 425.826936 -19.13636)
				(end 426.192696 -19.13636)
			)
		)
		(stroke
			(width 0)
			(type solid)
		)
		(fill yes)
		(layer "B.Cu")
		(net "GND")
	)
	(gr_poly
		(pts
			(arc
				(start 426.387768 -6.598158)
				(mid 426.022008 -6.598158)
				(end 426.387768 -6.598158)
			)
		)
		(stroke
			(width 0)
			(type solid)
		)
		(fill yes)
		(layer "B.Cu")
		(net "GND")
	)
	(gr_poly
		(pts
			(arc
				(start 426.417232 -5.597398)
				(mid 426.051472 -5.597398)
				(end 426.417232 -5.597398)
			)
		)
		(stroke
			(width 0)
			(type solid)
		)
		(fill yes)
		(layer "B.Cu")
		(net "GND")
	)
	(gr_poly
		(pts
			(arc
				(start 426.677836 -19.771106)
				(mid 426.312076 -19.771106)
				(end 426.677836 -19.771106)
			)
		)
		(stroke
			(width 0)
			(type solid)
		)
		(fill yes)
		(layer "B.Cu")
		(net "GND")
	)
	(gr_poly
		(pts
			(arc
				(start 426.677836 -18.503138)
				(mid 426.312076 -18.503138)
				(end 426.677836 -18.503138)
			)
		)
		(stroke
			(width 0)
			(type solid)
		)
		(fill yes)
		(layer "B.Cu")
		(net "GND")
	)
	(gr_poly
		(pts
			(arc
				(start 427.682152 -5.597398)
				(mid 427.316392 -5.597398)
				(end 427.682152 -5.597398)
			)
		)
		(stroke
			(width 0)
			(type solid)
		)
		(fill yes)
		(layer "B.Cu")
		(net "GND")
	)
	(gr_poly
		(pts
			(arc
				(start 427.712886 -6.598158)
				(mid 427.347126 -6.598158)
				(end 427.712886 -6.598158)
			)
		)
		(stroke
			(width 0)
			(type solid)
		)
		(fill yes)
		(layer "B.Cu")
		(net "GND")
	)
	(gr_poly
		(pts
			(arc
				(start 427.942756 -19.771106)
				(mid 427.576996 -19.771106)
				(end 427.942756 -19.771106)
			)
		)
		(stroke
			(width 0)
			(type solid)
		)
		(fill yes)
		(layer "B.Cu")
		(net "GND")
	)
	(gr_poly
		(pts
			(arc
				(start 428.192438 -4.963414)
				(mid 427.826678 -4.963414)
				(end 428.192438 -4.963414)
			)
		)
		(stroke
			(width 0)
			(type solid)
		)
		(fill yes)
		(layer "B.Cu")
		(net "GND")
	)
	(gr_poly
		(pts
			(arc
				(start 428.220886 -6.091174)
				(mid 427.855126 -6.091174)
				(end 428.220886 -6.091174)
			)
		)
		(stroke
			(width 0)
			(type solid)
		)
		(fill yes)
		(layer "B.Cu")
		(net "GND")
	)
	(gr_poly
		(pts
			(arc
				(start 429.47082 -16.9799)
				(mid 429.10506 -16.9799)
				(end 429.47082 -16.9799)
			)
		)
		(stroke
			(width 0)
			(type solid)
		)
		(fill yes)
		(layer "B.Cu")
		(net "GND")
	)
	(gr_poly
		(pts
			(arc
				(start 429.47971 -6.091174)
				(mid 429.11395 -6.091174)
				(end 429.47971 -6.091174)
			)
		)
		(stroke
			(width 0)
			(type solid)
		)
		(fill yes)
		(layer "B.Cu")
		(net "GND")
	)
	(gr_poly
		(pts
			(arc
				(start 429.517556 -4.963414)
				(mid 429.151796 -4.963414)
				(end 429.517556 -4.963414)
			)
		)
		(stroke
			(width 0)
			(type solid)
		)
		(fill yes)
		(layer "B.Cu")
		(net "GND")
	)
	(gr_poly
		(pts
			(arc
				(start 429.98771 -6.598158)
				(mid 429.62195 -6.598158)
				(end 429.98771 -6.598158)
			)
		)
		(stroke
			(width 0)
			(type solid)
		)
		(fill yes)
		(layer "B.Cu")
		(net "GND")
	)
	(gr_poly
		(pts
			(arc
				(start 430.017428 -5.597398)
				(mid 429.651668 -5.597398)
				(end 430.017428 -5.597398)
			)
		)
		(stroke
			(width 0)
			(type solid)
		)
		(fill yes)
		(layer "B.Cu")
		(net "GND")
	)
	(gr_poly
		(pts
			(arc
				(start 430.73574 -18.247868)
				(mid 430.36998 -18.247868)
				(end 430.73574 -18.247868)
			)
		)
		(stroke
			(width 0)
			(type solid)
		)
		(fill yes)
		(layer "B.Cu")
		(net "GND")
	)
	(gr_poly
		(pts
			(arc
				(start 430.73574 -16.9799)
				(mid 430.36998 -16.9799)
				(end 430.73574 -16.9799)
			)
		)
		(stroke
			(width 0)
			(type solid)
		)
		(fill yes)
		(layer "B.Cu")
		(net "GND")
	)
	(gr_poly
		(pts
			(arc
				(start 431.22088 -17.613122)
				(mid 430.85512 -17.613122)
				(end 431.22088 -17.613122)
			)
		)
		(stroke
			(width 0)
			(type solid)
		)
		(fill yes)
		(layer "B.Cu")
		(net "GND")
	)
	(gr_poly
		(pts
			(arc
				(start 431.282348 -5.597398)
				(mid 430.916588 -5.597398)
				(end 431.282348 -5.597398)
			)
		)
		(stroke
			(width 0)
			(type solid)
		)
		(fill yes)
		(layer "B.Cu")
		(net "GND")
	)
	(gr_poly
		(pts
			(arc
				(start 431.780696 -19.13636)
				(mid 431.414936 -19.13636)
				(end 431.780696 -19.13636)
			)
		)
		(stroke
			(width 0)
			(type solid)
		)
		(fill yes)
		(layer "B.Cu")
		(net "GND")
	)
	(gr_poly
		(pts
			(arc
				(start 432.265836 -19.771106)
				(mid 431.900076 -19.771106)
				(end 432.265836 -19.771106)
			)
		)
		(stroke
			(width 0)
			(type solid)
		)
		(fill yes)
		(layer "B.Cu")
		(net "GND")
	)
	(gr_poly
		(pts
			(arc
				(start 432.265836 -18.503138)
				(mid 431.900076 -18.503138)
				(end 432.265836 -18.503138)
			)
		)
		(stroke
			(width 0)
			(type solid)
		)
		(fill yes)
		(layer "B.Cu")
		(net "GND")
	)
	(gr_poly
		(pts
			(arc
				(start 433.530756 -18.503138)
				(mid 433.164996 -18.503138)
				(end 433.530756 -18.503138)
			)
		)
		(stroke
			(width 0)
			(type solid)
		)
		(fill yes)
		(layer "B.Cu")
		(net "GND")
	)
	(gr_poly
		(pts
			(arc
				(start 14.793976 -420.685722)
				(mid 14.813499 -420.681821)
				(end 14.830044 -420.670736)
			)
			(arc
				(start 14.926818 -420.573962)
				(mid 14.93788 -420.557545)
				(end 14.941804 -420.538148)
			)
			(arc
				(start 14.941804 -418.217096)
				(mid 14.937854 -418.197709)
				(end 14.926818 -418.181282)
			)
			(arc
				(start 14.842744 -418.097208)
				(mid 14.82621 -418.086097)
				(end 14.806676 -418.082222)
			)
			(arc
				(start 12.877292 -418.082222)
				(mid 12.857769 -418.086123)
				(end 12.841224 -418.097208)
			)
			(arc
				(start 12.743434 -418.194998)
				(mid 12.732323 -418.211532)
				(end 12.728448 -418.231066)
			)
			(arc
				(start 12.728448 -420.523416)
				(mid 12.732349 -420.542939)
				(end 12.743434 -420.559484)
			)
			(arc
				(start 12.854686 -420.670736)
				(mid 12.87122 -420.681847)
				(end 12.890754 -420.685722)
			)
		)
		(stroke
			(width 0)
			(type solid)
		)
		(fill yes)
		(layer "B.Cu")
		(net "GND")
	)
	(gr_poly
		(pts
			(arc
				(start 25.933654 -406.468834)
				(mid 25.953177 -406.464933)
				(end 25.969722 -406.453848)
			)
			(arc
				(start 26.058368 -406.365202)
				(mid 26.069479 -406.348668)
				(end 26.073354 -406.329134)
			)
			(arc
				(start 26.073354 -403.9616)
				(mid 26.069453 -403.942077)
				(end 26.058368 -403.925532)
			)
			(arc
				(start 25.903428 -403.770592)
				(mid 25.886894 -403.759481)
				(end 25.86736 -403.755606)
			)
			(arc
				(start 22.68347 -403.755606)
				(mid 22.663947 -403.759507)
				(end 22.647402 -403.770592)
			)
			(arc
				(start 22.411182 -404.006812)
				(mid 22.400071 -404.023346)
				(end 22.396196 -404.04288)
			)
			(arc
				(start 22.396196 -406.104852)
				(mid 22.400097 -406.124375)
				(end 22.411182 -406.14092)
			)
			(arc
				(start 22.72411 -406.453848)
				(mid 22.740644 -406.464959)
				(end 22.760178 -406.468834)
			)
		)
		(stroke
			(width 0)
			(type solid)
		)
		(fill yes)
		(layer "B.Cu")
		(net "P12V_AUX")
	)
	(gr_poly
		(pts
			(arc
				(start 46.66615 -400.562064)
				(mid 46.685507 -400.558231)
				(end 46.701964 -400.547332)
			)
			(arc
				(start 46.853348 -400.395948)
				(mid 46.864459 -400.379414)
				(end 46.868334 -400.35988)
			)
			(arc
				(start 46.868334 -398.737582)
				(mid 46.864433 -398.718059)
				(end 46.853348 -398.701514)
			)
			(arc
				(start 46.590966 -398.439132)
				(mid 46.574432 -398.428021)
				(end 46.554898 -398.424146)
			)
			(arc
				(start 45.047408 -398.424146)
				(mid 45.027885 -398.428047)
				(end 45.01134 -398.439132)
			)
			(arc
				(start 44.952666 -398.497806)
				(mid 44.941555 -398.51434)
				(end 44.93768 -398.533874)
			)
			(arc
				(start 44.93768 -400.013932)
				(mid 44.94163 -400.033319)
				(end 44.952666 -400.049746)
			)
			(arc
				(start 45.449998 -400.547332)
				(mid 45.466561 -400.558306)
				(end 45.486066 -400.562064)
			)
		)
		(stroke
			(width 0)
			(type solid)
		)
		(fill yes)
		(layer "B.Cu")
		(net "P0V9_CPU1_RT0_2A_2D")
	)
	(gr_poly
		(pts
			(arc
				(start 59.802268 -382.960372)
				(mid 59.821762 -382.956588)
				(end 59.838336 -382.94564)
			)
			(arc
				(start 60.048394 -382.735328)
				(mid 60.059456 -382.718911)
				(end 60.06338 -382.699514)
			)
			(arc
				(start 60.06338 -379.428502)
				(mid 60.059479 -379.408979)
				(end 60.048394 -379.392434)
			)
			(arc
				(start 60.019946 -379.363986)
				(mid 60.003412 -379.352875)
				(end 59.983878 -379.349)
			)
			(arc
				(start 53.820822 -379.349)
				(mid 53.801299 -379.352901)
				(end 53.784754 -379.363986)
			)
			(arc
				(start 53.72608 -379.42266)
				(mid 53.715154 -379.439106)
				(end 53.711348 -379.458474)
			)
			(arc
				(start 53.711348 -382.905508)
				(mid 53.715132 -382.925002)
				(end 53.72608 -382.941576)
			)
			(arc
				(start 53.730144 -382.94564)
				(mid 53.746707 -382.956614)
				(end 53.766212 -382.960372)
			)
		)
		(stroke
			(width 0)
			(type solid)
		)
		(fill yes)
		(layer "B.Cu")
		(net "GND")
	)
	(gr_poly
		(pts
			(arc
				(start 92.330016 -382.960372)
				(mid 92.34951 -382.956588)
				(end 92.366084 -382.94564)
			)
			(arc
				(start 92.576142 -382.735328)
				(mid 92.587204 -382.718911)
				(end 92.591128 -382.699514)
			)
			(arc
				(start 92.591128 -379.428502)
				(mid 92.587227 -379.408979)
				(end 92.576142 -379.392434)
			)
			(arc
				(start 92.547694 -379.363986)
				(mid 92.53116 -379.352875)
				(end 92.511626 -379.349)
			)
			(arc
				(start 86.34857 -379.349)
				(mid 86.329047 -379.352901)
				(end 86.312502 -379.363986)
			)
			(arc
				(start 86.253828 -379.42266)
				(mid 86.242902 -379.439106)
				(end 86.239096 -379.458474)
			)
			(arc
				(start 86.239096 -382.905508)
				(mid 86.24288 -382.925002)
				(end 86.253828 -382.941576)
			)
			(arc
				(start 86.257892 -382.94564)
				(mid 86.274455 -382.956614)
				(end 86.29396 -382.960372)
			)
		)
		(stroke
			(width 0)
			(type solid)
		)
		(fill yes)
		(layer "B.Cu")
		(net "GND")
	)
	(gr_poly
		(pts
			(arc
				(start 93.908372 -354.735384)
				(mid 93.927895 -354.731483)
				(end 93.94444 -354.720398)
			)
			(arc
				(start 94.79534 -353.869498)
				(mid 94.806451 -353.852964)
				(end 94.810326 -353.83343)
			)
			(arc
				(start 94.810326 -350.754442)
				(mid 94.806425 -350.734919)
				(end 94.79534 -350.718374)
			)
			(arc
				(start 94.307914 -350.230948)
				(mid 94.29138 -350.219837)
				(end 94.271846 -350.215962)
			)
			(arc
				(start 87.267288 -350.215962)
				(mid 87.247765 -350.219863)
				(end 87.23122 -350.230948)
			)
			(arc
				(start 86.705694 -350.756474)
				(mid 86.694583 -350.773008)
				(end 86.690708 -350.792542)
			)
			(arc
				(start 86.690708 -354.197158)
				(mid 86.694609 -354.216681)
				(end 86.705694 -354.233226)
			)
			(arc
				(start 87.192866 -354.720398)
				(mid 87.2094 -354.731509)
				(end 87.228934 -354.735384)
			)
		)
		(stroke
			(width 0)
			(type solid)
		)
		(fill yes)
		(layer "B.Cu")
		(net "P12V_AUX")
	)
	(gr_poly
		(pts
			(arc
				(start 126.90221 -382.960372)
				(mid 126.921704 -382.956588)
				(end 126.938278 -382.94564)
			)
			(arc
				(start 127.148336 -382.735328)
				(mid 127.159398 -382.718911)
				(end 127.163322 -382.699514)
			)
			(arc
				(start 127.163322 -379.428502)
				(mid 127.159421 -379.408979)
				(end 127.148336 -379.392434)
			)
			(arc
				(start 127.119888 -379.363986)
				(mid 127.103354 -379.352875)
				(end 127.08382 -379.349)
			)
			(arc
				(start 120.920764 -379.349)
				(mid 120.901241 -379.352901)
				(end 120.884696 -379.363986)
			)
			(arc
				(start 120.826022 -379.42266)
				(mid 120.81496 -379.439077)
				(end 120.811036 -379.458474)
			)
			(arc
				(start 120.811036 -382.905508)
				(mid 120.814937 -382.925031)
				(end 120.826022 -382.941576)
			)
			(arc
				(start 120.830086 -382.94564)
				(mid 120.846649 -382.956614)
				(end 120.866154 -382.960372)
			)
		)
		(stroke
			(width 0)
			(type solid)
		)
		(fill yes)
		(layer "B.Cu")
		(net "GND")
	)
	(gr_poly
		(pts
			(arc
				(start 159.429958 -382.960372)
				(mid 159.449452 -382.956588)
				(end 159.466026 -382.94564)
			)
			(arc
				(start 159.676084 -382.735328)
				(mid 159.687146 -382.718911)
				(end 159.69107 -382.699514)
			)
			(arc
				(start 159.69107 -379.428502)
				(mid 159.687169 -379.408979)
				(end 159.676084 -379.392434)
			)
			(arc
				(start 159.647636 -379.363986)
				(mid 159.631102 -379.352875)
				(end 159.611568 -379.349)
			)
			(arc
				(start 153.448512 -379.349)
				(mid 153.428989 -379.352901)
				(end 153.412444 -379.363986)
			)
			(arc
				(start 153.35377 -379.42266)
				(mid 153.342708 -379.439077)
				(end 153.338784 -379.458474)
			)
			(arc
				(start 153.338784 -382.905508)
				(mid 153.342685 -382.925031)
				(end 153.35377 -382.941576)
			)
			(arc
				(start 153.357834 -382.94564)
				(mid 153.374397 -382.956614)
				(end 153.393902 -382.960372)
			)
		)
		(stroke
			(width 0)
			(type solid)
		)
		(fill yes)
		(layer "B.Cu")
		(net "GND")
	)
	(gr_poly
		(pts
			(arc
				(start 165.374574 -424.495976)
				(mid 165.394097 -424.492075)
				(end 165.410642 -424.48099)
			)
			(arc
				(start 165.432486 -424.459146)
				(mid 165.443597 -424.442612)
				(end 165.447472 -424.423078)
			)
			(arc
				(start 165.447472 -423.78376)
				(mid 165.443571 -423.764237)
				(end 165.432486 -423.747692)
			)
			(arc
				(start 165.349428 -423.664634)
				(mid 165.332894 -423.653523)
				(end 165.31336 -423.649648)
			)
			(arc
				(start 162.588956 -423.649648)
				(mid 162.569433 -423.653549)
				(end 162.552888 -423.664634)
			)
			(arc
				(start 162.418268 -423.799254)
				(mid 162.407157 -423.815788)
				(end 162.403282 -423.835322)
			)
			(arc
				(start 162.403282 -424.409616)
				(mid 162.407183 -424.429139)
				(end 162.418268 -424.445684)
			)
			(arc
				(start 162.453574 -424.48099)
				(mid 162.470108 -424.492101)
				(end 162.489642 -424.495976)
			)
		)
		(stroke
			(width 0)
			(type solid)
		)
		(fill yes)
		(layer "B.Cu")
		(net "P1V8_CPU1_RT_1D")
	)
	(gr_poly
		(pts
			(arc
				(start 171.134786 -388.924292)
				(mid 171.154143 -388.920459)
				(end 171.1706 -388.90956)
			)
			(arc
				(start 171.172632 -388.907528)
				(mid 171.183743 -388.890994)
				(end 171.187618 -388.87146)
			)
			(arc
				(start 171.187618 -387.768846)
				(mid 171.183717 -387.749323)
				(end 171.172632 -387.732778)
			)
			(arc
				(start 171.02836 -387.588506)
				(mid 171.011943 -387.577444)
				(end 170.992546 -387.57352)
			)
			(arc
				(start 170.05681 -387.57352)
				(mid 170.037423 -387.57747)
				(end 170.020996 -387.588506)
			)
			(arc
				(start 169.66184 -387.947662)
				(mid 169.650729 -387.964196)
				(end 169.646854 -387.98373)
			)
			(arc
				(start 169.646854 -388.725156)
				(mid 169.650755 -388.744679)
				(end 169.66184 -388.761224)
			)
			(arc
				(start 169.810176 -388.90956)
				(mid 169.826622 -388.920486)
				(end 169.84599 -388.924292)
			)
		)
		(stroke
			(width 0)
			(type solid)
		)
		(fill yes)
		(layer "B.Cu")
		(net "P1V8_CPU1_RT2_1A_1D")
	)
	(gr_poly
		(pts
			(arc
				(start 224.366074 -273.762216)
				(mid 224.385597 -273.758315)
				(end 224.402142 -273.74723)
			)
			(arc
				(start 224.66554 -273.483832)
				(mid 224.676651 -273.467298)
				(end 224.680526 -273.447764)
			)
			(arc
				(start 224.680526 -269.300706)
				(mid 224.676625 -269.281183)
				(end 224.66554 -269.264638)
			)
			(arc
				(start 224.260156 -268.859254)
				(mid 224.243622 -268.848143)
				(end 224.224088 -268.844268)
			)
			(arc
				(start 221.611698 -268.844268)
				(mid 221.592175 -268.848169)
				(end 221.57563 -268.859254)
			)
			(arc
				(start 220.865954 -269.569184)
				(mid 220.854843 -269.585718)
				(end 220.850968 -269.605252)
			)
			(arc
				(start 220.850968 -273.099276)
				(mid 220.854869 -273.118799)
				(end 220.865954 -273.135344)
			)
			(arc
				(start 221.47784 -273.74723)
				(mid 221.494374 -273.758341)
				(end 221.513908 -273.762216)
			)
		)
		(stroke
			(width 0)
			(type solid)
		)
		(fill yes)
		(layer "B.Cu")
		(net "P12V_AUX")
	)
	(gr_poly
		(pts
			(arc
				(start 241.597942 -328.770488)
				(mid 241.617299 -328.766655)
				(end 241.633756 -328.755756)
			)
			(arc
				(start 241.74069 -328.648822)
				(mid 241.751801 -328.632288)
				(end 241.755676 -328.612754)
			)
			(arc
				(start 241.755676 -327.648062)
				(mid 241.751775 -327.628539)
				(end 241.74069 -327.611994)
			)
			(arc
				(start 241.667538 -327.538842)
				(mid 241.651004 -327.527731)
				(end 241.63147 -327.523856)
			)
			(arc
				(start 240.236502 -327.523856)
				(mid 240.216979 -327.527757)
				(end 240.200434 -327.538842)
			)
			(arc
				(start 240.115852 -327.623424)
				(mid 240.104741 -327.639958)
				(end 240.100866 -327.659492)
			)
			(arc
				(start 240.100866 -328.599038)
				(mid 240.104767 -328.618561)
				(end 240.115852 -328.635106)
			)
			(arc
				(start 240.236502 -328.755756)
				(mid 240.252948 -328.766682)
				(end 240.272316 -328.770488)
			)
		)
		(stroke
			(width 0)
			(type solid)
		)
		(fill yes)
		(layer "B.Cu")
		(net "P3V3_AUX")
	)
	(gr_poly
		(pts
			(arc
				(start 243.401342 -371.922294)
				(mid 243.420865 -371.918393)
				(end 243.43741 -371.907308)
			)
			(arc
				(start 243.666518 -371.6782)
				(mid 243.677629 -371.661666)
				(end 243.681504 -371.642132)
			)
			(arc
				(start 243.681504 -370.195094)
				(mid 243.677603 -370.175571)
				(end 243.666518 -370.159026)
			)
			(arc
				(start 243.269008 -369.761516)
				(mid 243.252474 -369.750405)
				(end 243.23294 -369.74653)
			)
			(arc
				(start 237.771178 -369.74653)
				(mid 237.751655 -369.750431)
				(end 237.73511 -369.761516)
			)
			(arc
				(start 237.505748 -369.990878)
				(mid 237.494637 -370.007412)
				(end 237.490762 -370.026946)
			)
			(arc
				(start 237.490762 -371.642132)
				(mid 237.494663 -371.661655)
				(end 237.505748 -371.6782)
			)
			(arc
				(start 237.734856 -371.907308)
				(mid 237.75139 -371.918419)
				(end 237.770924 -371.922294)
			)
		)
		(stroke
			(width 0)
			(type solid)
		)
		(fill yes)
		(layer "B.Cu")
		(net "GND")
	)
	(gr_poly
		(pts
			(arc
				(start 264.097516 -436.21198)
				(mid 264.117039 -436.208079)
				(end 264.133584 -436.196994)
			)
			(arc
				(start 264.72515 -435.605428)
				(mid 264.736261 -435.588894)
				(end 264.740136 -435.56936)
			)
			(arc
				(start 264.740136 -420.951152)
				(mid 264.736235 -420.931629)
				(end 264.72515 -420.915084)
			)
			(arc
				(start 263.977882 -420.167816)
				(mid 263.961348 -420.156705)
				(end 263.941814 -420.15283)
			)
			(arc
				(start 243.003832 -420.15283)
				(mid 242.984309 -420.156731)
				(end 242.967764 -420.167816)
			)
			(arc
				(start 242.531392 -420.604188)
				(mid 242.520281 -420.620722)
				(end 242.516406 -420.640256)
			)
			(arc
				(start 242.516406 -435.543198)
				(mid 242.520307 -435.562721)
				(end 242.531392 -435.579266)
			)
			(arc
				(start 243.14912 -436.196994)
				(mid 243.165654 -436.208105)
				(end 243.185188 -436.21198)
			)
		)
		(stroke
			(width 0)
			(type solid)
		)
		(fill yes)
		(layer "B.Cu")
		(net "GND")
	)
	(gr_poly
		(pts
			(arc
				(start 302.475138 -409.135072)
				(mid 302.494661 -409.131171)
				(end 302.511206 -409.120086)
			)
			(arc
				(start 302.853344 -408.777948)
				(mid 302.864455 -408.761414)
				(end 302.86833 -408.74188)
			)
			(arc
				(start 302.86833 -407.119582)
				(mid 302.864429 -407.100059)
				(end 302.853344 -407.083514)
			)
			(arc
				(start 302.590962 -406.821132)
				(mid 302.574428 -406.810021)
				(end 302.554894 -406.806146)
			)
			(arc
				(start 301.047404 -406.806146)
				(mid 301.027881 -406.810047)
				(end 301.011336 -406.821132)
			)
			(arc
				(start 300.952662 -406.879806)
				(mid 300.941551 -406.89634)
				(end 300.937676 -406.915874)
			)
			(arc
				(start 300.937676 -408.414474)
				(mid 300.941577 -408.433997)
				(end 300.952662 -408.450542)
			)
			(arc
				(start 301.622206 -409.120086)
				(mid 301.63874 -409.131197)
				(end 301.658274 -409.135072)
			)
		)
		(stroke
			(width 0)
			(type solid)
		)
		(fill yes)
		(layer "B.Cu")
		(net "P0V9_CPU0_RT0_2A_2D")
	)
	(gr_poly
		(pts
			(arc
				(start 315.80201 -391.342372)
				(mid 315.821504 -391.338588)
				(end 315.838078 -391.32764)
			)
			(arc
				(start 316.048136 -391.117328)
				(mid 316.059198 -391.100911)
				(end 316.063122 -391.081514)
			)
			(arc
				(start 316.063122 -387.810502)
				(mid 316.059221 -387.790979)
				(end 316.048136 -387.774434)
			)
			(arc
				(start 316.019688 -387.745986)
				(mid 316.003154 -387.734875)
				(end 315.98362 -387.731)
			)
			(arc
				(start 309.820564 -387.731)
				(mid 309.801041 -387.734901)
				(end 309.784496 -387.745986)
			)
			(arc
				(start 309.725822 -387.80466)
				(mid 309.71476 -387.821077)
				(end 309.710836 -387.840474)
			)
			(arc
				(start 309.710836 -391.287508)
				(mid 309.714737 -391.307031)
				(end 309.725822 -391.323576)
			)
			(arc
				(start 309.729886 -391.32764)
				(mid 309.746449 -391.338614)
				(end 309.765954 -391.342372)
			)
		)
		(stroke
			(width 0)
			(type solid)
		)
		(fill yes)
		(layer "B.Cu")
		(net "GND")
	)
	(gr_poly
		(pts
			(arc
				(start 382.902206 -391.342372)
				(mid 382.9217 -391.338588)
				(end 382.938274 -391.32764)
			)
			(arc
				(start 383.148332 -391.117328)
				(mid 383.159394 -391.100911)
				(end 383.163318 -391.081514)
			)
			(arc
				(start 383.163318 -387.810502)
				(mid 383.159417 -387.790979)
				(end 383.148332 -387.774434)
			)
			(arc
				(start 383.120138 -387.74624)
				(mid 383.103692 -387.735314)
				(end 383.084324 -387.731508)
			)
			(arc
				(start 376.920252 -387.731508)
				(mid 376.900895 -387.735341)
				(end 376.884438 -387.74624)
			)
			(arc
				(start 376.826018 -387.80466)
				(mid 376.814956 -387.821077)
				(end 376.811032 -387.840474)
			)
			(arc
				(start 376.811032 -391.287508)
				(mid 376.814933 -391.307031)
				(end 376.826018 -391.323576)
			)
			(arc
				(start 376.830082 -391.32764)
				(mid 376.846645 -391.338614)
				(end 376.86615 -391.342372)
			)
		)
		(stroke
			(width 0)
			(type solid)
		)
		(fill yes)
		(layer "B.Cu")
		(net "GND")
	)
	(gr_poly
		(pts
			(arc
				(start 415.429954 -391.342372)
				(mid 415.449448 -391.338588)
				(end 415.466022 -391.32764)
			)
			(arc
				(start 415.67608 -391.117328)
				(mid 415.687142 -391.100911)
				(end 415.691066 -391.081514)
			)
			(arc
				(start 415.691066 -387.810502)
				(mid 415.687165 -387.790979)
				(end 415.67608 -387.774434)
			)
			(arc
				(start 415.670746 -387.7691)
				(mid 415.6543 -387.758174)
				(end 415.634932 -387.754368)
			)
			(arc
				(start 409.42514 -387.754368)
				(mid 409.405783 -387.758201)
				(end 409.389326 -387.7691)
			)
			(arc
				(start 409.353766 -387.80466)
				(mid 409.342704 -387.821077)
				(end 409.33878 -387.840474)
			)
			(arc
				(start 409.33878 -391.287508)
				(mid 409.342681 -391.307031)
				(end 409.353766 -391.323576)
			)
			(arc
				(start 409.35783 -391.32764)
				(mid 409.374393 -391.338614)
				(end 409.393898 -391.342372)
			)
		)
		(stroke
			(width 0)
			(type solid)
		)
		(fill yes)
		(layer "B.Cu")
		(net "GND")
	)
	(gr_poly
		(pts
			(arc
				(start 427.134528 -397.306292)
				(mid 427.153885 -397.302459)
				(end 427.170342 -397.29156)
			)
			(arc
				(start 427.172374 -397.289528)
				(mid 427.183485 -397.272994)
				(end 427.18736 -397.25346)
			)
			(arc
				(start 427.18736 -396.150846)
				(mid 427.183459 -396.131323)
				(end 427.172374 -396.114778)
			)
			(arc
				(start 427.028102 -395.970506)
				(mid 427.011685 -395.959444)
				(end 426.992288 -395.95552)
			)
			(arc
				(start 426.056552 -395.95552)
				(mid 426.037165 -395.95947)
				(end 426.020738 -395.970506)
			)
			(arc
				(start 425.661582 -396.329662)
				(mid 425.650471 -396.346196)
				(end 425.646596 -396.36573)
			)
			(arc
				(start 425.646596 -397.107156)
				(mid 425.650497 -397.126679)
				(end 425.661582 -397.143224)
			)
			(arc
				(start 425.809918 -397.29156)
				(mid 425.826364 -397.302486)
				(end 425.845732 -397.306292)
			)
		)
		(stroke
			(width 0)
			(type solid)
		)
		(fill yes)
		(layer "B.Cu")
		(net "P1V8_CPU0_RT2_1A_1D")
	)
	(gr_poly
		(pts
			(arc
				(start 463.34426 -73.064116)
				(mid 463.363783 -73.060215)
				(end 463.380328 -73.04913)
			)
			(arc
				(start 464.209384 -72.220074)
				(mid 464.220495 -72.20354)
				(end 464.22437 -72.184006)
			)
			(arc
				(start 464.22437 -66.538856)
				(mid 464.220469 -66.519333)
				(end 464.209384 -66.502788)
			)
			(arc
				(start 463.612484 -65.905888)
				(mid 463.59595 -65.894777)
				(end 463.576416 -65.890902)
			)
			(arc
				(start 445.302386 -65.890902)
				(mid 445.282863 -65.894803)
				(end 445.266318 -65.905888)
			)
			(arc
				(start 444.36792 -66.804286)
				(mid 444.356809 -66.82082)
				(end 444.352934 -66.840354)
			)
			(arc
				(start 444.352934 -72.695054)
				(mid 444.356835 -72.714577)
				(end 444.36792 -72.731122)
			)
			(arc
				(start 444.685928 -73.04913)
				(mid 444.702462 -73.060241)
				(end 444.721996 -73.064116)
			)
		)
		(stroke
			(width 0)
			(type solid)
		)
		(fill yes)
		(layer "B.Cu")
		(net "P3V3_AUX")
	)
	(gr_poly
		(pts
			(xy 197.741794 -363.298486) (xy 197.741794 -353.189032) (xy 197.741794 -351.769172) (xy 197.512686 -351.540064)
			(xy 196.740272 -351.540064) (xy 191.65697 -351.540064) (xy 191.619632 -351.577402) (xy 191.619632 -354.537264)
			(xy 191.787272 -354.704904) (xy 193.31559 -354.704904) (xy 193.557652 -354.946966) (xy 193.557652 -355.835966)
			(xy 193.55562 -355.837998) (xy 193.55562 -356.853998) (xy 192.896744 -357.512874) (xy 187.737242 -357.512874)
			(xy 186.9186 -356.694232) (xy 186.9186 -351.616264) (xy 186.817 -351.514664) (xy 183.330342 -351.514664)
			(xy 183.293004 -351.552002) (xy 183.293004 -354.592636) (xy 183.405272 -354.704904) (xy 185.014362 -354.704904)
			(xy 185.231024 -354.921566) (xy 185.231024 -355.810566) (xy 185.228992 -355.812598) (xy 185.228992 -356.814882)
			(xy 185.22696 -356.816914) (xy 185.22696 -363.117638) (xy 185.22696 -363.84484) (xy 185.37682 -363.9947)
			(xy 186.104022 -363.9947) (xy 197.04558 -363.9947)
		)
		(stroke
			(width 0)
			(type solid)
		)
		(fill yes)
		(layer "B.Cu")
		(net "SW_P12V_AUX_PVDD11_S3_P1_FLT")
	)
	(gr_poly
		(pts
			(arc
				(start 305.25847 -428.327566)
				(mid 305.277993 -428.323665)
				(end 305.294538 -428.31258)
			)
			(arc
				(start 305.298856 -428.308262)
				(mid 305.309967 -428.291728)
				(end 305.313842 -428.272194)
			)
			(arc
				(start 305.313842 -425.496228)
				(mid 305.309941 -425.476705)
				(end 305.298856 -425.46016)
			)
			(xy 305.247802 -425.409106) (xy 305.236626 -425.400724)
			(arc
				(start 305.213512 -425.387008)
				(mid 305.200605 -425.381173)
				(end 305.186588 -425.379134)
			)
			(arc
				(start 304.447702 -425.379134)
				(mid 304.428179 -425.383035)
				(end 304.411634 -425.39412)
			)
			(arc
				(start 303.986184 -425.81957)
				(mid 303.975073 -425.836104)
				(end 303.971198 -425.855638)
			)
			(arc
				(start 303.971198 -427.498002)
				(mid 303.975099 -427.517525)
				(end 303.986184 -427.53407)
			)
			(arc
				(start 304.764694 -428.31258)
				(mid 304.781228 -428.323691)
				(end 304.800762 -428.327566)
			)
		)
		(stroke
			(width 0)
			(type solid)
		)
		(fill yes)
		(layer "B.Cu")
		(net "P1V8_CPU0_RT_1D")
	)
	(gr_poly
		(pts
			(arc
				(start 380.492254 -144.55013)
				(mid 380.511377 -144.546304)
				(end 380.52756 -144.535398)
			)
			(arc
				(start 380.574296 -144.488662)
				(mid 380.585136 -144.472451)
				(end 380.589028 -144.453356)
			)
			(arc
				(start 380.589028 -140.227304)
				(mid 380.585202 -140.208181)
				(end 380.574296 -140.191998)
			)
			(arc
				(start 380.55296 -140.170662)
				(mid 380.536749 -140.159822)
				(end 380.517654 -140.15593)
			)
			(arc
				(start 376.266202 -140.15593)
				(mid 376.247079 -140.159756)
				(end 376.230896 -140.170662)
			)
			(arc
				(start 376.20956 -140.191998)
				(mid 376.19872 -140.208209)
				(end 376.194828 -140.227304)
			)
			(arc
				(start 376.194828 -144.478756)
				(mid 376.198654 -144.497879)
				(end 376.20956 -144.514062)
			)
			(arc
				(start 376.230896 -144.535398)
				(mid 376.247107 -144.546238)
				(end 376.266202 -144.55013)
			)
			(xy 378.709428 -144.55013) (xy 380.081028 -144.55013)
		)
		(stroke
			(width 0)
			(type solid)
		)
		(fill yes)
		(layer "B.Cu")
		(net "GND")
	)
	(gr_poly
		(pts
			(xy 134.135114 -34.0614) (xy 134.135114 -32.366966) (xy 134.24916 -32.25292) (xy 135.18642 -32.25292)
			(xy 135.35152 -32.08782) (xy 135.35152 -31.84906) (xy 135.453374 -31.747206) (xy 137.425684 -31.747206)
			(xy 137.686796 -32.008318) (xy 138.537696 -32.008318) (xy 138.601196 -31.944818) (xy 138.601196 -31.1912)
			(xy 138.268964 -30.858968) (xy 137.472166 -30.858968) (xy 135.260842 -30.858968) (xy 134.787894 -30.38602)
			(xy 130.48488 -30.38602) (xy 130.24612 -30.62478) (xy 130.24612 -30.91942) (xy 130.39598 -31.06928)
			(xy 131.279138 -31.06928) (xy 131.504436 -31.294578) (xy 132.193792 -31.294578) (xy 132.61848 -31.719266)
			(xy 132.61848 -32.3215) (xy 132.502402 -32.437578) (xy 131.788662 -32.437578) (xy 131.58978 -32.63646)
			(xy 131.58978 -33.014158) (xy 131.6482 -33.072578) (xy 133.40969 -33.072578) (xy 133.500114 -33.163002)
			(xy 133.500114 -33.921954) (xy 133.67004 -34.09188) (xy 134.104634 -34.09188)
		)
		(stroke
			(width 0)
			(type solid)
		)
		(fill yes)
		(layer "B.Cu")
		(net "P3V3_AUX")
	)
	(gr_poly
		(pts
			(arc
				(start 437.714898 -364.84052)
				(mid 437.734421 -364.836619)
				(end 437.750966 -364.825534)
			)
			(xy 437.82996 -364.74654) (xy 437.83758 -364.727998) (xy 437.83758 -364.72368)
			(arc
				(start 438.289954 -364.271306)
				(mid 438.301065 -364.254772)
				(end 438.30494 -364.235238)
			)
			(arc
				(start 438.30494 -363.208062)
				(mid 438.301039 -363.188539)
				(end 438.289954 -363.171994)
			)
			(arc
				(start 438.286906 -363.168946)
				(mid 438.270372 -363.157835)
				(end 438.250838 -363.15396)
			)
			(arc
				(start 436.578502 -363.15396)
				(mid 436.558979 -363.157861)
				(end 436.542434 -363.168946)
			)
			(arc
				(start 436.503826 -363.207554)
				(mid 436.492715 -363.224088)
				(end 436.48884 -363.243622)
			)
			(arc
				(start 436.48884 -364.644178)
				(mid 436.492741 -364.663701)
				(end 436.503826 -364.680246)
			)
			(arc
				(start 436.649114 -364.825534)
				(mid 436.665648 -364.836645)
				(end 436.685182 -364.84052)
			)
		)
		(stroke
			(width 0)
			(type solid)
		)
		(fill yes)
		(layer "B.Cu")
		(net "GND")
	)
	(gr_poly
		(pts
			(arc
				(start 168.634664 -383.50317)
				(mid 168.654187 -383.499269)
				(end 168.670732 -383.488184)
			)
			(xy 168.675304 -383.483612) (xy 168.675304 -383.373122)
			(arc
				(start 168.674542 -383.368804)
				(mid 168.670508 -383.336659)
				(end 168.669208 -383.304288)
			)
			(xy 168.669208 -383.124456) (xy 168.665652 -383.121154)
			(arc
				(start 168.258236 -383.121154)
				(mid 168.238713 -383.117253)
				(end 168.222168 -383.106168)
			)
			(arc
				(start 167.717724 -382.601724)
				(mid 167.70119 -382.590613)
				(end 167.681656 -382.586738)
			)
			(arc
				(start 166.48811 -382.586738)
				(mid 166.468587 -382.590639)
				(end 166.452042 -382.601724)
			)
			(arc
				(start 166.36492 -382.688846)
				(mid 166.353809 -382.70538)
				(end 166.349934 -382.724914)
			)
			(arc
				(start 166.349934 -383.26822)
				(mid 166.353835 -383.287743)
				(end 166.36492 -383.304288)
			)
			(arc
				(start 166.548816 -383.488184)
				(mid 166.56535 -383.499295)
				(end 166.584884 -383.50317)
			)
		)
		(stroke
			(width 0)
			(type solid)
		)
		(fill yes)
		(layer "B.Cu")
		(net "NCF_CPU1_P2_GND")
	)
	(gr_poly
		(pts
			(arc
				(start 273.15541 -393.27836)
				(mid 273.174933 -393.274459)
				(end 273.191478 -393.263374)
			)
			(arc
				(start 273.669506 -392.785346)
				(mid 273.680617 -392.768812)
				(end 273.684492 -392.749278)
			)
			(arc
				(start 273.684492 -384.155442)
				(mid 273.680591 -384.135919)
				(end 273.669506 -384.119374)
			)
			(xy 273.445478 -383.895346) (xy 273.438366 -383.88798) (xy 273.41957 -383.88036) (xy 244.79504 -383.88036)
			(xy 244.3988 -384.2766) (xy 243.983764 -384.691636) (xy 239.317276 -384.691636) (xy 239.013492 -384.99542)
			(arc
				(start 239.013492 -393.003278)
				(mid 239.017393 -393.022801)
				(end 239.028478 -393.039346)
			)
			(arc
				(start 239.252506 -393.263374)
				(mid 239.26904 -393.274485)
				(end 239.288574 -393.27836)
			)
			(xy 243.76888 -393.27836) (xy 244.47246 -393.27836) (xy 251.78258 -393.27836) (xy 252.52426 -393.27836)
			(xy 259.77088 -393.27836) (xy 260.5786 -393.27836) (xy 267.79728 -393.27836) (xy 268.61262 -393.27836)
		)
		(stroke
			(width 0)
			(type solid)
		)
		(fill yes)
		(layer "B.Cu")
		(net "P12V_MAIN_R")
	)
	(gr_poly
		(pts
			(arc
				(start 424.63466 -391.88517)
				(mid 424.654183 -391.881269)
				(end 424.670728 -391.870184)
			)
			(xy 424.6753 -391.865612) (xy 424.6753 -391.755122)
			(arc
				(start 424.674538 -391.750804)
				(mid 424.670504 -391.718659)
				(end 424.669204 -391.686288)
			)
			(xy 424.669204 -391.506456) (xy 424.665648 -391.503154)
			(arc
				(start 424.258232 -391.503154)
				(mid 424.238709 -391.499253)
				(end 424.222164 -391.488168)
			)
			(arc
				(start 423.71772 -390.983724)
				(mid 423.701186 -390.972613)
				(end 423.681652 -390.968738)
			)
			(arc
				(start 422.488106 -390.968738)
				(mid 422.468583 -390.972639)
				(end 422.452038 -390.983724)
			)
			(arc
				(start 422.364916 -391.070846)
				(mid 422.353805 -391.08738)
				(end 422.34993 -391.106914)
			)
			(arc
				(start 422.34993 -391.65022)
				(mid 422.353831 -391.669743)
				(end 422.364916 -391.686288)
			)
			(arc
				(start 422.548812 -391.870184)
				(mid 422.565346 -391.881295)
				(end 422.58488 -391.88517)
			)
		)
		(stroke
			(width 0)
			(type solid)
		)
		(fill yes)
		(layer "B.Cu")
		(net "NCF_CPU0_P2_GND")
	)
	(gr_poly
		(pts
			(xy 73.654412 -173.299374)
			(arc
				(start 73.654666 -173.279054)
				(mid 73.766364 -173.016102)
				(end 74.029316 -172.904404)
			)
			(xy 74.049636 -172.90415) (xy 74.071734 -172.882052)
			(arc
				(start 75.67422 -172.882052)
				(mid 75.926442 -172.786787)
				(end 76.178664 -172.882052)
			)
			(xy 77.843634 -172.882052) (xy 77.940154 -172.785532) (xy 77.940154 -172.071792) (xy 77.061314 -171.192952)
			(xy 72.331834 -171.192952) (xy 71.988934 -171.535852) (xy 71.988934 -173.593252) (xy 72.014334 -173.618652)
			(xy 73.335134 -173.618652)
		)
		(stroke
			(width 0)
			(type solid)
		)
		(fill yes)
		(layer "B.Cu")
		(net "GND")
	)
	(gr_poly
		(pts
			(xy 9.227312 -334.593184) (xy 9.227312 -331.110844) (xy 8.323072 -330.206604) (xy 8.323072 -326.966834)
			(xy 9.227312 -326.062594) (xy 9.227312 -188.110876) (xy 9.227312 -185.504836) (xy 16.232632 -178.499516)
			(xy 16.232632 -177.145188) (xy 30.67939 -162.69843) (xy 31.681674 -162.69843) (xy 37.382196 -156.997908)
			(xy 37.382196 -146.98091) (xy 30.640528 -140.239242) (xy 30.640528 -132.88518) (xy 30.29458 -132.539232)
			(xy 30.29458 -132.21716) (xy 30.640528 -131.871212) (xy 30.640528 -101.329744) (xy 34.916872 -97.0534)
			(xy 64.368426 -97.0534) (xy 65.023238 -96.398588) (xy 65.023238 -94.62643) (xy 64.464692 -94.067884)
			(xy 32.643826 -94.067884) (xy 28.194254 -98.517456) (xy 28.194254 -141.029182) (xy 35.880294 -148.715222)
			(xy 35.880294 -156.013404) (xy 31.515304 -160.378394) (xy 27.81935 -160.378394) (xy 14.3256 -173.872144)
			(xy 14.3256 -178.435) (xy 7.345172 -185.415428) (xy 7.345172 -188.459364) (xy 7.345172 -334.462882)
			(xy 7.68731 -334.80502) (xy 9.015476 -334.80502)
		)
		(stroke
			(width 0)
			(type solid)
		)
		(fill yes)
		(layer "B.Cu")
		(net "P3V3_AUX")
	)
	(gr_poly
		(pts
			(arc
				(start 148.374608 -34.243772)
				(mid 148.394131 -34.239871)
				(end 148.410676 -34.228786)
			)
			(arc
				(start 148.444204 -34.195258)
				(mid 148.455315 -34.178724)
				(end 148.45919 -34.15919)
			)
			(arc
				(start 148.45919 -32.791654)
				(mid 148.455289 -32.772131)
				(end 148.444204 -32.755586)
			)
			(arc
				(start 148.410676 -32.722058)
				(mid 148.394142 -32.710947)
				(end 148.374608 -32.707072)
			)
			(xy 145.33753 -32.707072) (xy 145.26768 -32.776922) (xy 144.782286 -32.776922) (xy 144.712436 -32.707072)
			(xy 144.599152 -32.707072) (xy 144.143222 -32.707072)
			(arc
				(start 141.806422 -32.707072)
				(mid 141.786899 -32.710973)
				(end 141.770354 -32.722058)
			)
			(arc
				(start 141.736826 -32.755586)
				(mid 141.725715 -32.77212)
				(end 141.72184 -32.791654)
			)
			(arc
				(start 141.72184 -34.15919)
				(mid 141.725741 -34.178713)
				(end 141.736826 -34.195258)
			)
			(arc
				(start 141.770354 -34.228786)
				(mid 141.786888 -34.239897)
				(end 141.806422 -34.243772)
			)
		)
		(stroke
			(width 0)
			(type solid)
		)
		(fill yes)
		(layer "B.Cu")
		(net "P3V3_AUX")
	)
	(gr_poly
		(pts
			(xy 130.067304 -34.83102) (xy 130.067304 -33.013396) (xy 130.188208 -32.892492) (xy 130.88112 -32.892492)
			(xy 130.95732 -32.816292) (xy 130.95732 -32.44596) (xy 130.768852 -32.257492) (xy 130.35788 -32.257492)
			(xy 130.281934 -32.181546) (xy 130.281934 -31.417514) (xy 130.22326 -31.35884) (xy 129.80543 -31.35884)
			(xy 129.685796 -31.239206) (xy 129.216912 -30.770322) (xy 127.509524 -30.770322) (xy 127.446024 -30.833822)
			(xy 127.446024 -31.895796) (xy 127.236728 -32.105092) (xy 127.13462 -32.2072) (xy 126.5428 -32.2072)
			(xy 126.509018 -32.240982) (xy 126.509018 -32.701484) (xy 126.547626 -32.740092) (xy 128.105408 -32.740092)
			(xy 128.29159 -32.55391) (xy 128.29159 -32.24911) (xy 128.39192 -32.14878) (xy 128.397 -32.14878)
			(xy 128.41478 -32.131) (xy 129.152904 -32.131) (xy 129.206244 -32.131) (xy 129.257044 -32.131) (xy 129.432304 -32.30626)
			(xy 129.432304 -32.35706) (xy 129.432304 -32.4104) (xy 129.432304 -32.556704) (xy 129.432304 -34.868104)
			(xy 129.49428 -34.93008) (xy 129.968244 -34.93008)
		)
		(stroke
			(width 0)
			(type solid)
		)
		(fill yes)
		(layer "B.Cu")
		(net "P1V2_AUX")
	)
	(gr_poly
		(pts
			(xy 439.086498 -361.920282) (xy 439.086498 -353.567492) (xy 438.448958 -352.929952) (xy 438.377584 -352.858578)
			(xy 438.377584 -351.461578) (xy 438.275476 -351.35947) (xy 432.381152 -351.35947) (xy 432.343814 -351.396808)
			(xy 432.343814 -354.35667) (xy 432.511454 -354.52431) (xy 434.039772 -354.52431) (xy 434.281834 -354.766372)
			(xy 434.281834 -355.655372) (xy 434.279802 -355.657404) (xy 434.279802 -356.673404) (xy 433.620926 -357.33228)
			(xy 428.461424 -357.33228) (xy 427.642782 -356.513638) (xy 427.642782 -351.43567) (xy 427.541182 -351.33407)
			(xy 424.054524 -351.33407) (xy 424.017186 -351.371408) (xy 424.017186 -354.412042) (xy 424.129454 -354.52431)
			(xy 425.738544 -354.52431) (xy 425.955206 -354.740972) (xy 425.955206 -355.629972) (xy 425.953174 -355.632004)
			(xy 425.953174 -356.634288) (xy 425.951142 -356.63632) (xy 425.951142 -357.534972) (xy 426.09516 -357.67899)
			(xy 426.09516 -361.37342) (xy 426.231304 -361.509564) (xy 426.800518 -362.079032) (xy 427.552358 -362.830872)
			(xy 428.652178 -362.830872) (xy 429.301148 -362.830872) (xy 438.175908 -362.830872)
		)
		(stroke
			(width 0)
			(type solid)
		)
		(fill yes)
		(layer "B.Cu")
		(net "SW_P12V_AUX_PVDD11_S3_P0_FLT")
	)
	(gr_poly
		(pts
			(arc
				(start 107.827572 -411.925262)
				(mid 107.847095 -411.921361)
				(end 107.86364 -411.910276)
			)
			(arc
				(start 108.014262 -411.759654)
				(mid 108.025373 -411.74312)
				(end 108.029248 -411.723586)
			)
			(arc
				(start 108.029248 -409.649676)
				(mid 108.033149 -409.630153)
				(end 108.044234 -409.613608)
			)
			(arc
				(start 108.66501 -408.992832)
				(mid 108.676121 -408.976298)
				(end 108.679996 -408.956764)
			)
			(arc
				(start 108.679996 -408.210004)
				(mid 108.676095 -408.190481)
				(end 108.66501 -408.173936)
			)
			(arc
				(start 108.558076 -408.067002)
				(mid 108.541542 -408.055891)
				(end 108.522008 -408.052016)
			)
			(arc
				(start 104.827324 -408.052016)
				(mid 104.807801 -408.055917)
				(end 104.791256 -408.067002)
			)
			(arc
				(start 104.696768 -408.16149)
				(mid 104.685657 -408.178024)
				(end 104.681782 -408.197558)
			)
			(arc
				(start 104.681782 -411.47238)
				(mid 104.685683 -411.491903)
				(end 104.696768 -411.508448)
			)
			(arc
				(start 105.098596 -411.910276)
				(mid 105.11513 -411.921387)
				(end 105.134664 -411.925262)
			)
		)
		(stroke
			(width 0)
			(type solid)
		)
		(fill yes)
		(layer "B.Cu")
		(net "GND")
	)
	(gr_poly
		(pts
			(arc
				(start 246.752872 -330.606908)
				(mid 246.772395 -330.603007)
				(end 246.78894 -330.591922)
			)
			(arc
				(start 246.942864 -330.437998)
				(mid 246.953975 -330.421464)
				(end 246.95785 -330.40193)
			)
			(arc
				(start 246.95785 -330.050648)
				(mid 246.953949 -330.031125)
				(end 246.942864 -330.01458)
			)
			(arc
				(start 246.923052 -329.994768)
				(mid 246.906606 -329.983842)
				(end 246.887238 -329.980036)
			)
			(arc
				(start 246.84863 -329.980036)
				(mid 246.829243 -329.976086)
				(end 246.812816 -329.96505)
			)
			(arc
				(start 246.182642 -329.33513)
				(mid 246.166225 -329.324068)
				(end 246.146828 -329.320144)
			)
			(arc
				(start 243.776754 -329.320144)
				(mid 243.757231 -329.324045)
				(end 243.740686 -329.33513)
			)
			(arc
				(start 243.676678 -329.399138)
				(mid 243.665567 -329.415672)
				(end 243.661692 -329.435206)
			)
			(arc
				(start 243.661692 -330.282042)
				(mid 243.665642 -330.301429)
				(end 243.676678 -330.317856)
			)
			(arc
				(start 243.950744 -330.591922)
				(mid 243.967161 -330.602984)
				(end 243.986558 -330.606908)
			)
		)
		(stroke
			(width 0)
			(type solid)
		)
		(fill yes)
		(layer "B.Cu")
		(net "GND")
	)
	(gr_poly
		(pts
			(arc
				(start 171.441618 -53.961284)
				(mid 171.461112 -53.9575)
				(end 171.477686 -53.946552)
			)
			(arc
				(start 171.821348 -53.602636)
				(mid 171.83241 -53.586219)
				(end 171.836334 -53.566822)
			)
			(arc
				(start 171.836334 -50.38725)
				(mid 171.832433 -50.367727)
				(end 171.821348 -50.351182)
			)
			(arc
				(start 171.21632 -49.746154)
				(mid 171.199786 -49.735043)
				(end 171.180252 -49.731168)
			)
			(arc
				(start 170.564556 -49.731168)
				(mid 170.545033 -49.735069)
				(end 170.528488 -49.746154)
			)
			(arc
				(start 170.3578 -49.916842)
				(mid 170.346689 -49.933376)
				(end 170.342814 -49.95291)
			)
			(arc
				(start 170.342814 -50.639726)
				(mid 170.338913 -50.659249)
				(end 170.327828 -50.675794)
			)
			(arc
				(start 169.872914 -51.130708)
				(mid 169.861852 -51.147125)
				(end 169.857928 -51.166522)
			)
			(xy 169.857928 -53.673756) (xy 169.850308 -53.692298) (xy 169.850054 -53.692552)
			(arc
				(start 169.850054 -53.910484)
				(mid 169.864933 -53.946405)
				(end 169.900854 -53.961284)
			)
		)
		(stroke
			(width 0)
			(type solid)
		)
		(fill yes)
		(layer "B.Cu")
		(net "GND")
	)
	(gr_poly
		(pts
			(arc
				(start 81.154778 -2.750312)
				(mid 81.182917 -2.732466)
				(end 81.193894 -2.701036)
			)
			(arc
				(start 81.193894 -0.5588)
				(mid 81.179015 -0.522879)
				(end 81.143094 -0.508)
			)
			(arc
				(start 13.660882 -0.508)
				(mid 13.624961 -0.522879)
				(end 13.610082 -0.5588)
			)
			(arc
				(start 13.610082 -2.701036)
				(mid 13.621129 -2.732411)
				(end 13.649198 -2.750312)
			)
			(xy 13.762482 -2.77749) (xy 13.794486 -2.762504)
			(arc
				(start 13.80236 -2.746756)
				(mid 13.928356 -2.557713)
				(end 14.095984 -2.404364)
			)
			(xy 14.11732 -2.363216) (xy 14.11732 -1.014984) (xy 80.686656 -1.014984) (xy 80.686656 -2.363216)
			(arc
				(start 80.707992 -2.404364)
				(mid 80.875659 -2.55768)
				(end 81.001616 -2.746756)
			)
			(xy 81.00949 -2.762504) (xy 81.041494 -2.77749)
		)
		(stroke
			(width 0)
			(type solid)
		)
		(fill yes)
		(layer "B.Cu")
		(net "GND")
	)
	(gr_poly
		(pts
			(arc
				(start 194.154806 -8.03021)
				(mid 194.182945 -8.012364)
				(end 194.193922 -7.980934)
			)
			(arc
				(start 194.193922 -5.838698)
				(mid 194.179043 -5.802777)
				(end 194.143122 -5.787898)
			)
			(arc
				(start 126.66091 -5.787898)
				(mid 126.624989 -5.802777)
				(end 126.61011 -5.838698)
			)
			(arc
				(start 126.61011 -7.980934)
				(mid 126.621157 -8.012309)
				(end 126.649226 -8.03021)
			)
			(xy 126.76251 -8.057388) (xy 126.794514 -8.042402)
			(arc
				(start 126.802388 -8.026654)
				(mid 126.928384 -7.837611)
				(end 127.096012 -7.684262)
			)
			(xy 127.117348 -7.643114) (xy 127.117348 -6.295136) (xy 193.686684 -6.295136) (xy 193.686684 -7.643114)
			(arc
				(start 193.70802 -7.684262)
				(mid 193.875687 -7.837578)
				(end 194.001644 -8.026654)
			)
			(xy 194.009518 -8.042402) (xy 194.041522 -8.057388)
		)
		(stroke
			(width 0)
			(type solid)
		)
		(fill yes)
		(layer "B.Cu")
		(net "GND")
	)
	(gr_poly
		(pts
			(arc
				(start 452.065898 -52.935886)
				(mid 452.085421 -52.931985)
				(end 452.101966 -52.9209)
			)
			(arc
				(start 452.328534 -52.694586)
				(mid 452.339645 -52.678052)
				(end 452.34352 -52.658518)
			)
			(arc
				(start 452.34352 -50.450242)
				(mid 452.339619 -50.430719)
				(end 452.328534 -50.414174)
			)
			(xy 451.222364 -49.308004) (xy 451.204076 -49.300384) (xy 451.05066 -49.146968) (xy 451.05066 -48.295052)
			(xy 451.05066 -48.11776) (xy 450.807582 -47.874682) (xy 450.638926 -47.874682) (xy 450.629528 -47.87392)
			(arc
				(start 431.089562 -47.87392)
				(mid 431.070039 -47.877821)
				(end 431.053494 -47.888906)
			)
			(arc
				(start 430.750726 -48.191674)
				(mid 430.739615 -48.208208)
				(end 430.73574 -48.227742)
			)
			(arc
				(start 430.73574 -51.129438)
				(mid 430.739641 -51.148961)
				(end 430.750726 -51.165506)
			)
			(arc
				(start 431.071274 -51.486054)
				(mid 431.087808 -51.497165)
				(end 431.107342 -51.50104)
			)
			(arc
				(start 440.793378 -51.50104)
				(mid 440.812901 -51.504941)
				(end 440.829446 -51.516026)
			)
			(arc
				(start 442.23432 -52.9209)
				(mid 442.250854 -52.932011)
				(end 442.270388 -52.935886)
			)
		)
		(stroke
			(width 0)
			(type solid)
		)
		(fill yes)
		(layer "B.Cu")
		(net "SW_P3V3_AUX_FLT")
	)
	(gr_poly
		(pts
			(arc
				(start 259.639816 -328.165714)
				(mid 259.659339 -328.161813)
				(end 259.675884 -328.150728)
			)
			(arc
				(start 259.816346 -328.010266)
				(mid 259.827457 -327.993732)
				(end 259.831332 -327.974198)
			)
			(arc
				(start 259.831332 -325.713852)
				(mid 259.827431 -325.694329)
				(end 259.816346 -325.677784)
			)
			(arc
				(start 259.766816 -325.628254)
				(mid 259.750282 -325.617143)
				(end 259.730748 -325.613268)
			)
			(arc
				(start 257.54965 -325.613268)
				(mid 257.530127 -325.617169)
				(end 257.513582 -325.628254)
			)
			(xy 257.47345 -325.668386) (xy 257.465576 -325.687436) (xy 257.46583 -325.698104) (xy 257.466084 -325.700898)
			(arc
				(start 257.466084 -326.970898)
				(mid 257.437231 -327.051679)
				(end 257.363722 -327.095866)
			)
			(arc
				(start 257.363722 -327.095866)
				(mid 257.348788 -327.101298)
				(end 257.33629 -327.111106)
			)
			(arc
				(start 257.315208 -327.133966)
				(mid 257.305182 -327.149961)
				(end 257.301746 -327.16851)
			)
			(arc
				(start 257.301746 -328.008742)
				(mid 257.305647 -328.028265)
				(end 257.316732 -328.04481)
			)
			(arc
				(start 257.42265 -328.150728)
				(mid 257.439184 -328.161839)
				(end 257.458718 -328.165714)
			)
		)
		(stroke
			(width 0)
			(type solid)
		)
		(fill yes)
		(layer "B.Cu")
		(net "GND")
	)
	(gr_poly
		(pts
			(arc
				(start 325.693278 -391.88517)
				(mid 325.729199 -391.870291)
				(end 325.744078 -391.83437)
			)
			(arc
				(start 325.744078 -391.834116)
				(mid 325.773016 -391.688163)
				(end 325.855584 -391.564368)
			)
			(arc
				(start 325.923402 -391.496804)
				(mid 325.934513 -391.48027)
				(end 325.938388 -391.460736)
			)
			(arc
				(start 325.938388 -391.2616)
				(mid 325.939317 -391.234227)
				(end 325.942198 -391.20699)
			)
			(xy 325.942706 -391.203434)
			(arc
				(start 325.942706 -391.089388)
				(mid 325.938805 -391.069865)
				(end 325.92772 -391.05332)
			)
			(arc
				(start 325.858124 -390.983724)
				(mid 325.84159 -390.972613)
				(end 325.822056 -390.968738)
			)
			(arc
				(start 322.860162 -390.968738)
				(mid 322.840639 -390.972639)
				(end 322.824094 -390.983724)
			)
			(arc
				(start 322.736972 -391.070846)
				(mid 322.725861 -391.08738)
				(end 322.721986 -391.106914)
			)
			(arc
				(start 322.721986 -391.65022)
				(mid 322.725887 -391.669743)
				(end 322.736972 -391.686288)
			)
			(arc
				(start 322.920868 -391.870184)
				(mid 322.937402 -391.881295)
				(end 322.956936 -391.88517)
			)
		)
		(stroke
			(width 0)
			(type solid)
		)
		(fill yes)
		(layer "B.Cu")
		(net "NCF_CPU0_P0_GND")
	)
	(gr_poly
		(pts
			(arc
				(start 455.654918 -2.75082)
				(mid 455.683057 -2.732974)
				(end 455.694034 -2.701544)
			)
			(arc
				(start 455.694034 -0.5588)
				(mid 455.679155 -0.522879)
				(end 455.643234 -0.508)
			)
			(arc
				(start 388.160768 -0.508)
				(mid 388.124847 -0.522879)
				(end 388.109968 -0.5588)
			)
			(arc
				(start 388.109968 -2.701036)
				(mid 388.121015 -2.732411)
				(end 388.149084 -2.750312)
			)
			(xy 388.262368 -2.77749) (xy 388.294372 -2.762504)
			(arc
				(start 388.302246 -2.746756)
				(mid 388.428345 -2.557672)
				(end 388.596124 -2.404364)
			)
			(arc
				(start 388.596124 -2.404364)
				(mid 388.610195 -2.388884)
				(end 388.616952 -2.369058)
			)
			(xy 388.616952 -1.014984) (xy 455.186796 -1.014984) (xy 455.186796 -2.36347)
			(arc
				(start 455.208132 -2.404618)
				(mid 455.3758 -2.558068)
				(end 455.501756 -2.747264)
			)
			(xy 455.50963 -2.763012) (xy 455.54138 -2.777744)
		)
		(stroke
			(width 0)
			(type solid)
		)
		(fill yes)
		(layer "B.Cu")
		(net "GND")
	)
	(gr_poly
		(pts
			(arc
				(start 213.755732 -27.630628)
				(mid 213.910612 -27.539023)
				(end 214.08771 -27.507184)
			)
			(arc
				(start 214.08771 -27.507184)
				(mid 214.264798 -27.53905)
				(end 214.419688 -27.630628)
			)
			(arc
				(start 216.628472 -27.630628)
				(mid 216.647995 -27.626727)
				(end 216.66454 -27.615642)
			)
			(arc
				(start 217.317828 -26.962354)
				(mid 217.328939 -26.94582)
				(end 217.332814 -26.926286)
			)
			(arc
				(start 217.332814 -25.23363)
				(mid 217.328913 -25.214107)
				(end 217.317828 -25.197562)
			)
			(arc
				(start 216.75344 -24.633174)
				(mid 216.736906 -24.622063)
				(end 216.717372 -24.618188)
			)
			(arc
				(start 213.246716 -24.618188)
				(mid 213.227193 -24.622089)
				(end 213.210648 -24.633174)
			)
			(arc
				(start 213.05012 -24.793702)
				(mid 213.039009 -24.810236)
				(end 213.035134 -24.82977)
			)
			(arc
				(start 213.035134 -27.375866)
				(mid 213.039035 -27.395389)
				(end 213.05012 -27.411934)
			)
			(arc
				(start 213.253828 -27.615642)
				(mid 213.270362 -27.626753)
				(end 213.289896 -27.630628)
			)
		)
		(stroke
			(width 0)
			(type solid)
		)
		(fill yes)
		(layer "B.Cu")
		(net "GND")
	)
	(gr_poly
		(pts
			(arc
				(start 319.781936 -341.322152)
				(mid 319.801168 -341.318309)
				(end 319.817496 -341.30742)
			)
			(arc
				(start 320.143632 -340.981284)
				(mid 320.154587 -340.964983)
				(end 320.158364 -340.945724)
			)
			(arc
				(start 320.158364 -339.28558)
				(mid 320.154521 -339.266348)
				(end 320.143632 -339.25002)
			)
			(arc
				(start 320.071496 -339.177884)
				(mid 320.055195 -339.166929)
				(end 320.035936 -339.163152)
			)
			(arc
				(start 318.959992 -339.163152)
				(mid 318.94076 -339.166995)
				(end 318.924432 -339.177884)
			)
			(arc
				(start 318.826896 -339.27542)
				(mid 318.815941 -339.291721)
				(end 318.812164 -339.31098)
			)
			(arc
				(start 318.812164 -339.599524)
				(mid 318.808321 -339.618756)
				(end 318.797432 -339.635084)
			)
			(arc
				(start 318.649096 -339.78342)
				(mid 318.632795 -339.794375)
				(end 318.613536 -339.798152)
			)
			(arc
				(start 317.943992 -339.798152)
				(mid 317.92476 -339.801995)
				(end 317.908432 -339.812884)
			)
			(arc
				(start 317.810896 -339.91042)
				(mid 317.799941 -339.926721)
				(end 317.796164 -339.94598)
			)
			(arc
				(start 317.796164 -340.336124)
				(mid 317.800007 -340.355356)
				(end 317.810896 -340.371684)
			)
			(arc
				(start 318.746632 -341.30742)
				(mid 318.762933 -341.318375)
				(end 318.782192 -341.322152)
			)
		)
		(stroke
			(width 0)
			(type solid)
		)
		(fill yes)
		(layer "B.Cu")
		(net "GND")
	)
	(gr_poly
		(pts
			(arc
				(start 136.826244 -383.50317)
				(mid 136.845767 -383.499269)
				(end 136.862312 -383.488184)
			)
			(arc
				(start 137.02792 -383.322576)
				(mid 137.039031 -383.306042)
				(end 137.042906 -383.286508)
			)
			(xy 137.042906 -382.937766)
			(arc
				(start 137.042398 -382.93421)
				(mid 137.039506 -382.906974)
				(end 137.038588 -382.8796)
			)
			(arc
				(start 137.038588 -382.747012)
				(mid 137.034687 -382.727489)
				(end 137.023602 -382.710944)
			)
			(arc
				(start 136.964166 -382.651762)
				(mid 136.947749 -382.6407)
				(end 136.928352 -382.636776)
			)
			(arc
				(start 136.643364 -382.636776)
				(mid 136.623841 -382.640677)
				(end 136.607296 -382.651762)
			)
			(arc
				(start 136.15289 -383.106168)
				(mid 136.136356 -383.117279)
				(end 136.116822 -383.121154)
			)
			(arc
				(start 135.730488 -383.121154)
				(mid 135.710965 -383.117253)
				(end 135.69442 -383.106168)
			)
			(arc
				(start 135.189976 -382.601724)
				(mid 135.173442 -382.590613)
				(end 135.153908 -382.586738)
			)
			(arc
				(start 133.960362 -382.586738)
				(mid 133.940839 -382.590639)
				(end 133.924294 -382.601724)
			)
			(arc
				(start 133.837172 -382.688846)
				(mid 133.826061 -382.70538)
				(end 133.822186 -382.724914)
			)
			(arc
				(start 133.822186 -383.26822)
				(mid 133.826087 -383.287743)
				(end 133.837172 -383.304288)
			)
			(arc
				(start 134.021068 -383.488184)
				(mid 134.037602 -383.499295)
				(end 134.057136 -383.50317)
			)
		)
		(stroke
			(width 0)
			(type solid)
		)
		(fill yes)
		(layer "B.Cu")
		(net "NCF_CPU1_P3_GND")
	)
	(gr_poly
		(pts
			(arc
				(start 392.793474 -391.88517)
				(mid 392.829395 -391.870291)
				(end 392.844274 -391.83437)
			)
			(arc
				(start 392.844274 -391.834116)
				(mid 392.873212 -391.688163)
				(end 392.95578 -391.564368)
			)
			(arc
				(start 393.023598 -391.496804)
				(mid 393.034709 -391.48027)
				(end 393.038584 -391.460736)
			)
			(arc
				(start 393.038584 -391.2616)
				(mid 393.039513 -391.234227)
				(end 393.042394 -391.20699)
			)
			(xy 393.042902 -391.203434)
			(arc
				(start 393.042902 -391.089388)
				(mid 393.039001 -391.069865)
				(end 393.027916 -391.05332)
			)
			(arc
				(start 393.008358 -391.033762)
				(mid 392.991824 -391.022651)
				(end 392.97229 -391.018776)
			)
			(arc
				(start 392.750802 -391.018776)
				(mid 392.731279 -391.014875)
				(end 392.714734 -391.00379)
			)
			(arc
				(start 392.694668 -390.983724)
				(mid 392.678134 -390.972613)
				(end 392.6586 -390.968738)
			)
			(arc
				(start 389.960358 -390.968738)
				(mid 389.940835 -390.972639)
				(end 389.92429 -390.983724)
			)
			(arc
				(start 389.837168 -391.070846)
				(mid 389.826057 -391.08738)
				(end 389.822182 -391.106914)
			)
			(arc
				(start 389.822182 -391.65022)
				(mid 389.826083 -391.669743)
				(end 389.837168 -391.686288)
			)
			(arc
				(start 390.021064 -391.870184)
				(mid 390.037598 -391.881295)
				(end 390.057132 -391.88517)
			)
		)
		(stroke
			(width 0)
			(type solid)
		)
		(fill yes)
		(layer "B.Cu")
		(net "NCF_CPU0_P3_GND")
	)
	(gr_poly
		(pts
			(arc
				(start 16.862298 -421.44442)
				(mid 16.881821 -421.440519)
				(end 16.898366 -421.429434)
			)
			(arc
				(start 16.984472 -421.343328)
				(mid 16.995583 -421.326794)
				(end 16.999458 -421.30726)
			)
			(xy 16.999458 -417.698682) (xy 16.99895 -417.68014) (xy 16.999458 -417.661598)
			(arc
				(start 16.999458 -417.354004)
				(mid 16.995557 -417.334481)
				(end 16.984472 -417.317936)
			)
			(arc
				(start 16.887444 -417.220908)
				(mid 16.87091 -417.209797)
				(end 16.851376 -417.205922)
			)
			(arc
				(start 15.49654 -417.205922)
				(mid 15.477017 -417.209823)
				(end 15.460472 -417.220908)
			)
			(arc
				(start 15.38859 -417.29279)
				(mid 15.377879 -417.30839)
				(end 15.373604 -417.326826)
			)
			(xy 15.37081 -417.40582) (xy 15.376906 -417.4236)
			(arc
				(start 15.38351 -417.430966)
				(mid 15.452115 -417.547245)
				(end 15.475966 -417.68014)
			)
			(arc
				(start 15.475966 -417.68014)
				(mid 15.408148 -417.897274)
				(end 15.228824 -418.037264)
			)
			(xy 15.213838 -418.042852) (xy 15.196058 -418.068506)
			(arc
				(start 15.196058 -421.298624)
				(mid 15.199959 -421.318147)
				(end 15.211044 -421.334692)
			)
			(arc
				(start 15.305786 -421.429434)
				(mid 15.32232 -421.440545)
				(end 15.341854 -421.44442)
			)
		)
		(stroke
			(width 0)
			(type solid)
		)
		(fill yes)
		(layer "B.Cu")
		(net "P3V3_AUX")
	)
	(gr_poly
		(pts
			(xy 433.331112 -141.036294) (xy 433.331112 -139.776708) (xy 419.516814 -125.96241)
			(arc
				(start 401.70608 -125.96241)
				(mid 401.8924 -126.148645)
				(end 401.960588 -126.4031)
			)
			(arc
				(start 401.960588 -126.4031)
				(mid 401.451826 -126.911862)
				(end 400.943064 -126.4031)
			)
			(arc
				(start 400.943064 -126.4031)
				(mid 401.011264 -126.148652)
				(end 401.197572 -125.96241)
			)
			(xy 397.725392 -125.96241) (xy 397.557244 -126.130558) (xy 397.557244 -127.358648) (xy 398.26057 -128.061974)
			(xy 415.276284 -128.061974) (xy 428.628556 -141.414246) (xy 432.95316 -141.414246)
		)
		(stroke
			(width 0)
			(type solid)
		)
		(fill yes)
		(layer "B.Cu")
		(net "PVDD18_S5_P0")
	)
	(gr_poly
		(pts
			(xy 8.680196 -137.572242) (xy 8.680196 -132.686044) (xy 8.481568 -132.48767) (xy 4.300728 -132.48767)
			(xy 3.922268 -132.86613) (xy 3.922268 -135.39597) (xy 7.305037 -135.39597) (xy 7.30912 -135.334963)
			(xy 7.321299 -135.275045) (xy 7.341356 -135.217284) (xy 7.368932 -135.162713) (xy 7.403536 -135.112303)
			(xy 7.44455 -135.066956) (xy 7.491243 -135.02748) (xy 7.54278 -134.99458) (xy 7.598243 -134.968843)
			(xy 7.656641 -134.950727) (xy 7.716933 -134.940557) (xy 7.778042 -134.938514) (xy 7.838879 -134.944634)
			(xy 7.898357 -134.958809) (xy 7.955415 -134.980784) (xy 8.009034 -135.010169) (xy 8.058259 -135.046438)
			(xy 8.102211 -135.088944) (xy 8.140104 -135.13693) (xy 8.171264 -135.189537) (xy 8.195134 -135.245829)
			(xy 8.211288 -135.3048) (xy 8.219437 -135.365398) (xy 8.219948 -135.39597) (xy 8.219437 -135.426542)
			(xy 8.211288 -135.48714) (xy 8.195134 -135.546111) (xy 8.171264 -135.602403) (xy 8.140104 -135.65501)
			(xy 8.102211 -135.702996) (xy 8.058259 -135.745502) (xy 8.009034 -135.781771) (xy 7.955415 -135.811156)
			(xy 7.898357 -135.833131) (xy 7.838879 -135.847306) (xy 7.778042 -135.853426) (xy 7.716933 -135.851383)
			(xy 7.656641 -135.841213) (xy 7.598243 -135.823097) (xy 7.54278 -135.79736) (xy 7.491243 -135.76446)
			(xy 7.44455 -135.724984) (xy 7.403536 -135.679637) (xy 7.368932 -135.629227) (xy 7.341356 -135.574656)
			(xy 7.321299 -135.516895) (xy 7.30912 -135.456977) (xy 7.305037 -135.39597) (xy 3.922268 -135.39597)
			(xy 3.922268 -137.45845) (xy 4.318508 -137.85469) (xy 8.397748 -137.85469)
		)
		(stroke
			(width 0)
			(type solid)
		)
		(fill yes)
		(layer "B.Cu")
		(net "GND")
	)
	(gr_poly
		(pts
			(xy 112.7252 -34.8996) (xy 112.7252 -34.6964) (xy 113.248694 -34.172906) (xy 114.569494 -34.172906)
			(xy 115.417346 -33.325054) (xy 115.417346 -29.726128) (xy 115.417346 -28.615386) (xy 115.378738 -28.576778)
			(xy 113.463578 -28.576778) (xy 113.3094 -28.4226) (xy 113.3094 -27.6606) (xy 113.714022 -27.255978)
			(xy 113.714022 -25.687782) (xy 113.951004 -25.4508) (xy 114.893344 -25.4508) (xy 115.3414 -25.898856)
			(xy 117.046756 -25.898856) (xy 117.229128 -26.081228) (xy 117.229128 -28.802584) (xy 117.267736 -28.841192)
			(xy 117.825266 -28.841192) (xy 117.889528 -28.77693) (xy 117.889528 -25.433528) (xy 117.719856 -25.263856)
			(xy 117.3734 -24.9174) (xy 108.8136 -24.9174) (xy 107.442 -26.289) (xy 107.1372 -26.289) (xy 106.72191 -26.289)
			(xy 106.51871 -26.4922) (xy 106.51871 -26.78684) (xy 106.557318 -26.825448) (xy 112.326674 -26.825448)
			(xy 112.6998 -27.198574) (xy 112.6998 -27.813) (xy 111.68253 -28.83027) (xy 108.9406 -28.83027) (xy 108.8898 -28.88107)
			(xy 108.8898 -29.303726) (xy 108.511086 -29.68244) (xy 106.855514 -29.68244) (xy 106.613706 -29.924248)
			(xy 106.613706 -31.167832) (xy 106.652314 -31.20644) (xy 107.07116 -31.20644) (xy 107.1372 -31.1404)
			(xy 107.1372 -30.7086) (xy 107.2388 -30.607) (xy 107.4166 -30.607) (xy 107.8738 -30.607) (xy 108.5088 -29.972)
			(xy 109.461046 -29.972) (xy 109.677454 -30.188408) (xy 109.677454 -33.948116) (xy 109.299502 -34.326068)
			(xy 108.294932 -34.326068) (xy 108.2548 -34.3662) (xy 108.2548 -34.935668) (xy 108.2802 -34.961068)
			(xy 112.663732 -34.961068)
		)
		(stroke
			(width 0)
			(type solid)
		)
		(fill yes)
		(layer "B.Cu")
		(net "GND")
	)
	(gr_poly
		(pts
			(arc
				(start 69.693536 -383.50317)
				(mid 69.729457 -383.488291)
				(end 69.744336 -383.45237)
			)
			(arc
				(start 69.744336 -383.452116)
				(mid 69.773274 -383.306163)
				(end 69.855842 -383.182368)
			)
			(arc
				(start 69.92366 -383.114804)
				(mid 69.934634 -383.098241)
				(end 69.938392 -383.078736)
			)
			(arc
				(start 69.938392 -382.8796)
				(mid 69.939449 -382.852223)
				(end 69.942456 -382.82499)
			)
			(xy 69.942964 -382.821434)
			(arc
				(start 69.942964 -382.707388)
				(mid 69.939063 -382.687865)
				(end 69.927978 -382.67132)
			)
			(arc
				(start 69.90842 -382.651762)
				(mid 69.891886 -382.640651)
				(end 69.872352 -382.636776)
			)
			(arc
				(start 69.543422 -382.636776)
				(mid 69.523899 -382.640677)
				(end 69.507354 -382.651762)
			)
			(arc
				(start 69.052948 -383.106168)
				(mid 69.036414 -383.117279)
				(end 69.01688 -383.121154)
			)
			(arc
				(start 68.630546 -383.121154)
				(mid 68.611023 -383.117253)
				(end 68.594478 -383.106168)
			)
			(arc
				(start 68.090034 -382.601724)
				(mid 68.0735 -382.590613)
				(end 68.053966 -382.586738)
			)
			(arc
				(start 66.86042 -382.586738)
				(mid 66.840897 -382.590639)
				(end 66.824352 -382.601724)
			)
			(arc
				(start 66.73723 -382.688846)
				(mid 66.726119 -382.70538)
				(end 66.722244 -382.724914)
			)
			(arc
				(start 66.722244 -383.26822)
				(mid 66.726145 -383.287743)
				(end 66.73723 -383.304288)
			)
			(arc
				(start 66.921126 -383.488184)
				(mid 66.93766 -383.499295)
				(end 66.957194 -383.50317)
			)
		)
		(stroke
			(width 0)
			(type solid)
		)
		(fill yes)
		(layer "B.Cu")
		(net "NCF_CPU1_P0_GND")
	)
	(gr_poly
		(pts
			(xy 89.297002 -205.147164) (xy 89.932002 -205.147164) (xy 89.932002 -205.152752) (xy 90.186002 -205.152752)
			(xy 90.186002 -205.147164) (xy 90.821002 -205.147164) (xy 90.821002 -205.152752) (xy 91.075002 -205.152752)
			(xy 91.075002 -205.147164) (xy 91.710002 -205.147164) (xy 91.710002 -205.152752) (xy 91.964002 -205.152752)
			(xy 91.964002 -205.147164) (xy 92.599002 -205.147164) (xy 92.599002 -205.152752) (xy 92.853002 -205.152752)
			(xy 92.853002 -205.147164) (xy 93.488002 -205.147164) (xy 93.488002 -205.152752) (xy 93.742002 -205.152752)
			(xy 93.742002 -205.147164) (xy 94.377002 -205.147164) (xy 94.377002 -205.152752) (xy 94.631002 -205.152752)
			(xy 94.631002 -205.147164) (xy 95.266002 -205.147164) (xy 95.266002 -205.152752) (xy 95.520002 -205.152752)
			(xy 95.520002 -205.147164)
			(arc
				(start 96.091248 -205.147164)
				(mid 96.110343 -205.143272)
				(end 96.126554 -205.132432)
			)
			(arc
				(start 96.193102 -205.065884)
				(mid 96.204008 -205.049701)
				(end 96.207834 -205.030578)
			)
			(arc
				(start 96.207834 -203.954126)
				(mid 96.203942 -203.935031)
				(end 96.193102 -203.91882)
			)
			(arc
				(start 96.14916 -203.874878)
				(mid 96.133065 -203.864157)
				(end 96.114108 -203.8604)
			)
			(arc
				(start 88.612726 -203.8604)
				(mid 88.593523 -203.864126)
				(end 88.577166 -203.874878)
			)
			(arc
				(start 88.399366 -204.052932)
				(mid 88.38846 -204.069115)
				(end 88.384634 -204.088238)
			)
			(arc
				(start 88.384634 -205.005178)
				(mid 88.388526 -205.024273)
				(end 88.399366 -205.040484)
			)
			(arc
				(start 88.496902 -205.13802)
				(mid 88.513085 -205.148926)
				(end 88.532208 -205.152752)
			)
			(xy 89.297002 -205.152752)
		)
		(stroke
			(width 0)
			(type solid)
		)
		(fill yes)
		(layer "B.Cu")
		(net "PVDD18_S5_P1")
	)
	(gr_poly
		(pts
			(arc
				(start 102.221284 -383.50317)
				(mid 102.257205 -383.488291)
				(end 102.272084 -383.45237)
			)
			(arc
				(start 102.272084 -383.452116)
				(mid 102.301022 -383.306163)
				(end 102.38359 -383.182368)
			)
			(arc
				(start 102.451408 -383.114804)
				(mid 102.462382 -383.098241)
				(end 102.46614 -383.078736)
			)
			(arc
				(start 102.46614 -382.8796)
				(mid 102.467197 -382.852223)
				(end 102.470204 -382.82499)
			)
			(xy 102.470712 -382.821434)
			(arc
				(start 102.470712 -382.707388)
				(mid 102.466811 -382.687865)
				(end 102.455726 -382.67132)
			)
			(arc
				(start 102.436168 -382.651762)
				(mid 102.419634 -382.640651)
				(end 102.4001 -382.636776)
			)
			(arc
				(start 102.07117 -382.636776)
				(mid 102.051647 -382.640677)
				(end 102.035102 -382.651762)
			)
			(arc
				(start 101.580696 -383.106168)
				(mid 101.564162 -383.117279)
				(end 101.544628 -383.121154)
			)
			(arc
				(start 101.158294 -383.121154)
				(mid 101.138771 -383.117253)
				(end 101.122226 -383.106168)
			)
			(arc
				(start 100.617782 -382.601724)
				(mid 100.601248 -382.590613)
				(end 100.581714 -382.586738)
			)
			(arc
				(start 99.388168 -382.586738)
				(mid 99.368645 -382.590639)
				(end 99.3521 -382.601724)
			)
			(arc
				(start 99.264978 -382.688846)
				(mid 99.253867 -382.70538)
				(end 99.249992 -382.724914)
			)
			(arc
				(start 99.249992 -383.26822)
				(mid 99.253893 -383.287743)
				(end 99.264978 -383.304288)
			)
			(arc
				(start 99.448874 -383.488184)
				(mid 99.465408 -383.499295)
				(end 99.484942 -383.50317)
			)
		)
		(stroke
			(width 0)
			(type solid)
		)
		(fill yes)
		(layer "B.Cu")
		(net "NCF_CPU1_P1_GND")
	)
	(gr_poly
		(pts
			(xy 353.436174 -345.332812)
			(arc
				(start 353.436174 -344.218006)
				(mid 353.432331 -344.198774)
				(end 353.421442 -344.182446)
			)
			(arc
				(start 353.398328 -344.159332)
				(mid 353.382027 -344.148377)
				(end 353.362768 -344.1446)
			)
			(arc
				(start 352.071432 -344.1446)
				(mid 352.05162 -344.148689)
				(end 352.03511 -344.160348)
			)
			(xy 351.97796 -344.221054) (xy 351.971102 -344.240358) (xy 351.97161 -344.250772)
			(arc
				(start 351.972372 -344.274394)
				(mid 351.860631 -344.544161)
				(end 351.590864 -344.655902)
			)
			(arc
				(start 351.590864 -344.655902)
				(mid 351.508381 -344.646822)
				(end 351.429828 -344.620088)
			)
			(xy 351.419668 -344.615516)
			(arc
				(start 350.034352 -344.615516)
				(mid 350.012981 -344.620309)
				(end 349.995744 -344.633804)
			)
			(arc
				(start 349.995744 -344.633804)
				(mid 349.700596 -344.77355)
				(end 349.405448 -344.633804)
			)
			(arc
				(start 349.405448 -344.633804)
				(mid 349.388189 -344.620356)
				(end 349.36684 -344.615516)
			)
			(xy 347.875606 -344.615516) (xy 347.692472 -344.615516) (xy 347.517466 -344.790522) (xy 347.517466 -345.497658)
			(xy 347.747844 -345.728036) (xy 347.762576 -345.742768) (xy 347.975428 -345.742768) (xy 347.975682 -345.742768)
			(xy 353.026218 -345.742768)
		)
		(stroke
			(width 0)
			(type solid)
		)
		(fill yes)
		(layer "B.Cu")
		(net "GND")
	)
	(gr_poly
		(pts
			(arc
				(start 364.277656 -403.422104)
				(mid 364.297179 -403.418203)
				(end 364.313724 -403.407118)
			)
			(arc
				(start 364.59668 -403.124162)
				(mid 364.607791 -403.107628)
				(end 364.611666 -403.088094)
			)
			(arc
				(start 364.611666 -402.592794)
				(mid 364.607716 -402.573407)
				(end 364.59668 -402.55698)
			)
			(arc
				(start 364.005876 -401.965922)
				(mid 363.99495 -401.949476)
				(end 363.991144 -401.930108)
			)
			(arc
				(start 363.991144 -401.30349)
				(mid 363.976265 -401.267569)
				(end 363.940344 -401.25269)
			)
			(arc
				(start 363.397292 -401.25269)
				(mid 363.377769 -401.256591)
				(end 363.361224 -401.267676)
			)
			(arc
				(start 363.355382 -401.273518)
				(mid 363.346916 -401.360739)
				(end 363.323632 -401.445222)
			)
			(xy 363.32033 -401.453604) (xy 363.32033 -401.717256)
			(arc
				(start 363.323632 -401.725638)
				(mid 363.347405 -401.812868)
				(end 363.355382 -401.90293)
			)
			(arc
				(start 363.355382 -401.90293)
				(mid 363.252209 -402.209986)
				(end 362.984542 -402.392388)
			)
			(xy 362.978192 -402.394166) (xy 362.967016 -402.40077)
			(arc
				(start 362.879132 -402.488654)
				(mid 362.868021 -402.505188)
				(end 362.864146 -402.524722)
			)
			(arc
				(start 362.864146 -403.201632)
				(mid 362.868047 -403.221155)
				(end 362.879132 -403.2377)
			)
			(arc
				(start 363.04855 -403.407118)
				(mid 363.065084 -403.418229)
				(end 363.084618 -403.422104)
			)
		)
		(stroke
			(width 0)
			(type solid)
		)
		(fill yes)
		(layer "B.Cu")
		(net "P0V9_CPU0_RT3_2A_2D")
	)
	(gr_poly
		(pts
			(arc
				(start 355.537516 -391.88517)
				(mid 355.556903 -391.88122)
				(end 355.57333 -391.870184)
			)
			(arc
				(start 355.639624 -391.804144)
				(mid 355.65607 -391.793218)
				(end 355.675438 -391.789412)
			)
			(xy 358.249474 -391.789412) (xy 358.27716 -391.767314)
			(arc
				(start 358.281224 -391.749788)
				(mid 358.319157 -391.649852)
				(end 358.383332 -391.564368)
			)
			(arc
				(start 358.45115 -391.496804)
				(mid 358.462261 -391.48027)
				(end 358.466136 -391.460736)
			)
			(arc
				(start 358.466136 -391.2616)
				(mid 358.467065 -391.234227)
				(end 358.469946 -391.20699)
			)
			(xy 358.470454 -391.203434)
			(arc
				(start 358.470454 -391.089388)
				(mid 358.466553 -391.069865)
				(end 358.455468 -391.05332)
			)
			(arc
				(start 358.43591 -391.033762)
				(mid 358.419376 -391.022651)
				(end 358.399842 -391.018776)
			)
			(arc
				(start 358.168702 -391.018776)
				(mid 358.149179 -391.014875)
				(end 358.132634 -391.00379)
			)
			(xy 358.124506 -390.995662) (xy 358.099614 -390.98855)
			(arc
				(start 358.08666 -390.991344)
				(mid 358.044513 -390.998559)
				(end 358.001824 -391.000996)
			)
			(arc
				(start 358.001824 -391.000996)
				(mid 357.928175 -390.993815)
				(end 357.857298 -390.972548)
			)
			(xy 357.8479 -390.968738)
			(arc
				(start 355.38791 -390.968738)
				(mid 355.368387 -390.972639)
				(end 355.351842 -390.983724)
			)
			(arc
				(start 355.26472 -391.070846)
				(mid 355.253609 -391.08738)
				(end 355.249734 -391.106914)
			)
			(arc
				(start 355.249734 -391.65022)
				(mid 355.253635 -391.669743)
				(end 355.26472 -391.686288)
			)
			(arc
				(start 355.448616 -391.870184)
				(mid 355.46515 -391.881295)
				(end 355.484684 -391.88517)
			)
		)
		(stroke
			(width 0)
			(type solid)
		)
		(fill yes)
		(layer "B.Cu")
		(net "NCF_CPU0_P1_GND")
	)
	(gr_poly
		(pts
			(xy 16.159988 -138.85291) (xy 16.159988 -136.10717) (xy 15.705328 -135.65251) (xy 13.414248 -135.65251)
			(xy 13.317728 -135.74903) (xy 13.317728 -136.19353) (xy 13.264388 -136.24687) (xy 12.106148 -136.24687)
			(xy 11.900408 -136.04113) (xy 11.900408 -133.99897) (xy 11.628628 -133.72719) (xy 11.240008 -133.72719)
			(xy 11.1506 -133.637782) (xy 11.1506 -132.630418) (xy 11.240008 -132.54101) (xy 11.501628 -132.27939)
			(xy 14.387068 -132.27939) (xy 14.526768 -132.13969) (xy 14.526768 -131.04749) (xy 14.440408 -130.96113)
			(xy 11.511788 -130.96113) (xy 9.868408 -132.60451)
			(arc
				(start 9.868408 -133.417818)
				(mid 10.001974 -133.345904)
				(end 10.151618 -133.321044)
			)
			(arc
				(start 10.151618 -133.321044)
				(mid 10.61466 -133.784086)
				(end 10.151618 -134.247128)
			)
			(arc
				(start 10.151618 -134.247128)
				(mid 10.001974 -134.222266)
				(end 9.868408 -134.150354)
			)
			(xy 9.868408 -134.66953) (xy 11.143488 -135.94461) (xy 11.143488 -139.50315) (xy 11.229848 -139.58951)
			(xy 15.423388 -139.58951)
		)
		(stroke
			(width 0)
			(type solid)
		)
		(fill yes)
		(layer "B.Cu")
		(net "VFG3P3_CLK_GEN")
	)
	(gr_poly
		(pts
			(xy 105.499408 -345.27998)
			(arc
				(start 105.499408 -344.222832)
				(mid 105.495565 -344.2036)
				(end 105.484676 -344.187272)
			)
			(arc
				(start 105.461562 -344.164158)
				(mid 105.445261 -344.153203)
				(end 105.426002 -344.149426)
			)
			(arc
				(start 104.134666 -344.149426)
				(mid 104.114854 -344.153515)
				(end 104.098344 -344.165174)
			)
			(xy 104.041194 -344.22588) (xy 104.034336 -344.245184) (xy 104.034844 -344.255598)
			(arc
				(start 104.035606 -344.27922)
				(mid 103.923865 -344.548987)
				(end 103.654098 -344.660728)
			)
			(arc
				(start 103.654098 -344.660728)
				(mid 103.571615 -344.651648)
				(end 103.493062 -344.624914)
			)
			(xy 103.482902 -344.620342)
			(arc
				(start 102.097586 -344.620342)
				(mid 102.076215 -344.625135)
				(end 102.058978 -344.63863)
			)
			(arc
				(start 102.058978 -344.63863)
				(mid 101.76383 -344.778376)
				(end 101.468682 -344.63863)
			)
			(arc
				(start 101.468682 -344.63863)
				(mid 101.451423 -344.625182)
				(end 101.430074 -344.620342)
			)
			(arc
				(start 99.93884 -344.620342)
				(mid 99.919608 -344.624185)
				(end 99.90328 -344.635074)
			)
			(arc
				(start 99.771708 -344.766646)
				(mid 99.760753 -344.782947)
				(end 99.756976 -344.802206)
			)
			(xy 99.756976 -345.322398) (xy 99.900232 -345.465654) (xy 105.313734 -345.465654)
		)
		(stroke
			(width 0)
			(type solid)
		)
		(fill yes)
		(layer "B.Cu")
		(net "GND")
	)
	(gr_poly
		(pts
			(arc
				(start 247.734582 -329.725528)
				(mid 247.754105 -329.721627)
				(end 247.77065 -329.710542)
			)
			(arc
				(start 247.988582 -329.49261)
				(mid 247.999693 -329.476076)
				(end 248.003568 -329.456542)
			)
			(arc
				(start 248.003568 -327.639172)
				(mid 247.999667 -327.619649)
				(end 247.988582 -327.603104)
			)
			(arc
				(start 247.984772 -327.599294)
				(mid 247.968238 -327.588183)
				(end 247.948704 -327.584308)
			)
			(xy 247.455182 -327.584308) (xy 247.44426 -327.586848)
			(arc
				(start 247.438926 -327.589388)
				(mid 247.346672 -327.622011)
				(end 247.249442 -327.633076)
			)
			(arc
				(start 246.022876 -327.633076)
				(mid 245.925637 -327.62205)
				(end 245.833392 -327.589388)
			)
			(xy 245.828058 -327.586848) (xy 245.817136 -327.584308) (xy 245.602506 -327.584308)
			(arc
				(start 245.593108 -327.588118)
				(mid 245.487779 -327.620159)
				(end 245.378224 -327.631044)
			)
			(arc
				(start 245.041928 -327.631044)
				(mid 244.932373 -327.620158)
				(end 244.827044 -327.588118)
			)
			(xy 244.817646 -327.584308)
			(arc
				(start 242.492784 -327.584308)
				(mid 242.473261 -327.588209)
				(end 242.456716 -327.599294)
			)
			(arc
				(start 242.349782 -327.706228)
				(mid 242.338671 -327.722762)
				(end 242.334796 -327.742296)
			)
			(arc
				(start 242.334796 -328.637138)
				(mid 242.338697 -328.656661)
				(end 242.349782 -328.673206)
			)
			(arc
				(start 242.71224 -329.035664)
				(mid 242.728774 -329.046775)
				(end 242.748308 -329.05065)
			)
			(arc
				(start 246.236998 -329.05065)
				(mid 246.256521 -329.054551)
				(end 246.273066 -329.065636)
			)
			(arc
				(start 246.917972 -329.710542)
				(mid 246.934506 -329.721653)
				(end 246.95404 -329.725528)
			)
		)
		(stroke
			(width 0)
			(type solid)
		)
		(fill yes)
		(layer "B.Cu")
		(net "P3V3_MAX11617_2_VDD")
	)
	(gr_poly
		(pts
			(arc
				(start 329.705208 -403.422104)
				(mid 329.724731 -403.418203)
				(end 329.741276 -403.407118)
			)
			(arc
				(start 330.024232 -403.124162)
				(mid 330.035343 -403.107628)
				(end 330.039218 -403.088094)
			)
			(arc
				(start 330.039218 -402.49475)
				(mid 330.035317 -402.475227)
				(end 330.024232 -402.458682)
			)
			(arc
				(start 329.602338 -402.036788)
				(mid 329.591227 -402.020254)
				(end 329.587352 -402.00072)
			)
			(xy 329.587352 -401.972526) (xy 329.586844 -401.972018)
			(arc
				(start 329.586844 -401.35937)
				(mid 329.582943 -401.339847)
				(end 329.571858 -401.323302)
			)
			(arc
				(start 329.516232 -401.267676)
				(mid 329.499698 -401.256565)
				(end 329.480164 -401.25269)
			)
			(arc
				(start 328.824844 -401.25269)
				(mid 328.805321 -401.256591)
				(end 328.788776 -401.267676)
			)
			(arc
				(start 328.782934 -401.273518)
				(mid 328.774468 -401.360739)
				(end 328.751184 -401.445222)
			)
			(xy 328.747882 -401.453604) (xy 328.747882 -401.717256)
			(arc
				(start 328.751184 -401.725638)
				(mid 328.774957 -401.812868)
				(end 328.782934 -401.90293)
			)
			(arc
				(start 328.782934 -401.90293)
				(mid 328.679761 -402.209986)
				(end 328.412094 -402.392388)
			)
			(xy 328.405744 -402.394166) (xy 328.394568 -402.40077)
			(arc
				(start 328.306684 -402.488654)
				(mid 328.295573 -402.505188)
				(end 328.291698 -402.524722)
			)
			(arc
				(start 328.291698 -403.201632)
				(mid 328.295599 -403.221155)
				(end 328.306684 -403.2377)
			)
			(arc
				(start 328.476102 -403.407118)
				(mid 328.492636 -403.418229)
				(end 328.51217 -403.422104)
			)
		)
		(stroke
			(width 0)
			(type solid)
		)
		(fill yes)
		(layer "B.Cu")
		(net "P0V9_CPU0_RT1_2A_2D")
	)
	(gr_poly
		(pts
			(arc
				(start 396.805404 -403.422104)
				(mid 396.824927 -403.418203)
				(end 396.841472 -403.407118)
			)
			(arc
				(start 397.124428 -403.124162)
				(mid 397.135539 -403.107628)
				(end 397.139414 -403.088094)
			)
			(arc
				(start 397.139414 -402.49475)
				(mid 397.135513 -402.475227)
				(end 397.124428 -402.458682)
			)
			(arc
				(start 396.702534 -402.036788)
				(mid 396.691423 -402.020254)
				(end 396.687548 -402.00072)
			)
			(xy 396.687548 -401.972526) (xy 396.68704 -401.972018)
			(arc
				(start 396.68704 -401.35937)
				(mid 396.683139 -401.339847)
				(end 396.672054 -401.323302)
			)
			(arc
				(start 396.616428 -401.267676)
				(mid 396.599894 -401.256565)
				(end 396.58036 -401.25269)
			)
			(arc
				(start 395.92504 -401.25269)
				(mid 395.905517 -401.256591)
				(end 395.888972 -401.267676)
			)
			(arc
				(start 395.88313 -401.273518)
				(mid 395.874664 -401.360739)
				(end 395.85138 -401.445222)
			)
			(xy 395.848078 -401.453604) (xy 395.848078 -401.717256)
			(arc
				(start 395.85138 -401.725638)
				(mid 395.875153 -401.812868)
				(end 395.88313 -401.90293)
			)
			(arc
				(start 395.88313 -401.90293)
				(mid 395.779957 -402.209986)
				(end 395.51229 -402.392388)
			)
			(xy 395.50594 -402.394166) (xy 395.494764 -402.40077)
			(arc
				(start 395.40688 -402.488654)
				(mid 395.395769 -402.505188)
				(end 395.391894 -402.524722)
			)
			(arc
				(start 395.391894 -403.201632)
				(mid 395.395795 -403.221155)
				(end 395.40688 -403.2377)
			)
			(arc
				(start 395.576298 -403.407118)
				(mid 395.592832 -403.418229)
				(end 395.612366 -403.422104)
			)
		)
		(stroke
			(width 0)
			(type solid)
		)
		(fill yes)
		(layer "B.Cu")
		(net "P0V9_CPU0_RT2_2A_2D")
	)
	(gr_poly
		(pts
			(arc
				(start 73.705212 -395.040104)
				(mid 73.724735 -395.036203)
				(end 73.74128 -395.025118)
			)
			(arc
				(start 74.024236 -394.742162)
				(mid 74.035347 -394.725628)
				(end 74.039222 -394.706094)
			)
			(arc
				(start 74.039222 -394.11275)
				(mid 74.035321 -394.093227)
				(end 74.024236 -394.076682)
			)
			(arc
				(start 73.602342 -393.654788)
				(mid 73.591231 -393.638254)
				(end 73.587356 -393.61872)
			)
			(xy 73.587356 -393.590526) (xy 73.586848 -393.590018)
			(arc
				(start 73.586848 -392.97737)
				(mid 73.582947 -392.957847)
				(end 73.571862 -392.941302)
			)
			(arc
				(start 73.516236 -392.885676)
				(mid 73.499702 -392.874565)
				(end 73.480168 -392.87069)
			)
			(arc
				(start 72.836024 -392.87069)
				(mid 72.816637 -392.87464)
				(end 72.80021 -392.885676)
			)
			(xy 72.79005 -392.895582) (xy 72.782684 -392.912092)
			(arc
				(start 72.781922 -392.92149)
				(mid 72.776207 -392.969625)
				(end 72.76592 -393.016994)
			)
			(xy 72.764396 -393.023598) (xy 72.764396 -393.383262)
			(arc
				(start 72.76592 -393.389866)
				(mid 72.778822 -393.454835)
				(end 72.783192 -393.52093)
			)
			(arc
				(start 72.783192 -393.52093)
				(mid 72.778845 -393.587028)
				(end 72.76592 -393.651994)
			)
			(xy 72.764396 -393.658598) (xy 72.764396 -393.674854) (xy 72.757284 -393.681966)
			(arc
				(start 72.75322 -393.692634)
				(mid 72.634183 -393.880429)
				(end 72.446388 -393.999466)
			)
			(xy 72.43572 -394.00353)
			(arc
				(start 72.306688 -394.132562)
				(mid 72.295626 -394.148979)
				(end 72.291702 -394.168376)
			)
			(arc
				(start 72.291702 -394.819632)
				(mid 72.295603 -394.839155)
				(end 72.306688 -394.8557)
			)
			(arc
				(start 72.476106 -395.025118)
				(mid 72.49264 -395.036229)
				(end 72.512174 -395.040104)
			)
		)
		(stroke
			(width 0)
			(type solid)
		)
		(fill yes)
		(layer "B.Cu")
		(net "P0V9_CPU1_RT1_2A_2D")
	)
	(gr_poly
		(pts
			(arc
				(start 140.805408 -395.040104)
				(mid 140.824931 -395.036203)
				(end 140.841476 -395.025118)
			)
			(arc
				(start 141.124432 -394.742162)
				(mid 141.135543 -394.725628)
				(end 141.139418 -394.706094)
			)
			(arc
				(start 141.139418 -394.11275)
				(mid 141.135517 -394.093227)
				(end 141.124432 -394.076682)
			)
			(arc
				(start 140.702538 -393.654788)
				(mid 140.691427 -393.638254)
				(end 140.687552 -393.61872)
			)
			(xy 140.687552 -393.590526) (xy 140.687044 -393.590018)
			(arc
				(start 140.687044 -392.97737)
				(mid 140.683143 -392.957847)
				(end 140.672058 -392.941302)
			)
			(arc
				(start 140.616432 -392.885676)
				(mid 140.599898 -392.874565)
				(end 140.580364 -392.87069)
			)
			(arc
				(start 139.935966 -392.87069)
				(mid 139.916579 -392.87464)
				(end 139.900152 -392.885676)
			)
			(xy 139.889992 -392.895582) (xy 139.882626 -392.912092)
			(arc
				(start 139.881864 -392.92149)
				(mid 139.876149 -392.969625)
				(end 139.865862 -393.016994)
			)
			(xy 139.864084 -393.023598) (xy 139.864084 -393.383262)
			(arc
				(start 139.865862 -393.389866)
				(mid 139.878764 -393.454835)
				(end 139.883134 -393.52093)
			)
			(arc
				(start 139.883134 -393.52093)
				(mid 139.878787 -393.587028)
				(end 139.865862 -393.651994)
			)
			(xy 139.864084 -393.658598) (xy 139.864084 -393.674854) (xy 139.857226 -393.681966)
			(arc
				(start 139.853416 -393.692634)
				(mid 139.734379 -393.880429)
				(end 139.546584 -393.999466)
			)
			(xy 139.535916 -394.003276)
			(arc
				(start 139.406884 -394.132562)
				(mid 139.395822 -394.148979)
				(end 139.391898 -394.168376)
			)
			(arc
				(start 139.391898 -394.819632)
				(mid 139.395799 -394.839155)
				(end 139.406884 -394.8557)
			)
			(arc
				(start 139.576302 -395.025118)
				(mid 139.592836 -395.036229)
				(end 139.61237 -395.040104)
			)
		)
		(stroke
			(width 0)
			(type solid)
		)
		(fill yes)
		(layer "B.Cu")
		(net "P0V9_CPU1_RT2_2A_2D")
	)
	(gr_poly
		(pts
			(xy 300.2788 -357.6066) (xy 300.2788 -354.7364) (xy 300.284388 -354.730812) (xy 300.284388 -354.574602)
			(xy 301.091092 -353.767898) (xy 301.247302 -353.767898) (xy 303.939448 -353.767898) (xy 304.393346 -353.314)
			(xy 304.393346 -351.974912) (xy 304.393346 -347.060774) (xy 304.266346 -346.933774) (xy 300.785784 -346.933774)
			(xy 300.748446 -346.971112) (xy 300.748446 -348.983046) (xy 300.759114 -348.99346) (xy 300.759114 -350.360996)
			(xy 300.888146 -350.490028) (xy 302.187102 -350.490028) (xy 302.695102 -350.998028) (xy 302.695102 -352.305112)
			(xy 302.303434 -352.69678) (xy 300.794674 -352.69678) (xy 300.690788 -352.69678) (xy 297.682158 -352.69678)
			(xy 297.486832 -352.891852) (xy 296.66057 -352.891852) (xy 296.036746 -352.268028) (xy 296.036746 -347.187774)
			(xy 295.782746 -346.933774) (xy 292.429184 -346.933774) (xy 292.391846 -346.971112) (xy 292.391846 -350.375728)
			(xy 292.480746 -350.464628) (xy 293.982902 -350.464628) (xy 294.338502 -350.820228) (xy 294.338502 -351.807272)
			(xy 294.334946 -351.810828) (xy 294.334946 -352.623628) (xy 293.877746 -353.080828) (xy 288.442146 -353.080828)
			(xy 287.705546 -352.344228) (xy 287.705546 -347.111574) (xy 287.527746 -346.933774) (xy 284.123384 -346.933774)
			(xy 284.086046 -346.971112) (xy 284.086046 -350.324928) (xy 284.200346 -350.439228) (xy 285.600902 -350.439228)
			(xy 286.032702 -350.871028) (xy 286.032702 -351.756472) (xy 286.029146 -351.760028) (xy 286.029146 -352.623628)
			(xy 285.571946 -353.080828) (xy 280.161746 -353.080828) (xy 279.425146 -352.344228) (xy 279.425146 -347.060774)
			(xy 279.298146 -346.933774) (xy 275.842984 -346.933774) (xy 275.805646 -346.971112) (xy 275.805646 -350.350328)
			(xy 275.894546 -350.439228) (xy 277.345902 -350.439228) (xy 277.553166 -350.646746) (xy 277.553166 -352.957892)
			(xy 277.169626 -353.341432) (xy 275.24583 -353.341432) (xy 274.88515 -353.702112) (xy 274.88515 -359.686098)
			(xy 275.137372 -359.93832) (xy 292.170612 -359.93832) (xy 297.94708 -359.93832)
		)
		(stroke
			(width 0)
			(type solid)
		)
		(fill yes)
		(layer "B.Cu")
		(net "SW_P12V_AUX_PVDDIO_P0_FLT")
	)
	(gr_poly
		(pts
			(arc
				(start 80.544924 -340.83244)
				(mid 80.564156 -340.828597)
				(end 80.580484 -340.817708)
			)
			(arc
				(start 80.635348 -340.762844)
				(mid 80.646303 -340.746543)
				(end 80.65008 -340.727284)
			)
			(arc
				(start 80.65008 -339.307678)
				(mid 80.646237 -339.288446)
				(end 80.635348 -339.272118)
			)
			(arc
				(start 80.612234 -339.249004)
				(mid 80.595933 -339.238049)
				(end 80.576674 -339.234272)
			)
			(arc
				(start 79.154528 -339.234272)
				(mid 79.135296 -339.238115)
				(end 79.118968 -339.249004)
			)
			(xy 79.07782 -339.290152) (xy 79.070454 -339.309202) (xy 79.070708 -339.319616)
			(arc
				(start 79.070962 -339.332824)
				(mid 78.959221 -339.602591)
				(end 78.689454 -339.714332)
			)
			(arc
				(start 78.689454 -339.714332)
				(mid 78.650126 -339.7123)
				(end 78.611222 -339.706204)
			)
			(xy 78.606142 -339.705188)
			(arc
				(start 77.104748 -339.705188)
				(mid 77.085516 -339.709031)
				(end 77.069188 -339.71992)
			)
			(arc
				(start 77.069188 -339.71992)
				(mid 76.799186 -339.831907)
				(end 76.529184 -339.71992)
			)
			(arc
				(start 76.529184 -339.71992)
				(mid 76.512883 -339.708965)
				(end 76.493624 -339.705188)
			)
			(arc
				(start 75.089512 -339.705188)
				(mid 75.07028 -339.709031)
				(end 75.053952 -339.71992)
			)
			(arc
				(start 74.92238 -339.851492)
				(mid 74.911425 -339.867793)
				(end 74.907648 -339.887052)
			)
			(arc
				(start 74.907648 -340.5505)
				(mid 74.911491 -340.569732)
				(end 74.92238 -340.58606)
			)
			(arc
				(start 75.154028 -340.817708)
				(mid 75.170329 -340.828663)
				(end 75.189588 -340.83244)
			)
		)
		(stroke
			(width 0)
			(type solid)
		)
		(fill yes)
		(layer "B.Cu")
		(net "GND")
	)
	(gr_poly
		(pts
			(arc
				(start 108.27766 -395.040104)
				(mid 108.297183 -395.036203)
				(end 108.313728 -395.025118)
			)
			(arc
				(start 108.596684 -394.742162)
				(mid 108.607795 -394.725628)
				(end 108.61167 -394.706094)
			)
			(arc
				(start 108.61167 -394.11275)
				(mid 108.607769 -394.093227)
				(end 108.596684 -394.076682)
			)
			(arc
				(start 108.17479 -393.654788)
				(mid 108.163679 -393.638254)
				(end 108.159804 -393.61872)
			)
			(xy 108.159804 -393.590526) (xy 108.159296 -393.590018)
			(arc
				(start 108.159296 -392.97737)
				(mid 108.155395 -392.957847)
				(end 108.14431 -392.941302)
			)
			(arc
				(start 108.088684 -392.885676)
				(mid 108.07215 -392.874565)
				(end 108.052616 -392.87069)
			)
			(arc
				(start 107.408218 -392.87069)
				(mid 107.388831 -392.87464)
				(end 107.372404 -392.885676)
			)
			(xy 107.362244 -392.895582) (xy 107.354878 -392.912092)
			(arc
				(start 107.354116 -392.92149)
				(mid 107.348401 -392.969625)
				(end 107.338114 -393.016994)
			)
			(xy 107.336336 -393.023598) (xy 107.336336 -393.383262)
			(arc
				(start 107.338114 -393.389866)
				(mid 107.351016 -393.454835)
				(end 107.355386 -393.52093)
			)
			(arc
				(start 107.355386 -393.52093)
				(mid 107.351039 -393.587028)
				(end 107.338114 -393.651994)
			)
			(xy 107.336336 -393.658598) (xy 107.336336 -393.674854) (xy 107.329478 -393.681966)
			(arc
				(start 107.325414 -393.692634)
				(mid 107.206377 -393.880429)
				(end 107.018582 -393.999466)
			)
			(xy 107.007914 -394.00353)
			(arc
				(start 106.938318 -394.072872)
				(mid 106.921872 -394.083798)
				(end 106.902504 -394.087604)
			)
			(xy 106.898186 -394.087604)
			(arc
				(start 106.879136 -394.106654)
				(mid 106.868025 -394.123188)
				(end 106.86415 -394.142722)
			)
			(arc
				(start 106.86415 -394.819632)
				(mid 106.868051 -394.839155)
				(end 106.879136 -394.8557)
			)
			(arc
				(start 107.048554 -395.025118)
				(mid 107.065088 -395.036229)
				(end 107.084622 -395.040104)
			)
		)
		(stroke
			(width 0)
			(type solid)
		)
		(fill yes)
		(layer "B.Cu")
		(net "P0V9_CPU1_RT3_2A_2D")
	)
	(gr_poly
		(pts
			(arc
				(start 328.48169 -340.827614)
				(mid 328.500922 -340.823771)
				(end 328.51725 -340.812882)
			)
			(arc
				(start 328.572114 -340.758018)
				(mid 328.583069 -340.741717)
				(end 328.586846 -340.722458)
			)
			(arc
				(start 328.586846 -339.302852)
				(mid 328.583003 -339.28362)
				(end 328.572114 -339.267292)
			)
			(arc
				(start 328.549 -339.244178)
				(mid 328.532699 -339.233223)
				(end 328.51344 -339.229446)
			)
			(arc
				(start 327.091294 -339.229446)
				(mid 327.072062 -339.233289)
				(end 327.055734 -339.244178)
			)
			(xy 327.014586 -339.285326) (xy 327.00722 -339.304376) (xy 327.007474 -339.31479)
			(arc
				(start 327.007728 -339.327998)
				(mid 326.895987 -339.597765)
				(end 326.62622 -339.709506)
			)
			(arc
				(start 326.62622 -339.709506)
				(mid 326.586892 -339.707474)
				(end 326.547988 -339.701378)
			)
			(xy 326.542908 -339.700362)
			(arc
				(start 325.041514 -339.700362)
				(mid 325.022282 -339.704205)
				(end 325.005954 -339.715094)
			)
			(arc
				(start 325.005954 -339.715094)
				(mid 324.735952 -339.827081)
				(end 324.46595 -339.715094)
			)
			(arc
				(start 324.46595 -339.715094)
				(mid 324.449649 -339.704139)
				(end 324.43039 -339.700362)
			)
			(arc
				(start 323.026278 -339.700362)
				(mid 323.007046 -339.704205)
				(end 322.990718 -339.715094)
			)
			(arc
				(start 322.859146 -339.846666)
				(mid 322.848191 -339.862967)
				(end 322.844414 -339.882226)
			)
			(arc
				(start 322.844414 -340.545674)
				(mid 322.848257 -340.564906)
				(end 322.859146 -340.581234)
			)
			(arc
				(start 323.090794 -340.812882)
				(mid 323.107095 -340.823837)
				(end 323.126354 -340.827614)
			)
		)
		(stroke
			(width 0)
			(type solid)
		)
		(fill yes)
		(layer "B.Cu")
		(net "GND")
	)
	(gr_poly
		(pts
			(arc
				(start 38.546024 -352.529394)
				(mid 38.565256 -352.525551)
				(end 38.581584 -352.514662)
			)
			(arc
				(start 38.636448 -352.459798)
				(mid 38.647403 -352.443497)
				(end 38.65118 -352.424238)
			)
			(arc
				(start 38.65118 -351.004632)
				(mid 38.647337 -350.9854)
				(end 38.636448 -350.969072)
			)
			(arc
				(start 38.613334 -350.945958)
				(mid 38.597033 -350.935003)
				(end 38.577774 -350.931226)
			)
			(arc
				(start 37.286438 -350.931226)
				(mid 37.266626 -350.935315)
				(end 37.250116 -350.946974)
			)
			(xy 37.192966 -351.00768) (xy 37.186108 -351.026984) (xy 37.186616 -351.037398)
			(arc
				(start 37.187378 -351.06102)
				(mid 37.075637 -351.330787)
				(end 36.80587 -351.442528)
			)
			(arc
				(start 36.80587 -351.442528)
				(mid 36.723387 -351.433448)
				(end 36.644834 -351.406714)
			)
			(xy 36.634674 -351.402142)
			(arc
				(start 35.249358 -351.402142)
				(mid 35.227987 -351.406935)
				(end 35.21075 -351.42043)
			)
			(arc
				(start 35.21075 -351.42043)
				(mid 34.915602 -351.560176)
				(end 34.620454 -351.42043)
			)
			(arc
				(start 34.620454 -351.42043)
				(mid 34.603195 -351.406982)
				(end 34.581846 -351.402142)
			)
			(arc
				(start 33.090612 -351.402142)
				(mid 33.07138 -351.405985)
				(end 33.055052 -351.416874)
			)
			(arc
				(start 32.92348 -351.548446)
				(mid 32.912525 -351.564747)
				(end 32.908748 -351.584006)
			)
			(arc
				(start 32.908748 -352.247454)
				(mid 32.912591 -352.266686)
				(end 32.92348 -352.283014)
			)
			(arc
				(start 33.155128 -352.514662)
				(mid 33.171429 -352.525617)
				(end 33.190688 -352.529394)
			)
		)
		(stroke
			(width 0)
			(type solid)
		)
		(fill yes)
		(layer "B.Cu")
		(net "GND")
	)
	(gr_poly
		(pts
			(arc
				(start 46.851824 -352.529394)
				(mid 46.871056 -352.525551)
				(end 46.887384 -352.514662)
			)
			(arc
				(start 46.942248 -352.459798)
				(mid 46.953203 -352.443497)
				(end 46.95698 -352.424238)
			)
			(arc
				(start 46.95698 -351.004632)
				(mid 46.953137 -350.9854)
				(end 46.942248 -350.969072)
			)
			(arc
				(start 46.919134 -350.945958)
				(mid 46.902833 -350.935003)
				(end 46.883574 -350.931226)
			)
			(arc
				(start 45.592238 -350.931226)
				(mid 45.572426 -350.935315)
				(end 45.555916 -350.946974)
			)
			(xy 45.498766 -351.00768) (xy 45.491908 -351.026984) (xy 45.492416 -351.037398)
			(arc
				(start 45.493178 -351.06102)
				(mid 45.381437 -351.330787)
				(end 45.11167 -351.442528)
			)
			(arc
				(start 45.11167 -351.442528)
				(mid 45.029187 -351.433448)
				(end 44.950634 -351.406714)
			)
			(xy 44.940474 -351.402142)
			(arc
				(start 43.555158 -351.402142)
				(mid 43.533787 -351.406935)
				(end 43.51655 -351.42043)
			)
			(arc
				(start 43.51655 -351.42043)
				(mid 43.221402 -351.560176)
				(end 42.926254 -351.42043)
			)
			(arc
				(start 42.926254 -351.42043)
				(mid 42.908995 -351.406982)
				(end 42.887646 -351.402142)
			)
			(arc
				(start 41.396412 -351.402142)
				(mid 41.37718 -351.405985)
				(end 41.360852 -351.416874)
			)
			(arc
				(start 41.22928 -351.548446)
				(mid 41.218325 -351.564747)
				(end 41.214548 -351.584006)
			)
			(arc
				(start 41.214548 -352.247454)
				(mid 41.218391 -352.266686)
				(end 41.22928 -352.283014)
			)
			(arc
				(start 41.460928 -352.514662)
				(mid 41.477229 -352.525617)
				(end 41.496488 -352.529394)
			)
		)
		(stroke
			(width 0)
			(type solid)
		)
		(fill yes)
		(layer "B.Cu")
		(net "GND")
	)
	(gr_poly
		(pts
			(arc
				(start 55.208424 -352.529394)
				(mid 55.227656 -352.525551)
				(end 55.243984 -352.514662)
			)
			(arc
				(start 55.298848 -352.459798)
				(mid 55.309803 -352.443497)
				(end 55.31358 -352.424238)
			)
			(arc
				(start 55.31358 -351.004632)
				(mid 55.309737 -350.9854)
				(end 55.298848 -350.969072)
			)
			(arc
				(start 55.275734 -350.945958)
				(mid 55.259433 -350.935003)
				(end 55.240174 -350.931226)
			)
			(arc
				(start 53.948838 -350.931226)
				(mid 53.929026 -350.935315)
				(end 53.912516 -350.946974)
			)
			(xy 53.855366 -351.00768) (xy 53.848508 -351.026984) (xy 53.849016 -351.037398)
			(arc
				(start 53.849778 -351.06102)
				(mid 53.738037 -351.330787)
				(end 53.46827 -351.442528)
			)
			(arc
				(start 53.46827 -351.442528)
				(mid 53.385787 -351.433448)
				(end 53.307234 -351.406714)
			)
			(xy 53.297074 -351.402142)
			(arc
				(start 51.911758 -351.402142)
				(mid 51.890387 -351.406935)
				(end 51.87315 -351.42043)
			)
			(arc
				(start 51.87315 -351.42043)
				(mid 51.578002 -351.560176)
				(end 51.282854 -351.42043)
			)
			(arc
				(start 51.282854 -351.42043)
				(mid 51.265595 -351.406982)
				(end 51.244246 -351.402142)
			)
			(arc
				(start 49.753012 -351.402142)
				(mid 49.73378 -351.405985)
				(end 49.717452 -351.416874)
			)
			(arc
				(start 49.58588 -351.548446)
				(mid 49.574925 -351.564747)
				(end 49.571148 -351.584006)
			)
			(arc
				(start 49.571148 -352.247454)
				(mid 49.574991 -352.266686)
				(end 49.58588 -352.283014)
			)
			(arc
				(start 49.817528 -352.514662)
				(mid 49.833829 -352.525617)
				(end 49.853088 -352.529394)
			)
		)
		(stroke
			(width 0)
			(type solid)
		)
		(fill yes)
		(layer "B.Cu")
		(net "GND")
	)
	(gr_poly
		(pts
			(arc
				(start 88.787224 -340.78672)
				(mid 88.806456 -340.782877)
				(end 88.822784 -340.771988)
			)
			(arc
				(start 88.877648 -340.717124)
				(mid 88.888603 -340.700823)
				(end 88.89238 -340.681564)
			)
			(arc
				(start 88.89238 -339.261958)
				(mid 88.888537 -339.242726)
				(end 88.877648 -339.226398)
			)
			(arc
				(start 88.854534 -339.203284)
				(mid 88.838233 -339.192329)
				(end 88.818974 -339.188552)
			)
			(arc
				(start 87.527638 -339.188552)
				(mid 87.507826 -339.192641)
				(end 87.491316 -339.2043)
			)
			(xy 87.434166 -339.265006) (xy 87.427308 -339.28431) (xy 87.427816 -339.294724)
			(arc
				(start 87.428578 -339.318346)
				(mid 87.316837 -339.588113)
				(end 87.04707 -339.699854)
			)
			(arc
				(start 87.04707 -339.699854)
				(mid 86.964587 -339.690774)
				(end 86.886034 -339.66404)
			)
			(xy 86.875874 -339.659468)
			(arc
				(start 85.490558 -339.659468)
				(mid 85.469187 -339.664261)
				(end 85.45195 -339.677756)
			)
			(arc
				(start 85.45195 -339.677756)
				(mid 85.156802 -339.817502)
				(end 84.861654 -339.677756)
			)
			(arc
				(start 84.861654 -339.677756)
				(mid 84.844395 -339.664308)
				(end 84.823046 -339.659468)
			)
			(arc
				(start 83.331812 -339.659468)
				(mid 83.31258 -339.663311)
				(end 83.296252 -339.6742)
			)
			(arc
				(start 83.16468 -339.805772)
				(mid 83.153725 -339.822073)
				(end 83.149948 -339.841332)
			)
			(arc
				(start 83.149948 -340.50478)
				(mid 83.153791 -340.524012)
				(end 83.16468 -340.54034)
			)
			(arc
				(start 83.396328 -340.771988)
				(mid 83.412629 -340.782943)
				(end 83.431888 -340.78672)
			)
		)
		(stroke
			(width 0)
			(type solid)
		)
		(fill yes)
		(layer "B.Cu")
		(net "GND")
	)
	(gr_poly
		(pts
			(arc
				(start 97.022666 -341.194136)
				(mid 97.041898 -341.190293)
				(end 97.058226 -341.179404)
			)
			(arc
				(start 97.282762 -340.954868)
				(mid 97.293717 -340.938567)
				(end 97.297494 -340.919308)
			)
			(arc
				(start 97.297494 -339.386672)
				(mid 97.293651 -339.36744)
				(end 97.282762 -339.351112)
			)
			(arc
				(start 97.185734 -339.254084)
				(mid 97.169433 -339.243129)
				(end 97.150174 -339.239352)
			)
			(arc
				(start 95.858838 -339.239352)
				(mid 95.839026 -339.243441)
				(end 95.822516 -339.2551)
			)
			(xy 95.765366 -339.315806) (xy 95.758508 -339.33511) (xy 95.759016 -339.345524)
			(arc
				(start 95.759778 -339.369146)
				(mid 95.648037 -339.638913)
				(end 95.37827 -339.750654)
			)
			(arc
				(start 95.37827 -339.750654)
				(mid 95.295787 -339.741574)
				(end 95.217234 -339.71484)
			)
			(xy 95.207074 -339.710268)
			(arc
				(start 93.821758 -339.710268)
				(mid 93.800387 -339.715061)
				(end 93.78315 -339.728556)
			)
			(arc
				(start 93.78315 -339.728556)
				(mid 93.488002 -339.868302)
				(end 93.192854 -339.728556)
			)
			(arc
				(start 93.192854 -339.728556)
				(mid 93.175595 -339.715108)
				(end 93.154246 -339.710268)
			)
			(arc
				(start 91.663012 -339.710268)
				(mid 91.64378 -339.714111)
				(end 91.627452 -339.725)
			)
			(arc
				(start 91.49588 -339.856572)
				(mid 91.484925 -339.872873)
				(end 91.481148 -339.892132)
			)
			(arc
				(start 91.481148 -340.944962)
				(mid 91.484991 -340.964194)
				(end 91.49588 -340.980522)
			)
			(arc
				(start 91.694762 -341.179404)
				(mid 91.711063 -341.190359)
				(end 91.730322 -341.194136)
			)
		)
		(stroke
			(width 0)
			(type solid)
		)
		(fill yes)
		(layer "B.Cu")
		(net "GND")
	)
	(gr_poly
		(pts
			(arc
				(start 276.699472 -352.912172)
				(mid 276.718704 -352.908329)
				(end 276.735032 -352.89744)
			)
			(arc
				(start 277.1775 -352.454972)
				(mid 277.188455 -352.438671)
				(end 277.192232 -352.419412)
			)
			(arc
				(start 277.192232 -350.999806)
				(mid 277.188389 -350.980574)
				(end 277.1775 -350.964246)
			)
			(arc
				(start 277.154386 -350.941132)
				(mid 277.138085 -350.930177)
				(end 277.118826 -350.9264)
			)
			(arc
				(start 275.82749 -350.9264)
				(mid 275.807678 -350.930489)
				(end 275.791168 -350.942148)
			)
			(xy 275.734018 -351.002854) (xy 275.72716 -351.022158) (xy 275.727668 -351.032572)
			(arc
				(start 275.72843 -351.056194)
				(mid 275.616689 -351.325961)
				(end 275.346922 -351.437702)
			)
			(arc
				(start 275.346922 -351.437702)
				(mid 275.264439 -351.428622)
				(end 275.185886 -351.401888)
			)
			(xy 275.175726 -351.397316)
			(arc
				(start 273.79041 -351.397316)
				(mid 273.769039 -351.402109)
				(end 273.751802 -351.415604)
			)
			(arc
				(start 273.751802 -351.415604)
				(mid 273.456654 -351.55535)
				(end 273.161506 -351.415604)
			)
			(arc
				(start 273.161506 -351.415604)
				(mid 273.144247 -351.402156)
				(end 273.122898 -351.397316)
			)
			(arc
				(start 272.322798 -351.397316)
				(mid 272.303566 -351.401159)
				(end 272.287238 -351.412048)
			)
			(arc
				(start 272.258282 -351.441004)
				(mid 272.247327 -351.457305)
				(end 272.24355 -351.476564)
			)
			(arc
				(start 272.24355 -352.759264)
				(mid 272.247393 -352.778496)
				(end 272.258282 -352.794824)
			)
			(arc
				(start 272.360898 -352.89744)
				(mid 272.377199 -352.908395)
				(end 272.396458 -352.912172)
			)
		)
		(stroke
			(width 0)
			(type solid)
		)
		(fill yes)
		(layer "B.Cu")
		(net "GND")
	)
	(gr_poly
		(pts
			(arc
				(start 285.367476 -352.524568)
				(mid 285.386708 -352.520725)
				(end 285.403036 -352.509836)
			)
			(arc
				(start 285.4579 -352.454972)
				(mid 285.468855 -352.438671)
				(end 285.472632 -352.419412)
			)
			(arc
				(start 285.472632 -350.999806)
				(mid 285.468789 -350.980574)
				(end 285.4579 -350.964246)
			)
			(arc
				(start 285.434786 -350.941132)
				(mid 285.418485 -350.930177)
				(end 285.399226 -350.9264)
			)
			(arc
				(start 284.10789 -350.9264)
				(mid 284.088078 -350.930489)
				(end 284.071568 -350.942148)
			)
			(xy 284.014418 -351.002854) (xy 284.00756 -351.022158) (xy 284.008068 -351.032572)
			(arc
				(start 284.00883 -351.056194)
				(mid 283.897089 -351.325961)
				(end 283.627322 -351.437702)
			)
			(arc
				(start 283.627322 -351.437702)
				(mid 283.544839 -351.428622)
				(end 283.466286 -351.401888)
			)
			(xy 283.456126 -351.397316)
			(arc
				(start 282.07081 -351.397316)
				(mid 282.049439 -351.402109)
				(end 282.032202 -351.415604)
			)
			(arc
				(start 282.032202 -351.415604)
				(mid 281.737054 -351.55535)
				(end 281.441906 -351.415604)
			)
			(arc
				(start 281.441906 -351.415604)
				(mid 281.424647 -351.402156)
				(end 281.403298 -351.397316)
			)
			(arc
				(start 279.912064 -351.397316)
				(mid 279.892832 -351.401159)
				(end 279.876504 -351.412048)
			)
			(arc
				(start 279.744932 -351.54362)
				(mid 279.733977 -351.559921)
				(end 279.7302 -351.57918)
			)
			(arc
				(start 279.7302 -352.242628)
				(mid 279.734043 -352.26186)
				(end 279.744932 -352.278188)
			)
			(arc
				(start 279.97658 -352.509836)
				(mid 279.992881 -352.520791)
				(end 280.01214 -352.524568)
			)
		)
		(stroke
			(width 0)
			(type solid)
		)
		(fill yes)
		(layer "B.Cu")
		(net "GND")
	)
	(gr_poly
		(pts
			(arc
				(start 293.673276 -352.524568)
				(mid 293.692508 -352.520725)
				(end 293.708836 -352.509836)
			)
			(arc
				(start 293.7637 -352.454972)
				(mid 293.774655 -352.438671)
				(end 293.778432 -352.419412)
			)
			(arc
				(start 293.778432 -350.999806)
				(mid 293.774589 -350.980574)
				(end 293.7637 -350.964246)
			)
			(arc
				(start 293.740586 -350.941132)
				(mid 293.724285 -350.930177)
				(end 293.705026 -350.9264)
			)
			(arc
				(start 292.41369 -350.9264)
				(mid 292.393878 -350.930489)
				(end 292.377368 -350.942148)
			)
			(xy 292.320218 -351.002854) (xy 292.31336 -351.022158) (xy 292.313868 -351.032572)
			(arc
				(start 292.31463 -351.056194)
				(mid 292.202889 -351.325961)
				(end 291.933122 -351.437702)
			)
			(arc
				(start 291.933122 -351.437702)
				(mid 291.850639 -351.428622)
				(end 291.772086 -351.401888)
			)
			(xy 291.761926 -351.397316)
			(arc
				(start 290.37661 -351.397316)
				(mid 290.355239 -351.402109)
				(end 290.338002 -351.415604)
			)
			(arc
				(start 290.338002 -351.415604)
				(mid 290.042854 -351.55535)
				(end 289.747706 -351.415604)
			)
			(arc
				(start 289.747706 -351.415604)
				(mid 289.730447 -351.402156)
				(end 289.709098 -351.397316)
			)
			(arc
				(start 288.217864 -351.397316)
				(mid 288.198632 -351.401159)
				(end 288.182304 -351.412048)
			)
			(arc
				(start 288.050732 -351.54362)
				(mid 288.039777 -351.559921)
				(end 288.036 -351.57918)
			)
			(arc
				(start 288.036 -352.242628)
				(mid 288.039843 -352.26186)
				(end 288.050732 -352.278188)
			)
			(arc
				(start 288.28238 -352.509836)
				(mid 288.298681 -352.520791)
				(end 288.31794 -352.524568)
			)
		)
		(stroke
			(width 0)
			(type solid)
		)
		(fill yes)
		(layer "B.Cu")
		(net "GND")
	)
	(gr_poly
		(pts
			(xy 297.103546 -352.521774) (xy 297.233086 -352.521774) (xy 297.349672 -352.405188) (xy 297.349672 -352.159316)
			(xy 297.414696 -352.094292) (xy 302.122078 -352.094292) (xy 302.135032 -352.081338)
			(arc
				(start 302.135032 -350.999806)
				(mid 302.131189 -350.980574)
				(end 302.1203 -350.964246)
			)
			(arc
				(start 302.097186 -350.941132)
				(mid 302.080885 -350.930177)
				(end 302.061626 -350.9264)
			)
			(arc
				(start 300.77029 -350.9264)
				(mid 300.750478 -350.930489)
				(end 300.733968 -350.942148)
			)
			(xy 300.676818 -351.002854) (xy 300.66996 -351.022158) (xy 300.670468 -351.032572)
			(arc
				(start 300.67123 -351.056194)
				(mid 300.559489 -351.325961)
				(end 300.289722 -351.437702)
			)
			(arc
				(start 300.289722 -351.437702)
				(mid 300.207239 -351.428622)
				(end 300.128686 -351.401888)
			)
			(xy 300.118526 -351.397316)
			(arc
				(start 298.73321 -351.397316)
				(mid 298.711839 -351.402109)
				(end 298.694602 -351.415604)
			)
			(arc
				(start 298.694602 -351.415604)
				(mid 298.399454 -351.55535)
				(end 298.104306 -351.415604)
			)
			(arc
				(start 298.104306 -351.415604)
				(mid 298.087047 -351.402156)
				(end 298.065698 -351.397316)
			)
			(arc
				(start 296.574464 -351.397316)
				(mid 296.555232 -351.401159)
				(end 296.538904 -351.412048)
			)
			(arc
				(start 296.407332 -351.54362)
				(mid 296.396377 -351.559921)
				(end 296.3926 -351.57918)
			)
			(arc
				(start 296.3926 -352.242628)
				(mid 296.396443 -352.26186)
				(end 296.407332 -352.278188)
			)
			(arc
				(start 296.63898 -352.509836)
				(mid 296.655281 -352.520791)
				(end 296.67454 -352.524568)
			)
			(xy 297.100752 -352.524568)
		)
		(stroke
			(width 0)
			(type solid)
		)
		(fill yes)
		(layer "B.Cu")
		(net "GND")
	)
	(gr_poly
		(pts
			(arc
				(start 310.361076 -352.524568)
				(mid 310.380308 -352.520725)
				(end 310.396636 -352.509836)
			)
			(arc
				(start 310.4515 -352.454972)
				(mid 310.462455 -352.438671)
				(end 310.466232 -352.419412)
			)
			(arc
				(start 310.466232 -350.999806)
				(mid 310.462389 -350.980574)
				(end 310.4515 -350.964246)
			)
			(arc
				(start 310.428386 -350.941132)
				(mid 310.412085 -350.930177)
				(end 310.392826 -350.9264)
			)
			(arc
				(start 309.10149 -350.9264)
				(mid 309.081678 -350.930489)
				(end 309.065168 -350.942148)
			)
			(xy 309.008018 -351.002854) (xy 309.00116 -351.022158) (xy 309.001668 -351.032572)
			(arc
				(start 309.00243 -351.056194)
				(mid 308.890689 -351.325961)
				(end 308.620922 -351.437702)
			)
			(arc
				(start 308.620922 -351.437702)
				(mid 308.538439 -351.428622)
				(end 308.459886 -351.401888)
			)
			(xy 308.449726 -351.397316)
			(arc
				(start 307.06441 -351.397316)
				(mid 307.043039 -351.402109)
				(end 307.025802 -351.415604)
			)
			(arc
				(start 307.025802 -351.415604)
				(mid 306.730654 -351.55535)
				(end 306.435506 -351.415604)
			)
			(arc
				(start 306.435506 -351.415604)
				(mid 306.418247 -351.402156)
				(end 306.396898 -351.397316)
			)
			(arc
				(start 304.905664 -351.397316)
				(mid 304.886432 -351.401159)
				(end 304.870104 -351.412048)
			)
			(arc
				(start 304.738532 -351.54362)
				(mid 304.727577 -351.559921)
				(end 304.7238 -351.57918)
			)
			(arc
				(start 304.7238 -351.896934)
				(mid 304.727643 -351.916166)
				(end 304.738532 -351.932494)
			)
			(arc
				(start 305.315874 -352.509836)
				(mid 305.332175 -352.520791)
				(end 305.351434 -352.524568)
			)
		)
		(stroke
			(width 0)
			(type solid)
		)
		(fill yes)
		(layer "B.Cu")
		(net "GND")
	)
	(gr_poly
		(pts
			(arc
				(start 336.72399 -340.781894)
				(mid 336.743222 -340.778051)
				(end 336.75955 -340.767162)
			)
			(arc
				(start 336.814414 -340.712298)
				(mid 336.825369 -340.695997)
				(end 336.829146 -340.676738)
			)
			(arc
				(start 336.829146 -339.257132)
				(mid 336.825303 -339.2379)
				(end 336.814414 -339.221572)
			)
			(arc
				(start 336.7913 -339.198458)
				(mid 336.774999 -339.187503)
				(end 336.75574 -339.183726)
			)
			(arc
				(start 335.464404 -339.183726)
				(mid 335.444592 -339.187815)
				(end 335.428082 -339.199474)
			)
			(xy 335.370932 -339.26018) (xy 335.364074 -339.279484) (xy 335.364582 -339.289898)
			(arc
				(start 335.365344 -339.31352)
				(mid 335.253603 -339.583287)
				(end 334.983836 -339.695028)
			)
			(arc
				(start 334.983836 -339.695028)
				(mid 334.901353 -339.685948)
				(end 334.8228 -339.659214)
			)
			(xy 334.81264 -339.654642)
			(arc
				(start 333.427324 -339.654642)
				(mid 333.405953 -339.659435)
				(end 333.388716 -339.67293)
			)
			(arc
				(start 333.388716 -339.67293)
				(mid 333.093568 -339.812676)
				(end 332.79842 -339.67293)
			)
			(arc
				(start 332.79842 -339.67293)
				(mid 332.781161 -339.659482)
				(end 332.759812 -339.654642)
			)
			(arc
				(start 331.268578 -339.654642)
				(mid 331.249346 -339.658485)
				(end 331.233018 -339.669374)
			)
			(arc
				(start 331.101446 -339.800946)
				(mid 331.090491 -339.817247)
				(end 331.086714 -339.836506)
			)
			(arc
				(start 331.086714 -340.499954)
				(mid 331.090557 -340.519186)
				(end 331.101446 -340.535514)
			)
			(arc
				(start 331.333094 -340.767162)
				(mid 331.349395 -340.778117)
				(end 331.368654 -340.781894)
			)
		)
		(stroke
			(width 0)
			(type solid)
		)
		(fill yes)
		(layer "B.Cu")
		(net "GND")
	)
	(gr_poly
		(pts
			(arc
				(start 344.959432 -341.18931)
				(mid 344.978664 -341.185467)
				(end 344.994992 -341.174578)
			)
			(arc
				(start 345.219528 -340.950042)
				(mid 345.230483 -340.933741)
				(end 345.23426 -340.914482)
			)
			(arc
				(start 345.23426 -339.381846)
				(mid 345.230417 -339.362614)
				(end 345.219528 -339.346286)
			)
			(arc
				(start 345.1225 -339.249258)
				(mid 345.106199 -339.238303)
				(end 345.08694 -339.234526)
			)
			(arc
				(start 343.795604 -339.234526)
				(mid 343.775792 -339.238615)
				(end 343.759282 -339.250274)
			)
			(xy 343.702132 -339.31098) (xy 343.695274 -339.330284) (xy 343.695782 -339.340698)
			(arc
				(start 343.696544 -339.36432)
				(mid 343.584803 -339.634087)
				(end 343.315036 -339.745828)
			)
			(arc
				(start 343.315036 -339.745828)
				(mid 343.232553 -339.736748)
				(end 343.154 -339.710014)
			)
			(xy 343.14384 -339.705442)
			(arc
				(start 341.758524 -339.705442)
				(mid 341.737153 -339.710235)
				(end 341.719916 -339.72373)
			)
			(arc
				(start 341.719916 -339.72373)
				(mid 341.424768 -339.863476)
				(end 341.12962 -339.72373)
			)
			(arc
				(start 341.12962 -339.72373)
				(mid 341.112361 -339.710282)
				(end 341.091012 -339.705442)
			)
			(arc
				(start 339.599778 -339.705442)
				(mid 339.580546 -339.709285)
				(end 339.564218 -339.720174)
			)
			(arc
				(start 339.432646 -339.851746)
				(mid 339.421691 -339.868047)
				(end 339.417914 -339.887306)
			)
			(arc
				(start 339.417914 -340.940136)
				(mid 339.421757 -340.959368)
				(end 339.432646 -340.975696)
			)
			(arc
				(start 339.631528 -341.174578)
				(mid 339.647829 -341.185533)
				(end 339.667088 -341.18931)
			)
		)
		(stroke
			(width 0)
			(type solid)
		)
		(fill yes)
		(layer "B.Cu")
		(net "GND")
	)
	(gr_poly
		(pts
			(arc
				(start 284.230064 -420.409624)
				(mid 284.249587 -420.405723)
				(end 284.266132 -420.394638)
			)
			(arc
				(start 284.342586 -420.318184)
				(mid 284.35912 -420.307073)
				(end 284.378654 -420.303198)
			)
			(arc
				(start 288.497264 -420.303198)
				(mid 288.516787 -420.299297)
				(end 288.533332 -420.288212)
			)
			(arc
				(start 288.546794 -420.27475)
				(mid 288.557905 -420.258216)
				(end 288.56178 -420.238682)
			)
			(arc
				(start 288.56178 -419.79342)
				(mid 288.557879 -419.773897)
				(end 288.546794 -419.757352)
			)
			(arc
				(start 288.470848 -419.681406)
				(mid 288.454314 -419.670295)
				(end 288.43478 -419.66642)
			)
			(arc
				(start 288.078926 -419.66642)
				(mid 288.059403 -419.662519)
				(end 288.042858 -419.651434)
			)
			(arc
				(start 288.004758 -419.613334)
				(mid 287.993647 -419.5968)
				(end 287.989772 -419.577266)
			)
			(xy 287.989772 -419.360096) (xy 287.984692 -419.360096) (xy 287.984692 -419.232842)
			(arc
				(start 287.98012 -419.222936)
				(mid 287.942029 -419.04285)
				(end 287.98012 -418.862764)
			)
			(xy 287.984692 -418.852858) (xy 287.984692 -418.725604) (xy 287.989772 -418.725604)
			(arc
				(start 287.989772 -416.462464)
				(mid 287.985871 -416.442941)
				(end 287.974786 -416.426396)
			)
			(arc
				(start 287.473136 -415.924746)
				(mid 287.456602 -415.913635)
				(end 287.437068 -415.90976)
			)
			(arc
				(start 286.57931 -415.90976)
				(mid 286.559787 -415.913661)
				(end 286.543242 -415.924746)
			)
			(arc
				(start 286.114998 -416.35299)
				(mid 286.098464 -416.364101)
				(end 286.07893 -416.367976)
			)
			(arc
				(start 284.092142 -416.367976)
				(mid 284.072619 -416.371877)
				(end 284.056074 -416.382962)
			)
			(arc
				(start 283.758894 -416.680142)
				(mid 283.747783 -416.696676)
				(end 283.743908 -416.71621)
			)
			(arc
				(start 283.743908 -420.290244)
				(mid 283.747809 -420.309767)
				(end 283.758894 -420.326312)
			)
			(arc
				(start 283.82722 -420.394638)
				(mid 283.843754 -420.405749)
				(end 283.863288 -420.409624)
			)
		)
		(stroke
			(width 0)
			(type solid)
		)
		(fill yes)
		(layer "B.Cu")
		(net "GND")
	)
	(gr_poly
		(pts
			(xy 393.245594 -200.666858) (xy 393.245594 -196.222874) (xy 393.097512 -196.074792) (xy 391.888218 -196.074792)
			(xy 391.563098 -195.749672) (xy 391.563098 -191.774572) (xy 391.16508 -191.376554) (xy 368.111278 -191.376554)
			(xy 367.857278 -191.122554) (xy 367.857278 -187.349638) (xy 366.868964 -186.361324) (xy 360.772964 -186.361324)
			(xy 360.237278 -185.825638) (xy 360.237278 -180.051456) (xy 359.890314 -179.703984) (xy 358.471724 -179.703984)
			(xy 357.893874 -179.126134) (xy 357.893874 -178.061874) (xy 357.766874 -177.934874) (xy 351.584514 -177.934874)
			(xy 351.220278 -177.570638) (xy 351.220278 -171.647358) (xy 351.032064 -171.459144) (xy 349.660464 -171.459144)
			(xy 348.945454 -170.744134) (xy 348.945454 -169.969434) (xy 348.737174 -169.761154) (xy 341.445342 -169.761154)
			(xy 341.214202 -169.992294) (xy 341.214202 -171.64431) (xy 343.599006 -171.64431) (xy 343.603079 -171.588651)
			(xy 343.615214 -171.534178) (xy 343.63515 -171.482052) (xy 343.662464 -171.433384) (xy 343.696572 -171.389212)
			(xy 343.736749 -171.350477) (xy 343.782137 -171.318005) (xy 343.831769 -171.292487) (xy 343.884589 -171.274468)
			(xy 343.939468 -171.264331) (xy 343.995239 -171.262293) (xy 344.050713 -171.268396) (xy 344.104706 -171.282512)
			(xy 344.156069 -171.304339) (xy 344.203707 -171.333412) (xy 344.246603 -171.369111) (xy 344.283845 -171.410675)
			(xy 344.314639 -171.457219) (xy 344.338327 -171.50775) (xy 344.354405 -171.561192) (xy 344.362531 -171.616406)
			(xy 344.36304 -171.64431) (xy 344.362531 -171.672214) (xy 344.354405 -171.727428) (xy 344.338327 -171.78087)
			(xy 344.314639 -171.831401) (xy 344.283845 -171.877945) (xy 344.246603 -171.919509) (xy 344.203707 -171.955208)
			(xy 344.156069 -171.984281) (xy 344.104706 -172.006108) (xy 344.050713 -172.020224) (xy 343.995239 -172.026327)
			(xy 343.939468 -172.024289) (xy 343.884589 -172.014152) (xy 343.831769 -171.996133) (xy 343.782137 -171.970615)
			(xy 343.736749 -171.938143) (xy 343.696572 -171.899408) (xy 343.662464 -171.855236) (xy 343.63515 -171.806568)
			(xy 343.615214 -171.754442) (xy 343.603079 -171.699969) (xy 343.599006 -171.64431) (xy 341.214202 -171.64431)
			(xy 341.214202 -172.480732) (xy 341.214202 -172.829982) (xy 341.214202 -185.256424) (xy 357.29545 -201.337672)
			(xy 392.57478 -201.337672)
		)
		(stroke
			(width 0)
			(type solid)
		)
		(fill yes)
		(layer "B.Cu")
		(net "PVDDCR_CPU0_P0")
	)
	(gr_poly
		(pts
			(arc
				(start 372.264178 -178.670204)
				(mid 372.28341 -178.666361)
				(end 372.299738 -178.655472)
			)
			(xy 372.387114 -178.568096) (xy 372.393718 -178.540156)
			(arc
				(start 372.389146 -178.526694)
				(mid 372.37394 -178.466188)
				(end 372.368826 -178.404012)
			)
			(arc
				(start 372.368826 -178.404012)
				(mid 372.480567 -178.134245)
				(end 372.750334 -178.022504)
			)
			(arc
				(start 372.750334 -178.022504)
				(mid 372.832817 -178.031584)
				(end 372.91137 -178.058318)
			)
			(xy 372.92153 -178.06289)
			(arc
				(start 374.306846 -178.06289)
				(mid 374.328217 -178.058097)
				(end 374.345454 -178.044602)
			)
			(arc
				(start 374.345454 -178.044602)
				(mid 374.640602 -177.904856)
				(end 374.93575 -178.044602)
			)
			(arc
				(start 374.93575 -178.044602)
				(mid 374.953009 -178.05805)
				(end 374.974358 -178.06289)
			)
			(arc
				(start 376.465592 -178.06289)
				(mid 376.484824 -178.059047)
				(end 376.501152 -178.048158)
			)
			(arc
				(start 376.632724 -177.916586)
				(mid 376.643679 -177.900285)
				(end 376.647456 -177.881026)
			)
			(arc
				(start 376.647456 -177.217578)
				(mid 376.643613 -177.198346)
				(end 376.632724 -177.182018)
			)
			(xy 376.393964 -176.943258) (xy 376.375676 -176.935638) (xy 376.366278 -176.935638)
			(arc
				(start 376.06859 -176.63795)
				(mid 376.052377 -176.62718)
				(end 376.033284 -176.623472)
			)
			(arc
				(start 371.026944 -176.623472)
				(mid 371.007878 -176.627247)
				(end 370.991638 -176.63795)
			)
			(arc
				(start 370.919756 -176.709832)
				(mid 370.908801 -176.726133)
				(end 370.905024 -176.745392)
			)
			(arc
				(start 370.905024 -178.582066)
				(mid 370.908867 -178.601298)
				(end 370.919756 -178.617626)
			)
			(arc
				(start 370.957602 -178.655472)
				(mid 370.973903 -178.666427)
				(end 370.993162 -178.670204)
			)
		)
		(stroke
			(width 0)
			(type solid)
		)
		(fill yes)
		(layer "B.Cu")
		(net "GND")
	)
	(gr_poly
		(pts
			(arc
				(start 381.98425 -140.659104)
				(mid 382.003773 -140.655203)
				(end 382.020318 -140.644118)
			)
			(arc
				(start 382.135888 -140.528548)
				(mid 382.142173 -140.520837)
				(end 382.14681 -140.512038)
			)
			(arc
				(start 382.255268 -140.250164)
				(mid 382.258141 -140.240574)
				(end 382.259078 -140.230606)
			)
			(arc
				(start 382.259078 -139.818872)
				(mid 382.262979 -139.799349)
				(end 382.274064 -139.782804)
			)
			(xy 382.431036 -139.625832) (xy 382.437386 -139.61491)
			(arc
				(start 382.439164 -139.60856)
				(mid 382.535811 -139.445111)
				(end 382.69926 -139.348464)
			)
			(xy 382.70561 -139.346686) (xy 382.716532 -139.340336)
			(arc
				(start 383.664968 -138.3919)
				(mid 383.681502 -138.380789)
				(end 383.701036 -138.376914)
			)
			(arc
				(start 385.386326 -138.376914)
				(mid 385.405849 -138.373013)
				(end 385.422394 -138.361928)
			)
			(arc
				(start 385.495292 -138.28903)
				(mid 385.506403 -138.272496)
				(end 385.510278 -138.252962)
			)
			(arc
				(start 385.510278 -137.754614)
				(mid 385.506377 -137.735091)
				(end 385.495292 -137.718546)
			)
			(arc
				(start 385.45389 -137.677144)
				(mid 385.437356 -137.666033)
				(end 385.417822 -137.662158)
			)
			(arc
				(start 382.99136 -137.662158)
				(mid 382.971837 -137.666059)
				(end 382.955292 -137.677144)
			)
			(arc
				(start 382.858264 -137.774172)
				(mid 382.847153 -137.790706)
				(end 382.843278 -137.81024)
			)
			(arc
				(start 382.843278 -138.149076)
				(mid 382.839377 -138.168599)
				(end 382.828292 -138.185144)
			)
			(arc
				(start 381.867918 -139.145518)
				(mid 381.856856 -139.161935)
				(end 381.852932 -139.181332)
			)
			(xy 381.852932 -140.280644) (xy 381.852678 -140.280898)
			(arc
				(start 381.852678 -140.292836)
				(mid 381.848777 -140.312359)
				(end 381.837692 -140.328904)
			)
			(arc
				(start 381.700024 -140.466572)
				(mid 381.68349 -140.477683)
				(end 381.663956 -140.481558)
			)
			(xy 381.656082 -140.481558) (xy 381.655828 -140.481812)
			(arc
				(start 380.984252 -140.481812)
				(mid 380.964865 -140.485762)
				(end 380.948438 -140.496798)
			)
			(arc
				(start 380.946914 -140.498322)
				(mid 380.935803 -140.514856)
				(end 380.931928 -140.53439)
			)
			(xy 380.931928 -140.640562)
			(arc
				(start 380.935484 -140.644118)
				(mid 380.952018 -140.655229)
				(end 380.971552 -140.659104)
			)
		)
		(stroke
			(width 0)
			(type solid)
		)
		(fill yes)
		(layer "B.Cu")
		(net "PVDDCR_CPU0_P0_VCC")
	)
	(gr_poly
		(pts
			(arc
				(start 347.08846 -157.167834)
				(mid 347.107692 -157.163991)
				(end 347.12402 -157.153102)
			)
			(xy 347.41612 -156.861002) (xy 347.423486 -156.840682) (xy 347.422724 -156.82976)
			(arc
				(start 347.421454 -156.799534)
				(mid 347.533195 -156.529767)
				(end 347.802962 -156.418026)
			)
			(arc
				(start 347.802962 -156.418026)
				(mid 348.032705 -156.495022)
				(end 348.169738 -156.694886)
			)
			(xy 348.174564 -156.711142) (xy 348.20098 -156.731208) (xy 349.282512 -156.731208) (xy 349.311722 -156.701998)
			(arc
				(start 349.311722 -156.68117)
				(mid 349.69323 -156.300423)
				(end 350.074738 -156.68117)
			)
			(xy 350.074738 -156.701998) (xy 350.103948 -156.731208)
			(arc
				(start 351.192592 -156.731208)
				(mid 351.211824 -156.727365)
				(end 351.228152 -156.716476)
			)
			(arc
				(start 351.518982 -156.425646)
				(mid 351.529937 -156.409345)
				(end 351.533714 -156.390086)
			)
			(arc
				(start 351.533714 -155.606242)
				(mid 351.529871 -155.58701)
				(end 351.518982 -155.570682)
			)
			(arc
				(start 351.220786 -155.272486)
				(mid 351.204485 -155.261531)
				(end 351.185226 -155.257754)
			)
			(arc
				(start 346.055442 -155.257754)
				(mid 346.03621 -155.261597)
				(end 346.019882 -155.272486)
			)
			(arc
				(start 345.752166 -155.540202)
				(mid 345.741211 -155.556503)
				(end 345.737434 -155.575762)
			)
			(arc
				(start 345.737434 -157.045406)
				(mid 345.741277 -157.064638)
				(end 345.752166 -157.080966)
			)
			(arc
				(start 345.824302 -157.153102)
				(mid 345.840603 -157.164057)
				(end 345.859862 -157.167834)
			)
		)
		(stroke
			(width 0)
			(type solid)
		)
		(fill yes)
		(layer "B.Cu")
		(net "GND")
	)
	(gr_poly
		(pts
			(arc
				(start 363.69498 -173.751494)
				(mid 363.714212 -173.747651)
				(end 363.73054 -173.736762)
			)
			(xy 364.000288 -173.467014) (xy 364.007908 -173.448218) (xy 364.007654 -173.438058)
			(arc
				(start 364.007654 -173.431454)
				(mid 364.119395 -173.161687)
				(end 364.389162 -173.049946)
			)
			(arc
				(start 364.389162 -173.049946)
				(mid 364.618905 -173.126942)
				(end 364.755938 -173.326806)
			)
			(xy 364.760764 -173.343062) (xy 364.78718 -173.363128) (xy 365.868712 -173.363128) (xy 365.897922 -173.333918)
			(arc
				(start 365.897922 -173.31309)
				(mid 366.27943 -172.932343)
				(end 366.660938 -173.31309)
			)
			(xy 366.660938 -173.333918) (xy 366.690148 -173.363128)
			(arc
				(start 367.811812 -173.363128)
				(mid 367.831044 -173.359285)
				(end 367.847372 -173.348396)
			)
			(arc
				(start 368.079782 -173.115986)
				(mid 368.090737 -173.099685)
				(end 368.094514 -173.080426)
			)
			(arc
				(start 368.094514 -172.39361)
				(mid 368.090671 -172.374378)
				(end 368.079782 -172.35805)
			)
			(arc
				(start 367.490502 -171.76877)
				(mid 367.474201 -171.757815)
				(end 367.454942 -171.754038)
			)
			(arc
				(start 362.801662 -171.754038)
				(mid 362.78243 -171.757881)
				(end 362.766102 -171.76877)
			)
			(arc
				(start 362.409486 -172.125386)
				(mid 362.398531 -172.141687)
				(end 362.394754 -172.160946)
			)
			(arc
				(start 362.394754 -173.664626)
				(mid 362.398597 -173.683858)
				(end 362.409486 -173.700186)
			)
			(arc
				(start 362.446062 -173.736762)
				(mid 362.462363 -173.747717)
				(end 362.481622 -173.751494)
			)
		)
		(stroke
			(width 0)
			(type solid)
		)
		(fill yes)
		(layer "B.Cu")
		(net "GND")
	)
	(gr_poly
		(pts
			(arc
				(start 355.41966 -165.463474)
				(mid 355.438892 -165.459631)
				(end 355.45522 -165.448742)
			)
			(xy 355.719634 -165.184328) (xy 355.727254 -165.16604)
			(arc
				(start 355.727254 -165.15588)
				(mid 355.839085 -164.886277)
				(end 356.108762 -164.774626)
			)
			(arc
				(start 356.108762 -164.774626)
				(mid 356.338505 -164.851622)
				(end 356.475538 -165.051486)
			)
			(xy 356.480364 -165.067742) (xy 356.50678 -165.087808) (xy 357.588312 -165.087808) (xy 357.617522 -165.058598)
			(arc
				(start 357.617522 -165.03777)
				(mid 357.99903 -164.657023)
				(end 358.380538 -165.03777)
			)
			(xy 358.380538 -165.058598) (xy 358.409748 -165.087808) (xy 359.120186 -165.087808) (xy 359.123234 -165.085014)
			(arc
				(start 359.620566 -165.085014)
				(mid 359.639798 -165.081171)
				(end 359.656126 -165.070282)
			)
			(arc
				(start 359.773982 -164.952426)
				(mid 359.784937 -164.936125)
				(end 359.788714 -164.916866)
			)
			(arc
				(start 359.788714 -163.967922)
				(mid 359.784871 -163.94869)
				(end 359.773982 -163.932362)
			)
			(arc
				(start 359.541826 -163.700206)
				(mid 359.525525 -163.689251)
				(end 359.506266 -163.685474)
			)
			(arc
				(start 354.437442 -163.685474)
				(mid 354.41821 -163.689317)
				(end 354.401882 -163.700206)
			)
			(arc
				(start 354.141786 -163.960302)
				(mid 354.130831 -163.976603)
				(end 354.127054 -163.995862)
			)
			(arc
				(start 354.127054 -165.374066)
				(mid 354.130897 -165.393298)
				(end 354.141786 -165.409626)
			)
			(arc
				(start 354.180902 -165.448742)
				(mid 354.197203 -165.459697)
				(end 354.216462 -165.463474)
			)
		)
		(stroke
			(width 0)
			(type solid)
		)
		(fill yes)
		(layer "B.Cu")
		(net "GND")
	)
	(gr_poly
		(pts
			(arc
				(start 30.969966 -402.203666)
				(mid 30.989489 -402.199765)
				(end 31.006034 -402.18868)
			)
			(arc
				(start 31.274766 -401.919948)
				(mid 31.285877 -401.903414)
				(end 31.289752 -401.88388)
			)
			(arc
				(start 31.289752 -390.939274)
				(mid 31.285802 -390.919887)
				(end 31.274766 -390.90346)
			)
			(arc
				(start 29.412184 -389.040878)
				(mid 29.395767 -389.029816)
				(end 29.37637 -389.025892)
			)
			(arc
				(start 26.035762 -389.025892)
				(mid 26.016239 -389.029793)
				(end 25.999694 -389.040878)
			)
			(arc
				(start 25.97277 -389.067802)
				(mid 25.961659 -389.084336)
				(end 25.957784 -389.10387)
			)
			(arc
				(start 25.957784 -391.588244)
				(mid 25.961685 -391.607767)
				(end 25.97277 -391.624312)
			)
			(arc
				(start 26.742898 -392.39444)
				(mid 26.754009 -392.410974)
				(end 26.757884 -392.430508)
			)
			(xy 26.757884 -394.43533) (xy 26.754836 -394.438378)
			(arc
				(start 26.754836 -395.232382)
				(mid 26.750935 -395.251905)
				(end 26.73985 -395.26845)
			)
			(arc
				(start 26.523188 -395.485112)
				(mid 26.506654 -395.496223)
				(end 26.48712 -395.500098)
			)
			(arc
				(start 21.55063 -395.500098)
				(mid 21.531107 -395.496197)
				(end 21.514562 -395.485112)
			)
			(xy 20.597114 -394.567664) (xy 20.595336 -394.567664)
			(arc
				(start 20.595336 -389.203692)
				(mid 20.591435 -389.184169)
				(end 20.58035 -389.167624)
			)
			(arc
				(start 20.559268 -389.146542)
				(mid 20.542734 -389.135431)
				(end 20.5232 -389.131556)
			)
			(arc
				(start 17.068292 -389.131556)
				(mid 17.048769 -389.135457)
				(end 17.032224 -389.146542)
			)
			(arc
				(start 16.980916 -389.19785)
				(mid 16.969805 -389.214384)
				(end 16.96593 -389.233918)
			)
			(arc
				(start 16.96593 -392.660124)
				(mid 16.969831 -392.679647)
				(end 16.980916 -392.696192)
			)
			(arc
				(start 17.74825 -393.463526)
				(mid 17.759361 -393.48006)
				(end 17.763236 -393.499594)
			)
			(arc
				(start 17.763236 -394.400786)
				(mid 17.767137 -394.420309)
				(end 17.778222 -394.436854)
			)
			(arc
				(start 18.344388 -395.002766)
				(mid 18.355499 -395.0193)
				(end 18.359374 -395.038834)
			)
			(arc
				(start 18.359374 -401.728432)
				(mid 18.363275 -401.747955)
				(end 18.37436 -401.7645)
			)
			(arc
				(start 18.384012 -401.774152)
				(mid 18.400546 -401.785263)
				(end 18.42008 -401.789138)
			)
			(xy 18.944082 -401.789138) (xy 18.945606 -401.787614)
			(arc
				(start 19.426174 -401.787614)
				(mid 19.445697 -401.791515)
				(end 19.462242 -401.8026)
			)
			(arc
				(start 19.848322 -402.18868)
				(mid 19.864856 -402.199791)
				(end 19.88439 -402.203666)
			)
		)
		(stroke
			(width 0)
			(type solid)
		)
		(fill yes)
		(layer "B.Cu")
		(net "SW_P12V_AUX_P0V9_RETIMER_CPU1_FLT")
	)
	(gr_poly
		(pts
			(arc
				(start 380.550674 -178.754024)
				(mid 380.569769 -178.750132)
				(end 380.58598 -178.739292)
			)
			(xy 380.772924 -178.552348) (xy 380.78029 -178.528726)
			(arc
				(start 380.778004 -178.516534)
				(mid 380.773218 -178.481755)
				(end 380.771654 -178.446684)
			)
			(xy 380.772162 -178.427634)
			(arc
				(start 380.7714 -178.404012)
				(mid 380.883216 -178.134066)
				(end 381.153162 -178.02225)
			)
			(arc
				(start 381.153162 -178.02225)
				(mid 381.408717 -178.120403)
				(end 381.532892 -178.364388)
			)
			(xy 381.55118 -178.378358) (xy 382.632712 -178.378358) (xy 382.661922 -178.349148) (xy 382.661922 -178.32832)
			(xy 382.66243 -178.310032)
			(arc
				(start 382.661668 -178.28641)
				(mid 383.04343 -177.904648)
				(end 383.425192 -178.28641)
			)
			(xy 383.42443 -178.310032) (xy 383.424938 -178.32832) (xy 383.424938 -178.349148) (xy 383.454148 -178.378358)
			(arc
				(start 384.522726 -178.378358)
				(mid 384.541821 -178.374466)
				(end 384.558032 -178.363626)
			)
			(arc
				(start 384.864102 -178.057556)
				(mid 384.875008 -178.041373)
				(end 384.878834 -178.02225)
			)
			(arc
				(start 384.878834 -177.367946)
				(mid 384.874942 -177.348851)
				(end 384.864102 -177.33264)
			)
			(arc
				(start 384.395472 -176.86401)
				(mid 384.379289 -176.853104)
				(end 384.360166 -176.849278)
			)
			(arc
				(start 379.593348 -176.849278)
				(mid 379.574253 -176.85317)
				(end 379.558042 -176.86401)
			)
			(arc
				(start 379.206506 -177.215546)
				(mid 379.1956 -177.231729)
				(end 379.191774 -177.250852)
			)
			(arc
				(start 379.191774 -178.67503)
				(mid 379.195666 -178.694125)
				(end 379.206506 -178.710336)
			)
			(arc
				(start 379.235462 -178.739292)
				(mid 379.251645 -178.750198)
				(end 379.270768 -178.754024)
			)
		)
		(stroke
			(width 0)
			(type solid)
		)
		(fill yes)
		(layer "B.Cu")
		(net "GND")
	)
	(gr_poly
		(pts
			(xy 229.6795 -435.74208) (xy 229.6795 -422.049194) (xy 234.763056 -416.965638) (xy 272.832322 -416.965638)
			(xy 279.44318 -410.35478) (xy 280.05024 -409.74772)
			(arc
				(start 280.05024 -394.963396)
				(mid 280.046339 -394.943873)
				(end 280.035254 -394.927328)
			)
			(arc
				(start 279.651206 -394.54328)
				(mid 279.634672 -394.532169)
				(end 279.615138 -394.528294)
			)
			(xy 278.21382 -394.528294) (xy 241.711734 -394.528294) (xy 240.424208 -394.528294) (xy 239.91189 -395.040612)
			(xy 239.91189 -404.086822) (xy 239.455198 -404.543514) (xy 238.750856 -404.543514) (xy 238.252 -404.543514)
			(xy 235.566966 -404.543514) (xy 234.872784 -404.543514) (xy 233.845608 -404.543514) (xy 233.216704 -403.91461)
			(xy 233.216704 -402.887434) (xy 233.216704 -400.514312) (xy 233.06024 -400.357848) (xy 230.074724 -400.357848)
			(xy 229.851966 -400.580606) (xy 229.851966 -402.672042) (xy 229.851966 -404.582376) (xy 229.595172 -404.83917)
			(xy 228.476302 -405.95804) (xy 228.476302 -407.36266) (xy 227.122736 -408.716226) (xy 225.062034 -408.716226)
			(xy 225.04781 -408.716226) (xy 224.942654 -408.716226) (xy 223.244156 -407.017728) (xy 223.244156 -406.898348)
			(xy 223.244156 -404.84425) (xy 222.521272 -404.121366) (xy 222.521272 -400.388074) (xy 222.49892 -400.365722)
			(xy 219.379546 -400.365722) (xy 219.17914 -400.566128) (xy 219.17914 -404.12035) (xy 218.590114 -404.709376)
			(xy 218.590114 -405.022558) (xy 218.590114 -406.24379) (xy 216.384378 -408.449526) (xy 216.221056 -408.612848)
			(xy 214.150194 -408.612848) (xy 213.986872 -408.449526) (xy 212.38464 -406.847294) (xy 212.38464 -406.461976)
			(xy 212.38464 -405.18969) (xy 211.892642 -404.697692) (xy 211.892642 -400.421348) (xy 211.848192 -400.376898)
			(xy 208.728818 -400.376898) (xy 208.539334 -400.566382) (xy 208.539334 -404.721822) (xy 208.138268 -405.122888)
			(xy 208.045558 -405.215598) (xy 208.045558 -406.607772) (xy 206.106522 -408.546808) (xy 205.898242 -408.755088)
			(xy 203.091542 -408.755088) (xy 201.852276 -407.515822) (xy 201.852276 -407.031698) (xy 201.852276 -404.499318)
			(xy 201.209402 -403.856444) (xy 201.209402 -400.583908) (xy 200.997058 -400.371564) (xy 197.94982 -400.371564)
			(xy 197.743572 -400.577812) (xy 197.743572 -404.050246) (xy 195.828666 -405.965152) (xy 190.810896 -405.965152)
			(xy 188.435488 -403.589744) (xy 188.435488 -400.516344) (xy 188.290708 -400.371564) (xy 184.720484 -400.371564)
			(xy 184.581292 -400.510756) (xy 184.581292 -404.183342) (xy 185.25998 -404.86203) (xy 185.25998 -410.126434)
			(xy 185.950098 -410.816552) (xy 194.800728 -410.816552) (xy 196.26072 -412.276544) (xy 196.26072 -413.31007)
			(xy 196.26072 -414.072832) (xy 196.26072 -421.757602)
			(arc
				(start 206.039974 -431.536856)
				(mid 206.051085 -431.55339)
				(end 206.05496 -431.572924)
			)
			(xy 206.05496 -435.09946) (xy 207.43418 -436.47868) (xy 228.9429 -436.47868)
		)
		(stroke
			(width 0)
			(type solid)
		)
		(fill yes)
		(layer "B.Cu")
		(net "P12V_PSU")
	)
	(gr_poly
		(pts
			(arc
				(start 6.283452 -340.295992)
				(mid 6.302975 -340.292091)
				(end 6.31952 -340.281006)
			)
			(arc
				(start 6.898386 -339.70214)
				(mid 6.909497 -339.685606)
				(end 6.913372 -339.666072)
			)
			(arc
				(start 6.913372 -187.488068)
				(mid 6.915923 -187.472172)
				(end 6.923278 -187.457842)
			)
			(xy 6.928104 -187.451238) (xy 6.933184 -187.435998)
			(arc
				(start 6.933184 -185.051954)
				(mid 6.937085 -185.032431)
				(end 6.94817 -185.015886)
			)
			(arc
				(start 13.482828 -178.481228)
				(mid 13.493939 -178.464694)
				(end 13.497814 -178.44516)
			)
			(arc
				(start 13.497814 -173.390052)
				(mid 13.501715 -173.370529)
				(end 13.5128 -173.353984)
			)
			(arc
				(start 24.153622 -162.713162)
				(mid 24.164733 -162.696628)
				(end 24.168608 -162.677094)
			)
			(arc
				(start 24.168608 -142.91818)
				(mid 24.172509 -142.898657)
				(end 24.183594 -142.882112)
			)
			(arc
				(start 27.543506 -139.5222)
				(mid 27.554617 -139.505666)
				(end 27.558492 -139.486132)
			)
			(arc
				(start 27.558492 -98.03765)
				(mid 27.562393 -98.018127)
				(end 27.573478 -98.001582)
			)
			(arc
				(start 32.012382 -93.562678)
				(mid 32.028916 -93.551567)
				(end 32.04845 -93.547692)
			)
			(arc
				(start 81.43621 -93.547692)
				(mid 81.455733 -93.551593)
				(end 81.472278 -93.562678)
			)
			(arc
				(start 81.922874 -94.013274)
				(mid 81.939408 -94.024385)
				(end 81.958942 -94.02826)
			)
			(arc
				(start 82.948018 -94.02826)
				(mid 82.967541 -94.024359)
				(end 82.984086 -94.013274)
			)
			(arc
				(start 83.319874 -93.677486)
				(mid 83.330985 -93.660952)
				(end 83.33486 -93.641418)
			)
			(arc
				(start 83.33486 -91.415362)
				(mid 83.330959 -91.395839)
				(end 83.319874 -91.379294)
			)
			(xy 82.114136 -90.173556) (xy 82.107024 -90.16619) (xy 82.088228 -90.15857)
			(arc
				(start 30.969712 -90.15857)
				(mid 30.950189 -90.162471)
				(end 30.933644 -90.173556)
			)
			(xy 24.337772 -96.769428) (xy 24.330406 -96.77654) (xy 24.322786 -96.795336)
			(arc
				(start 24.322786 -137.830306)
				(mid 24.318885 -137.849829)
				(end 24.3078 -137.866374)
			)
			(xy 21.872448 -140.301726) (xy 21.865082 -140.308838) (xy 21.857462 -140.327634)
			(arc
				(start 21.857462 -160.482534)
				(mid 21.853561 -160.502057)
				(end 21.842476 -160.518602)
			)
			(xy 11.162538 -171.19854) (xy 11.155172 -171.205652) (xy 11.147552 -171.224448)
			(arc
				(start 11.147552 -178.820064)
				(mid 11.143651 -178.839587)
				(end 11.132566 -178.856132)
			)
			(xy 5.728208 -184.26049) (xy 5.724906 -184.264046) (xy 5.718302 -184.274714) (xy 5.641086 -184.437274)
			(xy 5.639308 -184.441592)
			(arc
				(start 5.305552 -185.357516)
				(mid 5.303309 -185.365895)
				(end 5.302504 -185.374534)
			)
			(xy 4.906518 -253.063756) (xy 4.63296 -311.778142)
			(arc
				(start 4.63296 -339.879178)
				(mid 4.636861 -339.898701)
				(end 4.647946 -339.915246)
			)
			(arc
				(start 5.013706 -340.281006)
				(mid 5.03024 -340.292117)
				(end 5.049774 -340.295992)
			)
		)
		(stroke
			(width 0)
			(type solid)
		)
		(fill yes)
		(layer "B.Cu")
		(net "P3V3")
	)
	(gr_poly
		(pts
			(arc
				(start 327.186798 -400.814286)
				(mid 327.206321 -400.810385)
				(end 327.222866 -400.7993)
			)
			(arc
				(start 327.241408 -400.780758)
				(mid 327.252519 -400.764224)
				(end 327.256394 -400.74469)
			)
			(arc
				(start 327.256394 -398.256506)
				(mid 327.260295 -398.236983)
				(end 327.27138 -398.220438)
			)
			(arc
				(start 327.352152 -398.139666)
				(mid 327.368686 -398.128555)
				(end 327.38822 -398.12468)
			)
			(arc
				(start 329.26528 -398.12468)
				(mid 329.284803 -398.128581)
				(end 329.301348 -398.139666)
			)
			(arc
				(start 329.4761 -398.314418)
				(mid 329.487211 -398.330952)
				(end 329.491086 -398.350486)
			)
			(arc
				(start 329.491086 -399.485866)
				(mid 329.494987 -399.505389)
				(end 329.506072 -399.521934)
			)
			(arc
				(start 329.583796 -399.599658)
				(mid 329.60033 -399.610769)
				(end 329.619864 -399.614644)
			)
			(arc
				(start 330.46416 -399.614644)
				(mid 330.483683 -399.610743)
				(end 330.500228 -399.599658)
			)
			(arc
				(start 330.539852 -399.560034)
				(mid 330.550963 -399.5435)
				(end 330.554838 -399.523966)
			)
			(arc
				(start 330.554838 -396.67942)
				(mid 330.550937 -396.659897)
				(end 330.539852 -396.643352)
			)
			(arc
				(start 330.478384 -396.581884)
				(mid 330.46185 -396.570773)
				(end 330.442316 -396.566898)
			)
			(arc
				(start 329.582272 -396.566898)
				(mid 329.562749 -396.562997)
				(end 329.546204 -396.551912)
			)
			(arc
				(start 329.363832 -396.36954)
				(mid 329.352721 -396.353006)
				(end 329.348846 -396.333472)
			)
			(arc
				(start 329.348846 -395.390878)
				(mid 329.344945 -395.371355)
				(end 329.33386 -395.35481)
			)
			(arc
				(start 329.26909 -395.29004)
				(mid 329.252556 -395.278929)
				(end 329.233022 -395.275054)
			)
			(arc
				(start 325.976234 -395.275054)
				(mid 325.956711 -395.278955)
				(end 325.940166 -395.29004)
			)
			(arc
				(start 325.602854 -395.627352)
				(mid 325.58632 -395.638463)
				(end 325.566786 -395.642338)
			)
			(arc
				(start 324.431152 -395.642338)
				(mid 324.411629 -395.646239)
				(end 324.395084 -395.657324)
			)
			(arc
				(start 324.165468 -395.88694)
				(mid 324.154357 -395.903474)
				(end 324.150482 -395.923008)
			)
			(xy 324.150482 -396.604236)
			(arc
				(start 324.151498 -396.608808)
				(mid 324.155913 -396.639911)
				(end 324.15734 -396.671292)
			)
			(arc
				(start 324.15734 -396.671292)
				(mid 324.155896 -396.702672)
				(end 324.151498 -396.733776)
			)
			(xy 324.150482 -396.738348)
			(arc
				(start 324.150482 -397.045942)
				(mid 324.154383 -397.065465)
				(end 324.165468 -397.08201)
			)
			(arc
				(start 324.629526 -397.546068)
				(mid 324.64606 -397.557179)
				(end 324.665594 -397.561054)
			)
			(arc
				(start 325.864474 -397.561054)
				(mid 325.883997 -397.564955)
				(end 325.900542 -397.57604)
			)
			(arc
				(start 326.047862 -397.72336)
				(mid 326.058973 -397.739894)
				(end 326.062848 -397.759428)
			)
			(arc
				(start 326.062848 -400.661124)
				(mid 326.066749 -400.680647)
				(end 326.077834 -400.697192)
			)
			(arc
				(start 326.179942 -400.7993)
				(mid 326.196476 -400.810411)
				(end 326.21601 -400.814286)
			)
		)
		(stroke
			(width 0)
			(type solid)
		)
		(fill yes)
		(layer "B.Cu")
		(net "GND")
	)
	(gr_poly
		(pts
			(arc
				(start 216.885774 -327.402698)
				(mid 216.905297 -327.398797)
				(end 216.921842 -327.387712)
			)
			(arc
				(start 217.22969 -327.079864)
				(mid 217.246224 -327.068753)
				(end 217.265758 -327.064878)
			)
			(arc
				(start 220.34627 -327.064878)
				(mid 220.365793 -327.060977)
				(end 220.382338 -327.049892)
			)
			(arc
				(start 220.418152 -327.014078)
				(mid 220.429263 -326.997544)
				(end 220.433138 -326.97801)
			)
			(arc
				(start 220.433138 -326.71258)
				(mid 220.429237 -326.693057)
				(end 220.418152 -326.676512)
			)
			(arc
				(start 220.404436 -326.662796)
				(mid 220.387902 -326.651685)
				(end 220.368368 -326.64781)
			)
			(arc
				(start 216.666064 -326.64781)
				(mid 216.646541 -326.643909)
				(end 216.629996 -326.632824)
			)
			(arc
				(start 215.292178 -325.295006)
				(mid 215.281067 -325.278472)
				(end 215.277192 -325.258938)
			)
			(xy 215.277192 -325.224394) (xy 215.255856 -325.196962)
			(arc
				(start 215.238584 -325.192644)
				(mid 215.097137 -325.136565)
				(end 214.975948 -325.044562)
			)
			(arc
				(start 213.889082 -323.957696)
				(mid 213.872665 -323.946634)
				(end 213.853268 -323.94271)
			)
			(arc
				(start 213.463632 -323.94271)
				(mid 213.444109 -323.946611)
				(end 213.427564 -323.957696)
			)
			(arc
				(start 213.37397 -324.01129)
				(mid 213.362859 -324.027824)
				(end 213.358984 -324.047358)
			)
			(xy 213.358984 -325.28002) (xy 213.356444 -325.28002)
			(arc
				(start 213.356444 -326.937624)
				(mid 213.360345 -326.957147)
				(end 213.37143 -326.973692)
			)
			(xy 213.371684 -326.973946)
			(arc
				(start 213.955376 -326.973946)
				(mid 213.974899 -326.970045)
				(end 213.991444 -326.95896)
			)
			(arc
				(start 214.2109 -326.739504)
				(mid 214.227434 -326.728393)
				(end 214.246968 -326.724518)
			)
			(xy 214.742522 -326.724518)
			(arc
				(start 214.748364 -326.723248)
				(mid 214.790637 -326.716019)
				(end 214.833454 -326.713596)
			)
			(arc
				(start 214.833454 -326.713596)
				(mid 214.876269 -326.716035)
				(end 214.918544 -326.723248)
			)
			(xy 214.924386 -326.724518) (xy 215.274906 -326.724518)
			(arc
				(start 215.283542 -326.721216)
				(mid 215.336876 -326.706405)
				(end 215.392 -326.701404)
			)
			(xy 215.422988 -326.701404) (xy 215.44026 -326.695054)
			(arc
				(start 215.447118 -326.688704)
				(mid 215.516827 -326.646478)
				(end 215.596978 -326.631808)
			)
			(arc
				(start 215.81364 -326.631808)
				(mid 215.849561 -326.646687)
				(end 215.86444 -326.682608)
			)
			(xy 215.86444 -326.691752)
			(arc
				(start 216.078816 -326.691752)
				(mid 216.114826 -326.706615)
				(end 216.129616 -326.742552)
			)
			(arc
				(start 216.129616 -326.746616)
				(mid 216.133449 -326.765973)
				(end 216.144348 -326.78243)
			)
			(xy 216.146888 -326.78497)
			(arc
				(start 216.146888 -327.324974)
				(mid 216.150789 -327.344497)
				(end 216.161874 -327.361042)
			)
			(arc
				(start 216.188544 -327.387712)
				(mid 216.205078 -327.398823)
				(end 216.224612 -327.402698)
			)
		)
		(stroke
			(width 0)
			(type solid)
		)
		(fill yes)
		(layer "B.Cu")
		(net "P3V3_ADC128_2_VCC")
	)
	(gr_poly
		(pts
			(xy 397.474694 -176.959768) (xy 397.474694 -173.83252) (xy 397.324834 -173.68266) (xy 396.029942 -173.68266)
			(xy 395.531594 -173.184312) (xy 395.531594 -169.685716) (xy 395.759178 -169.458132) (xy 399.719038 -169.458132)
			(xy 400.810476 -168.36644) (xy 405.760682 -168.36644) (xy 405.818594 -168.308528) (xy 405.818594 -165.2905)
			(xy 405.678894 -165.1508) (xy 404.332186 -165.1508) (xy 403.889718 -164.707824) (xy 403.889718 -162.960812)
			(xy 404.646638 -162.203638) (xy 410.140658 -162.203638) (xy 410.6164 -162.67938) (xy 410.6164 -163.43376)
			(xy 410.74848 -163.56584) (xy 414.137094 -163.56584) (xy 414.187894 -163.51504) (xy 414.187894 -160.42132)
			(xy 414.030414 -160.26384) (xy 412.486094 -160.26384) (xy 412.053278 -159.831024) (xy 412.053278 -158.012638)
			(xy 412.056834 -158.008828) (xy 412.056834 -157.48127) (xy 411.78226 -157.206696) (xy 394.617448 -157.206696)
			(xy 394.192506 -156.781754) (xy 393.696952 -156.2862) (xy 393.517628 -156.106622) (xy 393.133326 -155.72232)
			(xy 390.696958 -153.285952) (xy 385.108958 -153.285952) (xy 384.727958 -153.666952) (xy 384.727958 -165.195193)
			(xy 386.31774 -165.195193) (xy 386.31774 -165.110471) (xy 386.325793 -165.026134) (xy 386.341827 -164.942944)
			(xy 386.365695 -164.861654) (xy 386.397183 -164.783002) (xy 386.436005 -164.707699) (xy 386.481808 -164.636427)
			(xy 386.534179 -164.569831) (xy 386.592644 -164.508516) (xy 386.656672 -164.453035) (xy 386.725684 -164.403892)
			(xy 386.799054 -164.361532) (xy 386.876119 -164.326337) (xy 386.956181 -164.298628) (xy 387.038514 -164.278654)
			(xy 387.122373 -164.266597) (xy 387.206998 -164.262566) (xy 387.291623 -164.266597) (xy 387.375482 -164.278654)
			(xy 387.457815 -164.298628) (xy 387.537877 -164.326337) (xy 387.614942 -164.361532) (xy 387.688312 -164.403892)
			(xy 387.757324 -164.453035) (xy 387.821352 -164.508516) (xy 387.879817 -164.569831) (xy 387.932188 -164.636427)
			(xy 387.977991 -164.707699) (xy 388.016813 -164.783002) (xy 388.048301 -164.861654) (xy 388.072169 -164.942944)
			(xy 388.088203 -165.026134) (xy 388.096256 -165.110471) (xy 388.09676 -165.152832) (xy 388.096256 -165.195193)
			(xy 388.088203 -165.27953) (xy 388.072169 -165.36272) (xy 388.048301 -165.44401) (xy 388.016813 -165.522662)
			(xy 387.977991 -165.597965) (xy 387.932188 -165.669237) (xy 387.879817 -165.735833) (xy 387.821352 -165.797148)
			(xy 387.757324 -165.852629) (xy 387.688312 -165.901772) (xy 387.614942 -165.944132) (xy 387.537877 -165.979327)
			(xy 387.457815 -166.007036) (xy 387.375482 -166.02701) (xy 387.291623 -166.039067) (xy 387.206998 -166.043099)
			(xy 387.122373 -166.039067) (xy 387.038514 -166.02701) (xy 386.956181 -166.007036) (xy 386.876119 -165.979327)
			(xy 386.799054 -165.944132) (xy 386.725684 -165.901772) (xy 386.656672 -165.852629) (xy 386.592644 -165.797148)
			(xy 386.534179 -165.735833) (xy 386.481808 -165.669237) (xy 386.436005 -165.597965) (xy 386.397183 -165.522662)
			(xy 386.365695 -165.44401) (xy 386.341827 -165.36272) (xy 386.325793 -165.27953) (xy 386.31774 -165.195193)
			(xy 384.727958 -165.195193) (xy 384.727958 -167.636952) (xy 386.632958 -169.541952) (xy 390.823958 -169.541952)
			(xy 392.855958 -171.573952) (xy 392.855958 -176.153318) (xy 393.699746 -176.997106) (xy 397.437356 -176.997106)
		)
		(stroke
			(width 0)
			(type solid)
		)
		(fill yes)
		(layer "B.Cu")
		(net "SW_P12V_AUX_PVDDCR_SOC_P0_FLT")
	)
	(gr_poly
		(pts
			(xy 197.125082 -385.680966) (xy 197.135145 -385.680527) (xy 197.153725 -385.672788) (xy 197.16115 -385.66598)
			(xy 197.532244 -385.294886) (xy 197.539094 -385.28749) (xy 197.546833 -385.268891) (xy 197.54723 -385.258818)
			(xy 197.54723 -378.883672) (xy 197.547659 -378.873605) (xy 197.555384 -378.85501) (xy 197.562216 -378.847604)
			(xy 199.169782 -377.240038) (xy 199.177183 -377.2332) (xy 199.195782 -377.22549) (xy 199.20585 -377.225052)
			(xy 199.462136 -377.225052) (xy 199.479408 -377.218448) (xy 199.48652 -377.212098) (xy 199.525242 -377.178259)
			(xy 199.607286 -377.116247) (xy 199.694073 -377.061068) (xy 199.785035 -377.013083) (xy 199.879578 -376.972606)
			(xy 199.977083 -376.939902) (xy 200.076912 -376.915185) (xy 200.178412 -376.898617) (xy 200.280918 -376.890306)
			(xy 200.383762 -376.890306) (xy 200.486268 -376.898617) (xy 200.587768 -376.915185) (xy 200.687597 -376.939902)
			(xy 200.785102 -376.972606) (xy 200.879645 -377.013083) (xy 200.970607 -377.061068) (xy 201.057394 -377.116247)
			(xy 201.139438 -377.178259) (xy 201.17816 -377.212098) (xy 201.185353 -377.217963) (xy 201.202671 -377.224597)
			(xy 201.211942 -377.225052) (xy 218.552776 -377.225052) (xy 218.552776 -377.226322) (xy 277.779734 -377.226322)
			(xy 279.072086 -378.518674) (xy 279.072086 -378.535946) (xy 279.317196 -378.781056) (xy 279.317196 -380.512828)
			(xy 280.375614 -380.512828) (xy 280.754328 -380.134114) (xy 280.754328 -377.438158) (xy 278.258524 -374.942354)
			(xy 222.988378 -374.942354) (xy 222.977202 -374.941084) (xy 198.77151 -374.941084) (xy 198.761439 -374.941505)
			(xy 198.74283 -374.949215) (xy 198.735442 -374.95607) (xy 197.251066 -376.440446) (xy 198.820022 -376.440446)
			(xy 198.824095 -376.384787) (xy 198.83623 -376.330314) (xy 198.856166 -376.278188) (xy 198.88348 -376.22952)
			(xy 198.917588 -376.185348) (xy 198.957765 -376.146613) (xy 199.003153 -376.114141) (xy 199.052785 -376.088623)
			(xy 199.105605 -376.070604) (xy 199.160484 -376.060467) (xy 199.216255 -376.058429) (xy 199.271729 -376.064532)
			(xy 199.325722 -376.078648) (xy 199.377085 -376.100475) (xy 199.424723 -376.129548) (xy 199.467619 -376.165247)
			(xy 199.504861 -376.206811) (xy 199.535655 -376.253355) (xy 199.559343 -376.303886) (xy 199.575421 -376.357328)
			(xy 199.583547 -376.412542) (xy 199.584056 -376.440446) (xy 199.583547 -376.46835) (xy 199.575421 -376.523564)
			(xy 199.559343 -376.577006) (xy 199.535655 -376.627537) (xy 199.504861 -376.674081) (xy 199.467619 -376.715645)
			(xy 199.424723 -376.751344) (xy 199.377085 -376.780417) (xy 199.325722 -376.802244) (xy 199.271729 -376.81636)
			(xy 199.216255 -376.822463) (xy 199.160484 -376.820425) (xy 199.105605 -376.810288) (xy 199.052785 -376.792269)
			(xy 199.003153 -376.766751) (xy 198.957765 -376.734279) (xy 198.917588 -376.695544) (xy 198.88348 -376.651372)
			(xy 198.856166 -376.602704) (xy 198.83623 -376.550578) (xy 198.824095 -376.496105) (xy 198.820022 -376.440446)
			(xy 197.251066 -376.440446) (xy 195.735194 -377.956318) (xy 195.728351 -377.963718) (xy 195.720624 -377.982316)
			(xy 195.720208 -377.992386) (xy 195.720208 -385.392422) (xy 195.720635 -385.40249) (xy 195.728356 -385.421088)
			(xy 195.735194 -385.42849) (xy 195.972684 -385.66598) (xy 195.980086 -385.672815) (xy 195.998685 -385.680522)
			(xy 196.008752 -385.680966)
		)
		(stroke
			(width 0)
			(type solid)
		)
		(fill yes)
		(layer "B.Cu")
		(net "P12V_HSC_GATE1")
	)
	(gr_poly
		(pts
			(xy 392.581384 -395.1478) (xy 392.591447 -395.147361) (xy 392.61003 -395.139626) (xy 392.617452 -395.132814)
			(xy 392.772392 -394.977874) (xy 392.779235 -394.970474) (xy 392.786961 -394.951876) (xy 392.787378 -394.941806)
			(xy 392.787378 -393.85875) (xy 392.78781 -393.848683) (xy 392.795534 -393.83009) (xy 392.802364 -393.822682)
			(xy 392.948668 -393.676378) (xy 392.955515 -393.66898) (xy 392.963246 -393.650381) (xy 392.963654 -393.64031)
			(xy 392.963654 -392.277854) (xy 392.963221 -392.267789) (xy 392.95549 -392.249201) (xy 392.948668 -392.241786)
			(xy 392.861292 -392.15441) (xy 392.853947 -392.1476) (xy 392.835484 -392.139869) (xy 392.825478 -392.139424)
			(xy 390.364472 -392.139424) (xy 390.354474 -392.139947) (xy 390.336013 -392.147637) (xy 390.321864 -392.161772)
			(xy 390.314156 -392.180227) (xy 390.313672 -392.190224) (xy 390.313672 -393.531344) (xy 390.529318 -393.531344)
			(xy 390.529741 -393.506448) (xy 390.537193 -393.457216) (xy 390.551935 -393.409655) (xy 390.573634 -393.36484)
			(xy 390.601801 -393.32378) (xy 390.618472 -393.305284) (xy 390.625076 -393.298426) (xy 390.631934 -393.281408)
			(xy 390.63422 -393.195048) (xy 390.628124 -393.177522) (xy 390.622028 -393.17041) (xy 390.607263 -393.152421)
			(xy 390.582435 -393.113058) (xy 390.563373 -393.070602) (xy 390.550454 -393.025892) (xy 390.543935 -392.979812)
			(xy 390.543542 -392.956542) (xy 390.544052 -392.930555) (xy 390.552182 -392.87922) (xy 390.568243 -392.82979)
			(xy 390.591839 -392.78348) (xy 390.622389 -392.741432) (xy 390.65914 -392.704681) (xy 390.701188 -392.674131)
			(xy 390.747498 -392.650535) (xy 390.796928 -392.634474) (xy 390.848263 -392.626344) (xy 390.900237 -392.626344)
			(xy 390.951572 -392.634474) (xy 391.001002 -392.650535) (xy 391.047312 -392.674131) (xy 391.08936 -392.704681)
			(xy 391.126111 -392.741432) (xy 391.156661 -392.78348) (xy 391.180257 -392.82979) (xy 391.196318 -392.87922)
			(xy 391.204448 -392.930555) (xy 391.204958 -392.956542) (xy 391.204533 -392.981438) (xy 391.197082 -393.03067)
			(xy 391.182342 -393.078231) (xy 391.160643 -393.123047) (xy 391.132476 -393.164107) (xy 391.115804 -393.182602)
			(xy 391.1092 -393.18946) (xy 391.102342 -393.206478) (xy 391.100056 -393.292838) (xy 391.106152 -393.310364)
			(xy 391.112248 -393.317476) (xy 391.127003 -393.335473) (xy 391.151833 -393.374833) (xy 391.170898 -393.417288)
			(xy 391.183818 -393.461996) (xy 391.19034 -393.508075) (xy 391.190734 -393.531344) (xy 391.190224 -393.557331)
			(xy 391.182094 -393.608666) (xy 391.166033 -393.658096) (xy 391.142437 -393.704406) (xy 391.111887 -393.746454)
			(xy 391.075136 -393.783205) (xy 391.033088 -393.813755) (xy 390.986778 -393.837351) (xy 390.937348 -393.853412)
			(xy 390.886013 -393.861542) (xy 390.834039 -393.861542) (xy 390.782704 -393.853412) (xy 390.733274 -393.837351)
			(xy 390.686964 -393.813755) (xy 390.644916 -393.783205) (xy 390.608165 -393.746454) (xy 390.577615 -393.704406)
			(xy 390.554019 -393.658096) (xy 390.537958 -393.608666) (xy 390.529828 -393.557331) (xy 390.529318 -393.531344)
			(xy 390.313672 -393.531344) (xy 390.313672 -394.363448) (xy 390.314103 -394.373515) (xy 390.321827 -394.392109)
			(xy 390.328658 -394.399516) (xy 391.06221 -395.132814) (xy 391.069552 -395.139632) (xy 391.088015 -395.147375)
			(xy 391.098024 -395.1478)
		)
		(stroke
			(width 0)
			(type solid)
		)
		(fill yes)
		(layer "B.Cu")
		(net "P1V8_CPU0_RT3_1A")
	)
	(gr_poly
		(pts
			(xy 69.481446 -386.7658) (xy 69.491512 -386.765368) (xy 69.510105 -386.757642) (xy 69.517514 -386.750814)
			(xy 69.65188 -386.616448) (xy 69.658721 -386.609048) (xy 69.666439 -386.590449) (xy 69.666866 -386.58038)
			(xy 69.666866 -385.497324) (xy 69.667305 -385.487261) (xy 69.675046 -385.468683) (xy 69.681852 -385.461256)
			(xy 69.84873 -385.294378) (xy 69.85558 -385.286982) (xy 69.863318 -385.268383) (xy 69.863716 -385.25831)
			(xy 69.863716 -383.895854) (xy 69.863285 -383.885787) (xy 69.855561 -383.867193) (xy 69.84873 -383.859786)
			(xy 69.761354 -383.77241) (xy 69.754007 -383.765605) (xy 69.735544 -383.757888) (xy 69.72554 -383.757424)
			(xy 67.157346 -383.757424) (xy 67.147355 -383.757954) (xy 67.128913 -383.765658) (xy 67.121532 -383.77241)
			(xy 66.997326 -383.896616) (xy 66.990479 -383.904014) (xy 66.982747 -383.922612) (xy 66.98234 -383.932684)
			(xy 66.98234 -385.149344) (xy 67.42938 -385.149344) (xy 67.429813 -385.124448) (xy 67.437264 -385.075217)
			(xy 67.452004 -385.027657) (xy 67.4737 -384.982841) (xy 67.501864 -384.941781) (xy 67.518534 -384.923284)
			(xy 67.525138 -384.916426) (xy 67.531996 -384.899408) (xy 67.534282 -384.813048) (xy 67.528186 -384.795522)
			(xy 67.52209 -384.78841) (xy 67.507319 -384.770425) (xy 67.482493 -384.731061) (xy 67.463433 -384.688603)
			(xy 67.450516 -384.643892) (xy 67.443997 -384.597812) (xy 67.443604 -384.574542) (xy 67.444114 -384.548555)
			(xy 67.452244 -384.49722) (xy 67.468305 -384.44779) (xy 67.491901 -384.40148) (xy 67.522451 -384.359432)
			(xy 67.559202 -384.322681) (xy 67.60125 -384.292131) (xy 67.64756 -384.268535) (xy 67.69699 -384.252474)
			(xy 67.748325 -384.244344) (xy 67.800299 -384.244344) (xy 67.851634 -384.252474) (xy 67.901064 -384.268535)
			(xy 67.947374 -384.292131) (xy 67.989422 -384.322681) (xy 68.026173 -384.359432) (xy 68.056723 -384.40148)
			(xy 68.080319 -384.44779) (xy 68.09638 -384.49722) (xy 68.10451 -384.548555) (xy 68.10502 -384.574542)
			(xy 68.104578 -384.599438) (xy 68.097129 -384.648668) (xy 68.082392 -384.696228) (xy 68.060697 -384.741044)
			(xy 68.032535 -384.782105) (xy 68.015866 -384.800602) (xy 68.009262 -384.80746) (xy 68.002404 -384.824478)
			(xy 68.000118 -384.910838) (xy 68.006214 -384.928364) (xy 68.01231 -384.935476) (xy 68.027074 -384.953466)
			(xy 68.051901 -384.992829) (xy 68.070963 -385.035285) (xy 68.083881 -385.079995) (xy 68.090402 -385.126075)
			(xy 68.090796 -385.149344) (xy 68.090286 -385.175331) (xy 68.082156 -385.226666) (xy 68.066095 -385.276096)
			(xy 68.042499 -385.322406) (xy 68.011949 -385.364454) (xy 67.975198 -385.401205) (xy 67.93315 -385.431755)
			(xy 67.88684 -385.455351) (xy 67.83741 -385.471412) (xy 67.786075 -385.479542) (xy 67.734101 -385.479542)
			(xy 67.682766 -385.471412) (xy 67.633336 -385.455351) (xy 67.587026 -385.431755) (xy 67.544978 -385.401205)
			(xy 67.508227 -385.364454) (xy 67.477677 -385.322406) (xy 67.454081 -385.276096) (xy 67.43802 -385.226666)
			(xy 67.42989 -385.175331) (xy 67.42938 -385.149344) (xy 66.98234 -385.149344) (xy 66.98234 -385.743958)
			(xy 66.982775 -385.754023) (xy 66.990509 -385.772608) (xy 66.997326 -385.780026) (xy 67.968114 -386.750814)
			(xy 67.975509 -386.757668) (xy 67.994108 -386.76541) (xy 68.004182 -386.7658)
		)
		(stroke
			(width 0)
			(type solid)
		)
		(fill yes)
		(layer "B.Cu")
		(net "P1V8_CPU1_RT0_1A")
	)
	(gr_poly
		(pts
			(xy 358.008936 -395.1478) (xy 358.019003 -395.14737) (xy 358.037598 -395.139647) (xy 358.045004 -395.132814)
			(xy 358.199944 -394.977874) (xy 358.206792 -394.970477) (xy 358.214526 -394.951878) (xy 358.21493 -394.941806)
			(xy 358.21493 -393.85875) (xy 358.215363 -393.848684) (xy 358.223093 -393.830096) (xy 358.229916 -393.822682)
			(xy 358.37622 -393.676378) (xy 358.383072 -393.668982) (xy 358.390811 -393.650383) (xy 358.391206 -393.64031)
			(xy 358.391206 -392.277854) (xy 358.390775 -392.267787) (xy 358.383049 -392.249194) (xy 358.37622 -392.241786)
			(xy 358.193086 -392.058652) (xy 358.185689 -392.051802) (xy 358.167091 -392.044064) (xy 358.157018 -392.043666)
			(xy 355.780848 -392.043666) (xy 355.770783 -392.0441) (xy 355.752199 -392.051835) (xy 355.74478 -392.058652)
			(xy 355.524816 -392.278616) (xy 355.51797 -392.286015) (xy 355.510239 -392.304613) (xy 355.50983 -392.314684)
			(xy 355.50983 -393.531344) (xy 355.95687 -393.531344) (xy 355.957306 -393.506448) (xy 355.964757 -393.457218)
			(xy 355.979496 -393.409658) (xy 356.001192 -393.364842) (xy 356.029355 -393.323781) (xy 356.046024 -393.305284)
			(xy 356.052628 -393.298426) (xy 356.059486 -393.281408) (xy 356.061772 -393.195048) (xy 356.055676 -393.177522)
			(xy 356.04958 -393.17041) (xy 356.034823 -393.152415) (xy 356.009992 -393.113054) (xy 355.990927 -393.0706)
			(xy 355.978007 -393.025891) (xy 355.971487 -392.979811) (xy 355.971094 -392.956542) (xy 355.971604 -392.930555)
			(xy 355.979734 -392.87922) (xy 355.995795 -392.82979) (xy 356.019391 -392.78348) (xy 356.049941 -392.741432)
			(xy 356.086692 -392.704681) (xy 356.12874 -392.674131) (xy 356.17505 -392.650535) (xy 356.22448 -392.634474)
			(xy 356.275815 -392.626344) (xy 356.327789 -392.626344) (xy 356.379124 -392.634474) (xy 356.428554 -392.650535)
			(xy 356.474864 -392.674131) (xy 356.516912 -392.704681) (xy 356.553663 -392.741432) (xy 356.584213 -392.78348)
			(xy 356.607809 -392.82979) (xy 356.62387 -392.87922) (xy 356.632 -392.930555) (xy 356.63251 -392.956542)
			(xy 356.632071 -392.981438) (xy 356.624622 -393.030668) (xy 356.609884 -393.078228) (xy 356.588188 -393.123044)
			(xy 356.560025 -393.164105) (xy 356.543356 -393.182602) (xy 356.536752 -393.18946) (xy 356.529894 -393.206478)
			(xy 356.527608 -393.292838) (xy 356.533704 -393.310364) (xy 356.5398 -393.317476) (xy 356.554563 -393.335467)
			(xy 356.57939 -393.37483) (xy 356.598452 -393.417285) (xy 356.611371 -393.461995) (xy 356.617892 -393.508075)
			(xy 356.618286 -393.531344) (xy 356.617776 -393.557331) (xy 356.609646 -393.608666) (xy 356.593585 -393.658096)
			(xy 356.569989 -393.704406) (xy 356.539439 -393.746454) (xy 356.502688 -393.783205) (xy 356.46064 -393.813755)
			(xy 356.41433 -393.837351) (xy 356.3649 -393.853412) (xy 356.313565 -393.861542) (xy 356.261591 -393.861542)
			(xy 356.210256 -393.853412) (xy 356.160826 -393.837351) (xy 356.114516 -393.813755) (xy 356.072468 -393.783205)
			(xy 356.035717 -393.746454) (xy 356.005167 -393.704406) (xy 355.981571 -393.658096) (xy 355.96551 -393.608666)
			(xy 355.95738 -393.557331) (xy 355.95687 -393.531344) (xy 355.50983 -393.531344) (xy 355.50983 -394.153898)
			(xy 355.510253 -394.163968) (xy 355.517971 -394.18257) (xy 355.524816 -394.189966) (xy 356.467664 -395.132814)
			(xy 356.475062 -395.13966) (xy 356.493661 -395.147384) (xy 356.503732 -395.1478)
		)
		(stroke
			(width 0)
			(type solid)
		)
		(fill yes)
		(layer "B.Cu")
		(net "P1V8_CPU0_RT1_1A")
	)
	(gr_poly
		(pts
			(arc
				(start 138.286998 -392.432286)
				(mid 138.306521 -392.428385)
				(end 138.323066 -392.4173)
			)
			(arc
				(start 138.341608 -392.398758)
				(mid 138.352719 -392.382224)
				(end 138.356594 -392.36269)
			)
			(arc
				(start 138.356594 -389.874506)
				(mid 138.360495 -389.854983)
				(end 138.37158 -389.838438)
			)
			(arc
				(start 138.452352 -389.757666)
				(mid 138.468886 -389.746555)
				(end 138.48842 -389.74268)
			)
			(arc
				(start 140.36548 -389.74268)
				(mid 140.385003 -389.746581)
				(end 140.401548 -389.757666)
			)
			(arc
				(start 140.5763 -389.932418)
				(mid 140.587411 -389.948952)
				(end 140.591286 -389.968486)
			)
			(arc
				(start 140.591286 -391.103866)
				(mid 140.595187 -391.123389)
				(end 140.606272 -391.139934)
			)
			(arc
				(start 140.683996 -391.217658)
				(mid 140.70053 -391.228769)
				(end 140.720064 -391.232644)
			)
			(arc
				(start 141.56436 -391.232644)
				(mid 141.583883 -391.228743)
				(end 141.600428 -391.217658)
			)
			(arc
				(start 141.640052 -391.178034)
				(mid 141.651163 -391.1615)
				(end 141.655038 -391.141966)
			)
			(arc
				(start 141.655038 -388.29742)
				(mid 141.651137 -388.277897)
				(end 141.640052 -388.261352)
			)
			(arc
				(start 141.578584 -388.199884)
				(mid 141.56205 -388.188773)
				(end 141.542516 -388.184898)
			)
			(arc
				(start 140.812012 -388.184898)
				(mid 140.792489 -388.180997)
				(end 140.775944 -388.169912)
			)
			(xy 140.734288 -388.128256)
			(arc
				(start 140.727938 -388.1247)
				(mid 140.640754 -388.059484)
				(end 140.575538 -387.9723)
			)
			(xy 140.571982 -387.96595)
			(arc
				(start 140.464032 -387.858)
				(mid 140.452921 -387.841466)
				(end 140.449046 -387.821932)
			)
			(arc
				(start 140.449046 -387.024372)
				(mid 140.434167 -386.988451)
				(end 140.398246 -386.973572)
			)
			(arc
				(start 137.062718 -386.973572)
				(mid 137.043331 -386.969622)
				(end 137.026904 -386.958586)
			)
			(xy 136.98982 -386.958586)
			(arc
				(start 136.703054 -387.245352)
				(mid 136.68652 -387.256463)
				(end 136.666986 -387.260338)
			)
			(arc
				(start 135.531352 -387.260338)
				(mid 135.511829 -387.264239)
				(end 135.495284 -387.275324)
			)
			(arc
				(start 135.265668 -387.50494)
				(mid 135.254557 -387.521474)
				(end 135.250682 -387.541008)
			)
			(xy 135.250682 -388.222236)
			(arc
				(start 135.251698 -388.226808)
				(mid 135.256113 -388.257911)
				(end 135.25754 -388.289292)
			)
			(arc
				(start 135.25754 -388.289292)
				(mid 135.256096 -388.320672)
				(end 135.251698 -388.351776)
			)
			(xy 135.250682 -388.356348)
			(arc
				(start 135.250682 -388.663942)
				(mid 135.254583 -388.683465)
				(end 135.265668 -388.70001)
			)
			(arc
				(start 135.729726 -389.164068)
				(mid 135.74626 -389.175179)
				(end 135.765794 -389.179054)
			)
			(arc
				(start 136.964674 -389.179054)
				(mid 136.984197 -389.182955)
				(end 137.000742 -389.19404)
			)
			(arc
				(start 137.148062 -389.34136)
				(mid 137.159173 -389.357894)
				(end 137.163048 -389.377428)
			)
			(arc
				(start 137.163048 -392.279124)
				(mid 137.166949 -392.298647)
				(end 137.178034 -392.315192)
			)
			(arc
				(start 137.280142 -392.4173)
				(mid 137.296676 -392.428411)
				(end 137.31621 -392.432286)
			)
		)
		(stroke
			(width 0)
			(type solid)
		)
		(fill yes)
		(layer "B.Cu")
		(net "GND")
	)
	(gr_poly
		(pts
			(xy 325.481188 -395.1478) (xy 325.491259 -395.147379) (xy 325.509867 -395.139668) (xy 325.517256 -395.132814)
			(xy 325.663814 -394.986256) (xy 325.670663 -394.978859) (xy 325.678395 -394.96026) (xy 325.6788 -394.950188)
			(xy 325.6788 -393.867132) (xy 325.679236 -393.857067) (xy 325.686967 -393.838481) (xy 325.693786 -393.831064)
			(xy 325.848472 -393.676378) (xy 325.855318 -393.66898) (xy 325.863049 -393.650381) (xy 325.863458 -393.64031)
			(xy 325.863458 -392.277854) (xy 325.863025 -392.267788) (xy 325.855294 -392.2492) (xy 325.848472 -392.241786)
			(xy 325.761096 -392.15441) (xy 325.753751 -392.147599) (xy 325.735289 -392.139867) (xy 325.725282 -392.139424)
			(xy 323.157088 -392.139424) (xy 323.147102 -392.139964) (xy 323.128675 -392.147683) (xy 323.121274 -392.15441)
			(xy 323.03974 -392.235944) (xy 323.033043 -392.243349) (xy 323.025434 -392.261785) (xy 323.025008 -392.271758)
			(xy 323.025008 -393.531344) (xy 323.429122 -393.531344) (xy 323.429544 -393.506448) (xy 323.436996 -393.457216)
			(xy 323.451738 -393.409655) (xy 323.473437 -393.36484) (xy 323.501604 -393.32378) (xy 323.518276 -393.305284)
			(xy 323.52488 -393.298426) (xy 323.531738 -393.281408) (xy 323.534024 -393.195048) (xy 323.527928 -393.177522)
			(xy 323.521832 -393.17041) (xy 323.507068 -393.15242) (xy 323.482239 -393.113058) (xy 323.463177 -393.070602)
			(xy 323.450259 -393.025892) (xy 323.443739 -392.979812) (xy 323.443346 -392.956542) (xy 323.443856 -392.930555)
			(xy 323.451986 -392.87922) (xy 323.468047 -392.82979) (xy 323.491643 -392.78348) (xy 323.522193 -392.741432)
			(xy 323.558944 -392.704681) (xy 323.600992 -392.674131) (xy 323.647302 -392.650535) (xy 323.696732 -392.634474)
			(xy 323.748067 -392.626344) (xy 323.800041 -392.626344) (xy 323.851376 -392.634474) (xy 323.900806 -392.650535)
			(xy 323.947116 -392.674131) (xy 323.989164 -392.704681) (xy 324.025915 -392.741432) (xy 324.056465 -392.78348)
			(xy 324.080061 -392.82979) (xy 324.096122 -392.87922) (xy 324.104252 -392.930555) (xy 324.104762 -392.956542)
			(xy 324.104335 -392.981438) (xy 324.096885 -393.03067) (xy 324.082145 -393.078231) (xy 324.060446 -393.123047)
			(xy 324.03228 -393.164107) (xy 324.015608 -393.182602) (xy 324.009004 -393.18946) (xy 324.002146 -393.206478)
			(xy 323.99986 -393.292838) (xy 324.005956 -393.310364) (xy 324.012052 -393.317476) (xy 324.026807 -393.335473)
			(xy 324.051638 -393.374833) (xy 324.070702 -393.417287) (xy 324.083622 -393.461996) (xy 324.090144 -393.508075)
			(xy 324.090538 -393.531344) (xy 324.090028 -393.557331) (xy 324.081898 -393.608666) (xy 324.065837 -393.658096)
			(xy 324.042241 -393.704406) (xy 324.011691 -393.746454) (xy 323.97494 -393.783205) (xy 323.932892 -393.813755)
			(xy 323.886582 -393.837351) (xy 323.837152 -393.853412) (xy 323.785817 -393.861542) (xy 323.733843 -393.861542)
			(xy 323.682508 -393.853412) (xy 323.633078 -393.837351) (xy 323.586768 -393.813755) (xy 323.54472 -393.783205)
			(xy 323.507969 -393.746454) (xy 323.477419 -393.704406) (xy 323.453823 -393.658096) (xy 323.437762 -393.608666)
			(xy 323.429632 -393.557331) (xy 323.429122 -393.531344) (xy 323.025008 -393.531344) (xy 323.025008 -394.045948)
			(xy 323.025445 -394.055981) (xy 323.033019 -394.074556) (xy 323.03974 -394.082016) (xy 324.048882 -395.091158)
			(xy 324.055685 -395.098506) (xy 324.063399 -395.116968) (xy 324.063868 -395.126972) (xy 324.084442 -395.1478)
		)
		(stroke
			(width 0)
			(type solid)
		)
		(fill yes)
		(layer "B.Cu")
		(net "P1V8_CPU0_RT0_1A")
	)
	(gr_poly
		(pts
			(xy 102.009194 -386.7658) (xy 102.019265 -386.765378) (xy 102.037871 -386.757665) (xy 102.045262 -386.750814)
			(xy 102.114096 -386.68198) (xy 102.114096 -386.681726) (xy 102.192074 -386.603748) (xy 102.198915 -386.596348)
			(xy 102.206634 -386.577749) (xy 102.20706 -386.56768) (xy 102.20706 -385.484878) (xy 102.207489 -385.474811)
			(xy 102.215215 -385.456218) (xy 102.222046 -385.44881) (xy 102.376478 -385.294378) (xy 102.383323 -385.286979)
			(xy 102.391053 -385.268381) (xy 102.391464 -385.25831) (xy 102.391464 -383.895854) (xy 102.391032 -383.885788)
			(xy 102.383302 -383.867199) (xy 102.376478 -383.859786) (xy 102.289102 -383.77241) (xy 102.281757 -383.765598)
			(xy 102.263295 -383.757863) (xy 102.253288 -383.757424) (xy 99.685094 -383.757424) (xy 99.675108 -383.757963)
			(xy 99.656679 -383.765681) (xy 99.64928 -383.77241) (xy 99.525074 -383.896616) (xy 99.518222 -383.904012)
			(xy 99.510482 -383.922611) (xy 99.510088 -383.932684) (xy 99.510088 -385.149344) (xy 99.957128 -385.149344)
			(xy 99.957549 -385.124448) (xy 99.965001 -385.075215) (xy 99.979743 -385.027655) (xy 100.001442 -384.982839)
			(xy 100.02961 -384.941779) (xy 100.046282 -384.923284) (xy 100.052886 -384.916426) (xy 100.059744 -384.899408)
			(xy 100.06203 -384.813048) (xy 100.055934 -384.795522) (xy 100.049838 -384.78841) (xy 100.035075 -384.77042)
			(xy 100.010246 -384.731057) (xy 99.991183 -384.688601) (xy 99.978265 -384.643892) (xy 99.971745 -384.597812)
			(xy 99.971352 -384.574542) (xy 99.971862 -384.548555) (xy 99.979992 -384.49722) (xy 99.996053 -384.44779)
			(xy 100.019649 -384.40148) (xy 100.050199 -384.359432) (xy 100.08695 -384.322681) (xy 100.128998 -384.292131)
			(xy 100.175308 -384.268535) (xy 100.224738 -384.252474) (xy 100.276073 -384.244344) (xy 100.328047 -384.244344)
			(xy 100.379382 -384.252474) (xy 100.428812 -384.268535) (xy 100.475122 -384.292131) (xy 100.51717 -384.322681)
			(xy 100.553921 -384.359432) (xy 100.584471 -384.40148) (xy 100.608067 -384.44779) (xy 100.624128 -384.49722)
			(xy 100.632258 -384.548555) (xy 100.632768 -384.574542) (xy 100.63234 -384.599438) (xy 100.62489 -384.64867)
			(xy 100.61015 -384.69623) (xy 100.588452 -384.741046) (xy 100.560285 -384.782106) (xy 100.543614 -384.800602)
			(xy 100.53701 -384.80746) (xy 100.530152 -384.824478) (xy 100.527866 -384.910838) (xy 100.533962 -384.928364)
			(xy 100.540058 -384.935476) (xy 100.554814 -384.953472) (xy 100.579644 -384.992833) (xy 100.598708 -385.035287)
			(xy 100.611629 -385.079996) (xy 100.61815 -385.126075) (xy 100.618544 -385.149344) (xy 100.618034 -385.175331)
			(xy 100.609904 -385.226666) (xy 100.593843 -385.276096) (xy 100.570247 -385.322406) (xy 100.539697 -385.364454)
			(xy 100.502946 -385.401205) (xy 100.460898 -385.431755) (xy 100.414588 -385.455351) (xy 100.365158 -385.471412)
			(xy 100.313823 -385.479542) (xy 100.261849 -385.479542) (xy 100.210514 -385.471412) (xy 100.161084 -385.455351)
			(xy 100.114774 -385.431755) (xy 100.072726 -385.401205) (xy 100.035975 -385.364454) (xy 100.005425 -385.322406)
			(xy 99.981829 -385.276096) (xy 99.965768 -385.226666) (xy 99.957638 -385.175331) (xy 99.957128 -385.149344)
			(xy 99.510088 -385.149344) (xy 99.510088 -386.405374) (xy 99.510524 -386.415439) (xy 99.518256 -386.434025)
			(xy 99.525074 -386.441442) (xy 99.834446 -386.750814) (xy 99.841843 -386.757663) (xy 99.860442 -386.765394)
			(xy 99.870514 -386.7658)
		)
		(stroke
			(width 0)
			(type solid)
		)
		(fill yes)
		(layer "B.Cu")
		(net "P1V8_CPU1_RT1_1A")
	)
	(gr_poly
		(pts
			(xy 136.581642 -386.7658) (xy 136.591709 -386.765369) (xy 136.610302 -386.757644) (xy 136.61771 -386.750814)
			(xy 136.760458 -386.608066) (xy 136.767303 -386.600668) (xy 136.775032 -386.582069) (xy 136.775444 -386.571998)
			(xy 136.775444 -385.488942) (xy 136.775879 -385.478877) (xy 136.783613 -385.460293) (xy 136.79043 -385.452874)
			(xy 136.948926 -385.294378) (xy 136.955777 -385.286982) (xy 136.963515 -385.268383) (xy 136.963912 -385.25831)
			(xy 136.963912 -383.895854) (xy 136.963481 -383.885787) (xy 136.955756 -383.867194) (xy 136.948926 -383.859786)
			(xy 136.86155 -383.77241) (xy 136.854203 -383.765606) (xy 136.83574 -383.75789) (xy 136.825736 -383.757424)
			(xy 134.257542 -383.757424) (xy 134.247552 -383.757954) (xy 134.229111 -383.76566) (xy 134.221728 -383.77241)
			(xy 134.097522 -383.896616) (xy 134.090676 -383.904014) (xy 134.082944 -383.922613) (xy 134.082536 -383.932684)
			(xy 134.082536 -385.149344) (xy 134.529322 -385.149344) (xy 134.529744 -385.124448) (xy 134.537196 -385.075216)
			(xy 134.551938 -385.027655) (xy 134.573637 -384.98284) (xy 134.601804 -384.94178) (xy 134.618476 -384.923284)
			(xy 134.62508 -384.916426) (xy 134.631938 -384.899408) (xy 134.634224 -384.813048) (xy 134.628128 -384.795522)
			(xy 134.622032 -384.78841) (xy 134.607268 -384.77042) (xy 134.582439 -384.731058) (xy 134.563377 -384.688602)
			(xy 134.550459 -384.643892) (xy 134.543939 -384.597812) (xy 134.543546 -384.574542) (xy 134.544056 -384.548555)
			(xy 134.552186 -384.49722) (xy 134.568247 -384.44779) (xy 134.591843 -384.40148) (xy 134.622393 -384.359432)
			(xy 134.659144 -384.322681) (xy 134.701192 -384.292131) (xy 134.747502 -384.268535) (xy 134.796932 -384.252474)
			(xy 134.848267 -384.244344) (xy 134.900241 -384.244344) (xy 134.951576 -384.252474) (xy 135.001006 -384.268535)
			(xy 135.047316 -384.292131) (xy 135.089364 -384.322681) (xy 135.126115 -384.359432) (xy 135.156665 -384.40148)
			(xy 135.180261 -384.44779) (xy 135.196322 -384.49722) (xy 135.204452 -384.548555) (xy 135.204962 -384.574542)
			(xy 135.204535 -384.599438) (xy 135.197085 -384.64867) (xy 135.182345 -384.696231) (xy 135.160646 -384.741047)
			(xy 135.13248 -384.782107) (xy 135.115808 -384.800602) (xy 135.109204 -384.80746) (xy 135.102346 -384.824478)
			(xy 135.10006 -384.910838) (xy 135.106156 -384.928364) (xy 135.112252 -384.935476) (xy 135.127007 -384.953473)
			(xy 135.151838 -384.992833) (xy 135.170902 -385.035287) (xy 135.183822 -385.079996) (xy 135.190344 -385.126075)
			(xy 135.190738 -385.149344) (xy 135.190228 -385.175331) (xy 135.182098 -385.226666) (xy 135.166037 -385.276096)
			(xy 135.142441 -385.322406) (xy 135.111891 -385.364454) (xy 135.07514 -385.401205) (xy 135.033092 -385.431755)
			(xy 134.986782 -385.455351) (xy 134.937352 -385.471412) (xy 134.886017 -385.479542) (xy 134.834043 -385.479542)
			(xy 134.782708 -385.471412) (xy 134.733278 -385.455351) (xy 134.686968 -385.431755) (xy 134.64492 -385.401205)
			(xy 134.608169 -385.364454) (xy 134.577619 -385.322406) (xy 134.554023 -385.276096) (xy 134.537962 -385.226666)
			(xy 134.529832 -385.175331) (xy 134.529322 -385.149344) (xy 134.082536 -385.149344) (xy 134.082536 -385.766818)
			(xy 134.082963 -385.776886) (xy 134.090686 -385.795482) (xy 134.097522 -385.802886) (xy 134.986014 -386.691378)
			(xy 134.992857 -386.698777) (xy 135.000577 -386.717376) (xy 135.001 -386.727446) (xy 135.001 -386.736082)
			(xy 135.030718 -386.7658)
		)
		(stroke
			(width 0)
			(type solid)
		)
		(fill yes)
		(layer "B.Cu")
		(net "P1V8_CPU1_RT3_1A")
	)
	(gr_poly
		(pts
			(arc
				(start 124.102114 -12.795504)
				(mid 126.234222 -11.912198)
				(end 127.117348 -9.780016)
			)
			(arc
				(start 127.117348 -9.256776)
				(mid 127.111697 -9.233491)
				(end 127.096012 -9.215374)
			)
			(arc
				(start 127.096012 -9.215374)
				(mid 126.928345 -9.062058)
				(end 126.802388 -8.872982)
			)
			(xy 126.794514 -8.857234) (xy 126.76251 -8.842248)
			(arc
				(start 126.649226 -8.869426)
				(mid 126.621087 -8.887272)
				(end 126.61011 -8.918702)
			)
			(arc
				(start 126.61011 -9.780016)
				(mid 125.875535 -11.553437)
				(end 124.102114 -12.288012)
			)
			(arc
				(start 83.70189 -12.288012)
				(mid 82.233322 -11.813081)
				(end 81.320894 -10.568178)
			)
			(xy 81.315052 -10.550144) (xy 81.28762 -10.533634) (xy 81.255362 -10.565892) (xy 81.255362 -11.54303)
			(xy 81.260696 -11.549126) (xy 81.93278 -12.22121)
			(arc
				(start 81.938876 -12.22629)
				(mid 82.775587 -12.649625)
				(end 83.70189 -12.795504)
			)
		)
		(stroke
			(width 0)
			(type solid)
		)
		(fill yes)
		(layer "B.Cu")
		(net "GND")
	)
	(gr_poly
		(pts
			(xy 27.75839 -382.739392) (xy 27.768461 -382.73897) (xy 27.787067 -382.731258) (xy 27.794458 -382.724406)
			(xy 28.381706 -382.137158) (xy 28.388545 -382.129757) (xy 28.396263 -382.111159) (xy 28.396692 -382.10109)
			(xy 28.396692 -375.19737) (xy 28.396263 -375.187302) (xy 28.38854 -375.168707) (xy 28.381706 -375.161302)
			(xy 26.73731 -373.516906) (xy 26.729912 -373.510057) (xy 26.711314 -373.502318) (xy 26.701242 -373.50192)
			(xy 5.52577 -373.50192) (xy 5.515703 -373.502349) (xy 5.497108 -373.510073) (xy 5.489702 -373.516906)
			(xy 5.266944 -373.739664) (xy 5.260103 -373.747064) (xy 5.252385 -373.765663) (xy 5.251958 -373.775732)
			(xy 5.251958 -381.41402) (xy 6.401562 -381.41402) (xy 6.402101 -381.380681) (xy 6.410807 -381.314573)
			(xy 6.428085 -381.250172) (xy 6.453637 -381.188585) (xy 6.487026 -381.130868) (xy 6.527677 -381.078015)
			(xy 6.550914 -381.054102) (xy 6.558026 -381.04699) (xy 6.565646 -381.028194) (xy 6.565646 -380.936246)
			(xy 6.558026 -380.91745) (xy 6.550914 -380.910338) (xy 6.527674 -380.886428) (xy 6.48703 -380.833569)
			(xy 6.453645 -380.775851) (xy 6.428091 -380.714264) (xy 6.410806 -380.649865) (xy 6.402087 -380.583759)
			(xy 6.401562 -380.55042) (xy 6.402064 -380.518459) (xy 6.410075 -380.455041) (xy 6.425972 -380.393127)
			(xy 6.449504 -380.333694) (xy 6.480298 -380.277679) (xy 6.517871 -380.225964) (xy 6.561628 -380.179367)
			(xy 6.610881 -380.138622) (xy 6.664852 -380.104371) (xy 6.722691 -380.077154) (xy 6.783484 -380.057401)
			(xy 6.846274 -380.045423) (xy 6.91007 -380.04141) (xy 6.973866 -380.045423) (xy 7.036656 -380.057401)
			(xy 7.097449 -380.077154) (xy 7.155288 -380.104371) (xy 7.209259 -380.138622) (xy 7.258512 -380.179367)
			(xy 7.302269 -380.225964) (xy 7.339842 -380.277679) (xy 7.370636 -380.333694) (xy 7.394168 -380.393127)
			(xy 7.410065 -380.455041) (xy 7.418076 -380.518459) (xy 7.418578 -380.55042) (xy 7.418082 -380.583761)
			(xy 7.40937 -380.649871) (xy 7.392085 -380.714273) (xy 7.366524 -380.775861) (xy 7.333127 -380.833576)
			(xy 7.292467 -380.886427) (xy 7.269226 -380.910338) (xy 7.262114 -380.91745) (xy 7.254494 -380.936246)
			(xy 7.254494 -381.028194) (xy 7.262114 -381.04699) (xy 7.269226 -381.054102) (xy 7.292458 -381.078019)
			(xy 7.333102 -381.130877) (xy 7.366489 -381.188593) (xy 7.392044 -381.250179) (xy 7.409331 -381.314577)
			(xy 7.418051 -381.380681) (xy 7.418578 -381.41402) (xy 7.418076 -381.445981) (xy 7.410065 -381.509399)
			(xy 7.394168 -381.571313) (xy 7.370636 -381.630746) (xy 7.339842 -381.686761) (xy 7.302269 -381.738476)
			(xy 7.258512 -381.785073) (xy 7.209259 -381.825818) (xy 7.155288 -381.860069) (xy 7.097449 -381.887286)
			(xy 7.036656 -381.907039) (xy 6.973866 -381.919017) (xy 6.91007 -381.923031) (xy 6.846274 -381.919017)
			(xy 6.783484 -381.907039) (xy 6.722691 -381.887286) (xy 6.664852 -381.860069) (xy 6.610881 -381.825818)
			(xy 6.561628 -381.785073) (xy 6.517871 -381.738476) (xy 6.480298 -381.686761) (xy 6.449504 -381.630746)
			(xy 6.425972 -381.571313) (xy 6.410075 -381.509399) (xy 6.402064 -381.445981) (xy 6.401562 -381.41402)
			(xy 5.251958 -381.41402) (xy 5.251958 -382.349502) (xy 5.252383 -382.359571) (xy 5.260104 -382.378169)
			(xy 5.266944 -382.38557) (xy 5.60578 -382.724406) (xy 5.613183 -382.731239) (xy 5.631781 -382.738943)
			(xy 5.641848 -382.739392)
		)
		(stroke
			(width 0)
			(type solid)
		)
		(fill yes)
		(layer "B.Cu")
		(net "P0V9_CPU1_RT_2D")
	)
	(gr_poly
		(pts
			(arc
				(start 394.286994 -400.814286)
				(mid 394.306517 -400.810385)
				(end 394.323062 -400.7993)
			)
			(arc
				(start 394.341604 -400.780758)
				(mid 394.352715 -400.764224)
				(end 394.35659 -400.74469)
			)
			(arc
				(start 394.35659 -398.256506)
				(mid 394.360491 -398.236983)
				(end 394.371576 -398.220438)
			)
			(arc
				(start 394.452348 -398.139666)
				(mid 394.468882 -398.128555)
				(end 394.488416 -398.12468)
			)
			(arc
				(start 396.365476 -398.12468)
				(mid 396.384999 -398.128581)
				(end 396.401544 -398.139666)
			)
			(arc
				(start 396.576296 -398.314418)
				(mid 396.587407 -398.330952)
				(end 396.591282 -398.350486)
			)
			(arc
				(start 396.591282 -399.485866)
				(mid 396.595183 -399.505389)
				(end 396.606268 -399.521934)
			)
			(arc
				(start 396.683992 -399.599658)
				(mid 396.700526 -399.610769)
				(end 396.72006 -399.614644)
			)
			(arc
				(start 397.564356 -399.614644)
				(mid 397.583879 -399.610743)
				(end 397.600424 -399.599658)
			)
			(arc
				(start 397.640048 -399.560034)
				(mid 397.651159 -399.5435)
				(end 397.655034 -399.523966)
			)
			(arc
				(start 397.655034 -396.67942)
				(mid 397.651133 -396.659897)
				(end 397.640048 -396.643352)
			)
			(arc
				(start 397.57858 -396.581884)
				(mid 397.562046 -396.570773)
				(end 397.542512 -396.566898)
			)
			(arc
				(start 396.812008 -396.566898)
				(mid 396.792485 -396.562997)
				(end 396.77594 -396.551912)
			)
			(arc
				(start 396.739364 -396.515336)
				(mid 396.733957 -396.51061)
				(end 396.727934 -396.5067)
			)
			(arc
				(start 396.727934 -396.5067)
				(mid 396.64075 -396.441484)
				(end 396.575534 -396.3543)
			)
			(arc
				(start 396.575534 -396.3543)
				(mid 396.571618 -396.348282)
				(end 396.566898 -396.34287)
			)
			(arc
				(start 396.464028 -396.24)
				(mid 396.452917 -396.223466)
				(end 396.449042 -396.203932)
			)
			(arc
				(start 396.449042 -395.390878)
				(mid 396.445141 -395.371355)
				(end 396.434056 -395.35481)
			)
			(arc
				(start 396.369286 -395.29004)
				(mid 396.352752 -395.278929)
				(end 396.333218 -395.275054)
			)
			(arc
				(start 393.07643 -395.275054)
				(mid 393.056907 -395.278955)
				(end 393.040362 -395.29004)
			)
			(arc
				(start 392.70305 -395.627352)
				(mid 392.686516 -395.638463)
				(end 392.666982 -395.642338)
			)
			(arc
				(start 391.531348 -395.642338)
				(mid 391.511825 -395.646239)
				(end 391.49528 -395.657324)
			)
			(arc
				(start 391.265664 -395.88694)
				(mid 391.254553 -395.903474)
				(end 391.250678 -395.923008)
			)
			(xy 391.250678 -396.604236)
			(arc
				(start 391.251694 -396.608808)
				(mid 391.256109 -396.639911)
				(end 391.257536 -396.671292)
			)
			(arc
				(start 391.257536 -396.671292)
				(mid 391.256092 -396.702672)
				(end 391.251694 -396.733776)
			)
			(xy 391.250678 -396.738348)
			(arc
				(start 391.250678 -397.045942)
				(mid 391.254579 -397.065465)
				(end 391.265664 -397.08201)
			)
			(arc
				(start 391.729722 -397.546068)
				(mid 391.746256 -397.557179)
				(end 391.76579 -397.561054)
			)
			(arc
				(start 392.96467 -397.561054)
				(mid 392.984193 -397.564955)
				(end 393.000738 -397.57604)
			)
			(arc
				(start 393.148058 -397.72336)
				(mid 393.159169 -397.739894)
				(end 393.163044 -397.759428)
			)
			(arc
				(start 393.163044 -400.661124)
				(mid 393.166945 -400.680647)
				(end 393.17803 -400.697192)
			)
			(arc
				(start 393.280138 -400.7993)
				(mid 393.296672 -400.810411)
				(end 393.316206 -400.814286)
			)
		)
		(stroke
			(width 0)
			(type solid)
		)
		(fill yes)
		(layer "B.Cu")
		(net "GND")
	)
	(gr_poly
		(pts
			(arc
				(start 104.681782 -24.89454)
				(mid 104.706526 -24.888106)
				(end 104.724962 -24.87041)
			)
			(xy 104.77754 -24.78532) (xy 104.778556 -24.759158)
			(arc
				(start 104.77246 -24.74722)
				(mid 104.736054 -24.647202)
				(end 104.723692 -24.54148)
			)
			(arc
				(start 104.723692 -24.54148)
				(mid 105.1814 -24.083772)
				(end 105.639108 -24.54148)
			)
			(arc
				(start 105.639108 -24.54148)
				(mid 105.626789 -24.647212)
				(end 105.59034 -24.74722)
			)
			(xy 105.584244 -24.759158) (xy 105.58526 -24.78532)
			(arc
				(start 105.637838 -24.87041)
				(mid 105.656297 -24.888065)
				(end 105.681018 -24.89454)
			)
			(arc
				(start 106.154982 -24.89454)
				(mid 106.179726 -24.888106)
				(end 106.198162 -24.87041)
			)
			(xy 106.25074 -24.78532) (xy 106.251756 -24.759158)
			(arc
				(start 106.24566 -24.74722)
				(mid 106.209254 -24.647202)
				(end 106.196892 -24.54148)
			)
			(arc
				(start 106.196892 -24.54148)
				(mid 106.6546 -24.083772)
				(end 107.112308 -24.54148)
			)
			(arc
				(start 107.112308 -24.54148)
				(mid 107.099989 -24.647212)
				(end 107.06354 -24.74722)
			)
			(xy 107.057444 -24.759158) (xy 107.05846 -24.78532)
			(arc
				(start 107.111038 -24.87041)
				(mid 107.129497 -24.888065)
				(end 107.154218 -24.89454)
			)
			(arc
				(start 108.2802 -24.89454)
				(mid 108.316121 -24.879661)
				(end 108.331 -24.84374)
			)
			(arc
				(start 108.331 -20.05584)
				(mid 108.316121 -20.019919)
				(end 108.2802 -20.00504)
			)
			(arc
				(start 104.521 -20.00504)
				(mid 104.485079 -20.019919)
				(end 104.4702 -20.05584)
			)
			(xy 104.4702 -24.816054) (xy 104.484678 -24.83993)
			(arc
				(start 104.497124 -24.846788)
				(mid 104.526264 -24.863944)
				(end 104.553766 -24.883618)
			)
			(xy 104.560624 -24.888952) (xy 104.576626 -24.89454)
		)
		(stroke
			(width 0)
			(type solid)
		)
		(fill yes)
		(layer "B.Cu")
		(net "GND")
	)
	(gr_poly
		(pts
			(xy 130.6957 -43.16476) (xy 130.6957 -42.61866) (xy 129.92354 -41.8465) (xy 129.92354 -41.07942)
			(xy 130.122168 -40.880792) (xy 133.829552 -40.880792) (xy 134.078218 -41.129458) (xy 134.078218 -42.480738)
			(xy 134.2644 -42.66692) (xy 134.654798 -42.66692) (xy 134.713218 -42.6085) (xy 134.713218 -39.766748)
			(xy 134.886446 -39.59352) (xy 135.748776 -39.59352) (xy 135.970518 -39.815262) (xy 135.970518 -40.560498)
			(xy 136.311132 -40.901112) (xy 136.884918 -40.901112) (xy 136.948418 -40.837612) (xy 136.948418 -39.815262)
			(xy 136.884918 -39.751762) (xy 136.347962 -39.751762) (xy 135.913114 -39.316914) (xy 135.913114 -33.149286)
			(xy 136.426194 -32.636206) (xy 137.218928 -32.636206) (xy 137.623296 -33.040574) (xy 137.623296 -33.348168)
			(xy 137.67435 -33.399222) (xy 139.633198 -33.399222) (xy 139.671806 -33.360614) (xy 139.671806 -32.803084)
			(xy 139.632944 -32.764222) (xy 139.0396 -32.764222) (xy 138.537696 -32.262318) (xy 137.480294 -32.262318)
			(xy 137.219182 -32.001206) (xy 135.669274 -32.001206) (xy 135.669274 -32.402526) (xy 135.50646 -32.56534)
			(xy 135.36168 -32.56534) (xy 134.447534 -32.56534) (xy 134.389114 -32.62376) (xy 134.389114 -34.297366)
			(xy 134.25424 -34.43224) (xy 134.17296 -34.51352) (xy 133.49224 -34.51352) (xy 133.41096 -34.43224)
			(xy 133.2484 -34.26968) (xy 133.2484 -34.2392) (xy 133.1722 -34.163) (xy 133.1722 -33.401) (xy 133.097778 -33.326578)
			(xy 131.505198 -33.326578) (xy 131.33578 -33.15716) (xy 131.33578 -32.519112) (xy 131.671314 -32.183578)
			(xy 131.925822 -32.183578) (xy 132.1054 -32.004) (xy 132.1054 -31.606998) (xy 132.04698 -31.548578)
			(xy 131.210558 -31.548578) (xy 131.02336 -31.36138) (xy 130.571494 -31.36138) (xy 130.535934 -31.39694)
			(xy 130.535934 -31.8008) (xy 130.637534 -31.9024) (xy 130.9116 -31.9024) (xy 131.21132 -32.20212)
			(xy 131.21132 -32.334708) (xy 131.21132 -32.982154) (xy 131.046982 -33.146492) (xy 130.4798 -33.146492)
			(xy 130.429 -33.197292) (xy 130.429 -35.0012) (xy 130.319018 -35.111182) (xy 130.2258 -35.2044) (xy 129.286 -35.2044)
			(xy 129.178304 -35.096704) (xy 129.178304 -35.01517) (xy 129.178304 -32.447484) (xy 129.124202 -32.393382)
			(xy 128.7526 -32.393382) (xy 128.6256 -32.520382) (xy 128.6256 -32.8422) (xy 128.473708 -32.994092)
			(xy 128.252982 -32.994092) (xy 126.695708 -32.994092) (xy 126.619 -33.0708) (xy 126.619 -33.552892)
			(xy 126.6952 -33.629092) (xy 128.252728 -33.629092) (xy 128.632204 -34.008568) (xy 128.632204 -36.03117)
			(xy 128.670812 -36.069778) (xy 129.549398 -36.069778) (xy 129.73812 -36.2585) (xy 129.73812 -37.031168)
			(xy 129.546858 -37.22243) (xy 127.99187 -37.22243) (xy 127.802894 -37.411406) (xy 127.10287 -38.11143)
			(xy 126.41199 -38.11143) (xy 126.248668 -37.948108) (xy 126.248668 -34.935414) (xy 126.21006 -34.896806)
			(xy 125.65253 -34.896806) (xy 125.512322 -35.037014) (xy 125.512322 -38.579552) (xy 125.6792 -38.74643)
			(xy 127.71755 -38.74643) (xy 127.92456 -38.53942) (xy 128.82626 -38.53942) (xy 128.938528 -38.651688)
			(xy 128.938528 -40.305228) (xy 128.99644 -40.36314) (xy 129.342642 -40.36314) (xy 129.7051 -40.725598)
			(xy 129.7051 -42.011092) (xy 129.6416 -42.074592) (xy 127.505714 -42.074592) (xy 127.320294 -41.889172)
			(xy 126.469394 -41.889172) (xy 126.405894 -41.952672) (xy 126.405894 -42.975022) (xy 126.469394 -43.038522)
			(xy 129.539238 -43.038522) (xy 129.911602 -43.038522) (xy 130.10134 -43.22826) (xy 130.6322 -43.22826)
		)
		(stroke
			(width 0)
			(type solid)
		)
		(fill yes)
		(layer "B.Cu")
		(net "GND")
	)
	(gr_poly
		(pts
			(arc
				(start 71.044562 -392.388344)
				(mid 71.064085 -392.384443)
				(end 71.08063 -392.373358)
			)
			(arc
				(start 71.167752 -392.286236)
				(mid 71.178726 -392.269673)
				(end 71.182484 -392.250168)
			)
			(arc
				(start 71.182484 -390.411716)
				(mid 71.186434 -390.392329)
				(end 71.19747 -390.375902)
			)
			(arc
				(start 71.241666 -390.331452)
				(mid 71.252728 -390.315035)
				(end 71.256652 -390.295638)
			)
			(arc
				(start 71.256652 -389.874506)
				(mid 71.260553 -389.854983)
				(end 71.271638 -389.838438)
			)
			(arc
				(start 71.35241 -389.757666)
				(mid 71.368944 -389.746555)
				(end 71.388478 -389.74268)
			)
			(arc
				(start 73.265538 -389.74268)
				(mid 73.285061 -389.746581)
				(end 73.301606 -389.757666)
			)
			(arc
				(start 73.476358 -389.932418)
				(mid 73.487469 -389.948952)
				(end 73.491344 -389.968486)
			)
			(arc
				(start 73.491344 -390.029446)
				(mid 73.495294 -390.048833)
				(end 73.50633 -390.06526)
			)
			(arc
				(start 73.506584 -390.065768)
				(mid 73.51751 -390.082214)
				(end 73.521316 -390.101582)
			)
			(arc
				(start 73.521316 -391.134092)
				(mid 73.525266 -391.153479)
				(end 73.536302 -391.169906)
			)
			(arc
				(start 73.584054 -391.217658)
				(mid 73.600588 -391.228769)
				(end 73.620122 -391.232644)
			)
			(arc
				(start 74.464418 -391.232644)
				(mid 74.483941 -391.228743)
				(end 74.500486 -391.217658)
			)
			(arc
				(start 74.54011 -391.178034)
				(mid 74.551221 -391.1615)
				(end 74.555096 -391.141966)
			)
			(arc
				(start 74.555096 -388.29742)
				(mid 74.551195 -388.277897)
				(end 74.54011 -388.261352)
			)
			(arc
				(start 74.478642 -388.199884)
				(mid 74.462108 -388.188773)
				(end 74.442574 -388.184898)
			)
			(arc
				(start 73.71207 -388.184898)
				(mid 73.692547 -388.180997)
				(end 73.676002 -388.169912)
			)
			(xy 73.634346 -388.128256)
			(arc
				(start 73.627996 -388.1247)
				(mid 73.540812 -388.059484)
				(end 73.475596 -387.9723)
			)
			(xy 73.47204 -387.96595)
			(arc
				(start 73.36409 -387.858)
				(mid 73.352979 -387.841466)
				(end 73.349104 -387.821932)
			)
			(arc
				(start 73.349104 -387.024372)
				(mid 73.334225 -386.988451)
				(end 73.298304 -386.973572)
			)
			(arc
				(start 69.962776 -386.973572)
				(mid 69.943389 -386.969622)
				(end 69.926962 -386.958586)
			)
			(xy 69.889878 -386.958586)
			(arc
				(start 69.603112 -387.245352)
				(mid 69.586578 -387.256463)
				(end 69.567044 -387.260338)
			)
			(arc
				(start 68.43141 -387.260338)
				(mid 68.411887 -387.264239)
				(end 68.395342 -387.275324)
			)
			(arc
				(start 68.165726 -387.50494)
				(mid 68.154615 -387.521474)
				(end 68.15074 -387.541008)
			)
			(xy 68.15074 -388.222236)
			(arc
				(start 68.151756 -388.226808)
				(mid 68.156171 -388.257911)
				(end 68.157598 -388.289292)
			)
			(arc
				(start 68.157598 -388.289292)
				(mid 68.156154 -388.320672)
				(end 68.151756 -388.351776)
			)
			(xy 68.15074 -388.356348)
			(arc
				(start 68.15074 -388.663942)
				(mid 68.154641 -388.683465)
				(end 68.165726 -388.70001)
			)
			(arc
				(start 68.629784 -389.164068)
				(mid 68.646318 -389.175179)
				(end 68.665852 -389.179054)
			)
			(arc
				(start 69.864732 -389.179054)
				(mid 69.884255 -389.182955)
				(end 69.9008 -389.19404)
			)
			(arc
				(start 70.04812 -389.34136)
				(mid 70.059231 -389.357894)
				(end 70.063106 -389.377428)
			)
			(arc
				(start 70.063106 -392.279124)
				(mid 70.067007 -392.298647)
				(end 70.078092 -392.315192)
			)
			(arc
				(start 70.136258 -392.373358)
				(mid 70.152675 -392.38442)
				(end 70.172072 -392.388344)
			)
		)
		(stroke
			(width 0)
			(type solid)
		)
		(fill yes)
		(layer "B.Cu")
		(net "GND")
	)
	(gr_poly
		(pts
			(arc
				(start 68.897754 -26.246836)
				(mid 68.917277 -26.242935)
				(end 68.933822 -26.23185)
			)
			(arc
				(start 70.340982 -24.824436)
				(mid 70.352093 -24.807902)
				(end 70.355968 -24.788368)
			)
			(arc
				(start 70.355968 -22.416262)
				(mid 70.350763 -22.393863)
				(end 70.336156 -22.37613)
			)
			(arc
				(start 70.272656 -22.326854)
				(mid 70.251958 -22.317386)
				(end 70.229222 -22.317964)
			)
			(arc
				(start 70.228968 -22.317964)
				(mid 70.070999 -22.348387)
				(end 69.910452 -22.358604)
			)
			(arc
				(start 69.910452 -22.358604)
				(mid 68.639944 -21.088096)
				(end 69.910452 -19.817588)
			)
			(arc
				(start 69.910452 -19.817588)
				(mid 70.070871 -19.827821)
				(end 70.228714 -19.858228)
			)
			(arc
				(start 70.229222 -19.858228)
				(mid 70.251941 -19.858726)
				(end 70.272656 -19.849338)
			)
			(arc
				(start 70.336156 -19.800062)
				(mid 70.350676 -19.782287)
				(end 70.355968 -19.75993)
			)
			(arc
				(start 70.355968 -19.273774)
				(mid 70.352067 -19.254251)
				(end 70.340982 -19.237706)
			)
			(arc
				(start 70.086474 -18.983198)
				(mid 70.06994 -18.972087)
				(end 70.050406 -18.968212)
			)
			(arc
				(start 69.909436 -18.968212)
				(mid 69.889913 -18.972113)
				(end 69.873368 -18.983198)
			)
			(arc
				(start 69.16293 -19.693382)
				(mid 69.146396 -19.704493)
				(end 69.126862 -19.708368)
			)
			(xy 68.853812 -19.708368)
			(arc
				(start 68.847716 -19.709892)
				(mid 68.69719 -19.737467)
				(end 68.54444 -19.746722)
			)
			(arc
				(start 68.54444 -19.746722)
				(mid 68.391693 -19.737445)
				(end 68.241164 -19.709892)
			)
			(xy 68.235068 -19.708368)
			(arc
				(start 67.787266 -19.708368)
				(mid 67.767743 -19.704467)
				(end 67.751198 -19.693382)
			)
			(arc
				(start 67.059556 -19.00174)
				(mid 67.032893 -18.987603)
				(end 67.002914 -18.991072)
			)
			(arc
				(start 67.002914 -18.991072)
				(mid 66.9273 -19.015674)
				(end 66.848228 -19.024092)
			)
			(arc
				(start 66.848228 -19.024092)
				(mid 66.696307 -18.992493)
				(end 66.56959 -18.902934)
			)
			(arc
				(start 66.56959 -18.902934)
				(mid 66.552711 -18.891064)
				(end 66.532506 -18.886932)
			)
			(arc
				(start 65.31356 -18.886932)
				(mid 65.277639 -18.901811)
				(end 65.26276 -18.937732)
			)
			(arc
				(start 65.26276 -25.160478)
				(mid 65.266661 -25.180001)
				(end 65.277746 -25.196546)
			)
			(arc
				(start 66.31305 -26.23185)
				(mid 66.329584 -26.242961)
				(end 66.349118 -26.246836)
			)
		)
		(stroke
			(width 0)
			(type solid)
		)
		(fill yes)
		(layer "B.Cu")
		(net "P12V_OCP_V3_2")
	)
	(gr_poly
		(pts
			(arc
				(start 457.884276 -411.379924)
				(mid 457.903799 -411.376023)
				(end 457.920344 -411.364938)
			)
			(arc
				(start 458.30871 -410.976572)
				(mid 458.319821 -410.960038)
				(end 458.323696 -410.940504)
			)
			(arc
				(start 458.323696 -406.801574)
				(mid 458.327597 -406.782051)
				(end 458.338682 -406.765506)
			)
			(xy 458.340968 -406.76322) (xy 458.348588 -406.744678)
			(arc
				(start 458.348588 -397.679926)
				(mid 458.344687 -397.660403)
				(end 458.333602 -397.643858)
			)
			(arc
				(start 458.233526 -397.543782)
				(mid 458.216992 -397.532671)
				(end 458.197458 -397.528796)
			)
			(arc
				(start 454.658222 -397.528796)
				(mid 454.638699 -397.532697)
				(end 454.622154 -397.543782)
			)
			(arc
				(start 454.542652 -397.623284)
				(mid 454.531541 -397.639818)
				(end 454.527666 -397.659352)
			)
			(arc
				(start 454.527666 -399.979388)
				(mid 454.531567 -399.998911)
				(end 454.542652 -400.015456)
			)
			(arc
				(start 455.31278 -400.785584)
				(mid 455.323891 -400.802118)
				(end 455.327766 -400.821652)
			)
			(xy 455.327766 -402.826474) (xy 455.324718 -402.829522)
			(arc
				(start 455.324718 -403.678136)
				(mid 455.320817 -403.697659)
				(end 455.309732 -403.714204)
			)
			(arc
				(start 455.126852 -403.897084)
				(mid 455.110318 -403.908195)
				(end 455.090784 -403.91207)
			)
			(arc
				(start 454.167748 -403.91207)
				(mid 454.148225 -403.908169)
				(end 454.13168 -403.897084)
			)
			(arc
				(start 453.952356 -403.71776)
				(mid 453.935822 -403.706649)
				(end 453.916288 -403.702774)
			)
			(arc
				(start 450.012054 -403.702774)
				(mid 449.992531 -403.698873)
				(end 449.975986 -403.687788)
			)
			(xy 449.501514 -403.213316) (xy 449.475352 -403.206458)
			(arc
				(start 449.46189 -403.210268)
				(mid 449.401362 -403.222668)
				(end 449.339716 -403.226778)
			)
			(arc
				(start 449.339716 -403.226778)
				(mid 449.016068 -403.092718)
				(end 448.882008 -402.76907)
			)
			(arc
				(start 448.882008 -402.76907)
				(mid 448.928651 -402.567515)
				(end 449.0593 -402.40712)
			)
			(arc
				(start 449.0593 -402.40712)
				(mid 449.07382 -402.389345)
				(end 449.079112 -402.366988)
			)
			(arc
				(start 449.079112 -397.689578)
				(mid 449.075328 -397.670084)
				(end 449.06438 -397.65351)
			)
			(arc
				(start 448.948556 -397.537686)
				(mid 448.932022 -397.526575)
				(end 448.912488 -397.5227)
			)
			(arc
				(start 445.571626 -397.5227)
				(mid 445.535705 -397.537579)
				(end 445.520826 -397.5735)
			)
			(arc
				(start 445.520826 -399.974054)
				(mid 445.524727 -399.993577)
				(end 445.535812 -400.010122)
			)
			(arc
				(start 445.696086 -400.170396)
				(mid 445.707197 -400.18693)
				(end 445.711072 -400.206464)
			)
			(arc
				(start 445.711072 -401.070064)
				(mid 445.714973 -401.089587)
				(end 445.726058 -401.106132)
			)
			(arc
				(start 446.636648 -402.016468)
				(mid 446.647759 -402.033002)
				(end 446.651634 -402.052536)
			)
			(arc
				(start 446.651634 -404.27656)
				(mid 446.655535 -404.296083)
				(end 446.66662 -404.312628)
			)
			(arc
				(start 447.345054 -404.991062)
				(mid 447.356165 -405.007596)
				(end 447.36004 -405.02713)
			)
			(arc
				(start 447.36004 -410.18079)
				(mid 447.356139 -410.200313)
				(end 447.345054 -410.216858)
			)
			(arc
				(start 446.943988 -410.617924)
				(mid 446.932877 -410.634458)
				(end 446.929002 -410.653992)
			)
			(arc
				(start 446.929002 -410.906976)
				(mid 446.932903 -410.926499)
				(end 446.943988 -410.943044)
			)
			(arc
				(start 447.365882 -411.364938)
				(mid 447.382416 -411.376049)
				(end 447.40195 -411.379924)
			)
		)
		(stroke
			(width 0)
			(type solid)
		)
		(fill yes)
		(layer "B.Cu")
		(net "SW_P12V_AUX_P0V9_RETIMER_CPU0_FLT")
	)
	(gr_poly
		(pts
			(xy 121.167398 -146.68246) (xy 121.177467 -146.682036) (xy 121.196069 -146.674318) (xy 121.203466 -146.667474)
			(xy 122.105674 -145.765266) (xy 122.112518 -145.757867) (xy 122.120244 -145.739269) (xy 122.12066 -145.729198)
			(xy 122.12066 -140.033502) (xy 122.120236 -140.023433) (xy 122.112518 -140.004831) (xy 122.105674 -139.997434)
			(xy 121.538746 -139.430506) (xy 121.531634 -139.42314) (xy 121.512838 -139.41552) (xy 105.96753 -139.41552)
			(xy 105.960285 -139.415741) (xy 105.94636 -139.419742) (xy 105.940098 -139.423394) (xy 105.896435 -139.450577)
			(xy 105.805476 -139.498609) (xy 105.710931 -139.539127) (xy 105.613419 -139.571867) (xy 105.513578 -139.596614)
			(xy 105.412063 -139.613205) (xy 105.309539 -139.621532) (xy 105.258108 -139.622022) (xy 105.204758 -139.621488)
			(xy 105.098431 -139.612563) (xy 104.993228 -139.594751) (xy 104.889889 -139.568177) (xy 104.789144 -139.533028)
			(xy 104.740202 -139.511786) (xy 104.725724 -139.505182) (xy 104.694736 -139.511024) (xy 103.814118 -140.391642)
			(xy 103.8086 -140.39747) (xy 103.801219 -140.411713) (xy 103.79964 -140.419582) (xy 103.799132 -140.42771)
			(xy 103.799132 -140.86205) (xy 103.79865 -140.872014) (xy 103.79107 -140.890446) (xy 103.7844 -140.897864)
			(xy 103.620316 -141.061948) (xy 103.617268 -141.06652) (xy 103.617014 -141.066774) (xy 103.592054 -141.104637)
			(xy 103.536868 -141.176609) (xy 103.506778 -141.210538) (xy 103.500682 -141.217396) (xy 103.490776 -141.242796)
			(xy 103.489112 -141.247249) (xy 103.487327 -141.256585) (xy 103.48722 -141.261338) (xy 103.48722 -142.150338)
			(xy 103.487651 -142.160405) (xy 103.495377 -142.178997) (xy 103.502206 -142.186406) (xy 104.965246 -143.649446)
			(xy 111.617004 -143.649446) (xy 111.621021 -143.548464) (xy 111.63305 -143.44812) (xy 111.653012 -143.34905)
			(xy 111.680783 -143.251878) (xy 111.716186 -143.15722) (xy 111.758997 -143.065674) (xy 111.808947 -142.977819)
			(xy 111.865719 -142.89421) (xy 111.928954 -142.815376) (xy 111.998253 -142.741815) (xy 112.073177 -142.673993)
			(xy 112.153253 -142.612338) (xy 112.237974 -142.557239) (xy 112.326805 -142.509046) (xy 112.419184 -142.468063)
			(xy 112.514527 -142.434549) (xy 112.612232 -142.408716) (xy 112.71168 -142.390727) (xy 112.812243 -142.380696)
			(xy 112.913284 -142.378687) (xy 113.014167 -142.384712) (xy 113.114251 -142.398732) (xy 113.212905 -142.420661)
			(xy 113.309506 -142.450358) (xy 113.403441 -142.487636) (xy 113.494118 -142.532259) (xy 113.580962 -142.583946)
			(xy 113.663426 -142.642369) (xy 113.740987 -142.707159) (xy 113.813156 -142.777907) (xy 113.879475 -142.854164)
			(xy 113.939526 -142.93545) (xy 113.992929 -143.02125) (xy 114.039347 -143.111022) (xy 114.078485 -143.204197)
			(xy 114.110097 -143.300188) (xy 114.133982 -143.398387) (xy 114.14999 -143.498173) (xy 114.15802 -143.598915)
			(xy 114.158522 -143.649446) (xy 114.15802 -143.699977) (xy 114.14999 -143.800719) (xy 114.133982 -143.900505)
			(xy 114.110097 -143.998704) (xy 114.078485 -144.094695) (xy 114.039347 -144.18787) (xy 113.992929 -144.277642)
			(xy 113.939526 -144.363442) (xy 113.879475 -144.444728) (xy 113.813156 -144.520985) (xy 113.740987 -144.591733)
			(xy 113.663426 -144.656523) (xy 113.580962 -144.714946) (xy 113.494118 -144.766633) (xy 113.403441 -144.811256)
			(xy 113.309506 -144.848534) (xy 113.212905 -144.878231) (xy 113.114251 -144.90016) (xy 113.014167 -144.91418)
			(xy 112.913284 -144.920205) (xy 112.812243 -144.918196) (xy 112.71168 -144.908165) (xy 112.612232 -144.890176)
			(xy 112.514527 -144.864343) (xy 112.419184 -144.830829) (xy 112.326805 -144.789846) (xy 112.237974 -144.741653)
			(xy 112.153253 -144.686554) (xy 112.073177 -144.624899) (xy 111.998253 -144.557077) (xy 111.928954 -144.483516)
			(xy 111.865719 -144.404682) (xy 111.808947 -144.321073) (xy 111.758997 -144.233218) (xy 111.716186 -144.141672)
			(xy 111.680783 -144.047014) (xy 111.653012 -143.949842) (xy 111.63305 -143.850772) (xy 111.621021 -143.750428)
			(xy 111.617004 -143.649446) (xy 104.965246 -143.649446) (xy 107.983274 -146.667474) (xy 107.990675 -146.674312)
			(xy 108.009274 -146.682023) (xy 108.019342 -146.68246)
		)
		(stroke
			(width 0)
			(type solid)
		)
		(fill yes)
		(layer "B.Cu")
		(net "P12V_AUX")
	)
	(gr_poly
		(pts
			(arc
				(start 397.222472 -313.1693)
				(mid 397.240407 -313.166029)
				(end 397.256 -313.1566)
			)
			(arc
				(start 397.256 -313.1566)
				(mid 397.325709 -313.114374)
				(end 397.40586 -313.099704)
			)
			(arc
				(start 397.622776 -313.099704)
				(mid 397.658786 -313.114567)
				(end 397.673576 -313.150504)
			)
			(xy 397.673576 -313.159648)
			(arc
				(start 397.97736 -313.159648)
				(mid 398.013356 -313.144844)
				(end 398.02816 -313.108848)
			)
			(arc
				(start 398.02816 -312.838338)
				(mid 398.024376 -312.818844)
				(end 398.013428 -312.80227)
			)
			(arc
				(start 396.751048 -311.53989)
				(mid 396.734514 -311.528779)
				(end 396.71498 -311.524904)
			)
			(xy 394.347954 -311.524904) (xy 394.31976 -311.548526)
			(arc
				(start 394.316458 -311.566814)
				(mid 394.286345 -311.654717)
				(end 394.231368 -311.729628)
			)
			(arc
				(start 394.124688 -311.836308)
				(mid 394.024801 -311.902957)
				(end 393.90701 -311.926224)
			)
			(arc
				(start 393.63269 -311.926224)
				(mid 393.514925 -311.902893)
				(end 393.415012 -311.836308)
			)
			(arc
				(start 393.317984 -311.73928)
				(mid 393.28217 -311.724445)
				(end 393.246356 -311.73928)
			)
			(arc
				(start 393.149328 -311.836308)
				(mid 393.049441 -311.902957)
				(end 392.93165 -311.926224)
			)
			(arc
				(start 392.65733 -311.926224)
				(mid 392.539565 -311.902893)
				(end 392.439652 -311.836308)
			)
			(arc
				(start 392.332972 -311.729628)
				(mid 392.277986 -311.654722)
				(end 392.247882 -311.566814)
			)
			(xy 392.24458 -311.548526) (xy 392.216386 -311.524904)
			(arc
				(start 387.718046 -311.524904)
				(mid 387.600281 -311.501573)
				(end 387.500368 -311.434988)
			)
			(arc
				(start 384.564382 -308.499002)
				(mid 384.526192 -308.452368)
				(end 384.497834 -308.39918)
			)
			(arc
				(start 383.400554 -305.750722)
				(mid 383.377575 -305.725258)
				(end 383.343658 -305.720242)
			)
			(xy 383.325878 -305.723798) (xy 383.302764 -305.751738)
			(arc
				(start 383.302764 -306.233068)
				(mid 383.303806 -306.243055)
				(end 383.306828 -306.252626)
			)
			(arc
				(start 384.270504 -308.578758)
				(mid 384.275164 -308.587541)
				(end 384.281426 -308.595268)
			)
			(arc
				(start 387.77291 -312.086752)
				(mid 387.789473 -312.097726)
				(end 387.808978 -312.101484)
			)
			(arc
				(start 395.477492 -312.101484)
				(mid 395.5953 -312.124918)
				(end 395.69517 -312.191654)
			)
			(arc
				(start 395.975586 -312.47207)
				(mid 396.042318 -312.571942)
				(end 396.065756 -312.689748)
			)
			(arc
				(start 396.065756 -313.108848)
				(mid 396.080545 -313.144934)
				(end 396.116556 -313.159648)
			)
			(arc
				(start 396.36954 -313.159648)
				(mid 396.405536 -313.144844)
				(end 396.42034 -313.108848)
			)
			(xy 396.42034 -313.099704)
			(arc
				(start 396.688056 -313.099704)
				(mid 396.768169 -313.114472)
				(end 396.837916 -313.1566)
			)
			(arc
				(start 396.837916 -313.1566)
				(mid 396.853526 -313.165984)
				(end 396.871444 -313.1693)
			)
		)
		(stroke
			(width 0)
			(type solid)
		)
		(fill yes)
		(layer "B.Cu")
		(net "GND")
	)
	(gr_poly
		(pts
			(arc
				(start 140.51661 -42.164508)
				(mid 140.536133 -42.160607)
				(end 140.552678 -42.149522)
			)
			(arc
				(start 141.032484 -41.669716)
				(mid 141.043595 -41.653182)
				(end 141.04747 -41.633648)
			)
			(arc
				(start 141.04747 -41.044114)
				(mid 141.039853 -41.017359)
				(end 141.019276 -40.998648)
			)
			(xy 140.924534 -40.951658) (xy 140.89634 -40.954452)
			(arc
				(start 140.884656 -40.963342)
				(mid 140.775779 -41.020782)
				(end 140.654278 -41.040558)
			)
			(arc
				(start 140.654278 -41.040558)
				(mid 140.514849 -41.014185)
				(end 140.39469 -40.938704)
			)
			(xy 140.387578 -40.931846) (xy 140.369544 -40.924988) (xy 140.27912 -40.926512) (xy 140.26134 -40.933878)
			(arc
				(start 140.254228 -40.94099)
				(mid 140.130997 -41.022577)
				(end 139.986004 -41.051226)
			)
			(arc
				(start 139.986004 -41.051226)
				(mid 139.604496 -40.669718)
				(end 139.986004 -40.28821)
			)
			(arc
				(start 139.986004 -40.28821)
				(mid 140.125433 -40.314583)
				(end 140.245592 -40.390064)
			)
			(xy 140.252704 -40.396922) (xy 140.270738 -40.40378) (xy 140.361162 -40.402256) (xy 140.378942 -40.39489)
			(arc
				(start 140.386054 -40.387778)
				(mid 140.509285 -40.306191)
				(end 140.654278 -40.277542)
			)
			(arc
				(start 140.654278 -40.277542)
				(mid 140.775778 -40.297321)
				(end 140.884656 -40.354758)
			)
			(xy 140.89634 -40.363648) (xy 140.924534 -40.366442)
			(arc
				(start 141.019276 -40.319452)
				(mid 141.039833 -40.300729)
				(end 141.04747 -40.273986)
			)
			(arc
				(start 141.04747 -36.023804)
				(mid 141.043569 -36.004281)
				(end 141.032484 -35.987736)
			)
			(arc
				(start 140.99921 -35.954462)
				(mid 140.982793 -35.9434)
				(end 140.963396 -35.939476)
			)
			(xy 140.235432 -35.939476) (xy 140.235178 -35.939222)
			(arc
				(start 139.944856 -35.939222)
				(mid 139.925333 -35.935321)
				(end 139.908788 -35.924236)
			)
			(arc
				(start 139.762992 -35.77844)
				(mid 139.751881 -35.761906)
				(end 139.748006 -35.742372)
			)
			(arc
				(start 139.748006 -35.490912)
				(mid 139.744105 -35.471389)
				(end 139.73302 -35.454844)
			)
			(arc
				(start 139.724638 -35.446462)
				(mid 139.708221 -35.4354)
				(end 139.688824 -35.431476)
			)
			(arc
				(start 138.168634 -35.431476)
				(mid 138.149247 -35.435426)
				(end 138.13282 -35.446462)
			)
			(arc
				(start 138.109706 -35.469576)
				(mid 138.098595 -35.48611)
				(end 138.09472 -35.505644)
			)
			(xy 138.09472 -35.863276) (xy 138.095228 -35.86353) (xy 138.095228 -35.872674)
			(arc
				(start 138.155934 -35.933634)
				(mid 138.172468 -35.944745)
				(end 138.192002 -35.94862)
			)
			(arc
				(start 138.614658 -35.94862)
				(mid 138.634181 -35.952521)
				(end 138.650726 -35.963606)
			)
			(arc
				(start 138.765534 -36.078414)
				(mid 138.776645 -36.094948)
				(end 138.78052 -36.114482)
			)
			(xy 138.78052 -36.25088) (xy 138.781028 -36.251134)
			(arc
				(start 138.781028 -41.955466)
				(mid 138.784861 -41.974823)
				(end 138.79576 -41.99128)
			)
			(arc
				(start 138.954002 -42.149522)
				(mid 138.970536 -42.160633)
				(end 138.99007 -42.164508)
			)
		)
		(stroke
			(width 0)
			(type solid)
		)
		(fill yes)
		(layer "B.Cu")
		(net "GND")
	)
	(gr_poly
		(pts
			(arc
				(start 359.714546 -400.814286)
				(mid 359.734069 -400.810385)
				(end 359.750614 -400.7993)
			)
			(arc
				(start 359.769156 -400.780758)
				(mid 359.780267 -400.764224)
				(end 359.784142 -400.74469)
			)
			(arc
				(start 359.784142 -398.715738)
				(mid 359.788043 -398.696215)
				(end 359.799128 -398.67967)
			)
			(xy 359.82402 -398.654778) (xy 359.829608 -398.623282)
			(arc
				(start 359.822496 -398.60855)
				(mid 359.794948 -398.528687)
				(end 359.785666 -398.44472)
			)
			(arc
				(start 359.785666 -398.44472)
				(mid 359.897407 -398.174953)
				(end 360.167174 -398.063212)
			)
			(arc
				(start 360.167174 -398.063212)
				(mid 360.251138 -398.072509)
				(end 360.331004 -398.100042)
			)
			(xy 360.345736 -398.107154) (xy 360.377232 -398.101566) (xy 360.378756 -398.100042) (xy 360.397298 -398.092422)
			(arc
				(start 363.83849 -398.092422)
				(mid 363.858013 -398.096323)
				(end 363.874558 -398.107408)
			)
			(arc
				(start 364.167928 -398.400778)
				(mid 364.179039 -398.417312)
				(end 364.182914 -398.436846)
			)
			(arc
				(start 364.182914 -399.352262)
				(mid 364.186815 -399.371785)
				(end 364.1979 -399.38833)
			)
			(arc
				(start 364.306612 -399.497042)
				(mid 364.323146 -399.508153)
				(end 364.34268 -399.512028)
			)
			(arc
				(start 365.007144 -399.512028)
				(mid 365.026667 -399.508127)
				(end 365.043212 -399.497042)
			)
			(arc
				(start 365.132112 -399.408142)
				(mid 365.143223 -399.391608)
				(end 365.147098 -399.372074)
			)
			(arc
				(start 365.147098 -396.693898)
				(mid 365.143197 -396.674375)
				(end 365.132112 -396.65783)
			)
			(arc
				(start 364.850934 -396.376652)
				(mid 364.832384 -396.364751)
				(end 364.810548 -396.36192)
			)
			(xy 364.721394 -396.369794) (xy 364.702344 -396.380716)
			(arc
				(start 364.69574 -396.390114)
				(mid 364.559298 -396.510132)
				(end 364.382812 -396.553436)
			)
			(arc
				(start 364.382812 -396.553436)
				(mid 364.112955 -396.441605)
				(end 364.001304 -396.171674)
			)
			(arc
				(start 364.001304 -395.54785)
				(mid 363.997354 -395.528463)
				(end 363.986318 -395.512036)
			)
			(arc
				(start 363.764322 -395.29004)
				(mid 363.747788 -395.278929)
				(end 363.728254 -395.275054)
			)
			(arc
				(start 358.503982 -395.275054)
				(mid 358.484459 -395.278955)
				(end 358.467914 -395.29004)
			)
			(arc
				(start 358.130602 -395.627352)
				(mid 358.114068 -395.638463)
				(end 358.094534 -395.642338)
			)
			(arc
				(start 356.9589 -395.642338)
				(mid 356.939377 -395.646239)
				(end 356.922832 -395.657324)
			)
			(arc
				(start 356.693216 -395.88694)
				(mid 356.682105 -395.903474)
				(end 356.67823 -395.923008)
			)
			(xy 356.67823 -396.604236)
			(arc
				(start 356.679246 -396.608808)
				(mid 356.683661 -396.639911)
				(end 356.685088 -396.671292)
			)
			(arc
				(start 356.685088 -396.671292)
				(mid 356.683644 -396.702672)
				(end 356.679246 -396.733776)
			)
			(xy 356.67823 -396.738348)
			(arc
				(start 356.67823 -397.045942)
				(mid 356.682131 -397.065465)
				(end 356.693216 -397.08201)
			)
			(arc
				(start 357.157274 -397.546068)
				(mid 357.173808 -397.557179)
				(end 357.193342 -397.561054)
			)
			(arc
				(start 358.392222 -397.561054)
				(mid 358.411745 -397.564955)
				(end 358.42829 -397.57604)
			)
			(arc
				(start 358.57561 -397.72336)
				(mid 358.586721 -397.739894)
				(end 358.590596 -397.759428)
			)
			(arc
				(start 358.590596 -400.661124)
				(mid 358.594497 -400.680647)
				(end 358.605582 -400.697192)
			)
			(arc
				(start 358.70769 -400.7993)
				(mid 358.724224 -400.810411)
				(end 358.743758 -400.814286)
			)
		)
		(stroke
			(width 0)
			(type solid)
		)
		(fill yes)
		(layer "B.Cu")
		(net "GND")
	)
	(gr_poly
		(pts
			(xy 115.232434 -171.677838) (xy 115.2425 -171.677407) (xy 115.26109 -171.669677) (xy 115.268502 -171.662852)
			(xy 115.275868 -171.655486) (xy 115.282716 -171.648088) (xy 115.29045 -171.62949) (xy 115.290854 -171.619418)
			(xy 115.290854 -168.658794) (xy 115.290428 -168.648725) (xy 115.282707 -168.630127) (xy 115.275868 -168.622726)
			(xy 115.11534 -168.462198) (xy 115.107938 -168.455361) (xy 115.08934 -168.447649) (xy 115.079272 -168.447212)
			(xy 113.591594 -168.447212) (xy 112.809274 -167.664892) (xy 112.809274 -165.762686) (xy 113.574322 -164.997638)
			(xy 118.676674 -164.997638) (xy 123.538234 -164.997638) (xy 123.5483 -164.997207) (xy 123.56689 -164.989477)
			(xy 123.574302 -164.982652) (xy 123.581668 -164.975286) (xy 123.588516 -164.967888) (xy 123.59625 -164.94929)
			(xy 123.596654 -164.939218) (xy 123.596654 -161.851594) (xy 123.596228 -161.841525) (xy 123.588507 -161.822927)
			(xy 123.581668 -161.815526) (xy 123.49734 -161.731198) (xy 123.489938 -161.724361) (xy 123.47134 -161.716649)
			(xy 123.461272 -161.716212) (xy 121.814082 -161.716212) (xy 121.804013 -161.715786) (xy 121.785412 -161.708068)
			(xy 121.778014 -161.701226) (xy 121.564146 -161.487358) (xy 121.557301 -161.479959) (xy 121.549575 -161.461361)
			(xy 121.54916 -161.45129) (xy 121.54916 -159.327088) (xy 121.549587 -159.31702) (xy 121.557311 -159.298424)
			(xy 121.564146 -159.29102) (xy 122.053096 -158.80207) (xy 124.481082 -156.374084) (xy 124.744734 -156.374084)
			(xy 126.814834 -156.374084) (xy 131.725924 -156.374084) (xy 131.735992 -156.373656) (xy 131.754589 -156.365934)
			(xy 131.761992 -156.359098) (xy 132.104892 -156.016198) (xy 132.111739 -156.0088) (xy 132.119474 -155.990202)
			(xy 132.119878 -155.98013) (xy 132.119878 -153.347166) (xy 132.119448 -153.337099) (xy 132.111723 -153.318506)
			(xy 132.104892 -153.311098) (xy 131.838192 -153.044398) (xy 131.830793 -153.037553) (xy 131.812195 -153.029822)
			(xy 131.802124 -153.029412) (xy 130.320288 -153.029412) (xy 130.310218 -153.028987) (xy 130.291616 -153.021271)
			(xy 130.28422 -153.014426) (xy 130.01498 -152.745186) (xy 130.01498 -149.224492) (xy 129.408428 -148.61794)
			(xy 107.81411 -148.61794) (xy 105.97134 -150.46071) (xy 105.97134 -150.984147) (xy 111.75136 -150.984147)
			(xy 111.75136 -150.899425) (xy 111.759413 -150.815088) (xy 111.775447 -150.731898) (xy 111.799315 -150.650608)
			(xy 111.830803 -150.571956) (xy 111.869625 -150.496653) (xy 111.915428 -150.425381) (xy 111.967799 -150.358785)
			(xy 112.026264 -150.29747) (xy 112.090292 -150.241989) (xy 112.159304 -150.192846) (xy 112.232674 -150.150486)
			(xy 112.309739 -150.115291) (xy 112.389801 -150.087582) (xy 112.472134 -150.067608) (xy 112.555993 -150.055551)
			(xy 112.640618 -150.05152) (xy 112.725243 -150.055551) (xy 112.809102 -150.067608) (xy 112.891435 -150.087582)
			(xy 112.971497 -150.115291) (xy 113.048562 -150.150486) (xy 113.121932 -150.192846) (xy 113.190944 -150.241989)
			(xy 113.254972 -150.29747) (xy 113.313437 -150.358785) (xy 113.365808 -150.425381) (xy 113.411611 -150.496653)
			(xy 113.450433 -150.571956) (xy 113.481921 -150.650608) (xy 113.505789 -150.731898) (xy 113.521823 -150.815088)
			(xy 113.529876 -150.899425) (xy 113.53038 -150.941786) (xy 113.529876 -150.984147) (xy 113.521823 -151.068484)
			(xy 113.505789 -151.151674) (xy 113.481921 -151.232964) (xy 113.450433 -151.311616) (xy 113.411611 -151.386919)
			(xy 113.365808 -151.458191) (xy 113.313437 -151.524787) (xy 113.254972 -151.586102) (xy 113.190944 -151.641583)
			(xy 113.121932 -151.690726) (xy 113.048562 -151.733086) (xy 112.971497 -151.768281) (xy 112.891435 -151.79599)
			(xy 112.809102 -151.815964) (xy 112.725243 -151.828021) (xy 112.640618 -151.832053) (xy 112.555993 -151.828021)
			(xy 112.472134 -151.815964) (xy 112.389801 -151.79599) (xy 112.309739 -151.768281) (xy 112.232674 -151.733086)
			(xy 112.159304 -151.690726) (xy 112.090292 -151.641583) (xy 112.026264 -151.586102) (xy 111.967799 -151.524787)
			(xy 111.915428 -151.458191) (xy 111.869625 -151.386919) (xy 111.830803 -151.311616) (xy 111.799315 -151.232964)
			(xy 111.775447 -151.151674) (xy 111.759413 -151.068484) (xy 111.75136 -150.984147) (xy 105.97134 -150.984147)
			(xy 105.97134 -160.75279) (xy 110.15726 -164.93871) (xy 110.15726 -171.40174) (xy 110.433358 -171.677838)
		)
		(stroke
			(width 0)
			(type solid)
		)
		(fill yes)
		(layer "B.Cu")
		(net "SW_P12V_AUX_PVDDCR_SOC_P1_FLT")
	)
	(gr_poly
		(pts
			(arc
				(start 103.714804 -392.432286)
				(mid 103.734327 -392.428385)
				(end 103.750872 -392.4173)
			)
			(arc
				(start 103.769414 -392.398758)
				(mid 103.780525 -392.382224)
				(end 103.7844 -392.36269)
			)
			(xy 103.7844 -390.15543) (xy 103.79202 -390.136888) (xy 103.792274 -390.136634)
			(arc
				(start 103.788972 -390.111742)
				(mid 103.78665 -390.08728)
				(end 103.785924 -390.06272)
			)
			(arc
				(start 103.785924 -390.06272)
				(mid 103.897665 -389.792953)
				(end 104.167432 -389.681212)
			)
			(arc
				(start 104.167432 -389.681212)
				(mid 104.286548 -389.700298)
				(end 104.393746 -389.755634)
			)
			(arc
				(start 104.393746 -389.755634)
				(mid 104.40806 -389.763038)
				(end 104.423972 -389.76554)
			)
			(xy 105.550716 -389.76554) (xy 105.555542 -389.76046) (xy 107.773724 -389.76046) (xy 107.77855 -389.76554)
			(arc
				(start 107.998514 -389.76554)
				(mid 108.018037 -389.769441)
				(end 108.034582 -389.780526)
			)
			(arc
				(start 108.143294 -389.889238)
				(mid 108.154405 -389.905772)
				(end 108.15828 -389.925306)
			)
			(arc
				(start 108.15828 -391.005822)
				(mid 108.162181 -391.025345)
				(end 108.173266 -391.04189)
			)
			(arc
				(start 108.288582 -391.157206)
				(mid 108.305116 -391.168317)
				(end 108.32465 -391.172192)
			)
			(arc
				(start 108.96219 -391.172192)
				(mid 108.981713 -391.168291)
				(end 108.998258 -391.157206)
			)
			(arc
				(start 109.13364 -391.021824)
				(mid 109.144751 -391.00529)
				(end 109.148626 -390.985756)
			)
			(arc
				(start 109.148626 -388.347204)
				(mid 109.144725 -388.327681)
				(end 109.13364 -388.311136)
			)
			(arc
				(start 108.83646 -388.013956)
				(mid 108.818479 -388.002427)
				(end 108.797344 -387.999224)
			)
			(xy 108.710476 -388.004812) (xy 108.691172 -388.014972)
			(arc
				(start 108.684314 -388.023608)
				(mid 108.550695 -388.132472)
				(end 108.382816 -388.171436)
			)
			(arc
				(start 108.382816 -388.171436)
				(mid 108.112959 -388.059605)
				(end 108.001308 -387.789674)
			)
			(arc
				(start 108.001308 -387.199632)
				(mid 107.997358 -387.180245)
				(end 107.986322 -387.163818)
			)
			(arc
				(start 107.730544 -386.90804)
				(mid 107.71401 -386.896929)
				(end 107.694476 -386.893054)
			)
			(arc
				(start 106.867452 -386.893054)
				(mid 106.848065 -386.897004)
				(end 106.831638 -386.90804)
			)
			(arc
				(start 106.780838 -386.958586)
				(mid 106.764421 -386.969648)
				(end 106.745024 -386.973572)
			)
			(arc
				(start 102.490524 -386.973572)
				(mid 102.471137 -386.969622)
				(end 102.45471 -386.958586)
			)
			(xy 102.417626 -386.958586)
			(arc
				(start 102.13086 -387.245352)
				(mid 102.114326 -387.256463)
				(end 102.094792 -387.260338)
			)
			(arc
				(start 100.959158 -387.260338)
				(mid 100.939635 -387.264239)
				(end 100.92309 -387.275324)
			)
			(arc
				(start 100.693474 -387.50494)
				(mid 100.682363 -387.521474)
				(end 100.678488 -387.541008)
			)
			(xy 100.678488 -388.222236)
			(arc
				(start 100.679504 -388.226808)
				(mid 100.683919 -388.257911)
				(end 100.685346 -388.289292)
			)
			(arc
				(start 100.685346 -388.289292)
				(mid 100.683902 -388.320672)
				(end 100.679504 -388.351776)
			)
			(xy 100.678488 -388.356348)
			(arc
				(start 100.678488 -388.663942)
				(mid 100.682389 -388.683465)
				(end 100.693474 -388.70001)
			)
			(arc
				(start 101.157532 -389.164068)
				(mid 101.174066 -389.175179)
				(end 101.1936 -389.179054)
			)
			(arc
				(start 102.39248 -389.179054)
				(mid 102.412003 -389.182955)
				(end 102.428548 -389.19404)
			)
			(arc
				(start 102.575868 -389.34136)
				(mid 102.586979 -389.357894)
				(end 102.590854 -389.377428)
			)
			(arc
				(start 102.590854 -392.279124)
				(mid 102.594755 -392.298647)
				(end 102.60584 -392.315192)
			)
			(arc
				(start 102.707948 -392.4173)
				(mid 102.724482 -392.428411)
				(end 102.744016 -392.432286)
			)
		)
		(stroke
			(width 0)
			(type solid)
		)
		(fill yes)
		(layer "B.Cu")
		(net "GND")
	)
	(gr_poly
		(pts
			(xy 117.125496 -35.655504) (xy 117.125496 -32.175704) (xy 117.5766 -31.7246) (xy 121.99366 -31.7246)
			(xy 122.2502 -31.46806) (xy 122.2502 -26.5176) (xy 123.063 -25.7048) (xy 123.063 -22.41296) (xy 119.67464 -19.0246)
			(xy 111.8362 -19.0246) (xy 111.506 -19.3548) (xy 111.506 -21.0058) (xy 112.014 -21.5138) (xy 113.2078 -21.5138)
			(xy 113.8428 -20.8788) (xy 116.84 -20.8788) (xy 118.99698 -23.03578) (xy 121.310128 -23.03578) (xy 121.310128 -22.975812)
			(xy 121.317956 -22.916356) (xy 121.333477 -22.858431) (xy 121.356426 -22.803027) (xy 121.38641 -22.751093)
			(xy 121.422916 -22.703517) (xy 121.465321 -22.661112) (xy 121.512897 -22.624606) (xy 121.564831 -22.594622)
			(xy 121.620235 -22.571673) (xy 121.67816 -22.556152) (xy 121.737616 -22.548324) (xy 121.797584 -22.548324)
			(xy 121.85704 -22.556152) (xy 121.914965 -22.571673) (xy 121.970369 -22.594622) (xy 122.022303 -22.624606)
			(xy 122.069879 -22.661112) (xy 122.112284 -22.703517) (xy 122.14879 -22.751093) (xy 122.178774 -22.803027)
			(xy 122.201723 -22.858431) (xy 122.217244 -22.916356) (xy 122.225072 -22.975812) (xy 122.225562 -23.005796)
			(xy 122.225072 -23.03578) (xy 122.217244 -23.095236) (xy 122.201723 -23.153161) (xy 122.178774 -23.208565)
			(xy 122.14879 -23.260499) (xy 122.112284 -23.308075) (xy 122.069879 -23.35048) (xy 122.022303 -23.386986)
			(xy 121.970369 -23.41697) (xy 121.914965 -23.439919) (xy 121.85704 -23.45544) (xy 121.797584 -23.463268)
			(xy 121.737616 -23.463268) (xy 121.67816 -23.45544) (xy 121.620235 -23.439919) (xy 121.564831 -23.41697)
			(xy 121.512897 -23.386986) (xy 121.465321 -23.35048) (xy 121.422916 -23.308075) (xy 121.38641 -23.260499)
			(xy 121.356426 -23.208565) (xy 121.333477 -23.153161) (xy 121.317956 -23.095236) (xy 121.310128 -23.03578)
			(xy 118.99698 -23.03578) (xy 119.0498 -23.0886) (xy 119.0498 -24.783796) (xy 121.385328 -24.783796)
			(xy 121.389401 -24.728137) (xy 121.401536 -24.673664) (xy 121.421472 -24.621538) (xy 121.448786 -24.57287)
			(xy 121.482894 -24.528698) (xy 121.523071 -24.489963) (xy 121.568459 -24.457491) (xy 121.618091 -24.431973)
			(xy 121.670911 -24.413954) (xy 121.72579 -24.403817) (xy 121.781561 -24.401779) (xy 121.837035 -24.407882)
			(xy 121.891028 -24.421998) (xy 121.942391 -24.443825) (xy 121.990029 -24.472898) (xy 122.032925 -24.508597)
			(xy 122.070167 -24.550161) (xy 122.100961 -24.596705) (xy 122.124649 -24.647236) (xy 122.140727 -24.700678)
			(xy 122.148853 -24.755892) (xy 122.149362 -24.783796) (xy 122.148853 -24.8117) (xy 122.140727 -24.866914)
			(xy 122.124649 -24.920356) (xy 122.100961 -24.970887) (xy 122.070167 -25.017431) (xy 122.032925 -25.058995)
			(xy 121.990029 -25.094694) (xy 121.942391 -25.123767) (xy 121.891028 -25.145594) (xy 121.837035 -25.15971)
			(xy 121.781561 -25.165813) (xy 121.72579 -25.163775) (xy 121.670911 -25.153638) (xy 121.618091 -25.135619)
			(xy 121.568459 -25.110101) (xy 121.523071 -25.077629) (xy 121.482894 -25.038894) (xy 121.448786 -24.994722)
			(xy 121.421472 -24.946054) (xy 121.401536 -24.893928) (xy 121.389401 -24.839455) (xy 121.385328 -24.783796)
			(xy 119.0498 -24.783796) (xy 119.0498 -29.0576) (xy 118.330472 -29.776928) (xy 117.125496 -29.776928)
			(xy 116.975128 -29.62656) (xy 116.975128 -26.220928) (xy 116.907056 -26.152856) (xy 115.067842 -26.152856)
			(xy 114.695986 -25.781) (xy 114.018822 -25.781) (xy 113.968022 -25.8318) (xy 113.968022 -27.393392)
			(xy 113.634774 -27.72664) (xy 113.634774 -28.28417) (xy 113.673382 -28.322778) (xy 115.57 -28.322778)
			(xy 115.722146 -28.474924) (xy 115.722146 -33.66389) (xy 114.892836 -34.4932) (xy 113.3602 -34.4932)
			(xy 113.0554 -34.798) (xy 113.0554 -35.071812) (xy 112.912144 -35.215068) (xy 108.052616 -35.215068)
			(xy 108.0008 -35.163252) (xy 108.0008 -34.8488) (xy 107.6071 -34.4551) (xy 107.30484 -34.4551) (xy 107.1626 -34.31286)
			(xy 107.1626 -32.6898) (xy 108.936028 -30.916372) (xy 109.384846 -30.916372) (xy 109.423454 -30.877764)
			(xy 109.423454 -30.327854) (xy 109.3724 -30.2768) (xy 108.700316 -30.2768) (xy 107.989116 -30.988)
			(xy 107.6198 -30.988) (xy 107.4674 -31.1404) (xy 107.4674 -31.33471) (xy 107.34167 -31.46044) (xy 106.652314 -31.46044)
			(xy 106.613706 -31.499048) (xy 106.613706 -34.909506) (xy 107.777026 -36.072826) (xy 116.708174 -36.072826)
		)
		(stroke
			(width 0)
			(type solid)
		)
		(fill yes)
		(layer "B.Cu")
		(net "P1V2_CPU0_USB2_DVDD12")
	)
	(gr_poly
		(pts
			(xy 239.533176 -49.377346) (xy 239.545427 -49.376627) (xy 239.567185 -49.365354) (xy 239.574832 -49.355756)
			(xy 239.62995 -49.277778) (xy 239.633252 -49.253648) (xy 239.628934 -49.241964) (xy 239.620609 -49.217343)
			(xy 239.608945 -49.166692) (xy 239.603112 -49.115045) (xy 239.602772 -49.089056) (xy 239.603265 -49.05909)
			(xy 239.611093 -48.999671) (xy 239.626608 -48.941781) (xy 239.649547 -48.886412) (xy 239.679516 -48.834511)
			(xy 239.716002 -48.786964) (xy 239.758382 -48.744587) (xy 239.80593 -48.708103) (xy 239.857834 -48.678136)
			(xy 239.913204 -48.655201) (xy 239.971094 -48.639688) (xy 240.030514 -48.631863) (xy 240.06048 -48.631348)
			(xy 240.088336 -48.631743) (xy 240.143638 -48.638478) (xy 240.197711 -48.651886) (xy 240.249753 -48.671768)
			(xy 240.298991 -48.69783) (xy 240.3221 -48.71339) (xy 240.332162 -48.719619) (xy 240.355554 -48.723019)
			(xy 240.378015 -48.715655) (xy 240.38687 -48.707802) (xy 240.919762 -48.17491) (xy 240.926614 -48.167514)
			(xy 240.934358 -48.148916) (xy 240.934748 -48.138842) (xy 240.934748 -46.555914) (xy 240.934308 -46.545852)
			(xy 240.926566 -46.527275) (xy 240.919762 -46.519846) (xy 240.43132 -46.031404) (xy 240.423917 -46.02457)
			(xy 240.405319 -46.016864) (xy 240.395252 -46.016418) (xy 238.059214 -46.016418) (xy 238.049151 -46.016857)
			(xy 238.030571 -46.024596) (xy 238.023146 -46.031404) (xy 237.927896 -46.126654) (xy 237.921849 -46.133229)
			(xy 237.914372 -46.149441) (xy 237.912902 -46.167234) (xy 237.914942 -46.17593) (xy 237.941612 -46.274228)
			(xy 237.960916 -46.293278) (xy 237.974378 -46.296834) (xy 238.003433 -46.304876) (xy 238.059291 -46.327561)
			(xy 238.111688 -46.357381) (xy 238.159716 -46.393822) (xy 238.202546 -46.436252) (xy 238.239435 -46.483937)
			(xy 238.269746 -46.536051) (xy 238.292953 -46.591694) (xy 238.308655 -46.649901) (xy 238.316581 -46.709666)
			(xy 238.317024 -46.73981) (xy 238.316533 -46.769778) (xy 238.308709 -46.8292) (xy 238.293196 -46.887093)
			(xy 238.270259 -46.942465) (xy 238.240292 -46.994371) (xy 238.203806 -47.041921) (xy 238.161425 -47.084302)
			(xy 238.113876 -47.120788) (xy 238.061971 -47.150757) (xy 238.006598 -47.173694) (xy 237.948706 -47.189208)
			(xy 237.889284 -47.197033) (xy 237.859316 -47.197518) (xy 237.829173 -47.197038) (xy 237.769408 -47.189124)
			(xy 237.711199 -47.173431) (xy 237.655556 -47.150231) (xy 237.60344 -47.119925) (xy 237.555755 -47.083038)
			(xy 237.513327 -47.040209) (xy 237.476889 -46.99218) (xy 237.447074 -46.939782) (xy 237.424397 -46.883923)
			(xy 237.41634 -46.854872) (xy 237.412784 -46.84141) (xy 237.393734 -46.822106) (xy 237.295436 -46.795436)
			(xy 237.286739 -46.793406) (xy 237.268952 -46.794876) (xy 237.25275 -46.802361) (xy 237.24616 -46.80839)
			(xy 236.82452 -47.23003) (xy 236.817676 -47.237429) (xy 236.809949 -47.256027) (xy 236.809534 -47.266098)
			(xy 236.809534 -48.038508) (xy 237.6086 -48.038508) (xy 237.6086 -47.978572) (xy 237.616423 -47.91915)
			(xy 237.631936 -47.861257) (xy 237.654872 -47.805884) (xy 237.684839 -47.753978) (xy 237.721326 -47.706428)
			(xy 237.763706 -47.664048) (xy 237.811256 -47.627561) (xy 237.863162 -47.597594) (xy 237.918535 -47.574658)
			(xy 237.976428 -47.559145) (xy 238.03585 -47.551322) (xy 238.095786 -47.551322) (xy 238.155208 -47.559145)
			(xy 238.213101 -47.574658) (xy 238.268474 -47.597594) (xy 238.32038 -47.627561) (xy 238.36793 -47.664048)
			(xy 238.41031 -47.706428) (xy 238.446797 -47.753978) (xy 238.476764 -47.805884) (xy 238.4997 -47.861257)
			(xy 238.515213 -47.91915) (xy 238.523036 -47.978572) (xy 238.523526 -48.00854) (xy 238.523036 -48.038508)
			(xy 238.515213 -48.09793) (xy 238.4997 -48.155823) (xy 238.476764 -48.211196) (xy 238.446797 -48.263102)
			(xy 238.41031 -48.310652) (xy 238.36793 -48.353032) (xy 238.32038 -48.389519) (xy 238.268474 -48.419486)
			(xy 238.213101 -48.442422) (xy 238.155208 -48.457935) (xy 238.095786 -48.465758) (xy 238.03585 -48.465758)
			(xy 237.976428 -48.457935) (xy 237.918535 -48.442422) (xy 237.863162 -48.419486) (xy 237.811256 -48.389519)
			(xy 237.763706 -48.353032) (xy 237.721326 -48.310652) (xy 237.684839 -48.263102) (xy 237.654872 -48.211196)
			(xy 237.631936 -48.155823) (xy 237.616423 -48.09793) (xy 237.6086 -48.038508) (xy 236.809534 -48.038508)
			(xy 236.809534 -49.280064) (xy 236.80997 -49.290128) (xy 236.817704 -49.308713) (xy 236.82452 -49.316132)
			(xy 236.870748 -49.36236) (xy 236.878147 -49.369203) (xy 236.896746 -49.376926) (xy 236.906816 -49.377346)
		)
		(stroke
			(width 0)
			(type solid)
		)
		(fill yes)
		(layer "B.Cu")
		(net "P3V3_E1S_0")
	)
	(gr_poly
		(pts
			(arc
				(start 253.122176 -56.32958)
				(mid 253.148835 -56.322023)
				(end 253.167642 -56.30164)
			)
			(arc
				(start 253.167642 -56.30164)
				(mid 253.429685 -55.948188)
				(end 253.796546 -55.705248)
			)
			(arc
				(start 253.796546 -55.705248)
				(mid 253.81895 -55.686497)
				(end 253.82728 -55.658512)
			)
			(arc
				(start 253.82728 -54.828186)
				(mid 253.825631 -54.815598)
				(end 253.82093 -54.803802)
			)
			(arc
				(start 253.82093 -54.803802)
				(mid 253.773684 -54.619906)
				(end 253.82093 -54.43601)
			)
			(arc
				(start 253.82093 -54.43601)
				(mid 253.825651 -54.424219)
				(end 253.82728 -54.411626)
			)
			(arc
				(start 253.82728 -53.906166)
				(mid 253.908615 -53.496796)
				(end 254.140462 -53.149754)
			)
			(arc
				(start 254.4191 -52.871116)
				(mid 254.430026 -52.85467)
				(end 254.433832 -52.835302)
			)
			(arc
				(start 254.433832 -49.696878)
				(mid 254.429999 -49.677521)
				(end 254.4191 -49.661064)
			)
			(arc
				(start 254.415036 -49.657)
				(mid 254.39859 -49.646074)
				(end 254.379222 -49.642268)
			)
			(arc
				(start 253.322328 -49.642268)
				(mid 253.302971 -49.646101)
				(end 253.286514 -49.657)
			)
			(xy 253.228602 -49.715166) (xy 253.220728 -49.733708) (xy 253.220728 -49.743868)
			(arc
				(start 253.220728 -52.953158)
				(mid 253.1394 -53.361751)
				(end 252.9078 -53.708046)
			)
			(arc
				(start 252.212094 -54.403752)
				(mid 252.121752 -54.484431)
				(end 252.022864 -54.554374)
			)
			(xy 252.01118 -54.56174) (xy 251.99848 -54.58587) (xy 252.003052 -54.70144) (xy 252.017784 -54.724554)
			(arc
				(start 252.029976 -54.73065)
				(mid 252.180396 -54.871229)
				(end 252.23597 -55.069486)
			)
			(arc
				(start 252.23597 -55.069486)
				(mid 251.854462 -55.450994)
				(end 251.472954 -55.069486)
			)
			(arc
				(start 251.472954 -55.069486)
				(mid 251.501995 -54.923489)
				(end 251.584714 -54.799738)
			)
			(arc
				(start 251.584714 -54.799738)
				(mid 251.595026 -54.742318)
				(end 251.544582 -54.713124)
			)
			(arc
				(start 251.544582 -54.713124)
				(mid 251.500931 -54.715801)
				(end 251.457206 -54.71668)
			)
			(arc
				(start 249.668538 -54.71668)
				(mid 249.395948 -54.681208)
				(end 249.141488 -54.577234)
			)
			(arc
				(start 249.141488 -54.577234)
				(mid 249.08079 -54.552402)
				(end 249.015758 -54.54396)
			)
			(arc
				(start 249.015758 -54.54396)
				(mid 248.950732 -54.552425)
				(end 248.890028 -54.577234)
			)
			(arc
				(start 248.890028 -54.577234)
				(mid 248.759569 -54.640075)
				(end 248.621804 -54.684676)
			)
			(xy 248.614946 -54.686454) (xy 248.603008 -54.693312)
			(arc
				(start 248.350786 -54.945534)
				(mid 248.339675 -54.962068)
				(end 248.3358 -54.981602)
			)
			(arc
				(start 248.3358 -56.123078)
				(mid 248.339701 -56.142601)
				(end 248.350786 -56.159146)
			)
			(arc
				(start 248.506234 -56.314594)
				(mid 248.522768 -56.325705)
				(end 248.542302 -56.32958)
			)
		)
		(stroke
			(width 0)
			(type solid)
		)
		(fill yes)
		(layer "B.Cu")
		(net "P12V_AUX")
	)
	(gr_poly
		(pts
			(arc
				(start 303.940972 -337.917028)
				(mid 303.960067 -337.913136)
				(end 303.976278 -337.902296)
			)
			(arc
				(start 304.175414 -337.70316)
				(mid 304.18632 -337.686977)
				(end 304.190146 -337.667854)
			)
			(arc
				(start 304.190146 -337.348322)
				(mid 304.13689 -337.258961)
				(end 304.03292 -337.263232)
			)
			(arc
				(start 304.03292 -337.263232)
				(mid 303.933162 -337.309393)
				(end 303.824386 -337.325208)
			)
			(arc
				(start 303.824386 -337.325208)
				(mid 303.69337 -337.302022)
				(end 303.57826 -337.235292)
			)
			(arc
				(start 303.57826 -337.235292)
				(mid 303.511104 -337.211306)
				(end 303.444656 -337.237324)
			)
			(arc
				(start 303.444656 -337.237324)
				(mid 303.326105 -337.310014)
				(end 303.189386 -337.335368)
			)
			(arc
				(start 303.189386 -337.335368)
				(mid 302.91944 -337.223552)
				(end 302.807624 -336.953606)
			)
			(arc
				(start 302.807624 -336.953606)
				(mid 302.832781 -336.817061)
				(end 302.90516 -336.69859)
			)
			(arc
				(start 302.90516 -336.69859)
				(mid 302.931098 -336.630772)
				(end 302.90516 -336.562954)
			)
			(arc
				(start 302.90516 -336.562954)
				(mid 302.833017 -336.444682)
				(end 302.807878 -336.308446)
			)
			(arc
				(start 302.807878 -336.308446)
				(mid 302.832264 -336.174237)
				(end 302.902366 -336.05724)
			)
			(xy 302.90262 -336.056986) (xy 302.908462 -336.050128)
			(arc
				(start 302.91151 -336.042)
				(mid 302.914155 -336.033023)
				(end 302.915066 -336.023712)
			)
			(arc
				(start 302.915066 -335.95818)
				(mid 302.914112 -335.948878)
				(end 302.91151 -335.939892)
			)
			(xy 302.908462 -335.931764) (xy 302.90262 -335.924906)
			(arc
				(start 302.902366 -335.924652)
				(mid 302.832342 -335.807626)
				(end 302.807878 -335.673446)
			)
			(arc
				(start 302.807878 -335.673446)
				(mid 302.919619 -335.403679)
				(end 303.189386 -335.291938)
			)
			(arc
				(start 303.189386 -335.291938)
				(mid 303.329972 -335.318786)
				(end 303.450752 -335.39557)
			)
			(xy 303.45761 -335.402174) (xy 303.475644 -335.409286) (xy 303.563528 -335.409286) (xy 303.581562 -335.402174)
			(arc
				(start 303.58842 -335.39557)
				(mid 303.70921 -335.318811)
				(end 303.849786 -335.291938)
			)
			(arc
				(start 303.849786 -335.291938)
				(mid 303.948108 -335.304893)
				(end 304.039778 -335.342738)
			)
			(xy 304.051716 -335.349596) (xy 304.07864 -335.349342)
			(arc
				(start 304.164746 -335.299558)
				(mid 304.183308 -335.280982)
				(end 304.190146 -335.255616)
			)
			(arc
				(start 304.190146 -328.276712)
				(mid 304.186245 -328.257189)
				(end 304.17516 -328.240644)
			)
			(arc
				(start 303.360074 -327.425558)
				(mid 303.34354 -327.414447)
				(end 303.324006 -327.410572)
			)
			(arc
				(start 269.837662 -327.410572)
				(mid 269.801741 -327.425451)
				(end 269.786862 -327.461372)
			)
			(xy 269.786862 -333.629)
			(arc
				(start 269.788894 -333.636112)
				(mid 269.804574 -333.744316)
				(end 269.788894 -333.85252)
			)
			(xy 269.786862 -333.859632)
			(arc
				(start 269.786862 -337.798156)
				(mid 269.790763 -337.817679)
				(end 269.801848 -337.834224)
			)
			(arc
				(start 269.869666 -337.902042)
				(mid 269.8862 -337.913153)
				(end 269.905734 -337.917028)
			)
		)
		(stroke
			(width 0)
			(type solid)
		)
		(fill yes)
		(layer "B.Cu")
		(net "PVDDIO_P0")
	)
	(gr_poly
		(pts
			(arc
				(start 248.36247 -53.700426)
				(mid 248.375332 -53.698704)
				(end 248.387362 -53.693822)
			)
			(arc
				(start 248.387362 -53.693822)
				(mid 248.690737 -53.569743)
				(end 249.015758 -53.527452)
			)
			(arc
				(start 249.015758 -53.527452)
				(mid 249.340766 -53.569793)
				(end 249.644154 -53.693822)
			)
			(arc
				(start 249.644154 -53.693822)
				(mid 249.656172 -53.698751)
				(end 249.669046 -53.700426)
			)
			(arc
				(start 251.456952 -53.700426)
				(mid 251.476475 -53.696525)
				(end 251.49302 -53.68544)
			)
			(arc
				(start 252.189488 -52.988972)
				(mid 252.200599 -52.972438)
				(end 252.204474 -52.952904)
			)
			(arc
				(start 252.204474 -49.746408)
				(mid 252.200573 -49.726885)
				(end 252.189488 -49.71034)
			)
			(arc
				(start 252.187202 -49.708054)
				(mid 252.176091 -49.69152)
				(end 252.172216 -49.671986)
			)
			(arc
				(start 252.172216 -49.509934)
				(mid 252.168315 -49.490411)
				(end 252.15723 -49.473866)
			)
			(xy 251.164598 -48.481234) (xy 251.14377 -48.473614) (xy 251.132594 -48.474376)
			(arc
				(start 251.102622 -48.475646)
				(mid 250.922911 -48.430634)
				(end 250.78563 -48.306228)
			)
			(arc
				(start 250.78563 -48.306228)
				(mid 250.759383 -48.286367)
				(end 250.726448 -48.28667)
			)
			(arc
				(start 250.726448 -48.28667)
				(mid 250.517832 -48.341023)
				(end 250.30303 -48.359314)
			)
			(arc
				(start 250.30303 -48.359314)
				(mid 249.531268 -48.097985)
				(end 249.076972 -47.421546)
			)
			(arc
				(start 249.076972 -47.421546)
				(mid 249.069874 -47.406255)
				(end 249.058176 -47.394114)
			)
			(arc
				(start 249.058176 -47.394114)
				(mid 248.945848 -47.259467)
				(end 248.905522 -47.088806)
			)
			(arc
				(start 248.905522 -47.088806)
				(mid 248.941299 -46.927503)
				(end 249.04192 -46.796452)
			)
			(arc
				(start 249.04192 -46.796452)
				(mid 249.057352 -46.77432)
				(end 249.059192 -46.74743)
			)
			(arc
				(start 249.059192 -46.74743)
				(mid 249.051707 -46.706788)
				(end 249.04573 -46.665896)
			)
			(xy 249.039888 -46.6217) (xy 249.03684 -46.6217) (xy 249.03684 -45.368464) (xy 249.039888 -45.368464)
			(arc
				(start 249.04573 -45.324268)
				(mid 249.06468 -45.217044)
				(end 249.09399 -45.112178)
			)
			(xy 249.096784 -45.104304) (xy 249.096784 -45.10278)
			(arc
				(start 249.108722 -45.070776)
				(mid 249.160334 -44.954815)
				(end 249.2248 -44.845478)
			)
			(arc
				(start 249.2248 -44.845478)
				(mid 249.231239 -44.832026)
				(end 249.233436 -44.817284)
			)
			(xy 249.233436 -44.287694) (xy 249.230388 -44.276264)
			(arc
				(start 249.227594 -44.270676)
				(mid 249.115544 -43.970799)
				(end 249.07748 -43.652948)
			)
			(arc
				(start 249.07748 -43.652694)
				(mid 249.267176 -42.963531)
				(end 249.782838 -42.468546)
			)
			(arc
				(start 249.782838 -42.468546)
				(mid 249.802334 -42.44987)
				(end 249.809508 -42.423842)
			)
			(arc
				(start 249.809508 -41.889172)
				(mid 249.813409 -41.869649)
				(end 249.824494 -41.853104)
			)
			(arc
				(start 250.097798 -41.5798)
				(mid 250.108909 -41.563266)
				(end 250.112784 -41.543732)
			)
			(arc
				(start 250.112784 -41.491662)
				(mid 250.103797 -41.462812)
				(end 250.080018 -41.444164)
			)
			(arc
				(start 250.080018 -41.444164)
				(mid 249.551623 -41.080569)
				(end 249.25147 -40.513762)
			)
			(xy 249.247406 -40.496744) (xy 249.21972 -40.475408) (xy 246.928132 -40.475408) (xy 246.928132 -44.1071)
			(xy 246.32539 -44.709842) (xy 245.59641 -45.438822) (xy 245.59641 -46.225714) (xy 245.59641 -52.358798)
			(xy 245.417594 -52.537614) (xy 245.375176 -52.537614) (xy 245.375176 -53.626766) (xy 245.448836 -53.700426)
		)
		(stroke
			(width 0)
			(type solid)
		)
		(fill yes)
		(layer "B.Cu")
		(net "P12V_E1S_0")
	)
	(gr_poly
		(pts
			(xy 312.70829 -337.58886) (xy 312.70829 -334.802734) (xy 312.70829 -334.59674) (xy 316.030356 -331.274674)
			(xy 316.030356 -327.923906) (xy 316.03078 -327.913837) (xy 316.038499 -327.895236) (xy 316.045342 -327.887838)
			(xy 317.638938 -326.294242) (xy 317.646337 -326.287397) (xy 317.664935 -326.27967) (xy 317.675006 -326.279256)
			(xy 345.733878 -326.279256) (xy 345.743716 -326.279792) (xy 345.761879 -326.287376) (xy 345.769184 -326.293988)
			(xy 346.247466 -326.77227) (xy 346.254867 -326.779109) (xy 346.273465 -326.786824) (xy 346.283534 -326.787256)
			(xy 347.562678 -326.787256) (xy 347.572516 -326.787792) (xy 347.590679 -326.795376) (xy 347.597984 -326.801988)
			(xy 347.886528 -327.090532) (xy 347.893236 -327.097772) (xy 347.90082 -327.115977) (xy 347.90126 -327.125838)
			(xy 347.90126 -330.893166) (xy 347.901697 -330.90323) (xy 347.909435 -330.921811) (xy 347.916246 -330.929234)
			(xy 348.286832 -331.29982) (xy 348.294228 -331.30667) (xy 348.312827 -331.314406) (xy 348.3229 -331.314806)
			(xy 357.564436 -331.314806) (xy 357.574276 -331.314276) (xy 357.592447 -331.306698) (xy 357.599742 -331.300074)
			(xy 357.663242 -331.236574) (xy 357.669949 -331.229334) (xy 357.677534 -331.211129) (xy 357.677974 -331.201268)
			(xy 357.677974 -330.20508) (xy 357.677547 -330.195012) (xy 357.669824 -330.176415) (xy 357.662988 -330.169012)
			(xy 356.287832 -328.793856) (xy 356.280989 -328.786456) (xy 356.273266 -328.767858) (xy 356.272846 -328.757788)
			(xy 356.272846 -322.178426) (xy 356.272408 -322.168363) (xy 356.264669 -322.149783) (xy 356.25786 -322.142358)
			(xy 347.18625 -313.070748) (xy 318.47917 -313.070748) (xy 316.671452 -313.070748) (xy 307.380386 -322.361814)
			(xy 307.380386 -323.050408) (xy 307.380386 -325.819262) (xy 307.151786 -326.047862) (xy 304.45837 -328.741278)
			(xy 304.45837 -336.304128) (xy 305.101244 -336.304128) (xy 305.101705 -336.276216) (xy 305.109849 -336.220989)
			(xy 305.125953 -336.167539) (xy 305.149672 -336.117005) (xy 305.180501 -336.070466) (xy 305.19878 -336.049366)
			(xy 305.20828 -336.037904) (xy 305.220919 -336.01097) (xy 305.225262 -335.981536) (xy 305.22094 -335.952099)
			(xy 305.20832 -335.925156) (xy 305.19878 -335.91373) (xy 305.180492 -335.892639) (xy 305.149666 -335.846098)
			(xy 305.125953 -335.795561) (xy 305.109859 -335.742108) (xy 305.101728 -335.68688) (xy 305.101244 -335.658968)
			(xy 305.101695 -335.631698) (xy 305.109461 -335.577712) (xy 305.124831 -335.525382) (xy 305.147491 -335.475771)
			(xy 305.176981 -335.42989) (xy 305.2127 -335.388673) (xy 305.253921 -335.352958) (xy 305.299805 -335.323473)
			(xy 305.349417 -335.300817) (xy 305.40175 -335.285453) (xy 305.455736 -335.277692) (xy 305.483006 -335.277206)
			(xy 305.510376 -335.277657) (xy 305.564554 -335.285485) (xy 305.617056 -335.300981) (xy 305.666802 -335.323824)
			(xy 305.712771 -335.353547) (xy 305.733704 -335.371186) (xy 305.745032 -335.380422) (xy 305.771589 -335.392598)
			(xy 305.800506 -335.396771) (xy 305.829423 -335.392598) (xy 305.85598 -335.380422) (xy 305.867308 -335.371186)
			(xy 305.888272 -335.35359) (xy 305.934248 -335.323898) (xy 305.98399 -335.301067) (xy 306.036478 -335.285563)
			(xy 306.090641 -335.277702) (xy 306.118006 -335.277206) (xy 306.145274 -335.277719) (xy 306.199255 -335.28548)
			(xy 306.251582 -335.300845) (xy 306.30119 -335.323499) (xy 306.34707 -335.352983) (xy 306.388286 -335.388695)
			(xy 306.424001 -335.42991) (xy 306.453488 -335.475787) (xy 306.476146 -335.525393) (xy 306.491514 -335.57772)
			(xy 306.499279 -335.6317) (xy 306.499768 -335.658968) (xy 306.499301 -335.686338) (xy 306.491478 -335.740515)
			(xy 306.475986 -335.793017) (xy 306.453146 -335.842763) (xy 306.423426 -335.888732) (xy 306.405788 -335.909666)
			(xy 306.396583 -335.921017) (xy 306.384403 -335.947566) (xy 306.380225 -335.976476) (xy 306.384389 -336.005387)
			(xy 306.396557 -336.031943) (xy 306.405788 -336.04327) (xy 306.423409 -336.064214) (xy 306.453098 -336.110196)
			(xy 306.475924 -336.159942) (xy 306.491423 -336.212435) (xy 306.499276 -336.266602) (xy 306.499768 -336.293968)
			(xy 306.499269 -336.321238) (xy 306.491511 -336.375223) (xy 306.476149 -336.427555) (xy 306.453496 -336.477168)
			(xy 306.424012 -336.523051) (xy 306.388298 -336.564271) (xy 306.347082 -336.599989) (xy 306.301201 -336.629478)
			(xy 306.251591 -336.652136) (xy 306.19926 -336.667503) (xy 306.145276 -336.675266) (xy 306.118006 -336.67573)
			(xy 306.091245 -336.67532) (xy 306.038247 -336.667843) (xy 305.986813 -336.653035) (xy 305.937953 -336.631187)
			(xy 305.892625 -336.602727) (xy 305.87188 -336.585814) (xy 305.860403 -336.576744) (xy 305.833672 -336.564902)
			(xy 305.804678 -336.561139) (xy 305.77581 -336.565766) (xy 305.749445 -336.578402) (xy 305.738276 -336.587846)
			(xy 305.717157 -336.606205) (xy 305.670539 -336.63716) (xy 305.619906 -336.660987) (xy 305.56634 -336.677175)
			(xy 305.510985 -336.685379) (xy 305.483006 -336.68589) (xy 305.455738 -336.68537) (xy 305.401757 -336.67761)
			(xy 305.34943 -336.662247) (xy 305.299822 -336.639593) (xy 305.253942 -336.610111) (xy 305.212725 -336.574399)
			(xy 305.17701 -336.533185) (xy 305.147523 -336.487308) (xy 305.124865 -336.437702) (xy 305.109497 -336.385376)
			(xy 305.101732 -336.331396) (xy 305.101244 -336.304128) (xy 304.45837 -336.304128) (xy 304.45837 -337.63331)
			(xy 304.458794 -337.64338) (xy 304.466508 -337.661985) (xy 304.473356 -337.669378) (xy 304.549302 -337.745324)
			(xy 304.556697 -337.752178) (xy 304.575296 -337.759924) (xy 304.58537 -337.76031) (xy 312.53684 -337.76031)
		)
		(stroke
			(width 0)
			(type solid)
		)
		(fill yes)
		(layer "B.Cu")
		(net "PVDDCR_CPU1_P0")
	)
	(gr_poly
		(pts
			(arc
				(start 45.858176 -358.265476)
				(mid 45.87471 -358.254365)
				(end 45.894244 -358.25049)
			)
			(xy 56.223916 -358.25049) (xy 57.571894 -356.902512)
			(arc
				(start 57.571894 -347.086682)
				(mid 57.567993 -347.067159)
				(end 57.556908 -347.050614)
			)
			(arc
				(start 57.45988 -346.953586)
				(mid 57.443346 -346.942475)
				(end 57.423812 -346.9386)
			)
			(arc
				(start 53.985414 -346.9386)
				(mid 53.965891 -346.942501)
				(end 53.949346 -346.953586)
			)
			(arc
				(start 53.94198 -346.960952)
				(mid 53.930869 -346.977486)
				(end 53.926994 -346.99702)
			)
			(xy 53.926994 -348.97695) (xy 53.934868 -348.995492) (xy 53.937662 -348.998286)
			(arc
				(start 53.937662 -350.34474)
				(mid 53.941563 -350.364263)
				(end 53.952648 -350.380808)
			)
			(arc
				(start 54.051708 -350.479868)
				(mid 54.068242 -350.490979)
				(end 54.087776 -350.494854)
			)
			(arc
				(start 55.344568 -350.494854)
				(mid 55.364091 -350.498755)
				(end 55.380636 -350.50984)
			)
			(arc
				(start 55.643272 -350.772476)
				(mid 55.654383 -350.78901)
				(end 55.658258 -350.808544)
			)
			(arc
				(start 55.658258 -352.532696)
				(mid 55.654357 -352.552219)
				(end 55.643272 -352.568764)
			)
			(arc
				(start 55.361586 -352.85045)
				(mid 55.345052 -352.861561)
				(end 55.325518 -352.865436)
			)
			(arc
				(start 49.828958 -352.865436)
				(mid 49.809435 -352.861535)
				(end 49.79289 -352.85045)
			)
			(arc
				(start 49.23028 -352.28784)
				(mid 49.219169 -352.271306)
				(end 49.215294 -352.251772)
			)
			(arc
				(start 49.215294 -347.213682)
				(mid 49.211393 -347.194159)
				(end 49.200308 -347.177614)
			)
			(arc
				(start 48.97628 -346.953586)
				(mid 48.959746 -346.942475)
				(end 48.940212 -346.9386)
			)
			(arc
				(start 45.628814 -346.9386)
				(mid 45.609291 -346.942501)
				(end 45.592746 -346.953586)
			)
			(arc
				(start 45.58538 -346.960952)
				(mid 45.574269 -346.977486)
				(end 45.570394 -346.99702)
			)
			(arc
				(start 45.570394 -350.359472)
				(mid 45.574295 -350.378995)
				(end 45.58538 -350.39554)
			)
			(arc
				(start 45.644308 -350.454468)
				(mid 45.660842 -350.465579)
				(end 45.680376 -350.469454)
			)
			(arc
				(start 46.88586 -350.469454)
				(mid 46.905383 -350.473355)
				(end 46.921928 -350.48444)
			)
			(arc
				(start 47.299118 -350.86163)
				(mid 47.310229 -350.878164)
				(end 47.314104 -350.897698)
			)
			(arc
				(start 47.314104 -352.532696)
				(mid 47.310203 -352.552219)
				(end 47.299118 -352.568764)
			)
			(arc
				(start 46.998636 -352.8695)
				(mid 46.982102 -352.880611)
				(end 46.962568 -352.884486)
			)
			(arc
				(start 41.440608 -352.884486)
				(mid 41.421085 -352.880585)
				(end 41.40454 -352.8695)
			)
			(arc
				(start 40.89908 -352.36404)
				(mid 40.887969 -352.347506)
				(end 40.884094 -352.327972)
			)
			(arc
				(start 40.884094 -347.137482)
				(mid 40.880193 -347.117959)
				(end 40.869108 -347.101414)
			)
			(arc
				(start 40.72128 -346.953586)
				(mid 40.704746 -346.942475)
				(end 40.685212 -346.9386)
			)
			(arc
				(start 37.323014 -346.9386)
				(mid 37.303491 -346.942501)
				(end 37.286946 -346.953586)
			)
			(arc
				(start 37.27958 -346.960952)
				(mid 37.268469 -346.977486)
				(end 37.264594 -346.99702)
			)
			(arc
				(start 37.264594 -350.308672)
				(mid 37.268495 -350.328195)
				(end 37.27958 -350.34474)
			)
			(arc
				(start 37.363908 -350.429068)
				(mid 37.380442 -350.440179)
				(end 37.399976 -350.444054)
			)
			(arc
				(start 38.50386 -350.444054)
				(mid 38.523383 -350.447955)
				(end 38.539928 -350.45904)
			)
			(arc
				(start 38.929818 -350.84893)
				(mid 38.940929 -350.865464)
				(end 38.944804 -350.884998)
			)
			(arc
				(start 38.944804 -352.532696)
				(mid 38.940903 -352.552219)
				(end 38.929818 -352.568764)
			)
			(arc
				(start 38.559232 -352.939096)
				(mid 38.542698 -352.950207)
				(end 38.523164 -352.954082)
			)
			(arc
				(start 33.229804 -352.954082)
				(mid 33.210281 -352.950181)
				(end 33.193736 -352.939096)
			)
			(arc
				(start 32.61868 -352.36404)
				(mid 32.607569 -352.347506)
				(end 32.603694 -352.327972)
			)
			(arc
				(start 32.603694 -347.086682)
				(mid 32.599793 -347.067159)
				(end 32.588708 -347.050614)
			)
			(arc
				(start 32.49168 -346.953586)
				(mid 32.475146 -346.942475)
				(end 32.455612 -346.9386)
			)
			(arc
				(start 29.042614 -346.9386)
				(mid 29.023091 -346.942501)
				(end 29.006546 -346.953586)
			)
			(arc
				(start 28.99918 -346.960952)
				(mid 28.988069 -346.977486)
				(end 28.984194 -346.99702)
			)
			(arc
				(start 28.984194 -350.334072)
				(mid 28.988095 -350.353595)
				(end 28.99918 -350.37014)
			)
			(arc
				(start 29.058108 -350.429068)
				(mid 29.074642 -350.440179)
				(end 29.094176 -350.444054)
			)
			(arc
				(start 30.24886 -350.444054)
				(mid 30.268383 -350.447955)
				(end 30.284928 -350.45904)
			)
			(arc
				(start 30.716728 -350.89084)
				(mid 30.727839 -350.907374)
				(end 30.731714 -350.926908)
			)
			(arc
				(start 30.731714 -353.643692)
				(mid 30.735615 -353.663215)
				(end 30.7467 -353.67976)
			)
			(arc
				(start 31.571184 -354.504244)
				(mid 31.587718 -354.515355)
				(end 31.607252 -354.51923)
			)
			(arc
				(start 35.645344 -354.51923)
				(mid 35.664867 -354.523131)
				(end 35.681412 -354.534216)
			)
			(xy 40.986202 -359.839006) (xy 44.284646 -359.839006)
		)
		(stroke
			(width 0)
			(type solid)
		)
		(fill yes)
		(layer "B.Cu")
		(net "SW_P12V_AUX_PVDDIO_P1_FLT")
	)
	(gr_poly
		(pts
			(xy 451.301866 -435.59984) (xy 451.301365 -435.529025) (xy 451.293352 -435.387622) (xy 451.277352 -435.246898)
			(xy 451.253417 -435.107305) (xy 451.221622 -434.96929) (xy 451.18207 -434.833294) (xy 451.134887 -434.699755)
			(xy 451.080225 -434.569098) (xy 451.018259 -434.441743) (xy 450.949186 -434.318098) (xy 450.873229 -434.198559)
			(xy 450.790631 -434.083508) (xy 450.701656 -433.973315) (xy 450.60659 -433.868331) (xy 450.505736 -433.768895)
			(xy 450.399418 -433.675323) (xy 450.287977 -433.587917) (xy 450.171769 -433.506955) (xy 450.051167 -433.432697)
			(xy 449.926556 -433.365381) (xy 449.798337 -433.305223) (xy 449.66692 -433.252416) (xy 449.532726 -433.207127)
			(xy 449.396185 -433.169504) (xy 449.257733 -433.139665) (xy 449.117816 -433.117707) (xy 448.97688 -433.103701)
			(xy 448.835377 -433.09769) (xy 448.693761 -433.099694) (xy 448.552485 -433.109707) (xy 448.412002 -433.127696)
			(xy 448.272762 -433.153605) (xy 448.135211 -433.187349) (xy 447.999788 -433.228822) (xy 447.86693 -433.27789)
			(xy 447.73706 -433.334395) (xy 447.610594 -433.398158) (xy 447.487939 -433.468973) (xy 447.369486 -433.546614)
			(xy 447.255616 -433.630832) (xy 447.146693 -433.721357) (xy 447.043066 -433.8179) (xy 446.945066 -433.92015)
			(xy 446.853009 -434.027782) (xy 446.767188 -434.140449) (xy 446.687878 -434.257791) (xy 446.615335 -434.379432)
			(xy 446.549789 -434.504982) (xy 446.491451 -434.634039) (xy 446.440509 -434.766191) (xy 446.397124 -434.901012)
			(xy 446.361436 -435.038072) (xy 446.33356 -435.176932) (xy 446.313584 -435.317147) (xy 446.301573 -435.458267)
			(xy 446.297565 -435.59984) (xy 446.739528 -435.59984) (xy 446.743513 -435.471743) (xy 446.755455 -435.344142)
			(xy 446.775307 -435.21753) (xy 446.802991 -435.092397) (xy 446.838402 -434.969228) (xy 446.881401 -434.848498)
			(xy 446.931823 -434.730675) (xy 446.989472 -434.616214) (xy 447.054126 -434.505559) (xy 447.125534 -434.399138)
			(xy 447.203421 -434.297362) (xy 447.287484 -434.200625) (xy 447.377398 -434.109301) (xy 447.472816 -434.023744)
			(xy 447.573369 -433.944284) (xy 447.678667 -433.871229) (xy 447.788303 -433.804862) (xy 447.901853 -433.74544)
			(xy 448.018878 -433.693192) (xy 448.138924 -433.64832) (xy 448.261528 -433.610998) (xy 448.386215 -433.581371)
			(xy 448.512503 -433.559553) (xy 448.639903 -433.545628) (xy 448.767922 -433.539651) (xy 448.896066 -433.541644)
			(xy 449.023837 -433.5516) (xy 449.150742 -433.56948) (xy 449.276291 -433.595215) (xy 449.399996 -433.628706)
			(xy 449.52138 -433.669822) (xy 449.639973 -433.718406) (xy 449.755316 -433.774268) (xy 449.866963 -433.837193)
			(xy 449.974482 -433.906938) (xy 450.077458 -433.983232) (xy 450.17549 -434.06578) (xy 450.268201 -434.154263)
			(xy 450.355232 -434.248339) (xy 450.436246 -434.347644) (xy 450.510929 -434.451793) (xy 450.578993 -434.560384)
			(xy 450.640175 -434.672996) (xy 450.694236 -434.789194) (xy 450.74097 -434.908529) (xy 450.780194 -435.030537)
			(xy 450.811756 -435.154749) (xy 450.835536 -435.280682) (xy 450.85144 -435.40785) (xy 450.859408 -435.535761)
			(xy 450.859906 -435.59984) (xy 450.859408 -435.663919) (xy 450.85144 -435.79183) (xy 450.835536 -435.918998)
			(xy 450.811756 -436.044931) (xy 450.780194 -436.169143) (xy 450.74097 -436.291151) (xy 450.694236 -436.410486)
			(xy 450.640175 -436.526684) (xy 450.578993 -436.639296) (xy 450.510929 -436.747887) (xy 450.436246 -436.852036)
			(xy 450.355232 -436.951341) (xy 450.268201 -437.045417) (xy 450.17549 -437.1339) (xy 450.077458 -437.216448)
			(xy 449.974482 -437.292742) (xy 449.866963 -437.362487) (xy 449.755316 -437.425412) (xy 449.639973 -437.481274)
			(xy 449.52138 -437.529858) (xy 449.399996 -437.570974) (xy 449.276291 -437.604465) (xy 449.150742 -437.6302)
			(xy 449.023837 -437.64808) (xy 448.896066 -437.658036) (xy 448.767922 -437.660029) (xy 448.639903 -437.654052)
			(xy 448.512503 -437.640127) (xy 448.386215 -437.618309) (xy 448.261528 -437.588682) (xy 448.138924 -437.55136)
			(xy 448.018878 -437.506488) (xy 447.901853 -437.45424) (xy 447.788303 -437.394818) (xy 447.678667 -437.328451)
			(xy 447.573369 -437.255396) (xy 447.472816 -437.175936) (xy 447.377398 -437.090379) (xy 447.287484 -436.999055)
			(xy 447.203421 -436.902318) (xy 447.125534 -436.800542) (xy 447.054126 -436.694121) (xy 446.989472 -436.583466)
			(xy 446.931823 -436.469005) (xy 446.881401 -436.351182) (xy 446.838402 -436.230452) (xy 446.802991 -436.107283)
			(xy 446.775307 -435.98215) (xy 446.755455 -435.855538) (xy 446.743513 -435.727937) (xy 446.739528 -435.59984)
			(xy 446.297565 -435.59984) (xy 446.301573 -435.741413) (xy 446.313584 -435.882533) (xy 446.33356 -436.022748)
			(xy 446.361436 -436.161608) (xy 446.397124 -436.298668) (xy 446.440509 -436.433489) (xy 446.491451 -436.565641)
			(xy 446.549789 -436.694698) (xy 446.615335 -436.820248) (xy 446.687878 -436.941889) (xy 446.767188 -437.059231)
			(xy 446.853009 -437.171898) (xy 446.945066 -437.27953) (xy 447.043066 -437.38178) (xy 447.146693 -437.478323)
			(xy 447.255616 -437.568848) (xy 447.369486 -437.653066) (xy 447.487939 -437.730707) (xy 447.610594 -437.801522)
			(xy 447.73706 -437.865285) (xy 447.86693 -437.92179) (xy 447.999788 -437.970858) (xy 448.135211 -438.012331)
			(xy 448.272762 -438.046075) (xy 448.412002 -438.071984) (xy 448.552485 -438.089973) (xy 448.693761 -438.099986)
			(xy 448.835377 -438.10199) (xy 448.97688 -438.095979) (xy 449.117816 -438.081973) (xy 449.257733 -438.060015)
			(xy 449.396185 -438.030176) (xy 449.532726 -437.992553) (xy 449.66692 -437.947264) (xy 449.798337 -437.894457)
			(xy 449.926556 -437.834299) (xy 450.051167 -437.766983) (xy 450.171769 -437.692725) (xy 450.287977 -437.611763)
			(xy 450.399418 -437.524357) (xy 450.505736 -437.430785) (xy 450.60659 -437.331349) (xy 450.701656 -437.226365)
			(xy 450.790631 -437.116172) (xy 450.873229 -437.001121) (xy 450.949186 -436.881582) (xy 451.018259 -436.757937)
			(xy 451.080225 -436.630582) (xy 451.134887 -436.499925) (xy 451.18207 -436.366386) (xy 451.221622 -436.23039)
			(xy 451.253417 -436.092375) (xy 451.277352 -435.952782) (xy 451.293352 -435.812058) (xy 451.301365 -435.670655)
		)
		(stroke
			(width 0)
			(type solid)
		)
		(fill yes)
		(layer "B.Cu")
		(net "Net_2198")
	)
	(gr_poly
		(pts
			(arc
				(start 109.430312 -411.174692)
				(mid 109.449835 -411.170791)
				(end 109.46638 -411.159706)
			)
			(arc
				(start 109.882686 -410.7434)
				(mid 109.893797 -410.726866)
				(end 109.897672 -410.707332)
			)
			(arc
				(start 109.897672 -407.581862)
				(mid 109.893771 -407.562339)
				(end 109.882686 -407.545794)
			)
			(arc
				(start 108.757212 -406.42032)
				(mid 108.740678 -406.409209)
				(end 108.721144 -406.405334)
			)
			(xy 104.915716 -406.405334) (xy 104.889554 -406.423876)
			(arc
				(start 104.88422 -406.439116)
				(mid 104.52481 -406.692291)
				(end 104.1654 -406.439116)
			)
			(xy 104.160066 -406.423876) (xy 104.133904 -406.405334)
			(arc
				(start 101.640386 -406.405334)
				(mid 101.620863 -406.409235)
				(end 101.604318 -406.42032)
			)
			(arc
				(start 101.170232 -406.854406)
				(mid 101.159121 -406.87094)
				(end 101.155246 -406.890474)
			)
			(arc
				(start 101.155246 -409.78836)
				(mid 101.159147 -409.807883)
				(end 101.170232 -409.824428)
			)
			(arc
				(start 101.962966 -410.617162)
				(mid 101.9795 -410.628273)
				(end 101.999034 -410.632148)
			)
			(arc
				(start 102.152958 -410.632148)
				(mid 102.178101 -410.62549)
				(end 102.196646 -410.607256)
			)
			(xy 102.248208 -410.520642) (xy 102.248716 -410.493972)
			(arc
				(start 102.242112 -410.482034)
				(mid 102.207614 -410.393864)
				(end 102.195884 -410.299916)
			)
			(arc
				(start 102.195884 -410.299916)
				(mid 102.230753 -410.140575)
				(end 102.32898 -410.010356)
			)
			(xy 102.337616 -410.00299) (xy 102.34676 -409.98267) (xy 102.346506 -409.882848) (xy 102.337108 -409.862782)
			(arc
				(start 102.328472 -409.855416)
				(mid 102.228446 -409.7246)
				(end 102.192836 -409.563824)
			)
			(arc
				(start 102.192836 -408.700224)
				(mid 102.216345 -408.56858)
				(end 102.283768 -408.453082)
			)
			(xy 102.291134 -408.444446) (xy 102.296976 -408.423618) (xy 102.282498 -408.326082) (xy 102.270814 -408.307794)
			(arc
				(start 102.261416 -408.301698)
				(mid 102.132999 -408.163615)
				(end 102.08641 -407.980896)
			)
			(arc
				(start 102.08641 -407.980896)
				(mid 102.467918 -407.599388)
				(end 102.849426 -407.980896)
			)
			(arc
				(start 102.849426 -407.980896)
				(mid 102.825969 -408.112563)
				(end 102.758494 -408.228038)
			)
			(xy 102.751382 -408.23642) (xy 102.74554 -408.257248) (xy 102.760018 -408.355038) (xy 102.771702 -408.373326)
			(arc
				(start 102.7811 -408.379168)
				(mid 102.909672 -408.517342)
				(end 102.95636 -408.700224)
			)
			(arc
				(start 102.95636 -409.563824)
				(mid 102.921417 -409.723327)
				(end 102.82301 -409.853638)
			)
			(xy 102.814374 -409.861004) (xy 102.80523 -409.88107) (xy 102.805484 -409.981146) (xy 102.814882 -410.001212)
			(arc
				(start 102.823518 -410.008324)
				(mid 102.923392 -410.139176)
				(end 102.9589 -410.299916)
			)
			(arc
				(start 102.9589 -410.299916)
				(mid 102.94716 -410.393862)
				(end 102.912672 -410.482034)
			)
			(xy 102.906068 -410.493972) (xy 102.906576 -410.520642)
			(arc
				(start 102.958138 -410.607256)
				(mid 102.976687 -410.625483)
				(end 103.001826 -410.632148)
			)
			(arc
				(start 104.258364 -410.632148)
				(mid 104.277887 -410.628247)
				(end 104.294432 -410.617162)
			)
			(arc
				(start 104.378252 -410.533342)
				(mid 104.389363 -410.516808)
				(end 104.393238 -410.497274)
			)
			(arc
				(start 104.393238 -407.844244)
				(mid 104.397139 -407.824721)
				(end 104.408224 -407.808176)
			)
			(arc
				(start 104.596946 -407.619454)
				(mid 104.61348 -407.608343)
				(end 104.633014 -407.604468)
			)
			(arc
				(start 108.67771 -407.604468)
				(mid 108.697233 -407.608369)
				(end 108.713778 -407.619454)
			)
			(arc
				(start 108.98124 -407.886916)
				(mid 108.992351 -407.90345)
				(end 108.996226 -407.922984)
			)
			(arc
				(start 108.996226 -409.228544)
				(mid 108.992325 -409.248067)
				(end 108.98124 -409.264612)
			)
			(arc
				(start 108.354876 -409.890976)
				(mid 108.343765 -409.90751)
				(end 108.33989 -409.927044)
			)
			(arc
				(start 108.33989 -410.9085)
				(mid 108.343791 -410.928023)
				(end 108.354876 -410.944568)
			)
			(arc
				(start 108.570014 -411.159706)
				(mid 108.586548 -411.170817)
				(end 108.606082 -411.174692)
			)
		)
		(stroke
			(width 0)
			(type solid)
		)
		(fill yes)
		(layer "B.Cu")
		(net "P3V3_9ZXL045_P1_VDD")
	)
	(gr_poly
		(pts
			(xy 147.34032 -186.463178) (xy 149.880574 -183.663082) (xy 149.880574 -165.719252) (xy 149.281134 -165.119812)
			(xy 138.60526 -165.119812) (xy 130.627374 -165.119812) (xy 130.256534 -165.490652) (xy 130.256534 -166.96055)
			(xy 136.804652 -166.96055) (xy 136.808725 -166.904891) (xy 136.82086 -166.850418) (xy 136.840796 -166.798292)
			(xy 136.86811 -166.749624) (xy 136.902218 -166.705452) (xy 136.942395 -166.666717) (xy 136.987783 -166.634245)
			(xy 137.037415 -166.608727) (xy 137.090235 -166.590708) (xy 137.145114 -166.580571) (xy 137.200885 -166.578533)
			(xy 137.256359 -166.584636) (xy 137.310352 -166.598752) (xy 137.361715 -166.620579) (xy 137.409353 -166.649652)
			(xy 137.452249 -166.685351) (xy 137.489491 -166.726915) (xy 137.520285 -166.773459) (xy 137.543973 -166.82399)
			(xy 137.560051 -166.877432) (xy 137.568177 -166.932646) (xy 137.568686 -166.96055) (xy 137.568177 -166.988454)
			(xy 137.560051 -167.043668) (xy 137.543973 -167.09711) (xy 137.520285 -167.147641) (xy 137.489491 -167.194185)
			(xy 137.452249 -167.235749) (xy 137.409353 -167.271448) (xy 137.361715 -167.300521) (xy 137.310352 -167.322348)
			(xy 137.256359 -167.336464) (xy 137.200885 -167.342567) (xy 137.145114 -167.340529) (xy 137.090235 -167.330392)
			(xy 137.037415 -167.312373) (xy 136.987783 -167.286855) (xy 136.942395 -167.254383) (xy 136.902218 -167.215648)
			(xy 136.86811 -167.171476) (xy 136.840796 -167.122808) (xy 136.82086 -167.070682) (xy 136.808725 -167.016209)
			(xy 136.804652 -166.96055) (xy 130.256534 -166.96055) (xy 130.256534 -168.422828) (xy 138.832082 -168.422828)
			(xy 138.832082 -166.891208) (xy 139.282424 -166.440866) (xy 140.08735 -166.440866) (xy 140.567664 -166.92118)
			(xy 140.567664 -168.380664) (xy 140.081254 -168.867074) (xy 139.276328 -168.867074) (xy 138.832082 -168.422828)
			(xy 130.256534 -168.422828) (xy 130.256534 -169.676572) (xy 129.733294 -170.199812) (xy 124.544836 -170.199812)
			(xy 124.534771 -170.200247) (xy 124.516185 -170.207979) (xy 124.508768 -170.214798) (xy 121.119392 -173.604174)
			(xy 121.112558 -173.611577) (xy 121.104852 -173.630175) (xy 121.104406 -173.640242) (xy 121.104406 -176.385474)
			(xy 121.10397 -176.395538) (xy 121.096237 -176.414124) (xy 121.08942 -176.421542) (xy 120.424194 -177.086768)
			(xy 120.416797 -177.093617) (xy 120.398198 -177.101354) (xy 120.388126 -177.101754) (xy 116.63045 -177.101754)
			(xy 116.620385 -177.102188) (xy 116.601799 -177.109921) (xy 116.594382 -177.11674) (xy 113.593372 -180.11775)
			(xy 113.585974 -180.124597) (xy 113.567376 -180.132329) (xy 113.557304 -180.132736) (xy 112.050322 -180.132736)
			(xy 112.040259 -180.133174) (xy 112.021678 -180.140912) (xy 112.014254 -180.147722) (xy 111.88954 -180.272436)
			(xy 111.882695 -180.279835) (xy 111.874967 -180.298433) (xy 111.874554 -180.308504) (xy 111.874554 -182.736998)
			(xy 112.391952 -182.736998) (xy 112.39246 -182.708271) (xy 112.401061 -182.651465) (xy 112.418069 -182.596586)
			(xy 112.4431 -182.544871) (xy 112.475591 -182.497486) (xy 112.494822 -182.47614) (xy 112.504899 -182.464609)
			(xy 112.518248 -182.437063) (xy 112.522835 -182.406799) (xy 112.518247 -182.376534) (xy 112.504898 -182.348988)
			(xy 112.494822 -182.337456) (xy 112.475587 -182.31611) (xy 112.443069 -182.268739) (xy 112.418027 -182.217026)
			(xy 112.401025 -182.162141) (xy 112.39245 -182.105327) (xy 112.391952 -182.076598) (xy 112.3924 -182.049326)
			(xy 112.400162 -181.995338) (xy 112.41553 -181.943004) (xy 112.438188 -181.89339) (xy 112.467678 -181.847506)
			(xy 112.503397 -181.806285) (xy 112.544619 -181.770568) (xy 112.590504 -181.741081) (xy 112.640119 -181.718424)
			(xy 112.692454 -181.703059) (xy 112.746442 -181.695299) (xy 112.773714 -181.694836) (xy 112.802441 -181.695341)
			(xy 112.859247 -181.703943) (xy 112.914126 -181.720952) (xy 112.965841 -181.745984) (xy 113.013225 -181.778475)
			(xy 113.034572 -181.797706) (xy 113.046106 -181.807778) (xy 113.073652 -181.82112) (xy 113.103914 -181.825705)
			(xy 113.134176 -181.82112) (xy 113.161722 -181.807778) (xy 113.173256 -181.797706) (xy 113.194595 -181.778463)
			(xy 113.241968 -181.745947) (xy 113.293683 -181.720906) (xy 113.348569 -181.703906) (xy 113.405384 -181.695333)
			(xy 113.434114 -181.694836) (xy 113.461384 -181.695311) (xy 113.515368 -181.703075) (xy 113.567697 -181.718442)
			(xy 113.617307 -181.7411) (xy 113.663188 -181.770587) (xy 113.704405 -181.806303) (xy 113.74012 -181.847522)
			(xy 113.769606 -181.893403) (xy 113.792262 -181.943014) (xy 113.807628 -181.995344) (xy 113.815389 -182.049328)
			(xy 113.815876 -182.076598) (xy 113.815358 -182.105325) (xy 113.806758 -182.16213) (xy 113.789752 -182.217009)
			(xy 113.764724 -182.268723) (xy 113.732236 -182.316109) (xy 113.713006 -182.337456) (xy 113.702938 -182.348992)
			(xy 113.689599 -182.376538) (xy 113.685015 -182.406799) (xy 113.689598 -182.437059) (xy 113.702937 -182.464605)
			(xy 113.713006 -182.47614) (xy 113.732244 -182.497483) (xy 113.76476 -182.544855) (xy 113.789802 -182.596569)
			(xy 113.806802 -182.651454) (xy 113.815377 -182.708269) (xy 113.815876 -182.736998) (xy 113.815374 -182.764267)
			(xy 113.807613 -182.818249) (xy 113.792248 -182.870577) (xy 113.769593 -182.920187) (xy 113.740109 -182.966067)
			(xy 113.704395 -183.007284) (xy 113.66318 -183.042999) (xy 113.617301 -183.072486) (xy 113.567692 -183.095143)
			(xy 113.515365 -183.110509) (xy 113.461383 -183.118273) (xy 113.434114 -183.11876) (xy 113.405388 -183.118239)
			(xy 113.348582 -183.109641) (xy 113.293703 -183.092636) (xy 113.241988 -183.067607) (xy 113.194603 -183.03512)
			(xy 113.173256 -183.01589) (xy 113.161722 -183.005818) (xy 113.134176 -182.992476) (xy 113.103914 -182.987891)
			(xy 113.073652 -182.992476) (xy 113.046106 -183.005818) (xy 113.034572 -183.01589) (xy 113.013221 -183.035119)
			(xy 112.965852 -183.067637) (xy 112.91414 -183.092681) (xy 112.859256 -183.109684) (xy 112.802443 -183.118261)
			(xy 112.773714 -183.11876) (xy 112.746443 -183.118285) (xy 112.692457 -183.110525) (xy 112.640124 -183.095161)
			(xy 112.590511 -183.072505) (xy 112.544627 -183.043018) (xy 112.503407 -183.007302) (xy 112.467689 -182.966083)
			(xy 112.438201 -182.9202) (xy 112.415544 -182.870587) (xy 112.400177 -182.818255) (xy 112.392415 -182.764269)
			(xy 112.391952 -182.736998) (xy 111.874554 -182.736998) (xy 111.874554 -185.85561) (xy 111.87498 -185.865678)
			(xy 111.882703 -185.884275) (xy 111.88954 -185.891678) (xy 112.319308 -186.321446) (xy 112.326146 -186.328847)
			(xy 112.333863 -186.347445) (xy 112.334294 -186.357514) (xy 112.334294 -201.27849) (xy 112.334715 -201.288561)
			(xy 112.342426 -201.307169) (xy 112.34928 -201.314558) (xy 113.104676 -202.069954) (xy 113.112076 -202.076794)
			(xy 113.130675 -202.084508) (xy 113.140744 -202.08494) (xy 122.45594 -202.08494) (xy 122.465592 -202.094592)
			(xy 124.624338 -202.094592)
		)
		(stroke
			(width 0)
			(type solid)
		)
		(fill yes)
		(layer "B.Cu")
		(net "PVDDCR_SOC_P1")
	)
	(gr_poly
		(pts
			(xy 73.328022 -258.880356) (xy 73.327519 -258.796413) (xy 73.31947 -258.628721) (xy 73.30339 -258.461608)
			(xy 73.279316 -258.295458) (xy 73.247304 -258.130653) (xy 73.207427 -257.967572) (xy 73.159777 -257.806591)
			(xy 73.104464 -257.64808) (xy 73.041615 -257.492403) (xy 72.971374 -257.339918) (xy 72.893903 -257.190976)
			(xy 72.80938 -257.04592) (xy 72.717999 -256.905083) (xy 72.619971 -256.768789) (xy 72.515521 -256.637352)
			(xy 72.40489 -256.511074) (xy 72.288332 -256.390245) (xy 72.166114 -256.275144) (xy 72.038519 -256.166035)
			(xy 71.905839 -256.063169) (xy 71.768379 -255.966782) (xy 71.626457 -255.877097) (xy 71.480398 -255.794319)
			(xy 71.330538 -255.71864) (xy 71.177222 -255.650232) (xy 71.020802 -255.589254) (xy 70.861639 -255.535845)
			(xy 70.700098 -255.490129) (xy 70.536551 -255.45221) (xy 70.371374 -255.422177) (xy 70.204947 -255.400097)
			(xy 70.037653 -255.386022) (xy 69.869876 -255.379984) (xy 69.702003 -255.381997) (xy 69.53442 -255.392057)
			(xy 69.367511 -255.410139) (xy 69.201662 -255.436203) (xy 69.037252 -255.470189) (xy 68.874662 -255.512018)
			(xy 68.714263 -255.561595) (xy 68.556427 -255.618805) (xy 68.401514 -255.683517) (xy 68.249883 -255.755581)
			(xy 68.10188 -255.834832) (xy 67.957848 -255.921089) (xy 67.818117 -256.014151) (xy 67.683009 -256.113806)
			(xy 67.552833 -256.219825) (xy 67.427891 -256.331962) (xy 67.308469 -256.449961) (xy 67.194841 -256.57355)
			(xy 67.08727 -256.702444) (xy 66.986002 -256.836348) (xy 66.89127 -256.974953) (xy 66.803293 -257.117941)
			(xy 66.722273 -257.264982) (xy 66.648395 -257.415739) (xy 66.581831 -257.569864) (xy 66.522733 -257.727004)
			(xy 66.471236 -257.886796) (xy 66.427461 -258.048873) (xy 66.391506 -258.212863) (xy 66.363455 -258.378389)
			(xy 66.343372 -258.545068) (xy 66.331304 -258.712519) (xy 66.327279 -258.880356) (xy 67.312799 -258.880356)
			(xy 67.316827 -258.738064) (xy 67.328899 -258.596228) (xy 67.348976 -258.455301) (xy 67.376994 -258.315737)
			(xy 67.412863 -258.177981) (xy 67.456468 -258.042475) (xy 67.507669 -257.909653) (xy 67.566303 -257.77994)
			(xy 67.632181 -257.653753) (xy 67.705093 -257.531494) (xy 67.784805 -257.413557) (xy 67.871062 -257.300318)
			(xy 67.963586 -257.19214) (xy 68.062083 -257.08937) (xy 68.166237 -256.992337) (xy 68.275713 -256.901353)
			(xy 68.390161 -256.816707) (xy 68.509215 -256.738672) (xy 68.632493 -256.667498) (xy 68.7596 -256.603411)
			(xy 68.890129 -256.546619) (xy 69.023663 -256.497302) (xy 69.159772 -256.455619) (xy 69.298022 -256.421703)
			(xy 69.437969 -256.395663) (xy 69.579165 -256.377582) (xy 69.721158 -256.367519) (xy 69.863493 -256.365504)
			(xy 70.005714 -256.371546) (xy 70.147365 -256.385624) (xy 70.287993 -256.407693) (xy 70.427147 -256.437683)
			(xy 70.564382 -256.475498) (xy 70.699257 -256.521016) (xy 70.831341 -256.574092) (xy 70.960211 -256.634555)
			(xy 71.085454 -256.702212) (xy 71.206668 -256.776847) (xy 71.323466 -256.85822) (xy 71.435473 -256.94607)
			(xy 71.542331 -257.040117) (xy 71.643696 -257.140058) (xy 71.739245 -257.245574) (xy 71.828672 -257.356327)
			(xy 71.91169 -257.471961) (xy 71.988032 -257.592108) (xy 72.057455 -257.71638) (xy 72.119736 -257.844382)
			(xy 72.174676 -257.975702) (xy 72.222098 -258.109919) (xy 72.261851 -258.246605) (xy 72.293807 -258.385321)
			(xy 72.317864 -258.525622) (xy 72.333945 -258.66706) (xy 72.341998 -258.809181) (xy 72.342502 -258.880356)
			(xy 72.341998 -258.951531) (xy 72.333945 -259.093652) (xy 72.317864 -259.23509) (xy 72.293807 -259.375391)
			(xy 72.261851 -259.514107) (xy 72.222098 -259.650793) (xy 72.174676 -259.78501) (xy 72.119736 -259.91633)
			(xy 72.057455 -260.044332) (xy 71.988032 -260.168604) (xy 71.91169 -260.288751) (xy 71.828672 -260.404385)
			(xy 71.739245 -260.515138) (xy 71.643696 -260.620654) (xy 71.542331 -260.720595) (xy 71.435473 -260.814642)
			(xy 71.323466 -260.902492) (xy 71.206668 -260.983865) (xy 71.085454 -261.0585) (xy 70.960211 -261.126157)
			(xy 70.831341 -261.18662) (xy 70.699257 -261.239696) (xy 70.564382 -261.285214) (xy 70.427147 -261.323029)
			(xy 70.287993 -261.353019) (xy 70.147365 -261.375088) (xy 70.005714 -261.389166) (xy 69.863493 -261.395208)
			(xy 69.721158 -261.393193) (xy 69.579165 -261.38313) (xy 69.437969 -261.365049) (xy 69.298022 -261.339009)
			(xy 69.159772 -261.305093) (xy 69.023663 -261.26341) (xy 68.890129 -261.214093) (xy 68.7596 -261.157301)
			(xy 68.632493 -261.093214) (xy 68.509215 -261.02204) (xy 68.390161 -260.944005) (xy 68.275713 -260.859359)
			(xy 68.166237 -260.768375) (xy 68.062083 -260.671342) (xy 67.963586 -260.568572) (xy 67.871062 -260.460394)
			(xy 67.784805 -260.347155) (xy 67.705093 -260.229218) (xy 67.632181 -260.106959) (xy 67.566303 -259.980772)
			(xy 67.507669 -259.851059) (xy 67.456468 -259.718237) (xy 67.412863 -259.582731) (xy 67.376994 -259.444975)
			(xy 67.348976 -259.305411) (xy 67.328899 -259.164484) (xy 67.316827 -259.022648) (xy 67.312799 -258.880356)
			(xy 66.327279 -258.880356) (xy 66.331304 -259.048193) (xy 66.343372 -259.215644) (xy 66.363455 -259.382323)
			(xy 66.391506 -259.547849) (xy 66.427461 -259.711839) (xy 66.471236 -259.873916) (xy 66.522733 -260.033708)
			(xy 66.581831 -260.190848) (xy 66.648395 -260.344973) (xy 66.722273 -260.49573) (xy 66.803293 -260.642771)
			(xy 66.89127 -260.785759) (xy 66.986002 -260.924364) (xy 67.08727 -261.058268) (xy 67.194841 -261.187162)
			(xy 67.308469 -261.310751) (xy 67.427891 -261.42875) (xy 67.552833 -261.540887) (xy 67.683009 -261.646906)
			(xy 67.818117 -261.746561) (xy 67.957848 -261.839623) (xy 68.10188 -261.92588) (xy 68.249883 -262.005131)
			(xy 68.401514 -262.077195) (xy 68.556427 -262.141907) (xy 68.714263 -262.199117) (xy 68.874662 -262.248694)
			(xy 69.037252 -262.290523) (xy 69.201662 -262.324509) (xy 69.367511 -262.350573) (xy 69.53442 -262.368655)
			(xy 69.702003 -262.378715) (xy 69.869876 -262.380728) (xy 70.037653 -262.37469) (xy 70.204947 -262.360615)
			(xy 70.371374 -262.338535) (xy 70.536551 -262.308502) (xy 70.700098 -262.270583) (xy 70.861639 -262.224867)
			(xy 71.020802 -262.171458) (xy 71.177222 -262.11048) (xy 71.330538 -262.042072) (xy 71.480398 -261.966393)
			(xy 71.626457 -261.883615) (xy 71.768379 -261.79393) (xy 71.905839 -261.697543) (xy 72.038519 -261.594677)
			(xy 72.166114 -261.485568) (xy 72.288332 -261.370467) (xy 72.40489 -261.249638) (xy 72.515521 -261.12336)
			(xy 72.619971 -260.991923) (xy 72.717999 -260.855629) (xy 72.80938 -260.714792) (xy 72.893903 -260.569736)
			(xy 72.971374 -260.420794) (xy 73.041615 -260.268309) (xy 73.104464 -260.112632) (xy 73.159777 -259.954121)
			(xy 73.207427 -259.79314) (xy 73.247304 -259.630059) (xy 73.279316 -259.465254) (xy 73.30339 -259.299104)
			(xy 73.31947 -259.131991) (xy 73.327519 -258.964299)
		)
		(stroke
			(width 0)
			(type solid)
		)
		(fill yes)
		(layer "B.Cu")
		(net "Net_1973")
	)
	(gr_poly
		(pts
			(xy 84.827872 -304.780442) (xy 84.827369 -304.696506) (xy 84.81932 -304.528826) (xy 84.803242 -304.361724)
			(xy 84.77917 -304.195586) (xy 84.74716 -304.030793) (xy 84.707286 -303.867725) (xy 84.65964 -303.706755)
			(xy 84.60433 -303.548255) (xy 84.541486 -303.392589) (xy 84.47125 -303.240115) (xy 84.393784 -303.091184)
			(xy 84.309267 -302.946139) (xy 84.217893 -302.805312) (xy 84.119873 -302.669028) (xy 84.01543 -302.537601)
			(xy 83.904807 -302.411332) (xy 83.788257 -302.290512) (xy 83.666049 -302.175419) (xy 83.538462 -302.066318)
			(xy 83.405792 -301.963459) (xy 83.268343 -301.86708) (xy 83.12643 -301.777401) (xy 82.980382 -301.694629)
			(xy 82.830533 -301.618955) (xy 82.677228 -301.550552) (xy 82.520819 -301.489578) (xy 82.361668 -301.436174)
			(xy 82.200139 -301.390461) (xy 82.036603 -301.352545) (xy 81.871438 -301.322514) (xy 81.705024 -301.300436)
			(xy 81.537742 -301.286362) (xy 81.369977 -301.280324) (xy 81.202116 -301.282337) (xy 81.034545 -301.292396)
			(xy 80.867649 -301.310477) (xy 80.701811 -301.336539) (xy 80.537414 -301.370523) (xy 80.374835 -301.412349)
			(xy 80.214448 -301.461922) (xy 80.056623 -301.519128) (xy 79.901722 -301.583834) (xy 79.750101 -301.655894)
			(xy 79.60211 -301.735139) (xy 79.458088 -301.821389) (xy 79.318367 -301.914445) (xy 79.183268 -302.014093)
			(xy 79.053102 -302.120104) (xy 78.928169 -302.232233) (xy 78.808755 -302.350223) (xy 78.695136 -302.473803)
			(xy 78.587572 -302.602688) (xy 78.486312 -302.736583) (xy 78.391587 -302.875178) (xy 78.303617 -303.018155)
			(xy 78.222602 -303.165185) (xy 78.14873 -303.315931) (xy 78.082171 -303.470045) (xy 78.023077 -303.627173)
			(xy 77.971584 -303.786954) (xy 77.927811 -303.94902) (xy 77.891859 -304.112998) (xy 77.86381 -304.278511)
			(xy 77.843729 -304.445179) (xy 77.831662 -304.612617) (xy 77.827637 -304.780442) (xy 78.813157 -304.780442)
			(xy 78.817184 -304.638164) (xy 78.829255 -304.496342) (xy 78.84933 -304.35543) (xy 78.877345 -304.21588)
			(xy 78.913211 -304.078138) (xy 78.956811 -303.942646) (xy 79.008007 -303.809837) (xy 79.066635 -303.680137)
			(xy 79.132507 -303.553963) (xy 79.205411 -303.431717) (xy 79.285115 -303.313791) (xy 79.371363 -303.200563)
			(xy 79.463879 -303.092397) (xy 79.562366 -302.989637) (xy 79.666509 -302.892614) (xy 79.775974 -302.801638)
			(xy 79.89041 -302.717002) (xy 80.009452 -302.638974) (xy 80.132718 -302.567807) (xy 80.259812 -302.503727)
			(xy 80.390328 -302.446941) (xy 80.523848 -302.397629) (xy 80.659944 -302.35595) (xy 80.798179 -302.322038)
			(xy 80.938112 -302.296) (xy 81.079294 -302.277921) (xy 81.221273 -302.267858) (xy 81.363593 -302.265844)
			(xy 81.5058 -302.271885) (xy 81.647437 -302.285962) (xy 81.78805 -302.308029) (xy 81.92719 -302.338016)
			(xy 82.064411 -302.375827) (xy 82.199273 -302.42134) (xy 82.331344 -302.474411) (xy 82.460201 -302.534868)
			(xy 82.585431 -302.602518) (xy 82.706633 -302.677146) (xy 82.823419 -302.75851) (xy 82.935415 -302.846352)
			(xy 83.042261 -302.940389) (xy 83.143617 -303.04032) (xy 83.239156 -303.145825) (xy 83.328574 -303.256567)
			(xy 83.411583 -303.37219) (xy 83.487918 -303.492324) (xy 83.557334 -303.616584) (xy 83.619609 -303.744572)
			(xy 83.674543 -303.875879) (xy 83.72196 -304.010083) (xy 83.761709 -304.146755) (xy 83.793662 -304.285457)
			(xy 83.817716 -304.425744) (xy 83.833796 -304.567168) (xy 83.841848 -304.709275) (xy 83.842352 -304.780442)
			(xy 83.841848 -304.851609) (xy 83.833796 -304.993716) (xy 83.817716 -305.13514) (xy 83.793662 -305.275427)
			(xy 83.761709 -305.414129) (xy 83.72196 -305.550801) (xy 83.674543 -305.685005) (xy 83.619609 -305.816312)
			(xy 83.557334 -305.9443) (xy 83.487918 -306.06856) (xy 83.411583 -306.188694) (xy 83.328574 -306.304317)
			(xy 83.239156 -306.415059) (xy 83.143617 -306.520564) (xy 83.042261 -306.620495) (xy 82.935415 -306.714532)
			(xy 82.823419 -306.802374) (xy 82.706633 -306.883738) (xy 82.585431 -306.958366) (xy 82.460201 -307.026016)
			(xy 82.331344 -307.086473) (xy 82.199273 -307.139544) (xy 82.064411 -307.185057) (xy 81.92719 -307.222868)
			(xy 81.78805 -307.252855) (xy 81.647437 -307.274922) (xy 81.5058 -307.288999) (xy 81.363593 -307.29504)
			(xy 81.221273 -307.293026) (xy 81.079294 -307.282963) (xy 80.938112 -307.264884) (xy 80.798179 -307.238846)
			(xy 80.659944 -307.204934) (xy 80.523848 -307.163255) (xy 80.390328 -307.113943) (xy 80.259812 -307.057157)
			(xy 80.132718 -306.993077) (xy 80.009452 -306.92191) (xy 79.89041 -306.843882) (xy 79.775974 -306.759246)
			(xy 79.666509 -306.66827) (xy 79.562366 -306.571247) (xy 79.463879 -306.468487) (xy 79.371363 -306.360321)
			(xy 79.285115 -306.247093) (xy 79.205411 -306.129167) (xy 79.132507 -306.006921) (xy 79.066635 -305.880747)
			(xy 79.008007 -305.751047) (xy 78.956811 -305.618238) (xy 78.913211 -305.482746) (xy 78.877345 -305.345004)
			(xy 78.84933 -305.205454) (xy 78.829255 -305.064542) (xy 78.817184 -304.92272) (xy 78.813157 -304.780442)
			(xy 77.827637 -304.780442) (xy 77.831662 -304.948267) (xy 77.843729 -305.115705) (xy 77.86381 -305.282373)
			(xy 77.891859 -305.447886) (xy 77.927811 -305.611864) (xy 77.971584 -305.77393) (xy 78.023077 -305.933711)
			(xy 78.082171 -306.090839) (xy 78.14873 -306.244953) (xy 78.222602 -306.395699) (xy 78.303617 -306.542729)
			(xy 78.391587 -306.685706) (xy 78.486312 -306.824301) (xy 78.587572 -306.958196) (xy 78.695136 -307.087081)
			(xy 78.808755 -307.210661) (xy 78.928169 -307.328651) (xy 79.053102 -307.44078) (xy 79.183268 -307.546791)
			(xy 79.318367 -307.646439) (xy 79.458088 -307.739495) (xy 79.60211 -307.825745) (xy 79.750101 -307.90499)
			(xy 79.901722 -307.97705) (xy 80.056623 -308.041756) (xy 80.214448 -308.098962) (xy 80.374835 -308.148535)
			(xy 80.537414 -308.190361) (xy 80.701811 -308.224345) (xy 80.867649 -308.250407) (xy 81.034545 -308.268488)
			(xy 81.202116 -308.278547) (xy 81.369977 -308.28056) (xy 81.537742 -308.274522) (xy 81.705024 -308.260448)
			(xy 81.871438 -308.23837) (xy 82.036603 -308.208339) (xy 82.200139 -308.170423) (xy 82.361668 -308.12471)
			(xy 82.520819 -308.071306) (xy 82.677228 -308.010332) (xy 82.830533 -307.941929) (xy 82.980382 -307.866255)
			(xy 83.12643 -307.783483) (xy 83.268343 -307.693804) (xy 83.405792 -307.597425) (xy 83.538462 -307.494566)
			(xy 83.666049 -307.385465) (xy 83.788257 -307.270372) (xy 83.904807 -307.149552) (xy 84.01543 -307.023283)
			(xy 84.119873 -306.891856) (xy 84.217893 -306.755572) (xy 84.309267 -306.614745) (xy 84.393784 -306.4697)
			(xy 84.47125 -306.320769) (xy 84.541486 -306.168295) (xy 84.60433 -306.012629) (xy 84.65964 -305.854129)
			(xy 84.707286 -305.693159) (xy 84.74716 -305.530091) (xy 84.77917 -305.365298) (xy 84.803242 -305.19916)
			(xy 84.81932 -305.032058) (xy 84.827369 -304.864378)
		)
		(stroke
			(width 0)
			(type solid)
		)
		(fill yes)
		(layer "B.Cu")
		(net "Net_1972")
	)
	(gr_poly
		(pts
			(xy 84.827872 -212.98027) (xy 84.827369 -212.896334) (xy 84.81932 -212.728654) (xy 84.803242 -212.561552)
			(xy 84.77917 -212.395414) (xy 84.74716 -212.230621) (xy 84.707286 -212.067553) (xy 84.65964 -211.906583)
			(xy 84.60433 -211.748083) (xy 84.541486 -211.592417) (xy 84.47125 -211.439943) (xy 84.393784 -211.291012)
			(xy 84.309267 -211.145967) (xy 84.217893 -211.00514) (xy 84.119873 -210.868856) (xy 84.01543 -210.737429)
			(xy 83.904807 -210.61116) (xy 83.788257 -210.49034) (xy 83.666049 -210.375247) (xy 83.538462 -210.266146)
			(xy 83.405792 -210.163287) (xy 83.268343 -210.066908) (xy 83.12643 -209.977229) (xy 82.980382 -209.894457)
			(xy 82.830533 -209.818783) (xy 82.677228 -209.75038) (xy 82.520819 -209.689406) (xy 82.361668 -209.636002)
			(xy 82.200139 -209.590289) (xy 82.036603 -209.552373) (xy 81.871438 -209.522342) (xy 81.705024 -209.500264)
			(xy 81.537742 -209.48619) (xy 81.369977 -209.480152) (xy 81.202116 -209.482165) (xy 81.034545 -209.492224)
			(xy 80.867649 -209.510305) (xy 80.701811 -209.536367) (xy 80.537414 -209.570351) (xy 80.374835 -209.612177)
			(xy 80.214448 -209.66175) (xy 80.056623 -209.718956) (xy 79.901722 -209.783662) (xy 79.750101 -209.855722)
			(xy 79.60211 -209.934967) (xy 79.458088 -210.021217) (xy 79.318367 -210.114273) (xy 79.183268 -210.213921)
			(xy 79.053102 -210.319932) (xy 78.928169 -210.432061) (xy 78.808755 -210.550051) (xy 78.695136 -210.673631)
			(xy 78.587572 -210.802516) (xy 78.486312 -210.936411) (xy 78.391587 -211.075006) (xy 78.303617 -211.217983)
			(xy 78.222602 -211.365013) (xy 78.14873 -211.515759) (xy 78.082171 -211.669873) (xy 78.023077 -211.827001)
			(xy 77.971584 -211.986782) (xy 77.927811 -212.148848) (xy 77.891859 -212.312826) (xy 77.86381 -212.478339)
			(xy 77.843729 -212.645007) (xy 77.831662 -212.812445) (xy 77.827637 -212.98027) (xy 78.813157 -212.98027)
			(xy 78.817184 -212.837992) (xy 78.829255 -212.69617) (xy 78.84933 -212.555258) (xy 78.877345 -212.415708)
			(xy 78.913211 -212.277966) (xy 78.956811 -212.142474) (xy 79.008007 -212.009665) (xy 79.066635 -211.879965)
			(xy 79.132507 -211.753791) (xy 79.205411 -211.631545) (xy 79.285115 -211.513619) (xy 79.371363 -211.400391)
			(xy 79.463879 -211.292225) (xy 79.562366 -211.189465) (xy 79.666509 -211.092442) (xy 79.775974 -211.001466)
			(xy 79.89041 -210.91683) (xy 80.009452 -210.838802) (xy 80.132718 -210.767635) (xy 80.259812 -210.703555)
			(xy 80.390328 -210.646769) (xy 80.523848 -210.597457) (xy 80.659944 -210.555778) (xy 80.798179 -210.521866)
			(xy 80.938112 -210.495828) (xy 81.079294 -210.477749) (xy 81.221273 -210.467686) (xy 81.363593 -210.465672)
			(xy 81.5058 -210.471713) (xy 81.647437 -210.48579) (xy 81.78805 -210.507857) (xy 81.92719 -210.537844)
			(xy 82.064411 -210.575655) (xy 82.199273 -210.621168) (xy 82.331344 -210.674239) (xy 82.460201 -210.734696)
			(xy 82.585431 -210.802346) (xy 82.706633 -210.876974) (xy 82.823419 -210.958338) (xy 82.935415 -211.04618)
			(xy 83.042261 -211.140217) (xy 83.143617 -211.240148) (xy 83.239156 -211.345653) (xy 83.328574 -211.456395)
			(xy 83.411583 -211.572018) (xy 83.487918 -211.692152) (xy 83.557334 -211.816412) (xy 83.619609 -211.9444)
			(xy 83.674543 -212.075707) (xy 83.72196 -212.209911) (xy 83.761709 -212.346583) (xy 83.793662 -212.485285)
			(xy 83.817716 -212.625572) (xy 83.833796 -212.766996) (xy 83.841848 -212.909103) (xy 83.842352 -212.98027)
			(xy 83.841848 -213.051437) (xy 83.833796 -213.193544) (xy 83.817716 -213.334968) (xy 83.793662 -213.475255)
			(xy 83.761709 -213.613957) (xy 83.72196 -213.750629) (xy 83.674543 -213.884833) (xy 83.619609 -214.01614)
			(xy 83.557334 -214.144128) (xy 83.487918 -214.268388) (xy 83.411583 -214.388522) (xy 83.328574 -214.504145)
			(xy 83.239156 -214.614887) (xy 83.143617 -214.720392) (xy 83.042261 -214.820323) (xy 82.935415 -214.91436)
			(xy 82.823419 -215.002202) (xy 82.706633 -215.083566) (xy 82.585431 -215.158194) (xy 82.460201 -215.225844)
			(xy 82.331344 -215.286301) (xy 82.199273 -215.339372) (xy 82.064411 -215.384885) (xy 81.92719 -215.422696)
			(xy 81.78805 -215.452683) (xy 81.647437 -215.47475) (xy 81.5058 -215.488827) (xy 81.363593 -215.494868)
			(xy 81.221273 -215.492854) (xy 81.079294 -215.482791) (xy 80.938112 -215.464712) (xy 80.798179 -215.438674)
			(xy 80.659944 -215.404762) (xy 80.523848 -215.363083) (xy 80.390328 -215.313771) (xy 80.259812 -215.256985)
			(xy 80.132718 -215.192905) (xy 80.009452 -215.121738) (xy 79.89041 -215.04371) (xy 79.775974 -214.959074)
			(xy 79.666509 -214.868098) (xy 79.562366 -214.771075) (xy 79.463879 -214.668315) (xy 79.371363 -214.560149)
			(xy 79.285115 -214.446921) (xy 79.205411 -214.328995) (xy 79.132507 -214.206749) (xy 79.066635 -214.080575)
			(xy 79.008007 -213.950875) (xy 78.956811 -213.818066) (xy 78.913211 -213.682574) (xy 78.877345 -213.544832)
			(xy 78.84933 -213.405282) (xy 78.829255 -213.26437) (xy 78.817184 -213.122548) (xy 78.813157 -212.98027)
			(xy 77.827637 -212.98027) (xy 77.831662 -213.148095) (xy 77.843729 -213.315533) (xy 77.86381 -213.482201)
			(xy 77.891859 -213.647714) (xy 77.927811 -213.811692) (xy 77.971584 -213.973758) (xy 78.023077 -214.133539)
			(xy 78.082171 -214.290667) (xy 78.14873 -214.444781) (xy 78.222602 -214.595527) (xy 78.303617 -214.742557)
			(xy 78.391587 -214.885534) (xy 78.486312 -215.024129) (xy 78.587572 -215.158024) (xy 78.695136 -215.286909)
			(xy 78.808755 -215.410489) (xy 78.928169 -215.528479) (xy 79.053102 -215.640608) (xy 79.183268 -215.746619)
			(xy 79.318367 -215.846267) (xy 79.458088 -215.939323) (xy 79.60211 -216.025573) (xy 79.750101 -216.104818)
			(xy 79.901722 -216.176878) (xy 80.056623 -216.241584) (xy 80.214448 -216.29879) (xy 80.374835 -216.348363)
			(xy 80.537414 -216.390189) (xy 80.701811 -216.424173) (xy 80.867649 -216.450235) (xy 81.034545 -216.468316)
			(xy 81.202116 -216.478375) (xy 81.369977 -216.480388) (xy 81.537742 -216.47435) (xy 81.705024 -216.460276)
			(xy 81.871438 -216.438198) (xy 82.036603 -216.408167) (xy 82.200139 -216.370251) (xy 82.361668 -216.324538)
			(xy 82.520819 -216.271134) (xy 82.677228 -216.21016) (xy 82.830533 -216.141757) (xy 82.980382 -216.066083)
			(xy 83.12643 -215.983311) (xy 83.268343 -215.893632) (xy 83.405792 -215.797253) (xy 83.538462 -215.694394)
			(xy 83.666049 -215.585293) (xy 83.788257 -215.4702) (xy 83.904807 -215.34938) (xy 84.01543 -215.223111)
			(xy 84.119873 -215.091684) (xy 84.217893 -214.9554) (xy 84.309267 -214.814573) (xy 84.393784 -214.669528)
			(xy 84.47125 -214.520597) (xy 84.541486 -214.368123) (xy 84.60433 -214.212457) (xy 84.65964 -214.053957)
			(xy 84.707286 -213.892987) (xy 84.74716 -213.729919) (xy 84.77917 -213.565126) (xy 84.803242 -213.398988)
			(xy 84.81932 -213.231886) (xy 84.827369 -213.064206)
		)
		(stroke
			(width 0)
			(type solid)
		)
		(fill yes)
		(layer "B.Cu")
		(net "Net_1974")
	)
	(gr_poly
		(pts
			(xy 146.027902 -304.780442) (xy 146.027399 -304.696499) (xy 146.01935 -304.528807) (xy 146.00327 -304.361694)
			(xy 145.979196 -304.195544) (xy 145.947184 -304.030739) (xy 145.907307 -303.867658) (xy 145.859657 -303.706677)
			(xy 145.804344 -303.548166) (xy 145.741495 -303.392489) (xy 145.671254 -303.240004) (xy 145.593783 -303.091062)
			(xy 145.50926 -302.946006) (xy 145.417879 -302.805169) (xy 145.319851 -302.668875) (xy 145.215401 -302.537438)
			(xy 145.10477 -302.41116) (xy 144.988212 -302.290331) (xy 144.865994 -302.17523) (xy 144.738399 -302.066121)
			(xy 144.605719 -301.963255) (xy 144.468259 -301.866868) (xy 144.326337 -301.777183) (xy 144.180278 -301.694405)
			(xy 144.030418 -301.618726) (xy 143.877102 -301.550318) (xy 143.720682 -301.48934) (xy 143.561519 -301.435931)
			(xy 143.399978 -301.390215) (xy 143.236431 -301.352296) (xy 143.071254 -301.322263) (xy 142.904827 -301.300183)
			(xy 142.737533 -301.286108) (xy 142.569756 -301.28007) (xy 142.401883 -301.282083) (xy 142.2343 -301.292143)
			(xy 142.067391 -301.310225) (xy 141.901542 -301.336289) (xy 141.737132 -301.370275) (xy 141.574542 -301.412104)
			(xy 141.414143 -301.461681) (xy 141.256307 -301.518891) (xy 141.101394 -301.583603) (xy 140.949763 -301.655667)
			(xy 140.80176 -301.734918) (xy 140.657728 -301.821175) (xy 140.517997 -301.914237) (xy 140.382889 -302.013892)
			(xy 140.252713 -302.119911) (xy 140.127771 -302.232048) (xy 140.008349 -302.350047) (xy 139.894721 -302.473636)
			(xy 139.78715 -302.60253) (xy 139.685882 -302.736434) (xy 139.59115 -302.875039) (xy 139.503173 -303.018027)
			(xy 139.422153 -303.165068) (xy 139.348275 -303.315825) (xy 139.281711 -303.46995) (xy 139.222613 -303.62709)
			(xy 139.171116 -303.786882) (xy 139.127341 -303.948959) (xy 139.091386 -304.112949) (xy 139.063335 -304.278475)
			(xy 139.043252 -304.445154) (xy 139.031184 -304.612605) (xy 139.027159 -304.780442) (xy 140.012424 -304.780442)
			(xy 140.016453 -304.638135) (xy 140.028526 -304.496285) (xy 140.048605 -304.355344) (xy 140.076626 -304.215766)
			(xy 140.112498 -304.077996) (xy 140.156108 -303.942476) (xy 140.207314 -303.809641) (xy 140.265954 -303.679915)
			(xy 140.331839 -303.553715) (xy 140.404758 -303.431444) (xy 140.484478 -303.313494) (xy 140.570744 -303.200244)
			(xy 140.663278 -303.092055) (xy 140.761785 -302.989275) (xy 140.865949 -302.892232) (xy 140.975436 -302.801238)
			(xy 141.089896 -302.716584) (xy 141.208961 -302.638541) (xy 141.332252 -302.56736) (xy 141.459372 -302.503267)
			(xy 141.589914 -302.446469) (xy 141.723461 -302.397147) (xy 141.859585 -302.35546) (xy 141.997848 -302.321541)
			(xy 142.137809 -302.295498) (xy 142.27902 -302.277415) (xy 142.421027 -302.26735) (xy 142.563376 -302.265336)
			(xy 142.705612 -302.271378) (xy 142.847277 -302.285457) (xy 142.987919 -302.307529) (xy 143.127088 -302.337522)
			(xy 143.264336 -302.37534) (xy 143.399225 -302.420863) (xy 143.531323 -302.473944) (xy 143.660206 -302.534414)
			(xy 143.785461 -302.602078) (xy 143.906688 -302.67672) (xy 144.023497 -302.758101) (xy 144.135516 -302.845961)
			(xy 144.242384 -302.940017) (xy 144.34376 -303.039968) (xy 144.439319 -303.145495) (xy 144.528754 -303.256259)
			(xy 144.61178 -303.371905) (xy 144.688131 -303.492063) (xy 144.757561 -303.616349) (xy 144.819848 -303.744363)
			(xy 144.874793 -303.875696) (xy 144.92222 -304.009927) (xy 144.961977 -304.146627) (xy 144.993936 -304.285357)
			(xy 145.017996 -304.425673) (xy 145.034078 -304.567125) (xy 145.042133 -304.70926) (xy 145.042636 -304.780442)
			(xy 145.042133 -304.851624) (xy 145.034078 -304.993759) (xy 145.017996 -305.135211) (xy 144.993936 -305.275527)
			(xy 144.961977 -305.414257) (xy 144.92222 -305.550957) (xy 144.874793 -305.685188) (xy 144.819848 -305.816521)
			(xy 144.757561 -305.944535) (xy 144.688131 -306.068821) (xy 144.61178 -306.188979) (xy 144.528754 -306.304625)
			(xy 144.439319 -306.415389) (xy 144.34376 -306.520916) (xy 144.242384 -306.620867) (xy 144.135516 -306.714923)
			(xy 144.023497 -306.802783) (xy 143.906688 -306.884164) (xy 143.785461 -306.958806) (xy 143.660206 -307.02647)
			(xy 143.531323 -307.08694) (xy 143.399225 -307.140021) (xy 143.264336 -307.185544) (xy 143.127088 -307.223362)
			(xy 142.987919 -307.253355) (xy 142.847277 -307.275427) (xy 142.705612 -307.289506) (xy 142.563376 -307.295548)
			(xy 142.421027 -307.293534) (xy 142.27902 -307.283469) (xy 142.137809 -307.265386) (xy 141.997848 -307.239343)
			(xy 141.859585 -307.205424) (xy 141.723461 -307.163737) (xy 141.589914 -307.114415) (xy 141.459372 -307.057617)
			(xy 141.332252 -306.993524) (xy 141.208961 -306.922343) (xy 141.089896 -306.8443) (xy 140.975436 -306.759646)
			(xy 140.865949 -306.668652) (xy 140.761785 -306.571609) (xy 140.663278 -306.468829) (xy 140.570744 -306.36064)
			(xy 140.484478 -306.24739) (xy 140.404758 -306.12944) (xy 140.331839 -306.007169) (xy 140.265954 -305.880969)
			(xy 140.207314 -305.751243) (xy 140.156108 -305.618408) (xy 140.112498 -305.482888) (xy 140.076626 -305.345118)
			(xy 140.048605 -305.20554) (xy 140.028526 -305.064599) (xy 140.016453 -304.922749) (xy 140.012424 -304.780442)
			(xy 139.027159 -304.780442) (xy 139.031184 -304.948279) (xy 139.043252 -305.11573) (xy 139.063335 -305.282409)
			(xy 139.091386 -305.447935) (xy 139.127341 -305.611925) (xy 139.171116 -305.774002) (xy 139.222613 -305.933794)
			(xy 139.281711 -306.090934) (xy 139.348275 -306.245059) (xy 139.422153 -306.395816) (xy 139.503173 -306.542857)
			(xy 139.59115 -306.685845) (xy 139.685882 -306.82445) (xy 139.78715 -306.958354) (xy 139.894721 -307.087248)
			(xy 140.008349 -307.210837) (xy 140.127771 -307.328836) (xy 140.252713 -307.440973) (xy 140.382889 -307.546992)
			(xy 140.517997 -307.646647) (xy 140.657728 -307.739709) (xy 140.80176 -307.825966) (xy 140.949763 -307.905217)
			(xy 141.101394 -307.977281) (xy 141.256307 -308.041993) (xy 141.414143 -308.099203) (xy 141.574542 -308.14878)
			(xy 141.737132 -308.190609) (xy 141.901542 -308.224595) (xy 142.067391 -308.250659) (xy 142.2343 -308.268741)
			(xy 142.401883 -308.278801) (xy 142.569756 -308.280814) (xy 142.737533 -308.274776) (xy 142.904827 -308.260701)
			(xy 143.071254 -308.238621) (xy 143.236431 -308.208588) (xy 143.399978 -308.170669) (xy 143.561519 -308.124953)
			(xy 143.720682 -308.071544) (xy 143.877102 -308.010566) (xy 144.030418 -307.942158) (xy 144.180278 -307.866479)
			(xy 144.326337 -307.783701) (xy 144.468259 -307.694016) (xy 144.605719 -307.597629) (xy 144.738399 -307.494763)
			(xy 144.865994 -307.385654) (xy 144.988212 -307.270553) (xy 145.10477 -307.149724) (xy 145.215401 -307.023446)
			(xy 145.319851 -306.892009) (xy 145.417879 -306.755715) (xy 145.50926 -306.614878) (xy 145.593783 -306.469822)
			(xy 145.671254 -306.32088) (xy 145.741495 -306.168395) (xy 145.804344 -306.012718) (xy 145.859657 -305.854207)
			(xy 145.907307 -305.693226) (xy 145.947184 -305.530145) (xy 145.979196 -305.36534) (xy 146.00327 -305.19919)
			(xy 146.01935 -305.032077) (xy 146.027399 -304.864385)
		)
		(stroke
			(width 0)
			(type solid)
		)
		(fill yes)
		(layer "B.Cu")
		(net "Net_1977")
	)
	(gr_poly
		(pts
			(xy 146.027902 -212.98027) (xy 146.027399 -212.896327) (xy 146.01935 -212.728635) (xy 146.00327 -212.561522)
			(xy 145.979196 -212.395372) (xy 145.947184 -212.230567) (xy 145.907307 -212.067486) (xy 145.859657 -211.906505)
			(xy 145.804344 -211.747994) (xy 145.741495 -211.592317) (xy 145.671254 -211.439832) (xy 145.593783 -211.29089)
			(xy 145.50926 -211.145834) (xy 145.417879 -211.004997) (xy 145.319851 -210.868703) (xy 145.215401 -210.737266)
			(xy 145.10477 -210.610988) (xy 144.988212 -210.490159) (xy 144.865994 -210.375058) (xy 144.738399 -210.265949)
			(xy 144.605719 -210.163083) (xy 144.468259 -210.066696) (xy 144.326337 -209.977011) (xy 144.180278 -209.894233)
			(xy 144.030418 -209.818554) (xy 143.877102 -209.750146) (xy 143.720682 -209.689168) (xy 143.561519 -209.635759)
			(xy 143.399978 -209.590043) (xy 143.236431 -209.552124) (xy 143.071254 -209.522091) (xy 142.904827 -209.500011)
			(xy 142.737533 -209.485936) (xy 142.569756 -209.479898) (xy 142.401883 -209.481911) (xy 142.2343 -209.491971)
			(xy 142.067391 -209.510053) (xy 141.901542 -209.536117) (xy 141.737132 -209.570103) (xy 141.574542 -209.611932)
			(xy 141.414143 -209.661509) (xy 141.256307 -209.718719) (xy 141.101394 -209.783431) (xy 140.949763 -209.855495)
			(xy 140.80176 -209.934746) (xy 140.657728 -210.021003) (xy 140.517997 -210.114065) (xy 140.382889 -210.21372)
			(xy 140.252713 -210.319739) (xy 140.127771 -210.431876) (xy 140.008349 -210.549875) (xy 139.894721 -210.673464)
			(xy 139.78715 -210.802358) (xy 139.685882 -210.936262) (xy 139.59115 -211.074867) (xy 139.503173 -211.217855)
			(xy 139.422153 -211.364896) (xy 139.348275 -211.515653) (xy 139.281711 -211.669778) (xy 139.222613 -211.826918)
			(xy 139.171116 -211.98671) (xy 139.127341 -212.148787) (xy 139.091386 -212.312777) (xy 139.063335 -212.478303)
			(xy 139.043252 -212.644982) (xy 139.031184 -212.812433) (xy 139.027159 -212.98027) (xy 140.012424 -212.98027)
			(xy 140.016453 -212.837963) (xy 140.028526 -212.696113) (xy 140.048605 -212.555172) (xy 140.076626 -212.415594)
			(xy 140.112498 -212.277824) (xy 140.156108 -212.142304) (xy 140.207314 -212.009469) (xy 140.265954 -211.879743)
			(xy 140.331839 -211.753543) (xy 140.404758 -211.631272) (xy 140.484478 -211.513322) (xy 140.570744 -211.400072)
			(xy 140.663278 -211.291883) (xy 140.761785 -211.189103) (xy 140.865949 -211.09206) (xy 140.975436 -211.001066)
			(xy 141.089896 -210.916412) (xy 141.208961 -210.838369) (xy 141.332252 -210.767188) (xy 141.459372 -210.703095)
			(xy 141.589914 -210.646297) (xy 141.723461 -210.596975) (xy 141.859585 -210.555288) (xy 141.997848 -210.521369)
			(xy 142.137809 -210.495326) (xy 142.27902 -210.477243) (xy 142.421027 -210.467178) (xy 142.563376 -210.465164)
			(xy 142.705612 -210.471206) (xy 142.847277 -210.485285) (xy 142.987919 -210.507357) (xy 143.127088 -210.53735)
			(xy 143.264336 -210.575168) (xy 143.399225 -210.620691) (xy 143.531323 -210.673772) (xy 143.660206 -210.734242)
			(xy 143.785461 -210.801906) (xy 143.906688 -210.876548) (xy 144.023497 -210.957929) (xy 144.135516 -211.045789)
			(xy 144.242384 -211.139845) (xy 144.34376 -211.239796) (xy 144.439319 -211.345323) (xy 144.528754 -211.456087)
			(xy 144.61178 -211.571733) (xy 144.688131 -211.691891) (xy 144.757561 -211.816177) (xy 144.819848 -211.944191)
			(xy 144.874793 -212.075524) (xy 144.92222 -212.209755) (xy 144.961977 -212.346455) (xy 144.993936 -212.485185)
			(xy 145.017996 -212.625501) (xy 145.034078 -212.766953) (xy 145.042133 -212.909088) (xy 145.042636 -212.98027)
			(xy 145.042133 -213.051452) (xy 145.034078 -213.193587) (xy 145.017996 -213.335039) (xy 144.993936 -213.475355)
			(xy 144.961977 -213.614085) (xy 144.92222 -213.750785) (xy 144.874793 -213.885016) (xy 144.819848 -214.016349)
			(xy 144.757561 -214.144363) (xy 144.688131 -214.268649) (xy 144.61178 -214.388807) (xy 144.528754 -214.504453)
			(xy 144.439319 -214.615217) (xy 144.34376 -214.720744) (xy 144.242384 -214.820695) (xy 144.135516 -214.914751)
			(xy 144.023497 -215.002611) (xy 143.906688 -215.083992) (xy 143.785461 -215.158634) (xy 143.660206 -215.226298)
			(xy 143.531323 -215.286768) (xy 143.399225 -215.339849) (xy 143.264336 -215.385372) (xy 143.127088 -215.42319)
			(xy 142.987919 -215.453183) (xy 142.847277 -215.475255) (xy 142.705612 -215.489334) (xy 142.563376 -215.495376)
			(xy 142.421027 -215.493362) (xy 142.27902 -215.483297) (xy 142.137809 -215.465214) (xy 141.997848 -215.439171)
			(xy 141.859585 -215.405252) (xy 141.723461 -215.363565) (xy 141.589914 -215.314243) (xy 141.459372 -215.257445)
			(xy 141.332252 -215.193352) (xy 141.208961 -215.122171) (xy 141.089896 -215.044128) (xy 140.975436 -214.959474)
			(xy 140.865949 -214.86848) (xy 140.761785 -214.771437) (xy 140.663278 -214.668657) (xy 140.570744 -214.560468)
			(xy 140.484478 -214.447218) (xy 140.404758 -214.329268) (xy 140.331839 -214.206997) (xy 140.265954 -214.080797)
			(xy 140.207314 -213.951071) (xy 140.156108 -213.818236) (xy 140.112498 -213.682716) (xy 140.076626 -213.544946)
			(xy 140.048605 -213.405368) (xy 140.028526 -213.264427) (xy 140.016453 -213.122577) (xy 140.012424 -212.98027)
			(xy 139.027159 -212.98027) (xy 139.031184 -213.148107) (xy 139.043252 -213.315558) (xy 139.063335 -213.482237)
			(xy 139.091386 -213.647763) (xy 139.127341 -213.811753) (xy 139.171116 -213.97383) (xy 139.222613 -214.133622)
			(xy 139.281711 -214.290762) (xy 139.348275 -214.444887) (xy 139.422153 -214.595644) (xy 139.503173 -214.742685)
			(xy 139.59115 -214.885673) (xy 139.685882 -215.024278) (xy 139.78715 -215.158182) (xy 139.894721 -215.287076)
			(xy 140.008349 -215.410665) (xy 140.127771 -215.528664) (xy 140.252713 -215.640801) (xy 140.382889 -215.74682)
			(xy 140.517997 -215.846475) (xy 140.657728 -215.939537) (xy 140.80176 -216.025794) (xy 140.949763 -216.105045)
			(xy 141.101394 -216.177109) (xy 141.256307 -216.241821) (xy 141.414143 -216.299031) (xy 141.574542 -216.348608)
			(xy 141.737132 -216.390437) (xy 141.901542 -216.424423) (xy 142.067391 -216.450487) (xy 142.2343 -216.468569)
			(xy 142.401883 -216.478629) (xy 142.569756 -216.480642) (xy 142.737533 -216.474604) (xy 142.904827 -216.460529)
			(xy 143.071254 -216.438449) (xy 143.236431 -216.408416) (xy 143.399978 -216.370497) (xy 143.561519 -216.324781)
			(xy 143.720682 -216.271372) (xy 143.877102 -216.210394) (xy 144.030418 -216.141986) (xy 144.180278 -216.066307)
			(xy 144.326337 -215.983529) (xy 144.468259 -215.893844) (xy 144.605719 -215.797457) (xy 144.738399 -215.694591)
			(xy 144.865994 -215.585482) (xy 144.988212 -215.470381) (xy 145.10477 -215.349552) (xy 145.215401 -215.223274)
			(xy 145.319851 -215.091837) (xy 145.417879 -214.955543) (xy 145.50926 -214.814706) (xy 145.593783 -214.66965)
			(xy 145.671254 -214.520708) (xy 145.741495 -214.368223) (xy 145.804344 -214.212546) (xy 145.859657 -214.054035)
			(xy 145.907307 -213.893054) (xy 145.947184 -213.729973) (xy 145.979196 -213.565168) (xy 146.00327 -213.399018)
			(xy 146.01935 -213.231905) (xy 146.027399 -213.064213)
		)
		(stroke
			(width 0)
			(type solid)
		)
		(fill yes)
		(layer "B.Cu")
		(net "Net_1975")
	)
	(gr_poly
		(pts
			(xy 157.528006 -258.880356) (xy 157.527503 -258.796413) (xy 157.519454 -258.628721) (xy 157.503374 -258.461608)
			(xy 157.4793 -258.295458) (xy 157.447288 -258.130653) (xy 157.407411 -257.967572) (xy 157.359761 -257.806591)
			(xy 157.304448 -257.64808) (xy 157.241599 -257.492403) (xy 157.171358 -257.339918) (xy 157.093887 -257.190976)
			(xy 157.009364 -257.04592) (xy 156.917983 -256.905083) (xy 156.819955 -256.768789) (xy 156.715505 -256.637352)
			(xy 156.604874 -256.511074) (xy 156.488316 -256.390245) (xy 156.366098 -256.275144) (xy 156.238503 -256.166035)
			(xy 156.105823 -256.063169) (xy 155.968363 -255.966782) (xy 155.826441 -255.877097) (xy 155.680382 -255.794319)
			(xy 155.530522 -255.71864) (xy 155.377206 -255.650232) (xy 155.220786 -255.589254) (xy 155.061623 -255.535845)
			(xy 154.900082 -255.490129) (xy 154.736535 -255.45221) (xy 154.571358 -255.422177) (xy 154.404931 -255.400097)
			(xy 154.237637 -255.386022) (xy 154.06986 -255.379984) (xy 153.901987 -255.381997) (xy 153.734404 -255.392057)
			(xy 153.567495 -255.410139) (xy 153.401646 -255.436203) (xy 153.237236 -255.470189) (xy 153.074646 -255.512018)
			(xy 152.914247 -255.561595) (xy 152.756411 -255.618805) (xy 152.601498 -255.683517) (xy 152.449867 -255.755581)
			(xy 152.301864 -255.834832) (xy 152.157832 -255.921089) (xy 152.018101 -256.014151) (xy 151.882993 -256.113806)
			(xy 151.752817 -256.219825) (xy 151.627875 -256.331962) (xy 151.508453 -256.449961) (xy 151.394825 -256.57355)
			(xy 151.287254 -256.702444) (xy 151.185986 -256.836348) (xy 151.091254 -256.974953) (xy 151.003277 -257.117941)
			(xy 150.922257 -257.264982) (xy 150.848379 -257.415739) (xy 150.781815 -257.569864) (xy 150.722717 -257.727004)
			(xy 150.67122 -257.886796) (xy 150.627445 -258.048873) (xy 150.59149 -258.212863) (xy 150.563439 -258.378389)
			(xy 150.543356 -258.545068) (xy 150.531288 -258.712519) (xy 150.527263 -258.880356) (xy 151.512783 -258.880356)
			(xy 151.516811 -258.738064) (xy 151.528883 -258.596228) (xy 151.54896 -258.455301) (xy 151.576978 -258.315737)
			(xy 151.612847 -258.177981) (xy 151.656452 -258.042475) (xy 151.707653 -257.909653) (xy 151.766287 -257.77994)
			(xy 151.832165 -257.653753) (xy 151.905077 -257.531494) (xy 151.984789 -257.413557) (xy 152.071046 -257.300318)
			(xy 152.16357 -257.19214) (xy 152.262067 -257.08937) (xy 152.366221 -256.992337) (xy 152.475697 -256.901353)
			(xy 152.590145 -256.816707) (xy 152.709199 -256.738672) (xy 152.832477 -256.667498) (xy 152.959584 -256.603411)
			(xy 153.090113 -256.546619) (xy 153.223647 -256.497302) (xy 153.359756 -256.455619) (xy 153.498006 -256.421703)
			(xy 153.637953 -256.395663) (xy 153.779149 -256.377582) (xy 153.921142 -256.367519) (xy 154.063477 -256.365504)
			(xy 154.205698 -256.371546) (xy 154.347349 -256.385624) (xy 154.487977 -256.407693) (xy 154.627131 -256.437683)
			(xy 154.764366 -256.475498) (xy 154.899241 -256.521016) (xy 155.031325 -256.574092) (xy 155.160195 -256.634555)
			(xy 155.285438 -256.702212) (xy 155.406652 -256.776847) (xy 155.52345 -256.85822) (xy 155.635457 -256.94607)
			(xy 155.742315 -257.040117) (xy 155.84368 -257.140058) (xy 155.939229 -257.245574) (xy 156.028656 -257.356327)
			(xy 156.111674 -257.471961) (xy 156.188016 -257.592108) (xy 156.257439 -257.71638) (xy 156.31972 -257.844382)
			(xy 156.37466 -257.975702) (xy 156.422082 -258.109919) (xy 156.461835 -258.246605) (xy 156.493791 -258.385321)
			(xy 156.517848 -258.525622) (xy 156.533929 -258.66706) (xy 156.541982 -258.809181) (xy 156.542486 -258.880356)
			(xy 156.541982 -258.951531) (xy 156.533929 -259.093652) (xy 156.517848 -259.23509) (xy 156.493791 -259.375391)
			(xy 156.461835 -259.514107) (xy 156.422082 -259.650793) (xy 156.37466 -259.78501) (xy 156.31972 -259.91633)
			(xy 156.257439 -260.044332) (xy 156.188016 -260.168604) (xy 156.111674 -260.288751) (xy 156.028656 -260.404385)
			(xy 155.939229 -260.515138) (xy 155.84368 -260.620654) (xy 155.742315 -260.720595) (xy 155.635457 -260.814642)
			(xy 155.52345 -260.902492) (xy 155.406652 -260.983865) (xy 155.285438 -261.0585) (xy 155.160195 -261.126157)
			(xy 155.031325 -261.18662) (xy 154.899241 -261.239696) (xy 154.764366 -261.285214) (xy 154.627131 -261.323029)
			(xy 154.487977 -261.353019) (xy 154.347349 -261.375088) (xy 154.205698 -261.389166) (xy 154.063477 -261.395208)
			(xy 153.921142 -261.393193) (xy 153.779149 -261.38313) (xy 153.637953 -261.365049) (xy 153.498006 -261.339009)
			(xy 153.359756 -261.305093) (xy 153.223647 -261.26341) (xy 153.090113 -261.214093) (xy 152.959584 -261.157301)
			(xy 152.832477 -261.093214) (xy 152.709199 -261.02204) (xy 152.590145 -260.944005) (xy 152.475697 -260.859359)
			(xy 152.366221 -260.768375) (xy 152.262067 -260.671342) (xy 152.16357 -260.568572) (xy 152.071046 -260.460394)
			(xy 151.984789 -260.347155) (xy 151.905077 -260.229218) (xy 151.832165 -260.106959) (xy 151.766287 -259.980772)
			(xy 151.707653 -259.851059) (xy 151.656452 -259.718237) (xy 151.612847 -259.582731) (xy 151.576978 -259.444975)
			(xy 151.54896 -259.305411) (xy 151.528883 -259.164484) (xy 151.516811 -259.022648) (xy 151.512783 -258.880356)
			(xy 150.527263 -258.880356) (xy 150.531288 -259.048193) (xy 150.543356 -259.215644) (xy 150.563439 -259.382323)
			(xy 150.59149 -259.547849) (xy 150.627445 -259.711839) (xy 150.67122 -259.873916) (xy 150.722717 -260.033708)
			(xy 150.781815 -260.190848) (xy 150.848379 -260.344973) (xy 150.922257 -260.49573) (xy 151.003277 -260.642771)
			(xy 151.091254 -260.785759) (xy 151.185986 -260.924364) (xy 151.287254 -261.058268) (xy 151.394825 -261.187162)
			(xy 151.508453 -261.310751) (xy 151.627875 -261.42875) (xy 151.752817 -261.540887) (xy 151.882993 -261.646906)
			(xy 152.018101 -261.746561) (xy 152.157832 -261.839623) (xy 152.301864 -261.92588) (xy 152.449867 -262.005131)
			(xy 152.601498 -262.077195) (xy 152.756411 -262.141907) (xy 152.914247 -262.199117) (xy 153.074646 -262.248694)
			(xy 153.237236 -262.290523) (xy 153.401646 -262.324509) (xy 153.567495 -262.350573) (xy 153.734404 -262.368655)
			(xy 153.901987 -262.378715) (xy 154.06986 -262.380728) (xy 154.237637 -262.37469) (xy 154.404931 -262.360615)
			(xy 154.571358 -262.338535) (xy 154.736535 -262.308502) (xy 154.900082 -262.270583) (xy 155.061623 -262.224867)
			(xy 155.220786 -262.171458) (xy 155.377206 -262.11048) (xy 155.530522 -262.042072) (xy 155.680382 -261.966393)
			(xy 155.826441 -261.883615) (xy 155.968363 -261.79393) (xy 156.105823 -261.697543) (xy 156.238503 -261.594677)
			(xy 156.366098 -261.485568) (xy 156.488316 -261.370467) (xy 156.604874 -261.249638) (xy 156.715505 -261.12336)
			(xy 156.819955 -260.991923) (xy 156.917983 -260.855629) (xy 157.009364 -260.714792) (xy 157.093887 -260.569736)
			(xy 157.171358 -260.420794) (xy 157.241599 -260.268309) (xy 157.304448 -260.112632) (xy 157.359761 -259.954121)
			(xy 157.407411 -259.79314) (xy 157.447288 -259.630059) (xy 157.4793 -259.465254) (xy 157.503374 -259.299104)
			(xy 157.519454 -259.131991) (xy 157.527503 -258.964299)
		)
		(stroke
			(width 0)
			(type solid)
		)
		(fill yes)
		(layer "B.Cu")
		(net "Net_1976")
	)
	(gr_poly
		(pts
			(xy 321.26809 -258.880102) (xy 321.267587 -258.796159) (xy 321.259538 -258.628467) (xy 321.243458 -258.461354)
			(xy 321.219384 -258.295204) (xy 321.187372 -258.130399) (xy 321.147495 -257.967318) (xy 321.099845 -257.806337)
			(xy 321.044532 -257.647826) (xy 320.981683 -257.492149) (xy 320.911442 -257.339664) (xy 320.833971 -257.190722)
			(xy 320.749448 -257.045666) (xy 320.658067 -256.904829) (xy 320.560039 -256.768535) (xy 320.455589 -256.637098)
			(xy 320.344958 -256.51082) (xy 320.2284 -256.389991) (xy 320.106182 -256.27489) (xy 319.978587 -256.165781)
			(xy 319.845907 -256.062915) (xy 319.708447 -255.966528) (xy 319.566525 -255.876843) (xy 319.420466 -255.794065)
			(xy 319.270606 -255.718386) (xy 319.11729 -255.649978) (xy 318.96087 -255.589) (xy 318.801707 -255.535591)
			(xy 318.640166 -255.489875) (xy 318.476619 -255.451956) (xy 318.311442 -255.421923) (xy 318.145015 -255.399843)
			(xy 317.977721 -255.385768) (xy 317.809944 -255.37973) (xy 317.642071 -255.381743) (xy 317.474488 -255.391803)
			(xy 317.307579 -255.409885) (xy 317.14173 -255.435949) (xy 316.97732 -255.469935) (xy 316.81473 -255.511764)
			(xy 316.654331 -255.561341) (xy 316.496495 -255.618551) (xy 316.341582 -255.683263) (xy 316.189951 -255.755327)
			(xy 316.041948 -255.834578) (xy 315.897916 -255.920835) (xy 315.758185 -256.013897) (xy 315.623077 -256.113552)
			(xy 315.492901 -256.219571) (xy 315.367959 -256.331708) (xy 315.248537 -256.449707) (xy 315.134909 -256.573296)
			(xy 315.027338 -256.70219) (xy 314.92607 -256.836094) (xy 314.831338 -256.974699) (xy 314.743361 -257.117687)
			(xy 314.662341 -257.264728) (xy 314.588463 -257.415485) (xy 314.521899 -257.56961) (xy 314.462801 -257.72675)
			(xy 314.411304 -257.886542) (xy 314.367529 -258.048619) (xy 314.331574 -258.212609) (xy 314.303523 -258.378135)
			(xy 314.28344 -258.544814) (xy 314.271372 -258.712265) (xy 314.267347 -258.880102) (xy 315.252867 -258.880102)
			(xy 315.256895 -258.73781) (xy 315.268967 -258.595974) (xy 315.289044 -258.455047) (xy 315.317062 -258.315483)
			(xy 315.352931 -258.177727) (xy 315.396536 -258.042221) (xy 315.447737 -257.909399) (xy 315.506371 -257.779686)
			(xy 315.572249 -257.653499) (xy 315.645161 -257.53124) (xy 315.724873 -257.413303) (xy 315.81113 -257.300064)
			(xy 315.903654 -257.191886) (xy 316.002151 -257.089116) (xy 316.106305 -256.992083) (xy 316.215781 -256.901099)
			(xy 316.330229 -256.816453) (xy 316.449283 -256.738418) (xy 316.572561 -256.667244) (xy 316.699668 -256.603157)
			(xy 316.830197 -256.546365) (xy 316.963731 -256.497048) (xy 317.09984 -256.455365) (xy 317.23809 -256.421449)
			(xy 317.378037 -256.395409) (xy 317.519233 -256.377328) (xy 317.661226 -256.367265) (xy 317.803561 -256.36525)
			(xy 317.945782 -256.371292) (xy 318.087433 -256.38537) (xy 318.228061 -256.407439) (xy 318.367215 -256.437429)
			(xy 318.50445 -256.475244) (xy 318.639325 -256.520762) (xy 318.771409 -256.573838) (xy 318.900279 -256.634301)
			(xy 319.025522 -256.701958) (xy 319.146736 -256.776593) (xy 319.263534 -256.857966) (xy 319.375541 -256.945816)
			(xy 319.482399 -257.039863) (xy 319.583764 -257.139804) (xy 319.679313 -257.24532) (xy 319.76874 -257.356073)
			(xy 319.851758 -257.471707) (xy 319.9281 -257.591854) (xy 319.997523 -257.716126) (xy 320.059804 -257.844128)
			(xy 320.114744 -257.975448) (xy 320.162166 -258.109665) (xy 320.201919 -258.246351) (xy 320.233875 -258.385067)
			(xy 320.257932 -258.525368) (xy 320.274013 -258.666806) (xy 320.282066 -258.808927) (xy 320.28257 -258.880102)
			(xy 320.282066 -258.951277) (xy 320.274013 -259.093398) (xy 320.257932 -259.234836) (xy 320.233875 -259.375137)
			(xy 320.201919 -259.513853) (xy 320.162166 -259.650539) (xy 320.114744 -259.784756) (xy 320.059804 -259.916076)
			(xy 319.997523 -260.044078) (xy 319.9281 -260.16835) (xy 319.851758 -260.288497) (xy 319.76874 -260.404131)
			(xy 319.679313 -260.514884) (xy 319.583764 -260.6204) (xy 319.482399 -260.720341) (xy 319.375541 -260.814388)
			(xy 319.263534 -260.902238) (xy 319.146736 -260.983611) (xy 319.025522 -261.058246) (xy 318.900279 -261.125903)
			(xy 318.771409 -261.186366) (xy 318.639325 -261.239442) (xy 318.50445 -261.28496) (xy 318.367215 -261.322775)
			(xy 318.228061 -261.352765) (xy 318.087433 -261.374834) (xy 317.945782 -261.388912) (xy 317.803561 -261.394954)
			(xy 317.661226 -261.392939) (xy 317.519233 -261.382876) (xy 317.378037 -261.364795) (xy 317.23809 -261.338755)
			(xy 317.09984 -261.304839) (xy 316.963731 -261.263156) (xy 316.830197 -261.213839) (xy 316.699668 -261.157047)
			(xy 316.572561 -261.09296) (xy 316.449283 -261.021786) (xy 316.330229 -260.943751) (xy 316.215781 -260.859105)
			(xy 316.106305 -260.768121) (xy 316.002151 -260.671088) (xy 315.903654 -260.568318) (xy 315.81113 -260.46014)
			(xy 315.724873 -260.346901) (xy 315.645161 -260.228964) (xy 315.572249 -260.106705) (xy 315.506371 -259.980518)
			(xy 315.447737 -259.850805) (xy 315.396536 -259.717983) (xy 315.352931 -259.582477) (xy 315.317062 -259.444721)
			(xy 315.289044 -259.305157) (xy 315.268967 -259.16423) (xy 315.256895 -259.022394) (xy 315.252867 -258.880102)
			(xy 314.267347 -258.880102) (xy 314.271372 -259.047939) (xy 314.28344 -259.21539) (xy 314.303523 -259.382069)
			(xy 314.331574 -259.547595) (xy 314.367529 -259.711585) (xy 314.411304 -259.873662) (xy 314.462801 -260.033454)
			(xy 314.521899 -260.190594) (xy 314.588463 -260.344719) (xy 314.662341 -260.495476) (xy 314.743361 -260.642517)
			(xy 314.831338 -260.785505) (xy 314.92607 -260.92411) (xy 315.027338 -261.058014) (xy 315.134909 -261.186908)
			(xy 315.248537 -261.310497) (xy 315.367959 -261.428496) (xy 315.492901 -261.540633) (xy 315.623077 -261.646652)
			(xy 315.758185 -261.746307) (xy 315.897916 -261.839369) (xy 316.041948 -261.925626) (xy 316.189951 -262.004877)
			(xy 316.341582 -262.076941) (xy 316.496495 -262.141653) (xy 316.654331 -262.198863) (xy 316.81473 -262.24844)
			(xy 316.97732 -262.290269) (xy 317.14173 -262.324255) (xy 317.307579 -262.350319) (xy 317.474488 -262.368401)
			(xy 317.642071 -262.378461) (xy 317.809944 -262.380474) (xy 317.977721 -262.374436) (xy 318.145015 -262.360361)
			(xy 318.311442 -262.338281) (xy 318.476619 -262.308248) (xy 318.640166 -262.270329) (xy 318.801707 -262.224613)
			(xy 318.96087 -262.171204) (xy 319.11729 -262.110226) (xy 319.270606 -262.041818) (xy 319.420466 -261.966139)
			(xy 319.566525 -261.883361) (xy 319.708447 -261.793676) (xy 319.845907 -261.697289) (xy 319.978587 -261.594423)
			(xy 320.106182 -261.485314) (xy 320.2284 -261.370213) (xy 320.344958 -261.249384) (xy 320.455589 -261.123106)
			(xy 320.560039 -260.991669) (xy 320.658067 -260.855375) (xy 320.749448 -260.714538) (xy 320.833971 -260.569482)
			(xy 320.911442 -260.42054) (xy 320.981683 -260.268055) (xy 321.044532 -260.112378) (xy 321.099845 -259.953867)
			(xy 321.147495 -259.792886) (xy 321.187372 -259.629805) (xy 321.219384 -259.465) (xy 321.243458 -259.29885)
			(xy 321.259538 -259.131737) (xy 321.267587 -258.964045)
		)
		(stroke
			(width 0)
			(type solid)
		)
		(fill yes)
		(layer "B.Cu")
		(net "Net_1770")
	)
	(gr_poly
		(pts
			(xy 332.76794 -304.780188) (xy 332.767437 -304.696252) (xy 332.759388 -304.528572) (xy 332.74331 -304.36147)
			(xy 332.719238 -304.195332) (xy 332.687228 -304.030539) (xy 332.647354 -303.867471) (xy 332.599708 -303.706501)
			(xy 332.544398 -303.548001) (xy 332.481554 -303.392335) (xy 332.411318 -303.239861) (xy 332.333852 -303.09093)
			(xy 332.249335 -302.945885) (xy 332.157961 -302.805058) (xy 332.059941 -302.668774) (xy 331.955498 -302.537347)
			(xy 331.844875 -302.411078) (xy 331.728325 -302.290258) (xy 331.606117 -302.175165) (xy 331.47853 -302.066064)
			(xy 331.34586 -301.963205) (xy 331.208411 -301.866826) (xy 331.066498 -301.777147) (xy 330.92045 -301.694375)
			(xy 330.770601 -301.618701) (xy 330.617296 -301.550298) (xy 330.460887 -301.489324) (xy 330.301736 -301.43592)
			(xy 330.140207 -301.390207) (xy 329.976671 -301.352291) (xy 329.811506 -301.32226) (xy 329.645092 -301.300182)
			(xy 329.47781 -301.286108) (xy 329.310045 -301.28007) (xy 329.142184 -301.282083) (xy 328.974613 -301.292142)
			(xy 328.807717 -301.310223) (xy 328.641879 -301.336285) (xy 328.477482 -301.370269) (xy 328.314903 -301.412095)
			(xy 328.154516 -301.461668) (xy 327.996691 -301.518874) (xy 327.84179 -301.58358) (xy 327.690169 -301.65564)
			(xy 327.542178 -301.734885) (xy 327.398156 -301.821135) (xy 327.258435 -301.914191) (xy 327.123336 -302.013839)
			(xy 326.99317 -302.11985) (xy 326.868237 -302.231979) (xy 326.748823 -302.349969) (xy 326.635204 -302.473549)
			(xy 326.52764 -302.602434) (xy 326.42638 -302.736329) (xy 326.331655 -302.874924) (xy 326.243685 -303.017901)
			(xy 326.16267 -303.164931) (xy 326.088798 -303.315677) (xy 326.022239 -303.469791) (xy 325.963145 -303.626919)
			(xy 325.911652 -303.7867) (xy 325.867879 -303.948766) (xy 325.831927 -304.112744) (xy 325.803878 -304.278257)
			(xy 325.783797 -304.444925) (xy 325.77173 -304.612363) (xy 325.767705 -304.780188) (xy 326.753225 -304.780188)
			(xy 326.757252 -304.63791) (xy 326.769323 -304.496088) (xy 326.789398 -304.355176) (xy 326.817413 -304.215626)
			(xy 326.853279 -304.077884) (xy 326.896879 -303.942392) (xy 326.948075 -303.809583) (xy 327.006703 -303.679883)
			(xy 327.072575 -303.553709) (xy 327.145479 -303.431463) (xy 327.225183 -303.313537) (xy 327.311431 -303.200309)
			(xy 327.403947 -303.092143) (xy 327.502434 -302.989383) (xy 327.606577 -302.89236) (xy 327.716042 -302.801384)
			(xy 327.830478 -302.716748) (xy 327.94952 -302.63872) (xy 328.072786 -302.567553) (xy 328.19988 -302.503473)
			(xy 328.330396 -302.446687) (xy 328.463916 -302.397375) (xy 328.600012 -302.355696) (xy 328.738247 -302.321784)
			(xy 328.87818 -302.295746) (xy 329.019362 -302.277667) (xy 329.161341 -302.267604) (xy 329.303661 -302.26559)
			(xy 329.445868 -302.271631) (xy 329.587505 -302.285708) (xy 329.728118 -302.307775) (xy 329.867258 -302.337762)
			(xy 330.004479 -302.375573) (xy 330.139341 -302.421086) (xy 330.271412 -302.474157) (xy 330.400269 -302.534614)
			(xy 330.525499 -302.602264) (xy 330.646701 -302.676892) (xy 330.763487 -302.758256) (xy 330.875483 -302.846098)
			(xy 330.982329 -302.940135) (xy 331.083685 -303.040066) (xy 331.179224 -303.145571) (xy 331.268642 -303.256313)
			(xy 331.351651 -303.371936) (xy 331.427986 -303.49207) (xy 331.497402 -303.61633) (xy 331.559677 -303.744318)
			(xy 331.614611 -303.875625) (xy 331.662028 -304.009829) (xy 331.701777 -304.146501) (xy 331.73373 -304.285203)
			(xy 331.757784 -304.42549) (xy 331.773864 -304.566914) (xy 331.781916 -304.709021) (xy 331.78242 -304.780188)
			(xy 331.781916 -304.851355) (xy 331.773864 -304.993462) (xy 331.757784 -305.134886) (xy 331.73373 -305.275173)
			(xy 331.701777 -305.413875) (xy 331.662028 -305.550547) (xy 331.614611 -305.684751) (xy 331.559677 -305.816058)
			(xy 331.497402 -305.944046) (xy 331.427986 -306.068306) (xy 331.351651 -306.18844) (xy 331.268642 -306.304063)
			(xy 331.179224 -306.414805) (xy 331.083685 -306.52031) (xy 330.982329 -306.620241) (xy 330.875483 -306.714278)
			(xy 330.763487 -306.80212) (xy 330.646701 -306.883484) (xy 330.525499 -306.958112) (xy 330.400269 -307.025762)
			(xy 330.271412 -307.086219) (xy 330.139341 -307.13929) (xy 330.004479 -307.184803) (xy 329.867258 -307.222614)
			(xy 329.728118 -307.252601) (xy 329.587505 -307.274668) (xy 329.445868 -307.288745) (xy 329.303661 -307.294786)
			(xy 329.161341 -307.292772) (xy 329.019362 -307.282709) (xy 328.87818 -307.26463) (xy 328.738247 -307.238592)
			(xy 328.600012 -307.20468) (xy 328.463916 -307.163001) (xy 328.330396 -307.113689) (xy 328.19988 -307.056903)
			(xy 328.072786 -306.992823) (xy 327.94952 -306.921656) (xy 327.830478 -306.843628) (xy 327.716042 -306.758992)
			(xy 327.606577 -306.668016) (xy 327.502434 -306.570993) (xy 327.403947 -306.468233) (xy 327.311431 -306.360067)
			(xy 327.225183 -306.246839) (xy 327.145479 -306.128913) (xy 327.072575 -306.006667) (xy 327.006703 -305.880493)
			(xy 326.948075 -305.750793) (xy 326.896879 -305.617984) (xy 326.853279 -305.482492) (xy 326.817413 -305.34475)
			(xy 326.789398 -305.2052) (xy 326.769323 -305.064288) (xy 326.757252 -304.922466) (xy 326.753225 -304.780188)
			(xy 325.767705 -304.780188) (xy 325.77173 -304.948013) (xy 325.783797 -305.115451) (xy 325.803878 -305.282119)
			(xy 325.831927 -305.447632) (xy 325.867879 -305.61161) (xy 325.911652 -305.773676) (xy 325.963145 -305.933457)
			(xy 326.022239 -306.090585) (xy 326.088798 -306.244699) (xy 326.16267 -306.395445) (xy 326.243685 -306.542475)
			(xy 326.331655 -306.685452) (xy 326.42638 -306.824047) (xy 326.52764 -306.957942) (xy 326.635204 -307.086827)
			(xy 326.748823 -307.210407) (xy 326.868237 -307.328397) (xy 326.99317 -307.440526) (xy 327.123336 -307.546537)
			(xy 327.258435 -307.646185) (xy 327.398156 -307.739241) (xy 327.542178 -307.825491) (xy 327.690169 -307.904736)
			(xy 327.84179 -307.976796) (xy 327.996691 -308.041502) (xy 328.154516 -308.098708) (xy 328.314903 -308.148281)
			(xy 328.477482 -308.190107) (xy 328.641879 -308.224091) (xy 328.807717 -308.250153) (xy 328.974613 -308.268234)
			(xy 329.142184 -308.278293) (xy 329.310045 -308.280306) (xy 329.47781 -308.274268) (xy 329.645092 -308.260194)
			(xy 329.811506 -308.238116) (xy 329.976671 -308.208085) (xy 330.140207 -308.170169) (xy 330.301736 -308.124456)
			(xy 330.460887 -308.071052) (xy 330.617296 -308.010078) (xy 330.770601 -307.941675) (xy 330.92045 -307.866001)
			(xy 331.066498 -307.783229) (xy 331.208411 -307.69355) (xy 331.34586 -307.597171) (xy 331.47853 -307.494312)
			(xy 331.606117 -307.385211) (xy 331.728325 -307.270118) (xy 331.844875 -307.149298) (xy 331.955498 -307.023029)
			(xy 332.059941 -306.891602) (xy 332.157961 -306.755318) (xy 332.249335 -306.614491) (xy 332.333852 -306.469446)
			(xy 332.411318 -306.320515) (xy 332.481554 -306.168041) (xy 332.544398 -306.012375) (xy 332.599708 -305.853875)
			(xy 332.647354 -305.692905) (xy 332.687228 -305.529837) (xy 332.719238 -305.365044) (xy 332.74331 -305.198906)
			(xy 332.759388 -305.031804) (xy 332.767437 -304.864124)
		)
		(stroke
			(width 0)
			(type solid)
		)
		(fill yes)
		(layer "B.Cu")
		(net "Net_1769")
	)
	(gr_poly
		(pts
			(xy 332.76794 -212.980016) (xy 332.767437 -212.89608) (xy 332.759388 -212.7284) (xy 332.74331 -212.561298)
			(xy 332.719238 -212.39516) (xy 332.687228 -212.230367) (xy 332.647354 -212.067299) (xy 332.599708 -211.906329)
			(xy 332.544398 -211.747829) (xy 332.481554 -211.592163) (xy 332.411318 -211.439689) (xy 332.333852 -211.290758)
			(xy 332.249335 -211.145713) (xy 332.157961 -211.004886) (xy 332.059941 -210.868602) (xy 331.955498 -210.737175)
			(xy 331.844875 -210.610906) (xy 331.728325 -210.490086) (xy 331.606117 -210.374993) (xy 331.47853 -210.265892)
			(xy 331.34586 -210.163033) (xy 331.208411 -210.066654) (xy 331.066498 -209.976975) (xy 330.92045 -209.894203)
			(xy 330.770601 -209.818529) (xy 330.617296 -209.750126) (xy 330.460887 -209.689152) (xy 330.301736 -209.635748)
			(xy 330.140207 -209.590035) (xy 329.976671 -209.552119) (xy 329.811506 -209.522088) (xy 329.645092 -209.50001)
			(xy 329.47781 -209.485936) (xy 329.310045 -209.479898) (xy 329.142184 -209.481911) (xy 328.974613 -209.49197)
			(xy 328.807717 -209.510051) (xy 328.641879 -209.536113) (xy 328.477482 -209.570097) (xy 328.314903 -209.611923)
			(xy 328.154516 -209.661496) (xy 327.996691 -209.718702) (xy 327.84179 -209.783408) (xy 327.690169 -209.855468)
			(xy 327.542178 -209.934713) (xy 327.398156 -210.020963) (xy 327.258435 -210.114019) (xy 327.123336 -210.213667)
			(xy 326.99317 -210.319678) (xy 326.868237 -210.431807) (xy 326.748823 -210.549797) (xy 326.635204 -210.673377)
			(xy 326.52764 -210.802262) (xy 326.42638 -210.936157) (xy 326.331655 -211.074752) (xy 326.243685 -211.217729)
			(xy 326.16267 -211.364759) (xy 326.088798 -211.515505) (xy 326.022239 -211.669619) (xy 325.963145 -211.826747)
			(xy 325.911652 -211.986528) (xy 325.867879 -212.148594) (xy 325.831927 -212.312572) (xy 325.803878 -212.478085)
			(xy 325.783797 -212.644753) (xy 325.77173 -212.812191) (xy 325.767705 -212.980016) (xy 326.753225 -212.980016)
			(xy 326.757252 -212.837738) (xy 326.769323 -212.695916) (xy 326.789398 -212.555004) (xy 326.817413 -212.415454)
			(xy 326.853279 -212.277712) (xy 326.896879 -212.14222) (xy 326.948075 -212.009411) (xy 327.006703 -211.879711)
			(xy 327.072575 -211.753537) (xy 327.145479 -211.631291) (xy 327.225183 -211.513365) (xy 327.311431 -211.400137)
			(xy 327.403947 -211.291971) (xy 327.502434 -211.189211) (xy 327.606577 -211.092188) (xy 327.716042 -211.001212)
			(xy 327.830478 -210.916576) (xy 327.94952 -210.838548) (xy 328.072786 -210.767381) (xy 328.19988 -210.703301)
			(xy 328.330396 -210.646515) (xy 328.463916 -210.597203) (xy 328.600012 -210.555524) (xy 328.738247 -210.521612)
			(xy 328.87818 -210.495574) (xy 329.019362 -210.477495) (xy 329.161341 -210.467432) (xy 329.303661 -210.465418)
			(xy 329.445868 -210.471459) (xy 329.587505 -210.485536) (xy 329.728118 -210.507603) (xy 329.867258 -210.53759)
			(xy 330.004479 -210.575401) (xy 330.139341 -210.620914) (xy 330.271412 -210.673985) (xy 330.400269 -210.734442)
			(xy 330.525499 -210.802092) (xy 330.646701 -210.87672) (xy 330.763487 -210.958084) (xy 330.875483 -211.045926)
			(xy 330.982329 -211.139963) (xy 331.083685 -211.239894) (xy 331.179224 -211.345399) (xy 331.268642 -211.456141)
			(xy 331.351651 -211.571764) (xy 331.427986 -211.691898) (xy 331.497402 -211.816158) (xy 331.559677 -211.944146)
			(xy 331.614611 -212.075453) (xy 331.662028 -212.209657) (xy 331.701777 -212.346329) (xy 331.73373 -212.485031)
			(xy 331.757784 -212.625318) (xy 331.773864 -212.766742) (xy 331.781916 -212.908849) (xy 331.78242 -212.980016)
			(xy 331.781916 -213.051183) (xy 331.773864 -213.19329) (xy 331.757784 -213.334714) (xy 331.73373 -213.475001)
			(xy 331.701777 -213.613703) (xy 331.662028 -213.750375) (xy 331.614611 -213.884579) (xy 331.559677 -214.015886)
			(xy 331.497402 -214.143874) (xy 331.427986 -214.268134) (xy 331.351651 -214.388268) (xy 331.268642 -214.503891)
			(xy 331.179224 -214.614633) (xy 331.083685 -214.720138) (xy 330.982329 -214.820069) (xy 330.875483 -214.914106)
			(xy 330.763487 -215.001948) (xy 330.646701 -215.083312) (xy 330.525499 -215.15794) (xy 330.400269 -215.22559)
			(xy 330.271412 -215.286047) (xy 330.139341 -215.339118) (xy 330.004479 -215.384631) (xy 329.867258 -215.422442)
			(xy 329.728118 -215.452429) (xy 329.587505 -215.474496) (xy 329.445868 -215.488573) (xy 329.303661 -215.494614)
			(xy 329.161341 -215.4926) (xy 329.019362 -215.482537) (xy 328.87818 -215.464458) (xy 328.738247 -215.43842)
			(xy 328.600012 -215.404508) (xy 328.463916 -215.362829) (xy 328.330396 -215.313517) (xy 328.19988 -215.256731)
			(xy 328.072786 -215.192651) (xy 327.94952 -215.121484) (xy 327.830478 -215.043456) (xy 327.716042 -214.95882)
			(xy 327.606577 -214.867844) (xy 327.502434 -214.770821) (xy 327.403947 -214.668061) (xy 327.311431 -214.559895)
			(xy 327.225183 -214.446667) (xy 327.145479 -214.328741) (xy 327.072575 -214.206495) (xy 327.006703 -214.080321)
			(xy 326.948075 -213.950621) (xy 326.896879 -213.817812) (xy 326.853279 -213.68232) (xy 326.817413 -213.544578)
			(xy 326.789398 -213.405028) (xy 326.769323 -213.264116) (xy 326.757252 -213.122294) (xy 326.753225 -212.980016)
			(xy 325.767705 -212.980016) (xy 325.77173 -213.147841) (xy 325.783797 -213.315279) (xy 325.803878 -213.481947)
			(xy 325.831927 -213.64746) (xy 325.867879 -213.811438) (xy 325.911652 -213.973504) (xy 325.963145 -214.133285)
			(xy 326.022239 -214.290413) (xy 326.088798 -214.444527) (xy 326.16267 -214.595273) (xy 326.243685 -214.742303)
			(xy 326.331655 -214.88528) (xy 326.42638 -215.023875) (xy 326.52764 -215.15777) (xy 326.635204 -215.286655)
			(xy 326.748823 -215.410235) (xy 326.868237 -215.528225) (xy 326.99317 -215.640354) (xy 327.123336 -215.746365)
			(xy 327.258435 -215.846013) (xy 327.398156 -215.939069) (xy 327.542178 -216.025319) (xy 327.690169 -216.104564)
			(xy 327.84179 -216.176624) (xy 327.996691 -216.24133) (xy 328.154516 -216.298536) (xy 328.314903 -216.348109)
			(xy 328.477482 -216.389935) (xy 328.641879 -216.423919) (xy 328.807717 -216.449981) (xy 328.974613 -216.468062)
			(xy 329.142184 -216.478121) (xy 329.310045 -216.480134) (xy 329.47781 -216.474096) (xy 329.645092 -216.460022)
			(xy 329.811506 -216.437944) (xy 329.976671 -216.407913) (xy 330.140207 -216.369997) (xy 330.301736 -216.324284)
			(xy 330.460887 -216.27088) (xy 330.617296 -216.209906) (xy 330.770601 -216.141503) (xy 330.92045 -216.065829)
			(xy 331.066498 -215.983057) (xy 331.208411 -215.893378) (xy 331.34586 -215.796999) (xy 331.47853 -215.69414)
			(xy 331.606117 -215.585039) (xy 331.728325 -215.469946) (xy 331.844875 -215.349126) (xy 331.955498 -215.222857)
			(xy 332.059941 -215.09143) (xy 332.157961 -214.955146) (xy 332.249335 -214.814319) (xy 332.333852 -214.669274)
			(xy 332.411318 -214.520343) (xy 332.481554 -214.367869) (xy 332.544398 -214.212203) (xy 332.599708 -214.053703)
			(xy 332.647354 -213.892733) (xy 332.687228 -213.729665) (xy 332.719238 -213.564872) (xy 332.74331 -213.398734)
			(xy 332.759388 -213.231632) (xy 332.767437 -213.063952)
		)
		(stroke
			(width 0)
			(type solid)
		)
		(fill yes)
		(layer "B.Cu")
		(net "Net_1771")
	)
	(gr_poly
		(pts
			(xy 393.96797 -304.780188) (xy 393.967467 -304.696245) (xy 393.959418 -304.528553) (xy 393.943338 -304.36144)
			(xy 393.919264 -304.19529) (xy 393.887252 -304.030485) (xy 393.847375 -303.867404) (xy 393.799725 -303.706423)
			(xy 393.744412 -303.547912) (xy 393.681563 -303.392235) (xy 393.611322 -303.23975) (xy 393.533851 -303.090808)
			(xy 393.449328 -302.945752) (xy 393.357947 -302.804915) (xy 393.259919 -302.668621) (xy 393.155469 -302.537184)
			(xy 393.044838 -302.410906) (xy 392.92828 -302.290077) (xy 392.806062 -302.174976) (xy 392.678467 -302.065867)
			(xy 392.545787 -301.963001) (xy 392.408327 -301.866614) (xy 392.266405 -301.776929) (xy 392.120346 -301.694151)
			(xy 391.970486 -301.618472) (xy 391.81717 -301.550064) (xy 391.66075 -301.489086) (xy 391.501587 -301.435677)
			(xy 391.340046 -301.389961) (xy 391.176499 -301.352042) (xy 391.011322 -301.322009) (xy 390.844895 -301.299929)
			(xy 390.677601 -301.285854) (xy 390.509824 -301.279816) (xy 390.341951 -301.281829) (xy 390.174368 -301.291889)
			(xy 390.007459 -301.309971) (xy 389.84161 -301.336035) (xy 389.6772 -301.370021) (xy 389.51461 -301.41185)
			(xy 389.354211 -301.461427) (xy 389.196375 -301.518637) (xy 389.041462 -301.583349) (xy 388.889831 -301.655413)
			(xy 388.741828 -301.734664) (xy 388.597796 -301.820921) (xy 388.458065 -301.913983) (xy 388.322957 -302.013638)
			(xy 388.192781 -302.119657) (xy 388.067839 -302.231794) (xy 387.948417 -302.349793) (xy 387.834789 -302.473382)
			(xy 387.727218 -302.602276) (xy 387.62595 -302.73618) (xy 387.531218 -302.874785) (xy 387.443241 -303.017773)
			(xy 387.362221 -303.164814) (xy 387.288343 -303.315571) (xy 387.221779 -303.469696) (xy 387.162681 -303.626836)
			(xy 387.111184 -303.786628) (xy 387.067409 -303.948705) (xy 387.031454 -304.112695) (xy 387.003403 -304.278221)
			(xy 386.98332 -304.4449) (xy 386.971252 -304.612351) (xy 386.967227 -304.780188) (xy 387.952492 -304.780188)
			(xy 387.956521 -304.637881) (xy 387.968594 -304.496031) (xy 387.988673 -304.35509) (xy 388.016694 -304.215512)
			(xy 388.052566 -304.077742) (xy 388.096176 -303.942222) (xy 388.147382 -303.809387) (xy 388.206022 -303.679661)
			(xy 388.271907 -303.553461) (xy 388.344826 -303.43119) (xy 388.424546 -303.31324) (xy 388.510812 -303.19999)
			(xy 388.603346 -303.091801) (xy 388.701853 -302.989021) (xy 388.806017 -302.891978) (xy 388.915504 -302.800984)
			(xy 389.029964 -302.71633) (xy 389.149029 -302.638287) (xy 389.27232 -302.567106) (xy 389.39944 -302.503013)
			(xy 389.529982 -302.446215) (xy 389.663529 -302.396893) (xy 389.799653 -302.355206) (xy 389.937916 -302.321287)
			(xy 390.077877 -302.295244) (xy 390.219088 -302.277161) (xy 390.361095 -302.267096) (xy 390.503444 -302.265082)
			(xy 390.64568 -302.271124) (xy 390.787345 -302.285203) (xy 390.927987 -302.307275) (xy 391.067156 -302.337268)
			(xy 391.204404 -302.375086) (xy 391.339293 -302.420609) (xy 391.471391 -302.47369) (xy 391.600274 -302.53416)
			(xy 391.725529 -302.601824) (xy 391.846756 -302.676466) (xy 391.963565 -302.757847) (xy 392.075584 -302.845707)
			(xy 392.182452 -302.939763) (xy 392.283828 -303.039714) (xy 392.379387 -303.145241) (xy 392.468822 -303.256005)
			(xy 392.551848 -303.371651) (xy 392.628199 -303.491809) (xy 392.697629 -303.616095) (xy 392.759916 -303.744109)
			(xy 392.814861 -303.875442) (xy 392.862288 -304.009673) (xy 392.902045 -304.146373) (xy 392.934004 -304.285103)
			(xy 392.958064 -304.425419) (xy 392.974146 -304.566871) (xy 392.982201 -304.709006) (xy 392.982704 -304.780188)
			(xy 392.982201 -304.85137) (xy 392.974146 -304.993505) (xy 392.958064 -305.134957) (xy 392.934004 -305.275273)
			(xy 392.902045 -305.414003) (xy 392.862288 -305.550703) (xy 392.814861 -305.684934) (xy 392.759916 -305.816267)
			(xy 392.697629 -305.944281) (xy 392.628199 -306.068567) (xy 392.551848 -306.188725) (xy 392.468822 -306.304371)
			(xy 392.379387 -306.415135) (xy 392.283828 -306.520662) (xy 392.182452 -306.620613) (xy 392.075584 -306.714669)
			(xy 391.963565 -306.802529) (xy 391.846756 -306.88391) (xy 391.725529 -306.958552) (xy 391.600274 -307.026216)
			(xy 391.471391 -307.086686) (xy 391.339293 -307.139767) (xy 391.204404 -307.18529) (xy 391.067156 -307.223108)
			(xy 390.927987 -307.253101) (xy 390.787345 -307.275173) (xy 390.64568 -307.289252) (xy 390.503444 -307.295294)
			(xy 390.361095 -307.29328) (xy 390.219088 -307.283215) (xy 390.077877 -307.265132) (xy 389.937916 -307.239089)
			(xy 389.799653 -307.20517) (xy 389.663529 -307.163483) (xy 389.529982 -307.114161) (xy 389.39944 -307.057363)
			(xy 389.27232 -306.99327) (xy 389.149029 -306.922089) (xy 389.029964 -306.844046) (xy 388.915504 -306.759392)
			(xy 388.806017 -306.668398) (xy 388.701853 -306.571355) (xy 388.603346 -306.468575) (xy 388.510812 -306.360386)
			(xy 388.424546 -306.247136) (xy 388.344826 -306.129186) (xy 388.271907 -306.006915) (xy 388.206022 -305.880715)
			(xy 388.147382 -305.750989) (xy 388.096176 -305.618154) (xy 388.052566 -305.482634) (xy 388.016694 -305.344864)
			(xy 387.988673 -305.205286) (xy 387.968594 -305.064345) (xy 387.956521 -304.922495) (xy 387.952492 -304.780188)
			(xy 386.967227 -304.780188) (xy 386.971252 -304.948025) (xy 386.98332 -305.115476) (xy 387.003403 -305.282155)
			(xy 387.031454 -305.447681) (xy 387.067409 -305.611671) (xy 387.111184 -305.773748) (xy 387.162681 -305.93354)
			(xy 387.221779 -306.09068) (xy 387.288343 -306.244805) (xy 387.362221 -306.395562) (xy 387.443241 -306.542603)
			(xy 387.531218 -306.685591) (xy 387.62595 -306.824196) (xy 387.727218 -306.9581) (xy 387.834789 -307.086994)
			(xy 387.948417 -307.210583) (xy 388.067839 -307.328582) (xy 388.192781 -307.440719) (xy 388.322957 -307.546738)
			(xy 388.458065 -307.646393) (xy 388.597796 -307.739455) (xy 388.741828 -307.825712) (xy 388.889831 -307.904963)
			(xy 389.041462 -307.977027) (xy 389.196375 -308.041739) (xy 389.354211 -308.098949) (xy 389.51461 -308.148526)
			(xy 389.6772 -308.190355) (xy 389.84161 -308.224341) (xy 390.007459 -308.250405) (xy 390.174368 -308.268487)
			(xy 390.341951 -308.278547) (xy 390.509824 -308.28056) (xy 390.677601 -308.274522) (xy 390.844895 -308.260447)
			(xy 391.011322 -308.238367) (xy 391.176499 -308.208334) (xy 391.340046 -308.170415) (xy 391.501587 -308.124699)
			(xy 391.66075 -308.07129) (xy 391.81717 -308.010312) (xy 391.970486 -307.941904) (xy 392.120346 -307.866225)
			(xy 392.266405 -307.783447) (xy 392.408327 -307.693762) (xy 392.545787 -307.597375) (xy 392.678467 -307.494509)
			(xy 392.806062 -307.3854) (xy 392.92828 -307.270299) (xy 393.044838 -307.14947) (xy 393.155469 -307.023192)
			(xy 393.259919 -306.891755) (xy 393.357947 -306.755461) (xy 393.449328 -306.614624) (xy 393.533851 -306.469568)
			(xy 393.611322 -306.320626) (xy 393.681563 -306.168141) (xy 393.744412 -306.012464) (xy 393.799725 -305.853953)
			(xy 393.847375 -305.692972) (xy 393.887252 -305.529891) (xy 393.919264 -305.365086) (xy 393.943338 -305.198936)
			(xy 393.959418 -305.031823) (xy 393.967467 -304.864131)
		)
		(stroke
			(width 0)
			(type solid)
		)
		(fill yes)
		(layer "B.Cu")
		(net "Net_1774")
	)
	(gr_poly
		(pts
			(xy 393.96797 -212.980016) (xy 393.967467 -212.896073) (xy 393.959418 -212.728381) (xy 393.943338 -212.561268)
			(xy 393.919264 -212.395118) (xy 393.887252 -212.230313) (xy 393.847375 -212.067232) (xy 393.799725 -211.906251)
			(xy 393.744412 -211.74774) (xy 393.681563 -211.592063) (xy 393.611322 -211.439578) (xy 393.533851 -211.290636)
			(xy 393.449328 -211.14558) (xy 393.357947 -211.004743) (xy 393.259919 -210.868449) (xy 393.155469 -210.737012)
			(xy 393.044838 -210.610734) (xy 392.92828 -210.489905) (xy 392.806062 -210.374804) (xy 392.678467 -210.265695)
			(xy 392.545787 -210.162829) (xy 392.408327 -210.066442) (xy 392.266405 -209.976757) (xy 392.120346 -209.893979)
			(xy 391.970486 -209.8183) (xy 391.81717 -209.749892) (xy 391.66075 -209.688914) (xy 391.501587 -209.635505)
			(xy 391.340046 -209.589789) (xy 391.176499 -209.55187) (xy 391.011322 -209.521837) (xy 390.844895 -209.499757)
			(xy 390.677601 -209.485682) (xy 390.509824 -209.479644) (xy 390.341951 -209.481657) (xy 390.174368 -209.491717)
			(xy 390.007459 -209.509799) (xy 389.84161 -209.535863) (xy 389.6772 -209.569849) (xy 389.51461 -209.611678)
			(xy 389.354211 -209.661255) (xy 389.196375 -209.718465) (xy 389.041462 -209.783177) (xy 388.889831 -209.855241)
			(xy 388.741828 -209.934492) (xy 388.597796 -210.020749) (xy 388.458065 -210.113811) (xy 388.322957 -210.213466)
			(xy 388.192781 -210.319485) (xy 388.067839 -210.431622) (xy 387.948417 -210.549621) (xy 387.834789 -210.67321)
			(xy 387.727218 -210.802104) (xy 387.62595 -210.936008) (xy 387.531218 -211.074613) (xy 387.443241 -211.217601)
			(xy 387.362221 -211.364642) (xy 387.288343 -211.515399) (xy 387.221779 -211.669524) (xy 387.162681 -211.826664)
			(xy 387.111184 -211.986456) (xy 387.067409 -212.148533) (xy 387.031454 -212.312523) (xy 387.003403 -212.478049)
			(xy 386.98332 -212.644728) (xy 386.971252 -212.812179) (xy 386.967227 -212.980016) (xy 387.952492 -212.980016)
			(xy 387.956521 -212.837709) (xy 387.968594 -212.695859) (xy 387.988673 -212.554918) (xy 388.016694 -212.41534)
			(xy 388.052566 -212.27757) (xy 388.096176 -212.14205) (xy 388.147382 -212.009215) (xy 388.206022 -211.879489)
			(xy 388.271907 -211.753289) (xy 388.344826 -211.631018) (xy 388.424546 -211.513068) (xy 388.510812 -211.399818)
			(xy 388.603346 -211.291629) (xy 388.701853 -211.188849) (xy 388.806017 -211.091806) (xy 388.915504 -211.000812)
			(xy 389.029964 -210.916158) (xy 389.149029 -210.838115) (xy 389.27232 -210.766934) (xy 389.39944 -210.702841)
			(xy 389.529982 -210.646043) (xy 389.663529 -210.596721) (xy 389.799653 -210.555034) (xy 389.937916 -210.521115)
			(xy 390.077877 -210.495072) (xy 390.219088 -210.476989) (xy 390.361095 -210.466924) (xy 390.503444 -210.46491)
			(xy 390.64568 -210.470952) (xy 390.787345 -210.485031) (xy 390.927987 -210.507103) (xy 391.067156 -210.537096)
			(xy 391.204404 -210.574914) (xy 391.339293 -210.620437) (xy 391.471391 -210.673518) (xy 391.600274 -210.733988)
			(xy 391.725529 -210.801652) (xy 391.846756 -210.876294) (xy 391.963565 -210.957675) (xy 392.075584 -211.045535)
			(xy 392.182452 -211.139591) (xy 392.283828 -211.239542) (xy 392.379387 -211.345069) (xy 392.468822 -211.455833)
			(xy 392.551848 -211.571479) (xy 392.628199 -211.691637) (xy 392.697629 -211.815923) (xy 392.759916 -211.943937)
			(xy 392.814861 -212.07527) (xy 392.862288 -212.209501) (xy 392.902045 -212.346201) (xy 392.934004 -212.484931)
			(xy 392.958064 -212.625247) (xy 392.974146 -212.766699) (xy 392.982201 -212.908834) (xy 392.982704 -212.980016)
			(xy 392.982201 -213.051198) (xy 392.974146 -213.193333) (xy 392.958064 -213.334785) (xy 392.934004 -213.475101)
			(xy 392.902045 -213.613831) (xy 392.862288 -213.750531) (xy 392.814861 -213.884762) (xy 392.759916 -214.016095)
			(xy 392.697629 -214.144109) (xy 392.628199 -214.268395) (xy 392.551848 -214.388553) (xy 392.468822 -214.504199)
			(xy 392.379387 -214.614963) (xy 392.283828 -214.72049) (xy 392.182452 -214.820441) (xy 392.075584 -214.914497)
			(xy 391.963565 -215.002357) (xy 391.846756 -215.083738) (xy 391.725529 -215.15838) (xy 391.600274 -215.226044)
			(xy 391.471391 -215.286514) (xy 391.339293 -215.339595) (xy 391.204404 -215.385118) (xy 391.067156 -215.422936)
			(xy 390.927987 -215.452929) (xy 390.787345 -215.475001) (xy 390.64568 -215.48908) (xy 390.503444 -215.495122)
			(xy 390.361095 -215.493108) (xy 390.219088 -215.483043) (xy 390.077877 -215.46496) (xy 389.937916 -215.438917)
			(xy 389.799653 -215.404998) (xy 389.663529 -215.363311) (xy 389.529982 -215.313989) (xy 389.39944 -215.257191)
			(xy 389.27232 -215.193098) (xy 389.149029 -215.121917) (xy 389.029964 -215.043874) (xy 388.915504 -214.95922)
			(xy 388.806017 -214.868226) (xy 388.701853 -214.771183) (xy 388.603346 -214.668403) (xy 388.510812 -214.560214)
			(xy 388.424546 -214.446964) (xy 388.344826 -214.329014) (xy 388.271907 -214.206743) (xy 388.206022 -214.080543)
			(xy 388.147382 -213.950817) (xy 388.096176 -213.817982) (xy 388.052566 -213.682462) (xy 388.016694 -213.544692)
			(xy 387.988673 -213.405114) (xy 387.968594 -213.264173) (xy 387.956521 -213.122323) (xy 387.952492 -212.980016)
			(xy 386.967227 -212.980016) (xy 386.971252 -213.147853) (xy 386.98332 -213.315304) (xy 387.003403 -213.481983)
			(xy 387.031454 -213.647509) (xy 387.067409 -213.811499) (xy 387.111184 -213.973576) (xy 387.162681 -214.133368)
			(xy 387.221779 -214.290508) (xy 387.288343 -214.444633) (xy 387.362221 -214.59539) (xy 387.443241 -214.742431)
			(xy 387.531218 -214.885419) (xy 387.62595 -215.024024) (xy 387.727218 -215.157928) (xy 387.834789 -215.286822)
			(xy 387.948417 -215.410411) (xy 388.067839 -215.52841) (xy 388.192781 -215.640547) (xy 388.322957 -215.746566)
			(xy 388.458065 -215.846221) (xy 388.597796 -215.939283) (xy 388.741828 -216.02554) (xy 388.889831 -216.104791)
			(xy 389.041462 -216.176855) (xy 389.196375 -216.241567) (xy 389.354211 -216.298777) (xy 389.51461 -216.348354)
			(xy 389.6772 -216.390183) (xy 389.84161 -216.424169) (xy 390.007459 -216.450233) (xy 390.174368 -216.468315)
			(xy 390.341951 -216.478375) (xy 390.509824 -216.480388) (xy 390.677601 -216.47435) (xy 390.844895 -216.460275)
			(xy 391.011322 -216.438195) (xy 391.176499 -216.408162) (xy 391.340046 -216.370243) (xy 391.501587 -216.324527)
			(xy 391.66075 -216.271118) (xy 391.81717 -216.21014) (xy 391.970486 -216.141732) (xy 392.120346 -216.066053)
			(xy 392.266405 -215.983275) (xy 392.408327 -215.89359) (xy 392.545787 -215.797203) (xy 392.678467 -215.694337)
			(xy 392.806062 -215.585228) (xy 392.92828 -215.470127) (xy 393.044838 -215.349298) (xy 393.155469 -215.22302)
			(xy 393.259919 -215.091583) (xy 393.357947 -214.955289) (xy 393.449328 -214.814452) (xy 393.533851 -214.669396)
			(xy 393.611322 -214.520454) (xy 393.681563 -214.367969) (xy 393.744412 -214.212292) (xy 393.799725 -214.053781)
			(xy 393.847375 -213.8928) (xy 393.887252 -213.729719) (xy 393.919264 -213.564914) (xy 393.943338 -213.398764)
			(xy 393.959418 -213.231651) (xy 393.967467 -213.063959)
		)
		(stroke
			(width 0)
			(type solid)
		)
		(fill yes)
		(layer "B.Cu")
		(net "Net_1772")
	)
	(gr_poly
		(pts
			(xy 405.468074 -258.880102) (xy 405.467571 -258.796159) (xy 405.459522 -258.628467) (xy 405.443442 -258.461354)
			(xy 405.419368 -258.295204) (xy 405.387356 -258.130399) (xy 405.347479 -257.967318) (xy 405.299829 -257.806337)
			(xy 405.244516 -257.647826) (xy 405.181667 -257.492149) (xy 405.111426 -257.339664) (xy 405.033955 -257.190722)
			(xy 404.949432 -257.045666) (xy 404.858051 -256.904829) (xy 404.760023 -256.768535) (xy 404.655573 -256.637098)
			(xy 404.544942 -256.51082) (xy 404.428384 -256.389991) (xy 404.306166 -256.27489) (xy 404.178571 -256.165781)
			(xy 404.045891 -256.062915) (xy 403.908431 -255.966528) (xy 403.766509 -255.876843) (xy 403.62045 -255.794065)
			(xy 403.47059 -255.718386) (xy 403.317274 -255.649978) (xy 403.160854 -255.589) (xy 403.001691 -255.535591)
			(xy 402.84015 -255.489875) (xy 402.676603 -255.451956) (xy 402.511426 -255.421923) (xy 402.344999 -255.399843)
			(xy 402.177705 -255.385768) (xy 402.009928 -255.37973) (xy 401.842055 -255.381743) (xy 401.674472 -255.391803)
			(xy 401.507563 -255.409885) (xy 401.341714 -255.435949) (xy 401.177304 -255.469935) (xy 401.014714 -255.511764)
			(xy 400.854315 -255.561341) (xy 400.696479 -255.618551) (xy 400.541566 -255.683263) (xy 400.389935 -255.755327)
			(xy 400.241932 -255.834578) (xy 400.0979 -255.920835) (xy 399.958169 -256.013897) (xy 399.823061 -256.113552)
			(xy 399.692885 -256.219571) (xy 399.567943 -256.331708) (xy 399.448521 -256.449707) (xy 399.334893 -256.573296)
			(xy 399.227322 -256.70219) (xy 399.126054 -256.836094) (xy 399.031322 -256.974699) (xy 398.943345 -257.117687)
			(xy 398.862325 -257.264728) (xy 398.788447 -257.415485) (xy 398.721883 -257.56961) (xy 398.662785 -257.72675)
			(xy 398.611288 -257.886542) (xy 398.567513 -258.048619) (xy 398.531558 -258.212609) (xy 398.503507 -258.378135)
			(xy 398.483424 -258.544814) (xy 398.471356 -258.712265) (xy 398.467331 -258.880102) (xy 399.452851 -258.880102)
			(xy 399.456879 -258.73781) (xy 399.468951 -258.595974) (xy 399.489028 -258.455047) (xy 399.517046 -258.315483)
			(xy 399.552915 -258.177727) (xy 399.59652 -258.042221) (xy 399.647721 -257.909399) (xy 399.706355 -257.779686)
			(xy 399.772233 -257.653499) (xy 399.845145 -257.53124) (xy 399.924857 -257.413303) (xy 400.011114 -257.300064)
			(xy 400.103638 -257.191886) (xy 400.202135 -257.089116) (xy 400.306289 -256.992083) (xy 400.415765 -256.901099)
			(xy 400.530213 -256.816453) (xy 400.649267 -256.738418) (xy 400.772545 -256.667244) (xy 400.899652 -256.603157)
			(xy 401.030181 -256.546365) (xy 401.163715 -256.497048) (xy 401.299824 -256.455365) (xy 401.438074 -256.421449)
			(xy 401.578021 -256.395409) (xy 401.719217 -256.377328) (xy 401.86121 -256.367265) (xy 402.003545 -256.36525)
			(xy 402.145766 -256.371292) (xy 402.287417 -256.38537) (xy 402.428045 -256.407439) (xy 402.567199 -256.437429)
			(xy 402.704434 -256.475244) (xy 402.839309 -256.520762) (xy 402.971393 -256.573838) (xy 403.100263 -256.634301)
			(xy 403.225506 -256.701958) (xy 403.34672 -256.776593) (xy 403.463518 -256.857966) (xy 403.575525 -256.945816)
			(xy 403.682383 -257.039863) (xy 403.783748 -257.139804) (xy 403.879297 -257.24532) (xy 403.968724 -257.356073)
			(xy 404.051742 -257.471707) (xy 404.128084 -257.591854) (xy 404.197507 -257.716126) (xy 404.259788 -257.844128)
			(xy 404.314728 -257.975448) (xy 404.36215 -258.109665) (xy 404.401903 -258.246351) (xy 404.433859 -258.385067)
			(xy 404.457916 -258.525368) (xy 404.473997 -258.666806) (xy 404.48205 -258.808927) (xy 404.482554 -258.880102)
			(xy 404.48205 -258.951277) (xy 404.473997 -259.093398) (xy 404.457916 -259.234836) (xy 404.433859 -259.375137)
			(xy 404.401903 -259.513853) (xy 404.36215 -259.650539) (xy 404.314728 -259.784756) (xy 404.259788 -259.916076)
			(xy 404.197507 -260.044078) (xy 404.128084 -260.16835) (xy 404.051742 -260.288497) (xy 403.968724 -260.404131)
			(xy 403.879297 -260.514884) (xy 403.783748 -260.6204) (xy 403.682383 -260.720341) (xy 403.575525 -260.814388)
			(xy 403.463518 -260.902238) (xy 403.34672 -260.983611) (xy 403.225506 -261.058246) (xy 403.100263 -261.125903)
			(xy 402.971393 -261.186366) (xy 402.839309 -261.239442) (xy 402.704434 -261.28496) (xy 402.567199 -261.322775)
			(xy 402.428045 -261.352765) (xy 402.287417 -261.374834) (xy 402.145766 -261.388912) (xy 402.003545 -261.394954)
			(xy 401.86121 -261.392939) (xy 401.719217 -261.382876) (xy 401.578021 -261.364795) (xy 401.438074 -261.338755)
			(xy 401.299824 -261.304839) (xy 401.163715 -261.263156) (xy 401.030181 -261.213839) (xy 400.899652 -261.157047)
			(xy 400.772545 -261.09296) (xy 400.649267 -261.021786) (xy 400.530213 -260.943751) (xy 400.415765 -260.859105)
			(xy 400.306289 -260.768121) (xy 400.202135 -260.671088) (xy 400.103638 -260.568318) (xy 400.011114 -260.46014)
			(xy 399.924857 -260.346901) (xy 399.845145 -260.228964) (xy 399.772233 -260.106705) (xy 399.706355 -259.980518)
			(xy 399.647721 -259.850805) (xy 399.59652 -259.717983) (xy 399.552915 -259.582477) (xy 399.517046 -259.444721)
			(xy 399.489028 -259.305157) (xy 399.468951 -259.16423) (xy 399.456879 -259.022394) (xy 399.452851 -258.880102)
			(xy 398.467331 -258.880102) (xy 398.471356 -259.047939) (xy 398.483424 -259.21539) (xy 398.503507 -259.382069)
			(xy 398.531558 -259.547595) (xy 398.567513 -259.711585) (xy 398.611288 -259.873662) (xy 398.662785 -260.033454)
			(xy 398.721883 -260.190594) (xy 398.788447 -260.344719) (xy 398.862325 -260.495476) (xy 398.943345 -260.642517)
			(xy 399.031322 -260.785505) (xy 399.126054 -260.92411) (xy 399.227322 -261.058014) (xy 399.334893 -261.186908)
			(xy 399.448521 -261.310497) (xy 399.567943 -261.428496) (xy 399.692885 -261.540633) (xy 399.823061 -261.646652)
			(xy 399.958169 -261.746307) (xy 400.0979 -261.839369) (xy 400.241932 -261.925626) (xy 400.389935 -262.004877)
			(xy 400.541566 -262.076941) (xy 400.696479 -262.141653) (xy 400.854315 -262.198863) (xy 401.014714 -262.24844)
			(xy 401.177304 -262.290269) (xy 401.341714 -262.324255) (xy 401.507563 -262.350319) (xy 401.674472 -262.368401)
			(xy 401.842055 -262.378461) (xy 402.009928 -262.380474) (xy 402.177705 -262.374436) (xy 402.344999 -262.360361)
			(xy 402.511426 -262.338281) (xy 402.676603 -262.308248) (xy 402.84015 -262.270329) (xy 403.001691 -262.224613)
			(xy 403.160854 -262.171204) (xy 403.317274 -262.110226) (xy 403.47059 -262.041818) (xy 403.62045 -261.966139)
			(xy 403.766509 -261.883361) (xy 403.908431 -261.793676) (xy 404.045891 -261.697289) (xy 404.178571 -261.594423)
			(xy 404.306166 -261.485314) (xy 404.428384 -261.370213) (xy 404.544942 -261.249384) (xy 404.655573 -261.123106)
			(xy 404.760023 -260.991669) (xy 404.858051 -260.855375) (xy 404.949432 -260.714538) (xy 405.033955 -260.569482)
			(xy 405.111426 -260.42054) (xy 405.181667 -260.268055) (xy 405.244516 -260.112378) (xy 405.299829 -259.953867)
			(xy 405.347479 -259.792886) (xy 405.387356 -259.629805) (xy 405.419368 -259.465) (xy 405.443442 -259.29885)
			(xy 405.459522 -259.131737) (xy 405.467571 -258.964045)
		)
		(stroke
			(width 0)
			(type solid)
		)
		(fill yes)
		(layer "B.Cu")
		(net "Net_1773")
	)
	(gr_poly
		(pts
			(xy 217.68816 -360.764074) (xy 217.687662 -360.674653) (xy 217.679695 -360.495989) (xy 217.663777 -360.317856)
			(xy 217.63994 -360.14061) (xy 217.60823 -359.964602) (xy 217.568712 -359.79018) (xy 217.521463 -359.617693)
			(xy 217.466576 -359.447481) (xy 217.404162 -359.279884) (xy 217.334344 -359.115233) (xy 217.257261 -358.953856)
			(xy 217.173065 -358.796072) (xy 217.081925 -358.642196) (xy 216.984019 -358.492533) (xy 216.879545 -358.34738)
			(xy 216.768707 -358.207025) (xy 216.651728 -358.071747) (xy 216.528838 -357.941814) (xy 216.400282 -357.817484)
			(xy 216.266315 -357.699005) (xy 216.127204 -357.586611) (xy 215.983223 -357.480525) (xy 215.83466 -357.380959)
			(xy 215.681809 -357.28811) (xy 215.524974 -357.202161) (xy 215.364465 -357.123285) (xy 215.200602 -357.051637)
			(xy 215.03371 -356.98736) (xy 214.864121 -356.930581) (xy 214.69217 -356.881413) (xy 214.5182 -356.839954)
			(xy 214.342556 -356.806286) (xy 214.165586 -356.780475) (xy 213.987642 -356.762574) (xy 213.809078 -356.752617)
			(xy 213.630247 -356.750625) (xy 213.451505 -356.756601) (xy 213.273206 -356.770534) (xy 213.095705 -356.792395)
			(xy 212.919355 -356.822141) (xy 212.744504 -356.859714) (xy 212.571501 -356.905039) (xy 212.400688 -356.958026)
			(xy 212.232406 -357.018569) (xy 212.066987 -357.086548) (xy 211.904761 -357.161829) (xy 211.74605 -357.244262)
			(xy 211.591168 -357.333683) (xy 211.440424 -357.429915) (xy 211.294116 -357.532766) (xy 211.152535 -357.642033)
			(xy 211.015961 -357.757498) (xy 210.884668 -357.878933) (xy 210.758914 -358.006096) (xy 210.638949 -358.138734)
			(xy 210.525012 -358.276585) (xy 210.417329 -358.419375) (xy 210.316114 -358.566819) (xy 210.221568 -358.718627)
			(xy 210.133878 -358.874495) (xy 210.053218 -359.034115) (xy 209.979749 -359.197169) (xy 209.913617 -359.363335)
			(xy 209.854952 -359.532281) (xy 209.803872 -359.703673) (xy 209.760477 -359.877171) (xy 209.724855 -360.052429)
			(xy 209.697074 -360.2291) (xy 209.677192 -360.406834) (xy 209.665246 -360.585276) (xy 209.661262 -360.764074)
			(xy 211.159857 -360.764074) (xy 211.163885 -360.621782) (xy 211.175957 -360.479946) (xy 211.196034 -360.339019)
			(xy 211.224052 -360.199455) (xy 211.259921 -360.061699) (xy 211.303526 -359.926193) (xy 211.354727 -359.793371)
			(xy 211.413361 -359.663658) (xy 211.479239 -359.537471) (xy 211.552151 -359.415212) (xy 211.631863 -359.297275)
			(xy 211.71812 -359.184036) (xy 211.810644 -359.075858) (xy 211.909141 -358.973088) (xy 212.013295 -358.876055)
			(xy 212.122771 -358.785071) (xy 212.237219 -358.700425) (xy 212.356273 -358.62239) (xy 212.479551 -358.551216)
			(xy 212.606658 -358.487129) (xy 212.737187 -358.430337) (xy 212.870721 -358.38102) (xy 213.00683 -358.339337)
			(xy 213.14508 -358.305421) (xy 213.285027 -358.279381) (xy 213.426223 -358.2613) (xy 213.568216 -358.251237)
			(xy 213.710551 -358.249222) (xy 213.852772 -358.255264) (xy 213.994423 -358.269342) (xy 214.135051 -358.291411)
			(xy 214.274205 -358.321401) (xy 214.41144 -358.359216) (xy 214.546315 -358.404734) (xy 214.678399 -358.45781)
			(xy 214.807269 -358.518273) (xy 214.932512 -358.58593) (xy 215.053726 -358.660565) (xy 215.170524 -358.741938)
			(xy 215.282531 -358.829788) (xy 215.389389 -358.923835) (xy 215.490754 -359.023776) (xy 215.586303 -359.129292)
			(xy 215.67573 -359.240045) (xy 215.758748 -359.355679) (xy 215.83509 -359.475826) (xy 215.904513 -359.600098)
			(xy 215.966794 -359.7281) (xy 216.021734 -359.85942) (xy 216.069156 -359.993637) (xy 216.108909 -360.130323)
			(xy 216.140865 -360.269039) (xy 216.164922 -360.40934) (xy 216.181003 -360.550778) (xy 216.189056 -360.692899)
			(xy 216.18956 -360.764074) (xy 216.189056 -360.835249) (xy 216.181003 -360.97737) (xy 216.164922 -361.118808)
			(xy 216.140865 -361.259109) (xy 216.108909 -361.397825) (xy 216.069156 -361.534511) (xy 216.021734 -361.668728)
			(xy 215.966794 -361.800048) (xy 215.904513 -361.92805) (xy 215.83509 -362.052322) (xy 215.758748 -362.172469)
			(xy 215.67573 -362.288103) (xy 215.586303 -362.398856) (xy 215.490754 -362.504372) (xy 215.389389 -362.604313)
			(xy 215.282531 -362.69836) (xy 215.170524 -362.78621) (xy 215.053726 -362.867583) (xy 214.932512 -362.942218)
			(xy 214.807269 -363.009875) (xy 214.678399 -363.070338) (xy 214.546315 -363.123414) (xy 214.41144 -363.168932)
			(xy 214.274205 -363.206747) (xy 214.135051 -363.236737) (xy 213.994423 -363.258806) (xy 213.852772 -363.272884)
			(xy 213.710551 -363.278926) (xy 213.568216 -363.276911) (xy 213.426223 -363.266848) (xy 213.285027 -363.248767)
			(xy 213.14508 -363.222727) (xy 213.00683 -363.188811) (xy 212.870721 -363.147128) (xy 212.737187 -363.097811)
			(xy 212.606658 -363.041019) (xy 212.479551 -362.976932) (xy 212.356273 -362.905758) (xy 212.237219 -362.827723)
			(xy 212.122771 -362.743077) (xy 212.013295 -362.652093) (xy 211.909141 -362.55506) (xy 211.810644 -362.45229)
			(xy 211.71812 -362.344112) (xy 211.631863 -362.230873) (xy 211.552151 -362.112936) (xy 211.479239 -361.990677)
			(xy 211.413361 -361.86449) (xy 211.354727 -361.734777) (xy 211.303526 -361.601955) (xy 211.259921 -361.466449)
			(xy 211.224052 -361.328693) (xy 211.196034 -361.189129) (xy 211.175957 -361.048202) (xy 211.163885 -360.906366)
			(xy 211.159857 -360.764074) (xy 209.661262 -360.764074) (xy 209.665246 -360.942872) (xy 209.677192 -361.121314)
			(xy 209.697074 -361.299048) (xy 209.724855 -361.475719) (xy 209.760477 -361.650977) (xy 209.803872 -361.824475)
			(xy 209.854952 -361.995867) (xy 209.913617 -362.164813) (xy 209.979749 -362.330979) (xy 210.053218 -362.494033)
			(xy 210.133878 -362.653653) (xy 210.221568 -362.809521) (xy 210.316114 -362.961329) (xy 210.417329 -363.108773)
			(xy 210.525012 -363.251563) (xy 210.638949 -363.389414) (xy 210.758914 -363.522052) (xy 210.884668 -363.649215)
			(xy 211.015961 -363.77065) (xy 211.152535 -363.886115) (xy 211.294116 -363.995382) (xy 211.440424 -364.098233)
			(xy 211.591168 -364.194465) (xy 211.74605 -364.283886) (xy 211.904761 -364.366319) (xy 212.066987 -364.4416)
			(xy 212.232406 -364.509579) (xy 212.400688 -364.570122) (xy 212.571501 -364.623109) (xy 212.744504 -364.668434)
			(xy 212.919355 -364.706007) (xy 213.095705 -364.735753) (xy 213.273206 -364.757614) (xy 213.451505 -364.771547)
			(xy 213.630247 -364.777523) (xy 213.809078 -364.775531) (xy 213.987642 -364.765574) (xy 214.165586 -364.747673)
			(xy 214.342556 -364.721862) (xy 214.5182 -364.688194) (xy 214.69217 -364.646735) (xy 214.864121 -364.597567)
			(xy 215.03371 -364.540788) (xy 215.200602 -364.476511) (xy 215.364465 -364.404863) (xy 215.524974 -364.325987)
			(xy 215.681809 -364.240038) (xy 215.83466 -364.147189) (xy 215.983223 -364.047623) (xy 216.127204 -363.941537)
			(xy 216.266315 -363.829143) (xy 216.400282 -363.710664) (xy 216.528838 -363.586334) (xy 216.651728 -363.456401)
			(xy 216.768707 -363.321123) (xy 216.879545 -363.180768) (xy 216.984019 -363.035615) (xy 217.081925 -362.885952)
			(xy 217.173065 -362.732076) (xy 217.257261 -362.574292) (xy 217.334344 -362.412915) (xy 217.404162 -362.248264)
			(xy 217.466576 -362.080667) (xy 217.521463 -361.910455) (xy 217.568712 -361.737968) (xy 217.60823 -361.563546)
			(xy 217.63994 -361.387538) (xy 217.663777 -361.210292) (xy 217.679695 -361.032159) (xy 217.687662 -360.853495)
		)
		(stroke
			(width 0)
			(type solid)
		)
		(fill yes)
		(layer "B.Cu")
		(net "GND")
	)
	(gr_poly
		(pts
			(xy 262.13816 -360.764074) (xy 262.137662 -360.674653) (xy 262.129695 -360.495989) (xy 262.113777 -360.317856)
			(xy 262.08994 -360.14061) (xy 262.05823 -359.964602) (xy 262.018712 -359.79018) (xy 261.971463 -359.617693)
			(xy 261.916576 -359.447481) (xy 261.854162 -359.279884) (xy 261.784344 -359.115233) (xy 261.707261 -358.953856)
			(xy 261.623065 -358.796072) (xy 261.531925 -358.642196) (xy 261.434019 -358.492533) (xy 261.329545 -358.34738)
			(xy 261.218707 -358.207025) (xy 261.101728 -358.071747) (xy 260.978838 -357.941814) (xy 260.850282 -357.817484)
			(xy 260.716315 -357.699005) (xy 260.577204 -357.586611) (xy 260.433223 -357.480525) (xy 260.28466 -357.380959)
			(xy 260.131809 -357.28811) (xy 259.974974 -357.202161) (xy 259.814465 -357.123285) (xy 259.650602 -357.051637)
			(xy 259.48371 -356.98736) (xy 259.314121 -356.930581) (xy 259.14217 -356.881413) (xy 258.9682 -356.839954)
			(xy 258.792556 -356.806286) (xy 258.615586 -356.780475) (xy 258.437642 -356.762574) (xy 258.259078 -356.752617)
			(xy 258.080247 -356.750625) (xy 257.901505 -356.756601) (xy 257.723206 -356.770534) (xy 257.545705 -356.792395)
			(xy 257.369355 -356.822141) (xy 257.194504 -356.859714) (xy 257.021501 -356.905039) (xy 256.850688 -356.958026)
			(xy 256.682406 -357.018569) (xy 256.516987 -357.086548) (xy 256.354761 -357.161829) (xy 256.19605 -357.244262)
			(xy 256.041168 -357.333683) (xy 255.890424 -357.429915) (xy 255.744116 -357.532766) (xy 255.602535 -357.642033)
			(xy 255.465961 -357.757498) (xy 255.334668 -357.878933) (xy 255.208914 -358.006096) (xy 255.088949 -358.138734)
			(xy 254.975012 -358.276585) (xy 254.867329 -358.419375) (xy 254.766114 -358.566819) (xy 254.671568 -358.718627)
			(xy 254.583878 -358.874495) (xy 254.503218 -359.034115) (xy 254.429749 -359.197169) (xy 254.363617 -359.363335)
			(xy 254.304952 -359.532281) (xy 254.253872 -359.703673) (xy 254.210477 -359.877171) (xy 254.174855 -360.052429)
			(xy 254.147074 -360.2291) (xy 254.127192 -360.406834) (xy 254.115246 -360.585276) (xy 254.111262 -360.764074)
			(xy 255.609857 -360.764074) (xy 255.613885 -360.621782) (xy 255.625957 -360.479946) (xy 255.646034 -360.339019)
			(xy 255.674052 -360.199455) (xy 255.709921 -360.061699) (xy 255.753526 -359.926193) (xy 255.804727 -359.793371)
			(xy 255.863361 -359.663658) (xy 255.929239 -359.537471) (xy 256.002151 -359.415212) (xy 256.081863 -359.297275)
			(xy 256.16812 -359.184036) (xy 256.260644 -359.075858) (xy 256.359141 -358.973088) (xy 256.463295 -358.876055)
			(xy 256.572771 -358.785071) (xy 256.687219 -358.700425) (xy 256.806273 -358.62239) (xy 256.929551 -358.551216)
			(xy 257.056658 -358.487129) (xy 257.187187 -358.430337) (xy 257.320721 -358.38102) (xy 257.45683 -358.339337)
			(xy 257.59508 -358.305421) (xy 257.735027 -358.279381) (xy 257.876223 -358.2613) (xy 258.018216 -358.251237)
			(xy 258.160551 -358.249222) (xy 258.302772 -358.255264) (xy 258.444423 -358.269342) (xy 258.585051 -358.291411)
			(xy 258.724205 -358.321401) (xy 258.86144 -358.359216) (xy 258.996315 -358.404734) (xy 259.128399 -358.45781)
			(xy 259.257269 -358.518273) (xy 259.382512 -358.58593) (xy 259.503726 -358.660565) (xy 259.620524 -358.741938)
			(xy 259.732531 -358.829788) (xy 259.839389 -358.923835) (xy 259.940754 -359.023776) (xy 260.036303 -359.129292)
			(xy 260.12573 -359.240045) (xy 260.208748 -359.355679) (xy 260.28509 -359.475826) (xy 260.354513 -359.600098)
			(xy 260.416794 -359.7281) (xy 260.471734 -359.85942) (xy 260.519156 -359.993637) (xy 260.558909 -360.130323)
			(xy 260.590865 -360.269039) (xy 260.614922 -360.40934) (xy 260.631003 -360.550778) (xy 260.639056 -360.692899)
			(xy 260.63956 -360.764074) (xy 260.639056 -360.835249) (xy 260.631003 -360.97737) (xy 260.614922 -361.118808)
			(xy 260.590865 -361.259109) (xy 260.558909 -361.397825) (xy 260.519156 -361.534511) (xy 260.471734 -361.668728)
			(xy 260.416794 -361.800048) (xy 260.354513 -361.92805) (xy 260.28509 -362.052322) (xy 260.208748 -362.172469)
			(xy 260.12573 -362.288103) (xy 260.036303 -362.398856) (xy 259.940754 -362.504372) (xy 259.839389 -362.604313)
			(xy 259.732531 -362.69836) (xy 259.620524 -362.78621) (xy 259.503726 -362.867583) (xy 259.382512 -362.942218)
			(xy 259.257269 -363.009875) (xy 259.128399 -363.070338) (xy 258.996315 -363.123414) (xy 258.86144 -363.168932)
			(xy 258.724205 -363.206747) (xy 258.585051 -363.236737) (xy 258.444423 -363.258806) (xy 258.302772 -363.272884)
			(xy 258.160551 -363.278926) (xy 258.018216 -363.276911) (xy 257.876223 -363.266848) (xy 257.735027 -363.248767)
			(xy 257.59508 -363.222727) (xy 257.45683 -363.188811) (xy 257.320721 -363.147128) (xy 257.187187 -363.097811)
			(xy 257.056658 -363.041019) (xy 256.929551 -362.976932) (xy 256.806273 -362.905758) (xy 256.687219 -362.827723)
			(xy 256.572771 -362.743077) (xy 256.463295 -362.652093) (xy 256.359141 -362.55506) (xy 256.260644 -362.45229)
			(xy 256.16812 -362.344112) (xy 256.081863 -362.230873) (xy 256.002151 -362.112936) (xy 255.929239 -361.990677)
			(xy 255.863361 -361.86449) (xy 255.804727 -361.734777) (xy 255.753526 -361.601955) (xy 255.709921 -361.466449)
			(xy 255.674052 -361.328693) (xy 255.646034 -361.189129) (xy 255.625957 -361.048202) (xy 255.613885 -360.906366)
			(xy 255.609857 -360.764074) (xy 254.111262 -360.764074) (xy 254.115246 -360.942872) (xy 254.127192 -361.121314)
			(xy 254.147074 -361.299048) (xy 254.174855 -361.475719) (xy 254.210477 -361.650977) (xy 254.253872 -361.824475)
			(xy 254.304952 -361.995867) (xy 254.363617 -362.164813) (xy 254.429749 -362.330979) (xy 254.503218 -362.494033)
			(xy 254.583878 -362.653653) (xy 254.671568 -362.809521) (xy 254.766114 -362.961329) (xy 254.867329 -363.108773)
			(xy 254.975012 -363.251563) (xy 255.088949 -363.389414) (xy 255.208914 -363.522052) (xy 255.334668 -363.649215)
			(xy 255.465961 -363.77065) (xy 255.602535 -363.886115) (xy 255.744116 -363.995382) (xy 255.890424 -364.098233)
			(xy 256.041168 -364.194465) (xy 256.19605 -364.283886) (xy 256.354761 -364.366319) (xy 256.516987 -364.4416)
			(xy 256.682406 -364.509579) (xy 256.850688 -364.570122) (xy 257.021501 -364.623109) (xy 257.194504 -364.668434)
			(xy 257.369355 -364.706007) (xy 257.545705 -364.735753) (xy 257.723206 -364.757614) (xy 257.901505 -364.771547)
			(xy 258.080247 -364.777523) (xy 258.259078 -364.775531) (xy 258.437642 -364.765574) (xy 258.615586 -364.747673)
			(xy 258.792556 -364.721862) (xy 258.9682 -364.688194) (xy 259.14217 -364.646735) (xy 259.314121 -364.597567)
			(xy 259.48371 -364.540788) (xy 259.650602 -364.476511) (xy 259.814465 -364.404863) (xy 259.974974 -364.325987)
			(xy 260.131809 -364.240038) (xy 260.28466 -364.147189) (xy 260.433223 -364.047623) (xy 260.577204 -363.941537)
			(xy 260.716315 -363.829143) (xy 260.850282 -363.710664) (xy 260.978838 -363.586334) (xy 261.101728 -363.456401)
			(xy 261.218707 -363.321123) (xy 261.329545 -363.180768) (xy 261.434019 -363.035615) (xy 261.531925 -362.885952)
			(xy 261.623065 -362.732076) (xy 261.707261 -362.574292) (xy 261.784344 -362.412915) (xy 261.854162 -362.248264)
			(xy 261.916576 -362.080667) (xy 261.971463 -361.910455) (xy 262.018712 -361.737968) (xy 262.05823 -361.563546)
			(xy 262.08994 -361.387538) (xy 262.113777 -361.210292) (xy 262.129695 -361.032159) (xy 262.137662 -360.853495)
		)
		(stroke
			(width 0)
			(type solid)
		)
		(fill yes)
		(layer "B.Cu")
		(net "GND")
	)
	(gr_poly
		(pts
			(xy 414.318196 -358.804972) (xy 414.328266 -358.804549) (xy 414.346869 -358.796832) (xy 414.354264 -358.789986)
			(xy 415.030412 -358.113838) (xy 415.037258 -358.10644) (xy 415.044984 -358.087841) (xy 415.045398 -358.07777)
			(xy 415.045398 -355.765354) (xy 415.04583 -355.755288) (xy 415.053556 -355.736695) (xy 415.060384 -355.729286)
			(xy 415.927032 -354.862638) (xy 415.93443 -354.855792) (xy 415.953029 -354.848063) (xy 415.9631 -354.847652)
			(xy 416.371024 -354.847652) (xy 416.382842 -354.847094) (xy 416.404023 -354.83662) (xy 416.411664 -354.827586)
			(xy 416.460432 -354.762816) (xy 416.467082 -354.753059) (xy 416.471432 -354.729882) (xy 416.468814 -354.718366)
			(xy 416.462043 -354.692865) (xy 416.454772 -354.640607) (xy 416.454336 -354.614226) (xy 416.454336 -354.613972)
			(xy 416.454822 -354.586703) (xy 416.462584 -354.532719) (xy 416.477949 -354.480389) (xy 416.500606 -354.430779)
			(xy 416.530092 -354.384898) (xy 416.565807 -354.343681) (xy 416.607024 -354.307966) (xy 416.652905 -354.27848)
			(xy 416.702515 -354.255823) (xy 416.754845 -354.240458) (xy 416.808829 -354.232696) (xy 416.863367 -354.232696)
			(xy 416.917351 -354.240458) (xy 416.969681 -354.255823) (xy 417.019291 -354.27848) (xy 417.065172 -354.307966)
			(xy 417.106389 -354.343681) (xy 417.142104 -354.384898) (xy 417.17159 -354.430779) (xy 417.194247 -354.480389)
			(xy 417.209612 -354.532719) (xy 417.217374 -354.586703) (xy 417.21786 -354.613972) (xy 417.21786 -354.614226)
			(xy 417.217413 -354.640606) (xy 417.210144 -354.692863) (xy 417.203382 -354.718366) (xy 417.200785 -354.729877)
			(xy 417.205153 -354.753041) (xy 417.211764 -354.762816) (xy 417.260532 -354.827586) (xy 417.268171 -354.836622)
			(xy 417.289355 -354.8471) (xy 417.301172 -354.847652) (xy 417.333176 -354.847652) (xy 417.343239 -354.847214)
			(xy 417.361819 -354.839474) (xy 417.369244 -354.832666) (xy 418.845492 -353.356418) (xy 418.852326 -353.349015)
			(xy 418.860032 -353.330417) (xy 418.860478 -353.32035) (xy 418.860478 -351.568258) (xy 418.860908 -351.558191)
			(xy 418.868631 -351.539595) (xy 418.875464 -351.53219) (xy 419.317932 -351.089722) (xy 419.325331 -351.082878)
			(xy 419.343929 -351.075152) (xy 419.354 -351.074736) (xy 421.514524 -351.074736) (xy 421.524592 -351.075164)
			(xy 421.543186 -351.082889) (xy 421.550592 -351.089722) (xy 421.880538 -351.419668) (xy 421.887381 -351.427067)
			(xy 421.8951 -351.445666) (xy 421.895524 -351.455736) (xy 421.895524 -353.331018) (xy 421.895613 -353.336038)
			(xy 421.897528 -353.345892) (xy 421.899334 -353.350576) (xy 421.9067 -353.367848) (xy 421.908709 -353.37241)
			(xy 421.914212 -353.380721) (xy 421.917622 -353.384358) (xy 421.924226 -353.390962) (xy 421.927841 -353.3944)
			(xy 421.936155 -353.399909) (xy 421.940736 -353.401884) (xy 421.958008 -353.40925) (xy 421.962695 -353.411046)
			(xy 421.972547 -353.412961) (xy 421.977566 -353.41306) (xy 423.642282 -353.41306) (xy 423.647301 -353.412965)
			(xy 423.657151 -353.411041) (xy 423.66184 -353.40925) (xy 423.679112 -353.401884) (xy 423.683678 -353.39988)
			(xy 423.691999 -353.394388) (xy 423.695622 -353.390962) (xy 423.734992 -353.351592) (xy 423.737791 -353.348634)
			(xy 423.74251 -353.341997) (xy 423.74439 -353.338384) (xy 423.745406 -353.336352) (xy 423.745406 -351.217738)
			(xy 423.745841 -351.207673) (xy 423.753572 -351.189085) (xy 423.760392 -351.18167) (xy 423.912284 -351.029778)
			(xy 423.919683 -351.022936) (xy 423.938283 -351.01522) (xy 423.948352 -351.014792) (xy 429.609504 -351.014792)
			(xy 429.619574 -351.015215) (xy 429.638178 -351.02293) (xy 429.645572 -351.029778) (xy 430.207166 -351.591372)
			(xy 430.214005 -351.598773) (xy 430.221718 -351.617371) (xy 430.222152 -351.62744) (xy 430.222152 -353.356418)
			(xy 430.222241 -353.361438) (xy 430.224153 -353.371293) (xy 430.225962 -353.375976) (xy 430.233328 -353.393248)
			(xy 430.235335 -353.397812) (xy 430.240832 -353.406128) (xy 430.24425 -353.409758) (xy 430.250854 -353.416362)
			(xy 430.25447 -353.419798) (xy 430.262786 -353.425303) (xy 430.267364 -353.427284) (xy 430.284636 -353.43465)
			(xy 430.289324 -353.436443) (xy 430.299176 -353.438353) (xy 430.304194 -353.43846) (xy 431.96891 -353.43846)
			(xy 431.97393 -353.438372) (xy 431.983786 -353.436461) (xy 431.988468 -353.43465) (xy 432.00574 -353.427284)
			(xy 432.010305 -353.425278) (xy 432.018623 -353.419783) (xy 432.02225 -353.416362) (xy 432.06162 -353.376992)
			(xy 432.064422 -353.374036) (xy 432.069147 -353.367402) (xy 432.071018 -353.363784) (xy 432.072034 -353.361752)
			(xy 432.072034 -351.223072) (xy 432.072463 -351.213005) (xy 432.080188 -351.194411) (xy 432.08702 -351.187004)
			(xy 432.15814 -351.115884) (xy 432.165537 -351.109035) (xy 432.184136 -351.101301) (xy 432.194208 -351.100898)
			(xy 435.70779 -351.100898) (xy 435.710584 -351.098358) (xy 435.712362 -351.100136) (xy 438.50306 -351.100136)
			(xy 438.513125 -351.100571) (xy 438.53171 -351.108305) (xy 438.539128 -351.115122) (xy 438.696608 -351.272602)
			(xy 438.696608 -352.718878) (xy 439.547 -353.56927) (xy 439.547 -353.62388) (xy 439.547 -356.848918)
			(xy 439.547427 -356.858987) (xy 439.555146 -356.877586) (xy 439.561986 -356.884986) (xy 439.786014 -357.109014)
			(xy 439.793409 -357.115868) (xy 439.812008 -357.12361) (xy 439.822082 -357.124) (xy 444.865506 -357.124)
			(xy 444.875576 -357.123576) (xy 444.894179 -357.11586) (xy 444.901574 -357.109014) (xy 445.659764 -356.350824)
			(xy 445.666602 -356.343423) (xy 445.674315 -356.324824) (xy 445.67475 -356.314756) (xy 445.67475 -329.556618)
			(xy 445.67431 -329.546556) (xy 445.66657 -329.527978) (xy 445.659764 -329.52055) (xy 444.85052 -328.711306)
			(xy 444.843117 -328.704472) (xy 444.824519 -328.696765) (xy 444.814452 -328.69632) (xy 417.420552 -328.69632)
			(xy 417.40201 -328.704194) (xy 417.399724 -328.70648) (xy 416.851592 -328.70648) (xy 416.841522 -328.706904)
			(xy 416.822918 -328.714618) (xy 416.815524 -328.721466) (xy 415.666428 -329.870562) (xy 415.659588 -329.877963)
			(xy 415.651872 -329.896561) (xy 415.651442 -329.90663) (xy 415.651442 -337.111086) (xy 415.651002 -337.121148)
			(xy 415.643259 -337.139724) (xy 415.636456 -337.147154) (xy 411.016196 -341.767414) (xy 416.129724 -341.767414)
			(xy 416.129724 -336.4484) (xy 416.130486 -336.440272) (xy 416.51555 -334.116426) (xy 416.517836 -334.10779)
			(xy 416.902646 -333.023972) (xy 416.904676 -333.018673) (xy 416.910699 -333.009059) (xy 416.914584 -333.004922)
			(xy 417.404042 -332.51521) (xy 417.411435 -332.50836) (xy 417.430039 -332.500646) (xy 417.44011 -332.500224)
			(xy 441.34786 -332.500224) (xy 441.357928 -332.500664) (xy 441.376526 -332.508374) (xy 441.383928 -332.51521)
			(xy 442.544962 -333.676244) (xy 442.551808 -333.683639) (xy 442.559526 -333.702242) (xy 442.559948 -333.712312)
			(xy 442.559948 -341.462868) (xy 442.55952 -341.472937) (xy 442.551802 -341.491536) (xy 442.544962 -341.498936)
			(xy 441.83935 -342.204294) (xy 441.831926 -342.211104) (xy 441.813345 -342.218841) (xy 441.803282 -342.21928)
			(xy 416.58159 -342.21928) (xy 416.57152 -342.218865) (xy 416.552922 -342.211138) (xy 416.545522 -342.204294)
			(xy 416.14471 -341.803482) (xy 416.137871 -341.796081) (xy 416.13015 -341.777483) (xy 416.129724 -341.767414)
			(xy 411.016196 -341.767414) (xy 408.815286 -343.968324) (xy 408.808434 -343.97572) (xy 408.800695 -343.994319)
			(xy 408.8003 -344.004392) (xy 408.8003 -358.622346) (xy 408.800732 -358.632412) (xy 408.808458 -358.651005)
			(xy 408.815286 -358.658414) (xy 408.946858 -358.789986) (xy 408.954259 -358.796825) (xy 408.972857 -358.804541)
			(xy 408.982926 -358.804972)
		)
		(stroke
			(width 0)
			(type solid)
		)
		(fill yes)
		(layer "B.Cu")
		(net "GND")
	)
	(gr_poly
		(pts
			(xy 240.89995 -81.700116) (xy 240.899449 -81.600062) (xy 240.891443 -81.400115) (xy 240.875444 -81.200648)
			(xy 240.851476 -81.00198) (xy 240.819579 -80.804431) (xy 240.779804 -80.608316) (xy 240.732214 -80.41395)
			(xy 240.676886 -80.221643) (xy 240.613908 -80.031704) (xy 240.543381 -79.844437) (xy 240.465418 -79.660141)
			(xy 240.380144 -79.479112) (xy 240.287695 -79.30164) (xy 240.18822 -79.128009) (xy 240.081877 -78.958497)
			(xy 239.968838 -78.793376) (xy 239.849282 -78.632909) (xy 239.723402 -78.477354) (xy 239.591399 -78.32696)
			(xy 239.453485 -78.181968) (xy 239.30988 -78.04261) (xy 239.160814 -77.909109) (xy 239.006526 -77.781679)
			(xy 238.847264 -77.660524) (xy 238.683281 -77.545838) (xy 238.514842 -77.437805) (xy 238.342215 -77.336597)
			(xy 238.165676 -77.242377) (xy 237.98551 -77.155296) (xy 237.802003 -77.075493) (xy 237.615451 -77.003096)
			(xy 237.426152 -76.938221) (xy 237.234408 -76.880971) (xy 237.040527 -76.831439) (xy 236.84482 -76.789704)
			(xy 236.6476 -76.755832) (xy 236.449183 -76.729879) (xy 236.249886 -76.711884) (xy 236.050028 -76.701878)
			(xy 235.849931 -76.699876) (xy 235.649913 -76.705881) (xy 235.450296 -76.719884) (xy 235.251399 -76.741863)
			(xy 235.05354 -76.771782) (xy 234.857037 -76.809593) (xy 234.662204 -76.855236) (xy 234.469354 -76.908637)
			(xy 234.278794 -76.969712) (xy 234.090831 -77.038361) (xy 233.905764 -77.114477) (xy 233.723891 -77.197935)
			(xy 233.545503 -77.288604) (xy 233.370886 -77.386337) (xy 233.200318 -77.490978) (xy 233.034074 -77.60236)
			(xy 232.872419 -77.720304) (xy 232.715612 -77.844622) (xy 232.563905 -77.975113) (xy 232.417541 -78.11157)
			(xy 232.276753 -78.253774) (xy 232.141767 -78.401497) (xy 232.0128 -78.554502) (xy 231.890057 -78.712544)
			(xy 231.773737 -78.875371) (xy 231.664024 -79.042721) (xy 231.561094 -79.214327) (xy 231.465113 -79.389914)
			(xy 231.376233 -79.5692) (xy 231.294598 -79.751899) (xy 231.220339 -79.937718) (xy 231.153573 -80.126359)
			(xy 231.094408 -80.31752) (xy 231.042938 -80.510895) (xy 230.999247 -80.706175) (xy 230.963404 -80.903046)
			(xy 230.935466 -81.101194) (xy 230.915479 -81.300301) (xy 230.903473 -81.500048) (xy 230.899643 -81.691489)
			(xy 232.138767 -81.691489) (xy 232.143191 -81.51754) (xy 232.155655 -81.343981) (xy 232.176134 -81.171185)
			(xy 232.204582 -80.999521) (xy 232.24094 -80.829356) (xy 232.285129 -80.661055) (xy 232.337055 -80.494978)
			(xy 232.396606 -80.331481) (xy 232.463656 -80.170912) (xy 232.53806 -80.013617) (xy 232.61966 -79.859931)
			(xy 232.708281 -79.710183) (xy 232.803732 -79.564695) (xy 232.905811 -79.423777) (xy 233.014297 -79.287731)
			(xy 233.12896 -79.156848) (xy 233.249554 -79.031409) (xy 233.37582 -78.911681) (xy 233.507489 -78.797922)
			(xy 233.644278 -78.690374) (xy 233.714798 -78.639416) (xy 238.085122 -78.639416) (xy 238.155642 -78.690374)
			(xy 238.292431 -78.797922) (xy 238.4241 -78.911681) (xy 238.550366 -79.031409) (xy 238.67096 -79.156848)
			(xy 238.785623 -79.287731) (xy 238.894109 -79.423777) (xy 238.996188 -79.564695) (xy 239.091639 -79.710183)
			(xy 239.18026 -79.859931) (xy 239.26186 -80.013617) (xy 239.336264 -80.170912) (xy 239.403314 -80.331481)
			(xy 239.462865 -80.494978) (xy 239.514791 -80.661055) (xy 239.55898 -80.829356) (xy 239.595338 -80.999521)
			(xy 239.623786 -81.171185) (xy 239.644265 -81.343981) (xy 239.656729 -81.51754) (xy 239.661153 -81.691489)
			(xy 239.657527 -81.865456) (xy 239.645859 -82.03907) (xy 239.626174 -82.211958) (xy 239.598513 -82.383751)
			(xy 239.562936 -82.554081) (xy 239.51952 -82.722583) (xy 239.468356 -82.888896) (xy 239.409555 -83.052665)
			(xy 239.343243 -83.21354) (xy 239.269561 -83.371175) (xy 239.188667 -83.525234) (xy 239.100735 -83.675386)
			(xy 239.005951 -83.821311) (xy 238.904521 -83.962695) (xy 238.796659 -84.099238) (xy 238.682598 -84.230645)
			(xy 238.562581 -84.356636) (xy 238.436865 -84.476942) (xy 238.30572 -84.591304) (xy 238.169425 -84.699479)
			(xy 238.028273 -84.801234) (xy 237.882567 -84.896351) (xy 237.732616 -84.984628) (xy 237.578744 -85.065875)
			(xy 237.421278 -85.139919) (xy 237.260556 -85.2066) (xy 237.096922 -85.265776) (xy 236.930726 -85.317321)
			(xy 236.762325 -85.361124) (xy 236.592077 -85.397091) (xy 236.420348 -85.425146) (xy 236.247505 -85.445228)
			(xy 236.073919 -85.457294) (xy 235.89996 -85.461319) (xy 235.726001 -85.457294) (xy 235.552415 -85.445228)
			(xy 235.379572 -85.425146) (xy 235.207843 -85.397091) (xy 235.037595 -85.361124) (xy 234.869194 -85.317321)
			(xy 234.702998 -85.265776) (xy 234.539364 -85.2066) (xy 234.378642 -85.139919) (xy 234.221176 -85.065875)
			(xy 234.067304 -84.984628) (xy 233.917353 -84.896351) (xy 233.771647 -84.801234) (xy 233.630495 -84.699479)
			(xy 233.4942 -84.591304) (xy 233.363055 -84.476942) (xy 233.237339 -84.356636) (xy 233.117322 -84.230645)
			(xy 233.003261 -84.099238) (xy 232.895399 -83.962695) (xy 232.793969 -83.821311) (xy 232.699185 -83.675386)
			(xy 232.611253 -83.525234) (xy 232.530359 -83.371175) (xy 232.456677 -83.21354) (xy 232.390365 -83.052665)
			(xy 232.331564 -82.888896) (xy 232.2804 -82.722583) (xy 232.236984 -82.554081) (xy 232.201407 -82.383751)
			(xy 232.173746 -82.211958) (xy 232.154061 -82.03907) (xy 232.142393 -81.865456) (xy 232.138767 -81.691489)
			(xy 230.899643 -81.691489) (xy 230.89947 -81.700116) (xy 230.903473 -81.900184) (xy 230.915479 -82.099931)
			(xy 230.935466 -82.299038) (xy 230.963404 -82.497186) (xy 230.999247 -82.694057) (xy 231.042938 -82.889337)
			(xy 231.094408 -83.082712) (xy 231.153573 -83.273873) (xy 231.220339 -83.462514) (xy 231.294598 -83.648333)
			(xy 231.376233 -83.831032) (xy 231.465113 -84.010318) (xy 231.561094 -84.185905) (xy 231.664024 -84.357511)
			(xy 231.773737 -84.524861) (xy 231.890057 -84.687688) (xy 232.0128 -84.84573) (xy 232.141767 -84.998735)
			(xy 232.276753 -85.146458) (xy 232.417541 -85.288662) (xy 232.563905 -85.425119) (xy 232.715612 -85.55561)
			(xy 232.872419 -85.679928) (xy 233.034074 -85.797872) (xy 233.200318 -85.909254) (xy 233.370886 -86.013895)
			(xy 233.545503 -86.111628) (xy 233.723891 -86.202297) (xy 233.905764 -86.285755) (xy 234.090831 -86.361871)
			(xy 234.278794 -86.43052) (xy 234.469354 -86.491595) (xy 234.662204 -86.544996) (xy 234.857037 -86.590639)
			(xy 235.05354 -86.62845) (xy 235.251399 -86.658369) (xy 235.450296 -86.680348) (xy 235.649913 -86.694351)
			(xy 235.849931 -86.700356) (xy 236.050028 -86.698354) (xy 236.249886 -86.688348) (xy 236.449183 -86.670353)
			(xy 236.6476 -86.6444) (xy 236.84482 -86.610528) (xy 237.040527 -86.568793) (xy 237.234408 -86.519261)
			(xy 237.426152 -86.462011) (xy 237.615451 -86.397136) (xy 237.802003 -86.324739) (xy 237.98551 -86.244936)
			(xy 238.165676 -86.157855) (xy 238.342215 -86.063635) (xy 238.514842 -85.962427) (xy 238.683281 -85.854394)
			(xy 238.847264 -85.739708) (xy 239.006526 -85.618553) (xy 239.160814 -85.491123) (xy 239.30988 -85.357622)
			(xy 239.453485 -85.218264) (xy 239.591399 -85.073272) (xy 239.723402 -84.922878) (xy 239.849282 -84.767323)
			(xy 239.968838 -84.606856) (xy 240.081877 -84.441735) (xy 240.18822 -84.272223) (xy 240.287695 -84.098592)
			(xy 240.380144 -83.92112) (xy 240.465418 -83.740091) (xy 240.543381 -83.555795) (xy 240.613908 -83.368528)
			(xy 240.676886 -83.178589) (xy 240.732214 -82.986282) (xy 240.779804 -82.791916) (xy 240.819579 -82.595801)
			(xy 240.851476 -82.398252) (xy 240.875444 -82.199584) (xy 240.891443 -82.000117) (xy 240.899449 -81.80017)
		)
		(stroke
			(width 0)
			(type solid)
		)
		(fill yes)
		(layer "B.Cu")
		(net "GND")
	)
	(gr_poly
		(pts
			(xy 36.047426 -406.543002) (xy 36.057494 -406.542574) (xy 36.076092 -406.534853) (xy 36.083494 -406.528016)
			(xy 36.49853 -406.11298) (xy 36.505381 -406.105584) (xy 36.513119 -406.086985) (xy 36.513516 -406.076912)
			(xy 36.513516 -402.594318) (xy 36.513955 -402.584255) (xy 36.521692 -402.565673) (xy 36.528502 -402.55825)
			(xy 37.750496 -401.336256) (xy 37.757336 -401.328855) (xy 37.765055 -401.310257) (xy 37.765482 -401.300188)
			(xy 37.765482 -391.004806) (xy 37.765482 -387.914388) (xy 37.765482 -384.854704) (xy 37.765059 -384.844634)
			(xy 37.757344 -384.82603) (xy 37.750496 -384.818636) (xy 36.001198 -383.069338) (xy 35.993801 -383.062488)
			(xy 35.975203 -383.054748) (xy 35.96513 -383.054352) (xy 5.152898 -383.054352) (xy 5.142829 -383.053927)
			(xy 5.12423 -383.046207) (xy 5.11683 -383.039366) (xy 4.87934 -382.801876) (xy 4.872493 -382.794478)
			(xy 4.864761 -382.77588) (xy 4.864354 -382.765808) (xy 4.864354 -373.684038) (xy 4.86479 -373.673974)
			(xy 4.872526 -373.655391) (xy 4.87934 -373.64797) (xy 5.29971 -373.2276) (xy 5.307109 -373.220755)
			(xy 5.325707 -373.213025) (xy 5.335778 -373.212614) (xy 26.17089 -373.212614) (xy 26.180961 -373.212193)
			(xy 26.19957 -373.204483) (xy 26.206958 -373.197628) (xy 26.451814 -372.952772) (xy 26.458665 -372.945376)
			(xy 26.466403 -372.926777) (xy 26.4668 -372.916704) (xy 26.4668 -368.764312) (xy 26.466379 -368.754241)
			(xy 26.458668 -368.735633) (xy 26.451814 -368.728244) (xy 26.163016 -368.439446) (xy 26.155615 -368.432608)
			(xy 26.137016 -368.424897) (xy 26.126948 -368.42446) (xy 3.59537 -368.42446) (xy 3.585304 -368.42489)
			(xy 3.566713 -368.432619) (xy 3.559302 -368.439446) (xy 3.349752 -368.648996) (xy 3.342899 -368.656392)
			(xy 3.335155 -368.67499) (xy 3.334766 -368.685064) (xy 3.334766 -401.417282) (xy 3.335206 -401.427344)
			(xy 3.342949 -401.445921) (xy 3.349752 -401.45335) (xy 3.81762 -401.921218) (xy 3.825016 -401.92807)
			(xy 3.843615 -401.93581) (xy 3.853688 -401.936204) (xy 17.615408 -401.936204) (xy 17.625478 -401.935779)
			(xy 17.64408 -401.928063) (xy 17.651476 -401.921218) (xy 17.773396 -401.799298) (xy 17.780243 -401.7919)
			(xy 17.787977 -401.773302) (xy 17.788382 -401.76323) (xy 17.788382 -395.350492) (xy 17.787957 -395.340423)
			(xy 17.780239 -395.321822) (xy 17.773396 -395.314424) (xy 17.529302 -395.07033) (xy 17.51076 -395.06271)
			(xy 17.502632 -395.06271) (xy 17.436846 -394.996924) (xy 17.429425 -394.990137) (xy 17.410828 -394.982522)
			(xy 17.400778 -394.982192) (xy 14.851634 -394.982192) (xy 14.84503 -394.988796) (xy 14.626336 -394.988796)
			(xy 14.616271 -394.989231) (xy 14.597683 -394.996961) (xy 14.590268 -395.003782) (xy 12.858496 -396.735554)
			(xy 12.851099 -396.742405) (xy 12.832501 -396.750145) (xy 12.822428 -396.75054) (xy 12.009882 -396.75054)
			(xy 11.999815 -396.750112) (xy 11.981221 -396.742386) (xy 11.973814 -396.735554) (xy 11.433556 -396.195296)
			(xy 11.426704 -396.1879) (xy 11.418962 -396.169301) (xy 11.41857 -396.159228) (xy 11.41857 -389.310626)
			(xy 11.419074 -389.300575) (xy 11.426794 -389.282012) (xy 11.433556 -389.274558) (xy 12.149074 -388.55904)
			(xy 12.156475 -388.552201) (xy 12.175073 -388.544487) (xy 12.185142 -388.544054) (xy 13.574014 -388.544054)
			(xy 13.584082 -388.544481) (xy 13.602678 -388.552205) (xy 13.610082 -388.55904) (xy 13.75283 -388.701788)
			(xy 13.759686 -388.709182) (xy 13.767436 -388.727781) (xy 13.767816 -388.737856) (xy 13.767816 -390.000998)
			(xy 13.768239 -390.011068) (xy 13.775955 -390.029671) (xy 13.782802 -390.037066) (xy 14.812264 -391.066528)
			(xy 14.819662 -391.073372) (xy 14.838262 -391.081095) (xy 14.848332 -391.081514) (xy 16.482568 -391.081514)
			(xy 16.492633 -391.081079) (xy 16.511221 -391.073349) (xy 16.518636 -391.066528) (xy 16.539464 -391.0457)
			(xy 16.546314 -391.038303) (xy 16.554054 -391.019705) (xy 16.55445 -391.009632) (xy 16.55445 -388.892796)
			(xy 16.554875 -388.882727) (xy 16.562596 -388.864129) (xy 16.569436 -388.856728) (xy 16.65224 -388.773924)
			(xy 16.659639 -388.767081) (xy 16.678238 -388.759357) (xy 16.688308 -388.758938) (xy 20.83054 -388.758938)
			(xy 20.830794 -388.759192) (xy 21.034502 -388.759192) (xy 21.044572 -388.758768) (xy 21.063175 -388.751052)
			(xy 21.07057 -388.744206) (xy 21.143722 -388.671054) (xy 21.151119 -388.664205) (xy 21.169718 -388.65647)
			(xy 21.17979 -388.656068) (xy 22.863302 -388.656068) (xy 22.873373 -388.656491) (xy 22.89198 -388.664202)
			(xy 22.89937 -388.671054) (xy 23.047198 -388.818882) (xy 23.054032 -388.826285) (xy 23.061736 -388.844883)
			(xy 23.062184 -388.85495) (xy 23.062184 -389.600186) (xy 23.061745 -389.610249) (xy 23.054007 -389.628829)
			(xy 23.047198 -389.636254) (xy 23.045928 -389.637524) (xy 23.045928 -390.200642) (xy 23.046359 -390.210708)
			(xy 23.054088 -390.229299) (xy 23.060914 -390.23671) (xy 23.890986 -391.066528) (xy 23.898386 -391.073369)
			(xy 23.916985 -391.081083) (xy 23.927054 -391.081514) (xy 25.56129 -391.081514) (xy 25.571361 -391.081093)
			(xy 25.58997 -391.073383) (xy 25.597358 -391.066528) (xy 25.618186 -391.0457) (xy 25.625034 -391.038302)
			(xy 25.63277 -391.019704) (xy 25.633172 -391.009632) (xy 25.633172 -388.920736) (xy 25.633675 -388.910684)
			(xy 25.641392 -388.892119) (xy 25.648158 -388.884668) (xy 25.90165 -388.631176) (xy 25.909047 -388.624329)
			(xy 25.927647 -388.616601) (xy 25.937718 -388.61619) (xy 29.326332 -388.61619) (xy 29.3364 -388.616618)
			(xy 29.354997 -388.62434) (xy 29.3624 -388.631176) (xy 31.66237 -390.931146) (xy 31.670498 -390.931146)
			(xy 31.670498 -395.257782) (xy 35.12769 -395.257782) (xy 35.131761 -395.20216) (xy 35.143887 -395.147723)
			(xy 35.16381 -395.095632) (xy 35.191106 -395.046997) (xy 35.225192 -395.002854) (xy 35.265341 -394.964145)
			(xy 35.310699 -394.931694) (xy 35.360299 -394.906193) (xy 35.413083 -394.888186) (xy 35.467926 -394.878056)
			(xy 35.52366 -394.876019) (xy 35.579097 -394.882119) (xy 35.633054 -394.896225) (xy 35.684383 -394.918037)
			(xy 35.731989 -394.947091) (xy 35.774857 -394.982766) (xy 35.812074 -395.024303) (xy 35.842847 -395.070816)
			(xy 35.866519 -395.121313) (xy 35.882587 -395.17472) (xy 35.890707 -395.229896) (xy 35.891216 -395.257782)
			(xy 35.890707 -395.285668) (xy 35.882587 -395.340844) (xy 35.866519 -395.394251) (xy 35.842847 -395.444748)
			(xy 35.812074 -395.491261) (xy 35.774857 -395.532798) (xy 35.731989 -395.568473) (xy 35.684383 -395.597527)
			(xy 35.633054 -395.619339) (xy 35.579097 -395.633445) (xy 35.52366 -395.639545) (xy 35.467926 -395.637508)
			(xy 35.413083 -395.627378) (xy 35.360299 -395.609371) (xy 35.310699 -395.58387) (xy 35.265341 -395.551419)
			(xy 35.225192 -395.51271) (xy 35.191106 -395.468567) (xy 35.16381 -395.419932) (xy 35.143887 -395.367841)
			(xy 35.131761 -395.313404) (xy 35.12769 -395.257782) (xy 31.670498 -395.257782) (xy 31.670498 -402.370544)
			(xy 31.670067 -402.380611) (xy 31.662341 -402.399203) (xy 31.655512 -402.406612) (xy 31.21279 -402.849334)
			(xy 31.205394 -402.856186) (xy 31.186795 -402.863927) (xy 31.176722 -402.86432) (xy 27.048206 -402.86432)
			(xy 27.038136 -402.864742) (xy 27.019532 -402.872458) (xy 27.012138 -402.879306) (xy 26.731214 -403.16023)
			(xy 26.724371 -403.16763) (xy 26.716645 -403.186228) (xy 26.716228 -403.196298) (xy 26.716228 -406.211024)
			(xy 26.716656 -406.221092) (xy 26.72438 -406.239687) (xy 26.731214 -406.247092) (xy 27.012138 -406.528016)
			(xy 27.019534 -406.534866) (xy 27.038134 -406.5426) (xy 27.048206 -406.543002)
		)
		(stroke
			(width 0)
			(type solid)
		)
		(fill yes)
		(layer "B.Cu")
		(net "GND")
	)
	(gr_poly
		(pts
			(xy 180.90642 -404.770844) (xy 180.91515 -404.770492) (xy 180.931588 -404.764611) (xy 180.945067 -404.753515)
			(xy 180.949854 -404.746206) (xy 180.96753 -404.717873) (xy 181.008353 -404.665021) (xy 181.054929 -404.617162)
			(xy 181.106654 -404.57492) (xy 181.162853 -404.538843) (xy 181.222795 -404.509402) (xy 181.2857 -404.486979)
			(xy 181.350749 -404.471866) (xy 181.417097 -404.46426) (xy 181.483879 -404.46426) (xy 181.550227 -404.471866)
			(xy 181.615276 -404.486979) (xy 181.678181 -404.509402) (xy 181.738123 -404.538843) (xy 181.794322 -404.57492)
			(xy 181.846047 -404.617162) (xy 181.892623 -404.665021) (xy 181.933446 -404.717873) (xy 181.951122 -404.746206)
			(xy 181.955934 -404.753487) (xy 181.969427 -404.764539) (xy 181.985837 -404.770446) (xy 181.994556 -404.770844)
			(xy 182.041038 -404.770844) (xy 182.051104 -404.770412) (xy 182.069693 -404.762682) (xy 182.077106 -404.755858)
			(xy 182.376572 -404.456392) (xy 182.38342 -404.448994) (xy 182.391156 -404.430396) (xy 182.391558 -404.420324)
			(xy 182.391558 -402.290788) (xy 182.391985 -402.28072) (xy 182.399709 -402.262124) (xy 182.406544 -402.25472)
			(xy 182.833518 -401.827746) (xy 182.840915 -401.820897) (xy 182.859514 -401.813162) (xy 182.869586 -401.81276)
			(xy 183.875934 -401.81276) (xy 183.886001 -401.812329) (xy 183.904592 -401.804602) (xy 183.912002 -401.797774)
			(xy 184.125616 -401.58416) (xy 184.132465 -401.576763) (xy 184.140199 -401.558164) (xy 184.140602 -401.548092)
			(xy 184.140602 -400.567144) (xy 184.140169 -400.557078) (xy 184.13244 -400.538489) (xy 184.125616 -400.531076)
			(xy 183.85536 -400.26082) (xy 183.84796 -400.253978) (xy 183.829362 -400.246255) (xy 183.819292 -400.245834)
			(xy 181.083204 -400.245834) (xy 181.072278 -400.246358) (xy 181.052406 -400.255449) (xy 181.04485 -400.26336)
			(xy 180.987192 -400.330162) (xy 180.981096 -400.35099) (xy 180.98262 -400.36242) (xy 180.985214 -400.380917)
			(xy 180.98801 -400.418165) (xy 180.988208 -400.436842) (xy 180.987741 -400.467571) (xy 180.980329 -400.528581)
			(xy 180.965617 -400.588253) (xy 180.943819 -400.645717) (xy 180.915255 -400.700134) (xy 180.88034 -400.750712)
			(xy 180.839583 -400.796713) (xy 180.793579 -400.837466) (xy 180.742998 -400.872377) (xy 180.688579 -400.900937)
			(xy 180.631113 -400.922729) (xy 180.57144 -400.937436) (xy 180.510429 -400.944844) (xy 180.4797 -400.94535)
			(xy 180.444711 -400.944768) (xy 180.375392 -400.935175) (xy 180.308044 -400.91617) (xy 180.243936 -400.888112)
			(xy 180.18428 -400.85153) (xy 180.156866 -400.82978) (xy 180.150008 -400.823938) (xy 180.133752 -400.818096)
			(xy 180.024532 -400.818096) (xy 180.014542 -400.818628) (xy 179.996101 -400.826333) (xy 179.988718 -400.833082)
			(xy 179.894738 -400.927062) (xy 179.887897 -400.934462) (xy 179.880179 -400.953061) (xy 179.879752 -400.96313)
			(xy 179.879752 -401.69465) (xy 181.001922 -401.69465) (xy 181.005993 -401.639028) (xy 181.018119 -401.584591)
			(xy 181.038042 -401.5325) (xy 181.065338 -401.483865) (xy 181.099424 -401.439722) (xy 181.139573 -401.401013)
			(xy 181.184931 -401.368562) (xy 181.234531 -401.343061) (xy 181.287315 -401.325054) (xy 181.342158 -401.314924)
			(xy 181.397892 -401.312887) (xy 181.453329 -401.318987) (xy 181.507286 -401.333093) (xy 181.558615 -401.354905)
			(xy 181.606221 -401.383959) (xy 181.649089 -401.419634) (xy 181.686306 -401.461171) (xy 181.717079 -401.507684)
			(xy 181.740751 -401.558181) (xy 181.756819 -401.611588) (xy 181.764939 -401.666764) (xy 181.765448 -401.69465)
			(xy 181.764939 -401.722536) (xy 181.756819 -401.777712) (xy 181.740751 -401.831119) (xy 181.717079 -401.881616)
			(xy 181.686306 -401.928129) (xy 181.649089 -401.969666) (xy 181.606221 -402.005341) (xy 181.558615 -402.034395)
			(xy 181.507286 -402.056207) (xy 181.453329 -402.070313) (xy 181.397892 -402.076413) (xy 181.342158 -402.074376)
			(xy 181.287315 -402.064246) (xy 181.234531 -402.046239) (xy 181.184931 -402.020738) (xy 181.139573 -401.988287)
			(xy 181.099424 -401.949578) (xy 181.065338 -401.905435) (xy 181.038042 -401.8568) (xy 181.018119 -401.804709)
			(xy 181.005993 -401.750272) (xy 181.001922 -401.69465) (xy 179.879752 -401.69465) (xy 179.879752 -401.955508)
			(xy 179.880178 -401.965576) (xy 179.8879 -401.984174) (xy 179.894738 -401.991576) (xy 180.082444 -402.179282)
			(xy 180.089844 -402.186124) (xy 180.108442 -402.193845) (xy 180.118512 -402.194268) (xy 180.184298 -402.194268)
			(xy 180.196744 -402.19122) (xy 180.202332 -402.187918) (xy 180.230519 -402.173036) (xy 180.28981 -402.149638)
			(xy 180.351564 -402.133847) (xy 180.414809 -402.125914) (xy 180.44668 -402.125434) (xy 180.477412 -402.125878)
			(xy 180.538428 -402.133285) (xy 180.598106 -402.147993) (xy 180.655576 -402.169788) (xy 180.71 -402.198352)
			(xy 180.760583 -402.233268) (xy 180.806589 -402.274026) (xy 180.847346 -402.320034) (xy 180.88226 -402.370619)
			(xy 180.910821 -402.425044) (xy 180.932613 -402.482515) (xy 180.947319 -402.542194) (xy 180.954723 -402.60321)
			(xy 180.955188 -402.633942) (xy 180.954653 -402.667047) (xy 180.946056 -402.732696) (xy 180.929012 -402.796675)
			(xy 180.903809 -402.857901) (xy 180.870875 -402.915339) (xy 180.830765 -402.968017) (xy 180.784159 -403.015045)
			(xy 180.758338 -403.03577) (xy 180.748686 -403.043136) (xy 180.738526 -403.06498) (xy 180.741574 -403.17166)
			(xy 180.753004 -403.192742) (xy 180.763164 -403.1996) (xy 180.791997 -403.2201) (xy 180.844978 -403.266985)
			(xy 180.891919 -403.319916) (xy 180.932134 -403.378122) (xy 180.965038 -403.440753) (xy 180.990148 -403.506894)
			(xy 181.0071 -403.575581) (xy 181.015645 -403.64581) (xy 181.016148 -403.681184) (xy 181.015653 -403.715211)
			(xy 181.007753 -403.782804) (xy 180.992059 -403.849022) (xy 180.968783 -403.912971) (xy 180.938241 -403.973786)
			(xy 180.900845 -404.030643) (xy 180.857102 -404.082775) (xy 180.807602 -404.129476) (xy 180.753015 -404.170114)
			(xy 180.694079 -404.204141) (xy 180.631591 -404.231095) (xy 180.566397 -404.250613) (xy 180.499378 -404.262431)
			(xy 180.43144 -404.266388) (xy 180.363502 -404.262431) (xy 180.296483 -404.250613) (xy 180.231289 -404.231095)
			(xy 180.168801 -404.204141) (xy 180.109865 -404.170114) (xy 180.055278 -404.129476) (xy 180.005778 -404.082775)
			(xy 179.962035 -404.030643) (xy 179.924639 -403.973786) (xy 179.894097 -403.912971) (xy 179.870821 -403.849022)
			(xy 179.855127 -403.782804) (xy 179.847227 -403.715211) (xy 179.846732 -403.681184) (xy 179.84723 -403.646437)
			(xy 179.855466 -403.577431) (xy 179.87182 -403.509888) (xy 179.896062 -403.444758) (xy 179.927849 -403.38296)
			(xy 179.966735 -403.325362) (xy 180.012171 -403.272778) (xy 180.063517 -403.225948) (xy 180.12005 -403.185531)
			(xy 180.150262 -403.168358) (xy 180.157665 -403.163887) (xy 180.169194 -403.15101) (xy 180.175842 -403.135056)
			(xy 180.176678 -403.126448) (xy 180.179726 -403.066758) (xy 180.175154 -403.063964) (xy 180.169013 -403.060354)
			(xy 180.155348 -403.056354) (xy 180.14823 -403.05609) (xy 179.039012 -403.05609) (xy 179.028941 -403.05651)
			(xy 179.010332 -403.064221) (xy 179.002944 -403.071076) (xy 178.85029 -403.22373) (xy 178.843438 -403.231126)
			(xy 178.835701 -403.249725) (xy 178.835304 -403.259798) (xy 178.835304 -403.66188) (xy 178.835742 -403.671944)
			(xy 178.843477 -403.690527) (xy 178.85029 -403.697948) (xy 179.82438 -404.672038) (xy 179.831446 -404.678578)
			(xy 179.849071 -404.686294) (xy 179.85867 -404.687024) (xy 179.937918 -404.689564) (xy 179.955698 -404.683214)
			(xy 179.963318 -404.67661) (xy 179.98655 -404.656859) (xy 180.036899 -404.622456) (xy 180.091 -404.59432)
			(xy 180.148078 -404.572855) (xy 180.207312 -404.558369) (xy 180.267854 -404.551071) (xy 180.298344 -404.550626)
			(xy 180.331748 -404.551157) (xy 180.397979 -404.55991) (xy 180.462494 -404.577259) (xy 180.524182 -404.602906)
			(xy 180.581981 -404.63641) (xy 180.634896 -404.677193) (xy 180.682016 -404.724553) (xy 180.702712 -404.750778)
			(xy 180.710299 -404.759777) (xy 180.731344 -404.770262) (xy 180.743098 -404.770844)
		)
		(stroke
			(width 0)
			(type solid)
		)
		(fill yes)
		(layer "B.Cu")
		(net "HSC_VDD_R")
	)
	(gr_poly
		(pts
			(xy 209.64525 -51.999896) (xy 209.644749 -51.899842) (xy 209.636743 -51.699895) (xy 209.620744 -51.500428)
			(xy 209.596776 -51.30176) (xy 209.564879 -51.104211) (xy 209.525104 -50.908096) (xy 209.477514 -50.71373)
			(xy 209.422186 -50.521423) (xy 209.359208 -50.331484) (xy 209.288681 -50.144217) (xy 209.210718 -49.959921)
			(xy 209.125444 -49.778892) (xy 209.032995 -49.60142) (xy 208.93352 -49.427789) (xy 208.827177 -49.258277)
			(xy 208.714138 -49.093156) (xy 208.594582 -48.932689) (xy 208.468702 -48.777134) (xy 208.336699 -48.62674)
			(xy 208.198785 -48.481748) (xy 208.05518 -48.34239) (xy 207.906114 -48.208889) (xy 207.751826 -48.081459)
			(xy 207.592564 -47.960304) (xy 207.428581 -47.845618) (xy 207.260142 -47.737585) (xy 207.087515 -47.636377)
			(xy 206.910976 -47.542157) (xy 206.73081 -47.455076) (xy 206.547303 -47.375273) (xy 206.360751 -47.302876)
			(xy 206.171452 -47.238001) (xy 205.979708 -47.180751) (xy 205.785827 -47.131219) (xy 205.59012 -47.089484)
			(xy 205.3929 -47.055612) (xy 205.194483 -47.029659) (xy 204.995186 -47.011664) (xy 204.795328 -47.001658)
			(xy 204.595231 -46.999656) (xy 204.395213 -47.005661) (xy 204.195596 -47.019664) (xy 203.996699 -47.041643)
			(xy 203.79884 -47.071562) (xy 203.602337 -47.109373) (xy 203.407504 -47.155016) (xy 203.214654 -47.208417)
			(xy 203.024094 -47.269492) (xy 202.836131 -47.338141) (xy 202.651064 -47.414257) (xy 202.469191 -47.497715)
			(xy 202.290803 -47.588384) (xy 202.116186 -47.686117) (xy 201.945618 -47.790758) (xy 201.779374 -47.90214)
			(xy 201.617719 -48.020084) (xy 201.460912 -48.144402) (xy 201.309205 -48.274893) (xy 201.162841 -48.41135)
			(xy 201.022053 -48.553554) (xy 200.887067 -48.701277) (xy 200.7581 -48.854282) (xy 200.635357 -49.012324)
			(xy 200.519037 -49.175151) (xy 200.409324 -49.342501) (xy 200.306394 -49.514107) (xy 200.210413 -49.689694)
			(xy 200.121533 -49.86898) (xy 200.039898 -50.051679) (xy 199.965639 -50.237498) (xy 199.898873 -50.426139)
			(xy 199.839708 -50.6173) (xy 199.788238 -50.810675) (xy 199.744547 -51.005955) (xy 199.708704 -51.202826)
			(xy 199.680766 -51.400974) (xy 199.660779 -51.600081) (xy 199.648773 -51.799828) (xy 199.64477 -51.999896)
			(xy 201.365618 -51.999896) (xy 201.369631 -51.837706) (xy 201.38166 -51.675912) (xy 201.401675 -51.514911)
			(xy 201.429628 -51.355097) (xy 201.465451 -51.196861) (xy 201.509055 -51.04059) (xy 201.560333 -50.886667)
			(xy 201.619161 -50.735468) (xy 201.685395 -50.587364) (xy 201.758871 -50.442716) (xy 201.839411 -50.301878)
			(xy 201.926818 -50.165196) (xy 202.020877 -50.033004) (xy 202.121358 -49.905625) (xy 202.228016 -49.783371)
			(xy 202.340589 -49.666542) (xy 202.458802 -49.555422) (xy 202.582365 -49.450285) (xy 202.710977 -49.351387)
			(xy 202.844323 -49.25897) (xy 202.982075 -49.173261) (xy 203.123898 -49.094468) (xy 203.269444 -49.022786)
			(xy 203.418356 -48.95839) (xy 203.570271 -48.901437) (xy 203.724817 -48.852066) (xy 203.881615 -48.810398)
			(xy 204.040282 -48.776535) (xy 204.200429 -48.750561) (xy 204.361665 -48.732538) (xy 204.523595 -48.722511)
			(xy 204.685823 -48.720505) (xy 204.847952 -48.726523) (xy 205.009584 -48.740553) (xy 205.170325 -48.762558)
			(xy 205.329781 -48.792485) (xy 205.487562 -48.830262) (xy 205.643281 -48.875795) (xy 205.796558 -48.928974)
			(xy 205.947018 -48.989667) (xy 206.094293 -49.057727) (xy 206.238021 -49.132987) (xy 206.377851 -49.215263)
			(xy 206.513442 -49.304354) (xy 206.64446 -49.40004) (xy 206.770587 -49.502089) (xy 206.891512 -49.610251)
			(xy 207.00694 -49.72426) (xy 207.116589 -49.843839) (xy 207.22019 -49.968693) (xy 207.31749 -50.098518)
			(xy 207.408251 -50.232997) (xy 207.49225 -50.371799) (xy 207.569282 -50.514585) (xy 207.639158 -50.661006)
			(xy 207.701708 -50.810704) (xy 207.756778 -50.963312) (xy 207.804234 -51.118456) (xy 207.843959 -51.275758)
			(xy 207.875856 -51.434831) (xy 207.899848 -51.595288) (xy 207.915875 -51.756734) (xy 207.923899 -51.918776)
			(xy 207.9244 -51.999896) (xy 207.923899 -52.081016) (xy 207.915875 -52.243058) (xy 207.899848 -52.404504)
			(xy 207.875856 -52.564961) (xy 207.843959 -52.724034) (xy 207.804234 -52.881336) (xy 207.756778 -53.03648)
			(xy 207.701708 -53.189088) (xy 207.639158 -53.338786) (xy 207.569282 -53.485207) (xy 207.49225 -53.627993)
			(xy 207.408251 -53.766795) (xy 207.31749 -53.901274) (xy 207.22019 -54.031099) (xy 207.116589 -54.155953)
			(xy 207.00694 -54.275532) (xy 206.891512 -54.389541) (xy 206.770587 -54.497703) (xy 206.64446 -54.599752)
			(xy 206.513442 -54.695438) (xy 206.377851 -54.784529) (xy 206.238021 -54.866805) (xy 206.094293 -54.942065)
			(xy 205.947018 -55.010125) (xy 205.796558 -55.070818) (xy 205.643281 -55.123997) (xy 205.487562 -55.16953)
			(xy 205.329781 -55.207307) (xy 205.170325 -55.237234) (xy 205.009584 -55.259239) (xy 204.847952 -55.273269)
			(xy 204.685823 -55.279287) (xy 204.523595 -55.277281) (xy 204.361665 -55.267254) (xy 204.200429 -55.249231)
			(xy 204.040282 -55.223257) (xy 203.881615 -55.189394) (xy 203.724817 -55.147726) (xy 203.570271 -55.098355)
			(xy 203.418356 -55.041402) (xy 203.269444 -54.977006) (xy 203.123898 -54.905324) (xy 202.982075 -54.826531)
			(xy 202.844323 -54.740822) (xy 202.710977 -54.648405) (xy 202.582365 -54.549507) (xy 202.458802 -54.44437)
			(xy 202.340589 -54.33325) (xy 202.228016 -54.216421) (xy 202.121358 -54.094167) (xy 202.020877 -53.966788)
			(xy 201.926818 -53.834596) (xy 201.839411 -53.697914) (xy 201.758871 -53.557076) (xy 201.685395 -53.412428)
			(xy 201.619161 -53.264324) (xy 201.560333 -53.113125) (xy 201.509055 -52.959202) (xy 201.465451 -52.802931)
			(xy 201.429628 -52.644695) (xy 201.401675 -52.484881) (xy 201.38166 -52.32388) (xy 201.369631 -52.162086)
			(xy 201.365618 -51.999896) (xy 199.64477 -51.999896) (xy 199.648773 -52.199964) (xy 199.660779 -52.399711)
			(xy 199.680766 -52.598818) (xy 199.708704 -52.796966) (xy 199.744547 -52.993837) (xy 199.788238 -53.189117)
			(xy 199.839708 -53.382492) (xy 199.898873 -53.573653) (xy 199.965639 -53.762294) (xy 200.039898 -53.948113)
			(xy 200.121533 -54.130812) (xy 200.210413 -54.310098) (xy 200.306394 -54.485685) (xy 200.409324 -54.657291)
			(xy 200.519037 -54.824641) (xy 200.635357 -54.987468) (xy 200.7581 -55.14551) (xy 200.887067 -55.298515)
			(xy 201.022053 -55.446238) (xy 201.162841 -55.588442) (xy 201.309205 -55.724899) (xy 201.460912 -55.85539)
			(xy 201.617719 -55.979708) (xy 201.779374 -56.097652) (xy 201.945618 -56.209034) (xy 202.116186 -56.313675)
			(xy 202.290803 -56.411408) (xy 202.469191 -56.502077) (xy 202.651064 -56.585535) (xy 202.836131 -56.661651)
			(xy 203.024094 -56.7303) (xy 203.214654 -56.791375) (xy 203.407504 -56.844776) (xy 203.602337 -56.890419)
			(xy 203.79884 -56.92823) (xy 203.996699 -56.958149) (xy 204.195596 -56.980128) (xy 204.395213 -56.994131)
			(xy 204.595231 -57.000136) (xy 204.795328 -56.998134) (xy 204.995186 -56.988128) (xy 205.194483 -56.970133)
			(xy 205.3929 -56.94418) (xy 205.59012 -56.910308) (xy 205.785827 -56.868573) (xy 205.979708 -56.819041)
			(xy 206.171452 -56.761791) (xy 206.360751 -56.696916) (xy 206.547303 -56.624519) (xy 206.73081 -56.544716)
			(xy 206.910976 -56.457635) (xy 207.087515 -56.363415) (xy 207.260142 -56.262207) (xy 207.428581 -56.154174)
			(xy 207.592564 -56.039488) (xy 207.751826 -55.918333) (xy 207.906114 -55.790903) (xy 208.05518 -55.657402)
			(xy 208.198785 -55.518044) (xy 208.336699 -55.373052) (xy 208.468702 -55.222658) (xy 208.594582 -55.067103)
			(xy 208.714138 -54.906636) (xy 208.827177 -54.741515) (xy 208.93352 -54.572003) (xy 209.032995 -54.398372)
			(xy 209.125444 -54.2209) (xy 209.210718 -54.039871) (xy 209.288681 -53.855575) (xy 209.359208 -53.668308)
			(xy 209.422186 -53.478369) (xy 209.477514 -53.286062) (xy 209.525104 -53.091696) (xy 209.564879 -52.895581)
			(xy 209.596776 -52.698032) (xy 209.620744 -52.499364) (xy 209.636743 -52.299897) (xy 209.644749 -52.09995)
		)
		(stroke
			(width 0)
			(type solid)
		)
		(fill yes)
		(layer "B.Cu")
		(net "GND")
	)
	(gr_poly
		(pts
			(xy 273.645376 -51.999896) (xy 273.644875 -51.899842) (xy 273.636869 -51.699895) (xy 273.62087 -51.500428)
			(xy 273.596902 -51.30176) (xy 273.565005 -51.104211) (xy 273.52523 -50.908096) (xy 273.47764 -50.71373)
			(xy 273.422312 -50.521423) (xy 273.359334 -50.331484) (xy 273.288807 -50.144217) (xy 273.210844 -49.959921)
			(xy 273.12557 -49.778892) (xy 273.033121 -49.60142) (xy 272.933646 -49.427789) (xy 272.827303 -49.258277)
			(xy 272.714264 -49.093156) (xy 272.594708 -48.932689) (xy 272.468828 -48.777134) (xy 272.336825 -48.62674)
			(xy 272.198911 -48.481748) (xy 272.055306 -48.34239) (xy 271.90624 -48.208889) (xy 271.751952 -48.081459)
			(xy 271.59269 -47.960304) (xy 271.428707 -47.845618) (xy 271.260268 -47.737585) (xy 271.087641 -47.636377)
			(xy 270.911102 -47.542157) (xy 270.730936 -47.455076) (xy 270.547429 -47.375273) (xy 270.360877 -47.302876)
			(xy 270.171578 -47.238001) (xy 269.979834 -47.180751) (xy 269.785953 -47.131219) (xy 269.590246 -47.089484)
			(xy 269.393026 -47.055612) (xy 269.194609 -47.029659) (xy 268.995312 -47.011664) (xy 268.795454 -47.001658)
			(xy 268.595357 -46.999656) (xy 268.395339 -47.005661) (xy 268.195722 -47.019664) (xy 267.996825 -47.041643)
			(xy 267.798966 -47.071562) (xy 267.602463 -47.109373) (xy 267.40763 -47.155016) (xy 267.21478 -47.208417)
			(xy 267.02422 -47.269492) (xy 266.836257 -47.338141) (xy 266.65119 -47.414257) (xy 266.469317 -47.497715)
			(xy 266.290929 -47.588384) (xy 266.116312 -47.686117) (xy 265.945744 -47.790758) (xy 265.7795 -47.90214)
			(xy 265.617845 -48.020084) (xy 265.461038 -48.144402) (xy 265.309331 -48.274893) (xy 265.162967 -48.41135)
			(xy 265.022179 -48.553554) (xy 264.887193 -48.701277) (xy 264.758226 -48.854282) (xy 264.635483 -49.012324)
			(xy 264.519163 -49.175151) (xy 264.40945 -49.342501) (xy 264.30652 -49.514107) (xy 264.210539 -49.689694)
			(xy 264.121659 -49.86898) (xy 264.040024 -50.051679) (xy 263.965765 -50.237498) (xy 263.898999 -50.426139)
			(xy 263.839834 -50.6173) (xy 263.788364 -50.810675) (xy 263.744673 -51.005955) (xy 263.70883 -51.202826)
			(xy 263.680892 -51.400974) (xy 263.660905 -51.600081) (xy 263.648899 -51.799828) (xy 263.644896 -51.999896)
			(xy 265.365744 -51.999896) (xy 265.369757 -51.837706) (xy 265.381786 -51.675912) (xy 265.401801 -51.514911)
			(xy 265.429754 -51.355097) (xy 265.465577 -51.196861) (xy 265.509181 -51.04059) (xy 265.560459 -50.886667)
			(xy 265.619287 -50.735468) (xy 265.685521 -50.587364) (xy 265.758997 -50.442716) (xy 265.839537 -50.301878)
			(xy 265.926944 -50.165196) (xy 266.021003 -50.033004) (xy 266.121484 -49.905625) (xy 266.228142 -49.783371)
			(xy 266.340715 -49.666542) (xy 266.458928 -49.555422) (xy 266.582491 -49.450285) (xy 266.711103 -49.351387)
			(xy 266.844449 -49.25897) (xy 266.982201 -49.173261) (xy 267.124024 -49.094468) (xy 267.26957 -49.022786)
			(xy 267.418482 -48.95839) (xy 267.570397 -48.901437) (xy 267.724943 -48.852066) (xy 267.881741 -48.810398)
			(xy 268.040408 -48.776535) (xy 268.200555 -48.750561) (xy 268.361791 -48.732538) (xy 268.523721 -48.722511)
			(xy 268.685949 -48.720505) (xy 268.848078 -48.726523) (xy 269.00971 -48.740553) (xy 269.170451 -48.762558)
			(xy 269.329907 -48.792485) (xy 269.487688 -48.830262) (xy 269.643407 -48.875795) (xy 269.796684 -48.928974)
			(xy 269.947144 -48.989667) (xy 270.094419 -49.057727) (xy 270.238147 -49.132987) (xy 270.377977 -49.215263)
			(xy 270.513568 -49.304354) (xy 270.644586 -49.40004) (xy 270.770713 -49.502089) (xy 270.891638 -49.610251)
			(xy 271.007066 -49.72426) (xy 271.116715 -49.843839) (xy 271.220316 -49.968693) (xy 271.317616 -50.098518)
			(xy 271.408377 -50.232997) (xy 271.492376 -50.371799) (xy 271.569408 -50.514585) (xy 271.639284 -50.661006)
			(xy 271.701834 -50.810704) (xy 271.756904 -50.963312) (xy 271.80436 -51.118456) (xy 271.844085 -51.275758)
			(xy 271.875982 -51.434831) (xy 271.899974 -51.595288) (xy 271.916001 -51.756734) (xy 271.924025 -51.918776)
			(xy 271.924526 -51.999896) (xy 271.924025 -52.081016) (xy 271.916001 -52.243058) (xy 271.899974 -52.404504)
			(xy 271.875982 -52.564961) (xy 271.844085 -52.724034) (xy 271.80436 -52.881336) (xy 271.756904 -53.03648)
			(xy 271.701834 -53.189088) (xy 271.639284 -53.338786) (xy 271.569408 -53.485207) (xy 271.492376 -53.627993)
			(xy 271.408377 -53.766795) (xy 271.317616 -53.901274) (xy 271.220316 -54.031099) (xy 271.116715 -54.155953)
			(xy 271.007066 -54.275532) (xy 270.891638 -54.389541) (xy 270.770713 -54.497703) (xy 270.644586 -54.599752)
			(xy 270.513568 -54.695438) (xy 270.377977 -54.784529) (xy 270.238147 -54.866805) (xy 270.094419 -54.942065)
			(xy 269.947144 -55.010125) (xy 269.796684 -55.070818) (xy 269.643407 -55.123997) (xy 269.487688 -55.16953)
			(xy 269.329907 -55.207307) (xy 269.170451 -55.237234) (xy 269.00971 -55.259239) (xy 268.848078 -55.273269)
			(xy 268.685949 -55.279287) (xy 268.523721 -55.277281) (xy 268.361791 -55.267254) (xy 268.200555 -55.249231)
			(xy 268.040408 -55.223257) (xy 267.881741 -55.189394) (xy 267.724943 -55.147726) (xy 267.570397 -55.098355)
			(xy 267.418482 -55.041402) (xy 267.26957 -54.977006) (xy 267.124024 -54.905324) (xy 266.982201 -54.826531)
			(xy 266.844449 -54.740822) (xy 266.711103 -54.648405) (xy 266.582491 -54.549507) (xy 266.458928 -54.44437)
			(xy 266.340715 -54.33325) (xy 266.228142 -54.216421) (xy 266.121484 -54.094167) (xy 266.021003 -53.966788)
			(xy 265.926944 -53.834596) (xy 265.839537 -53.697914) (xy 265.758997 -53.557076) (xy 265.685521 -53.412428)
			(xy 265.619287 -53.264324) (xy 265.560459 -53.113125) (xy 265.509181 -52.959202) (xy 265.465577 -52.802931)
			(xy 265.429754 -52.644695) (xy 265.401801 -52.484881) (xy 265.381786 -52.32388) (xy 265.369757 -52.162086)
			(xy 265.365744 -51.999896) (xy 263.644896 -51.999896) (xy 263.648899 -52.199964) (xy 263.660905 -52.399711)
			(xy 263.680892 -52.598818) (xy 263.70883 -52.796966) (xy 263.744673 -52.993837) (xy 263.788364 -53.189117)
			(xy 263.839834 -53.382492) (xy 263.898999 -53.573653) (xy 263.965765 -53.762294) (xy 264.040024 -53.948113)
			(xy 264.121659 -54.130812) (xy 264.210539 -54.310098) (xy 264.30652 -54.485685) (xy 264.40945 -54.657291)
			(xy 264.519163 -54.824641) (xy 264.635483 -54.987468) (xy 264.758226 -55.14551) (xy 264.887193 -55.298515)
			(xy 265.022179 -55.446238) (xy 265.162967 -55.588442) (xy 265.309331 -55.724899) (xy 265.461038 -55.85539)
			(xy 265.617845 -55.979708) (xy 265.7795 -56.097652) (xy 265.945744 -56.209034) (xy 266.116312 -56.313675)
			(xy 266.290929 -56.411408) (xy 266.469317 -56.502077) (xy 266.65119 -56.585535) (xy 266.836257 -56.661651)
			(xy 267.02422 -56.7303) (xy 267.21478 -56.791375) (xy 267.40763 -56.844776) (xy 267.602463 -56.890419)
			(xy 267.798966 -56.92823) (xy 267.996825 -56.958149) (xy 268.195722 -56.980128) (xy 268.395339 -56.994131)
			(xy 268.595357 -57.000136) (xy 268.795454 -56.998134) (xy 268.995312 -56.988128) (xy 269.194609 -56.970133)
			(xy 269.393026 -56.94418) (xy 269.590246 -56.910308) (xy 269.785953 -56.868573) (xy 269.979834 -56.819041)
			(xy 270.171578 -56.761791) (xy 270.360877 -56.696916) (xy 270.547429 -56.624519) (xy 270.730936 -56.544716)
			(xy 270.911102 -56.457635) (xy 271.087641 -56.363415) (xy 271.260268 -56.262207) (xy 271.428707 -56.154174)
			(xy 271.59269 -56.039488) (xy 271.751952 -55.918333) (xy 271.90624 -55.790903) (xy 272.055306 -55.657402)
			(xy 272.198911 -55.518044) (xy 272.336825 -55.373052) (xy 272.468828 -55.222658) (xy 272.594708 -55.067103)
			(xy 272.714264 -54.906636) (xy 272.827303 -54.741515) (xy 272.933646 -54.572003) (xy 273.033121 -54.398372)
			(xy 273.12557 -54.2209) (xy 273.210844 -54.039871) (xy 273.288807 -53.855575) (xy 273.359334 -53.668308)
			(xy 273.422312 -53.478369) (xy 273.47764 -53.286062) (xy 273.52523 -53.091696) (xy 273.565005 -52.895581)
			(xy 273.596902 -52.698032) (xy 273.62087 -52.499364) (xy 273.636869 -52.299897) (xy 273.644875 -52.09995)
		)
		(stroke
			(width 0)
			(type solid)
		)
		(fill yes)
		(layer "B.Cu")
		(net "GND")
	)
	(gr_poly
		(pts
			(arc
				(start 399.315686 -367.862612)
				(mid 399.335043 -367.858779)
				(end 399.3515 -367.84788)
			)
			(xy 404.68804 -362.51134) (xy 404.69566 -362.51134)
			(arc
				(start 404.709376 -362.500672)
				(mid 404.856206 -362.42143)
				(end 405.02078 -362.393992)
			)
			(arc
				(start 406.377394 -362.393992)
				(mid 406.541963 -362.421445)
				(end 406.688798 -362.500672)
			)
			(xy 406.695656 -362.506006) (xy 406.711404 -362.51134)
			(arc
				(start 406.825958 -362.51134)
				(mid 406.845481 -362.515241)
				(end 406.862026 -362.526326)
			)
			(arc
				(start 408.417014 -364.081314)
				(mid 408.428125 -364.097848)
				(end 408.432 -364.117382)
			)
			(xy 408.432 -364.250224) (xy 408.435556 -364.262924)
			(arc
				(start 408.438858 -364.26902)
				(mid 408.490226 -364.39222)
				(end 408.507692 -364.524544)
			)
			(arc
				(start 408.507692 -364.910624)
				(mid 408.490169 -365.042933)
				(end 408.438858 -365.166148)
			)
			(arc
				(start 408.438858 -365.166148)
				(mid 408.433745 -365.178522)
				(end 408.432 -365.191802)
			)
			(arc
				(start 408.432 -366.650778)
				(mid 408.435901 -366.670301)
				(end 408.446986 -366.686846)
			)
			(arc
				(start 409.242514 -367.482374)
				(mid 409.259048 -367.493485)
				(end 409.278582 -367.49736)
			)
			(arc
				(start 410.481018 -367.49736)
				(mid 410.500541 -367.493459)
				(end 410.517086 -367.482374)
			)
			(arc
				(start 410.61894 -367.38052)
				(mid 410.633775 -367.344617)
				(end 410.61894 -367.308638)
			)
			(arc
				(start 410.599636 -367.289588)
				(mid 410.532987 -367.189701)
				(end 410.50972 -367.07191)
			)
			(arc
				(start 410.50972 -364.594902)
				(mid 410.505819 -364.575379)
				(end 410.494734 -364.558834)
			)
			(arc
				(start 406.838912 -360.903012)
				(mid 406.822349 -360.892038)
				(end 406.802844 -360.88828)
			)
			(arc
				(start 403.594824 -360.88828)
				(mid 403.57533 -360.892064)
				(end 403.558756 -360.903012)
			)
			(arc
				(start 398.886426 -365.575596)
				(mid 398.875364 -365.592013)
				(end 398.87144 -365.61141)
			)
			(arc
				(start 398.87144 -365.639858)
				(mid 398.867539 -365.659381)
				(end 398.856454 -365.675926)
			)
			(arc
				(start 398.703546 -365.828834)
				(mid 398.687012 -365.839945)
				(end 398.667478 -365.84382)
			)
			(arc
				(start 398.63903 -365.84382)
				(mid 398.619643 -365.84777)
				(end 398.603216 -365.858806)
			)
			(arc
				(start 398.59077 -365.871252)
				(mid 398.490883 -365.937901)
				(end 398.373092 -365.961168)
			)
			(arc
				(start 328.13625 -365.961168)
				(mid 328.018485 -365.937837)
				(end 327.918572 -365.871252)
			)
			(arc
				(start 325.755508 -363.707934)
				(mid 325.730425 -363.694319)
				(end 325.701914 -363.69625)
			)
			(xy 325.60133 -363.733588) (xy 325.58355 -363.75721)
			(arc
				(start 325.58228 -363.772196)
				(mid 325.396794 -364.156718)
				(end 324.99935 -364.312708)
			)
			(arc
				(start 324.99935 -364.312708)
				(mid 324.779178 -364.269651)
				(end 324.591426 -364.146846)
			)
			(arc
				(start 324.591426 -364.146846)
				(mid 324.559808 -364.132649)
				(end 324.526402 -364.14202)
			)
			(arc
				(start 324.526402 -364.14202)
				(mid 324.386077 -364.212309)
				(end 324.231 -364.236508)
			)
			(arc
				(start 324.231 -364.236508)
				(mid 323.722492 -363.728)
				(end 324.231 -363.219492)
			)
			(arc
				(start 324.231 -363.219492)
				(mid 324.386093 -363.243639)
				(end 324.526402 -363.31398)
			)
			(arc
				(start 324.526402 -363.31398)
				(mid 324.559815 -363.323455)
				(end 324.591426 -363.309154)
			)
			(arc
				(start 324.591426 -363.309154)
				(mid 324.75885 -363.195089)
				(end 324.955154 -363.14507)
			)
			(xy 324.97014 -363.1438) (xy 324.993762 -363.12602)
			(arc
				(start 325.0311 -363.025436)
				(mid 325.033154 -362.996899)
				(end 325.019416 -362.971842)
			)
			(xy 322.922646 -360.875072) (xy 322.90131 -360.867452)
			(arc
				(start 322.890134 -360.868468)
				(mid 322.867424 -360.869995)
				(end 322.844668 -360.8705)
			)
			(arc
				(start 322.844668 -360.8705)
				(mid 322.485099 -360.721561)
				(end 322.33616 -360.361992)
			)
			(arc
				(start 322.33616 -360.361992)
				(mid 322.347064 -360.25725)
				(end 322.37934 -360.157014)
			)
			(xy 322.38569 -360.142536) (xy 322.379848 -360.111548)
			(arc
				(start 320.072766 -357.804466)
				(mid 320.056232 -357.793355)
				(end 320.036698 -357.78948)
			)
			(arc
				(start 319.390522 -357.78948)
				(mid 319.370999 -357.793381)
				(end 319.354454 -357.804466)
			)
			(arc
				(start 319.038986 -358.119934)
				(mid 319.027875 -358.136468)
				(end 319.024 -358.156002)
			)
			(arc
				(start 319.024 -359.644188)
				(mid 319.027189 -359.661652)
				(end 319.036192 -359.676954)
			)
			(arc
				(start 319.036192 -359.676954)
				(mid 319.103923 -359.792636)
				(end 319.127378 -359.924604)
			)
			(arc
				(start 319.127378 -359.924604)
				(mid 319.103838 -360.05654)
				(end 319.036192 -360.172254)
			)
			(xy 319.03035 -360.179112) (xy 319.024 -360.19613)
			(arc
				(start 319.024 -360.249978)
				(mid 319.027901 -360.269501)
				(end 319.038986 -360.286046)
			)
			(arc
				(start 319.137538 -360.384598)
				(mid 319.153955 -360.39566)
				(end 319.173352 -360.399584)
			)
			(arc
				(start 319.999868 -360.399584)
				(mid 320.194368 -360.438273)
				(end 320.359278 -360.548428)
			)
			(arc
				(start 321.95897 -362.14812)
				(mid 322.008138 -362.205003)
				(end 322.048378 -362.268516)
			)
			(arc
				(start 322.048378 -362.268516)
				(mid 322.052359 -362.274951)
				(end 322.057268 -362.280708)
			)
			(arc
				(start 322.140834 -362.364274)
				(mid 322.151945 -362.380808)
				(end 322.15582 -362.400342)
			)
			(arc
				(start 322.15582 -366.292638)
				(mid 322.15977 -366.312025)
				(end 322.170806 -366.328452)
			)
			(arc
				(start 323.68998 -367.84788)
				(mid 323.706543 -367.858854)
				(end 323.726048 -367.862612)
			)
		)
		(stroke
			(width 0)
			(type solid)
		)
		(fill yes)
		(layer "B.Cu")
		(net "P5V_AUX")
	)
	(gr_poly
		(pts
			(xy 235.603288 -319.83045) (xy 235.613358 -319.830028) (xy 235.631961 -319.822311) (xy 235.639356 -319.815464)
			(xy 236.127544 -319.327276) (xy 236.134393 -319.319879) (xy 236.142127 -319.30128) (xy 236.14253 -319.291208)
			(xy 236.14253 -281.69616) (xy 236.1421 -281.686092) (xy 236.134379 -281.667496) (xy 236.127544 -281.660092)
			(xy 229.959916 -275.492464) (xy 229.953073 -275.485064) (xy 229.94535 -275.466466) (xy 229.94493 -275.456396)
			(xy 229.94493 -265.338052) (xy 229.944499 -265.327985) (xy 229.936776 -265.30939) (xy 229.929944 -265.301984)
			(xy 229.253796 -264.625836) (xy 229.246399 -264.618986) (xy 229.227801 -264.611248) (xy 229.217728 -264.61085)
			(xy 214.948516 -264.61085) (xy 214.938454 -264.61129) (xy 214.919876 -264.619031) (xy 214.912448 -264.625836)
			(xy 214.178134 -265.36015) (xy 214.171292 -265.36755) (xy 214.16357 -265.386148) (xy 214.163148 -265.396218)
			(xy 214.163148 -273.204686) (xy 220.59646 -273.204686) (xy 220.59646 -269.499842) (xy 220.596891 -269.489773)
			(xy 220.604606 -269.471174) (xy 220.611446 -269.463774) (xy 221.47022 -268.604746) (xy 221.477624 -268.597911)
			(xy 221.49622 -268.590187) (xy 221.506288 -268.58976) (xy 224.329498 -268.58976) (xy 224.339569 -268.590171)
			(xy 224.358168 -268.5979) (xy 224.365566 -268.604746) (xy 224.919794 -269.159228) (xy 224.926638 -269.166625)
			(xy 224.934356 -269.185227) (xy 224.93478 -269.195296) (xy 224.93478 -273.553174) (xy 224.934346 -273.563242)
			(xy 224.926632 -273.581841) (xy 224.919794 -273.589242) (xy 224.507552 -274.001738) (xy 224.500094 -274.008495)
			(xy 224.481534 -274.016218) (xy 224.471484 -274.016724) (xy 221.408498 -274.016724) (xy 221.398426 -274.01632)
			(xy 221.379827 -274.008586) (xy 221.37243 -274.001738) (xy 220.611446 -273.240754) (xy 220.604644 -273.233324)
			(xy 220.5969 -273.214748) (xy 220.59646 -273.204686) (xy 214.163148 -273.204686) (xy 214.163148 -277.394924)
			(xy 214.163577 -277.404991) (xy 214.171303 -277.423585) (xy 214.178134 -277.430992) (xy 222.629984 -285.882842)
			(xy 222.637384 -285.889681) (xy 222.655983 -285.897394) (xy 222.666052 -285.897828) (xy 225.937826 -285.897828)
			(xy 225.947894 -285.898256) (xy 225.966489 -285.905981) (xy 225.973894 -285.912814) (xy 228.007418 -287.946338)
			(xy 228.014815 -287.953188) (xy 228.033413 -287.960926) (xy 228.043486 -287.961324) (xy 228.150928 -287.961324)
			(xy 228.178781 -287.961964) (xy 228.233684 -287.971411) (xy 228.260148 -287.98012) (xy 228.26853 -287.982914)
			(xy 230.071168 -287.982914) (xy 230.081232 -287.98335) (xy 230.099818 -287.991083) (xy 230.107236 -287.9979)
			(xy 231.791256 -289.68192) (xy 231.798104 -289.689317) (xy 231.805838 -289.707916) (xy 231.806242 -289.717988)
			(xy 231.806242 -292.328346) (xy 231.806675 -292.338412) (xy 231.814406 -292.357) (xy 231.821228 -292.364414)
			(xy 232.586022 -293.129208) (xy 232.593422 -293.13605) (xy 232.61202 -293.143775) (xy 232.62209 -293.144194)
			(xy 233.375454 -293.144194) (xy 233.381958 -293.144032) (xy 233.394562 -293.140823) (xy 233.400346 -293.137844)
			(xy 233.426763 -293.1236) (xy 233.482516 -293.101383) (xy 233.540694 -293.086639) (xy 233.600299 -293.07962)
			(xy 233.66031 -293.080447) (xy 233.719699 -293.089106) (xy 233.777449 -293.105448) (xy 233.832569 -293.129193)
			(xy 233.858562 -293.144194) (xy 233.865166 -293.144194) (xy 233.872786 -293.151814) (xy 233.880152 -293.15791)
			(xy 233.904059 -293.174619) (xy 233.947845 -293.213153) (xy 233.986379 -293.256939) (xy 234.003088 -293.280846)
			(xy 234.005882 -293.28491) (xy 234.083098 -293.362126) (xy 234.08994 -293.369526) (xy 234.097666 -293.388124)
			(xy 234.098084 -293.398194) (xy 234.098084 -293.971218) (xy 234.097657 -293.981286) (xy 234.089936 -293.999885)
			(xy 234.083098 -294.007286) (xy 233.828336 -294.262048) (xy 233.820937 -294.26889) (xy 233.802338 -294.276609)
			(xy 233.792268 -294.277034) (xy 231.08793 -294.277034) (xy 231.077867 -294.276596) (xy 231.059287 -294.268857)
			(xy 231.051862 -294.262048) (xy 230.60279 -293.812976) (xy 230.595395 -293.806123) (xy 230.576796 -293.79838)
			(xy 230.566722 -293.79799) (xy 228.976936 -293.79799) (xy 228.966871 -293.798424) (xy 228.948282 -293.806154)
			(xy 228.940868 -293.812976) (xy 228.504496 -294.249348) (xy 228.4971 -294.2562) (xy 228.478501 -294.263941)
			(xy 228.468428 -294.264334) (xy 226.697032 -294.264334) (xy 226.686969 -294.263897) (xy 226.668388 -294.256158)
			(xy 226.660964 -294.249348) (xy 224.82429 -292.412674) (xy 224.816415 -292.405512) (xy 224.796612 -292.397772)
			(xy 224.775371 -292.398705) (xy 224.756324 -292.408152) (xy 224.749106 -292.415976) (xy 224.743518 -292.424358)
			(xy 224.705712 -292.493837) (xy 224.624209 -292.629422) (xy 224.536161 -292.76085) (xy 224.441777 -292.887804)
			(xy 224.341285 -293.009981) (xy 224.234926 -293.127087) (xy 224.122957 -293.238839) (xy 224.005646 -293.344971)
			(xy 223.883274 -293.445226) (xy 223.756137 -293.539363) (xy 223.624539 -293.627157) (xy 223.488796 -293.708397)
			(xy 223.349236 -293.782886) (xy 223.206193 -293.850447) (xy 223.060011 -293.910917) (xy 222.911041 -293.964151)
			(xy 222.759641 -294.01002) (xy 222.606176 -294.048415) (xy 222.451013 -294.079243) (xy 222.294526 -294.10243)
			(xy 222.137091 -294.117921) (xy 221.979086 -294.125678) (xy 221.899988 -294.126158) (xy 221.820798 -294.125672)
			(xy 221.66261 -294.1179) (xy 221.504993 -294.102376) (xy 221.348328 -294.079136) (xy 221.192991 -294.048238)
			(xy 221.039358 -294.009755) (xy 220.887799 -293.963779) (xy 220.738677 -293.910423) (xy 220.592354 -293.849814)
			(xy 220.44918 -293.782098) (xy 220.309502 -293.707439) (xy 220.173655 -293.626016) (xy 220.041967 -293.538026)
			(xy 219.914755 -293.44368) (xy 219.792325 -293.343205) (xy 219.674973 -293.236845) (xy 219.562981 -293.124854)
			(xy 219.456619 -293.007503) (xy 219.356144 -292.885075) (xy 219.261796 -292.757864) (xy 219.173804 -292.626177)
			(xy 219.09238 -292.490331) (xy 219.017719 -292.350654) (xy 218.950001 -292.207481) (xy 218.889391 -292.061158)
			(xy 218.836032 -291.912038) (xy 218.790055 -291.760478) (xy 218.75157 -291.606846) (xy 218.72067 -291.45151)
			(xy 218.697429 -291.294845) (xy 218.681903 -291.137228) (xy 218.674129 -290.97904) (xy 218.67368 -290.89985)
			(xy 218.674162 -290.820751) (xy 218.681913 -290.662744) (xy 218.697398 -290.505306) (xy 218.72058 -290.348817)
			(xy 218.751403 -290.193651) (xy 218.789794 -290.040183) (xy 218.83566 -289.88878) (xy 218.88889 -289.739808)
			(xy 218.949358 -289.593623) (xy 219.016917 -289.450577) (xy 219.091406 -289.311014) (xy 219.172644 -289.175269)
			(xy 219.260438 -289.043668) (xy 219.354576 -288.916529) (xy 219.454831 -288.794155) (xy 219.560964 -288.676842)
			(xy 219.672718 -288.564872) (xy 219.789825 -288.458512) (xy 219.912004 -288.35802) (xy 220.038961 -288.263637)
			(xy 220.170391 -288.175588) (xy 220.305979 -288.094087) (xy 220.37548 -288.05632) (xy 220.383862 -288.050732)
			(xy 220.391703 -288.043519) (xy 220.401176 -288.024464) (xy 220.402122 -288.003205) (xy 220.394377 -287.983384)
			(xy 220.387164 -287.975548) (xy 220.006926 -287.59531) (xy 219.999524 -287.588474) (xy 219.980926 -287.580765)
			(xy 219.970858 -287.580324) (xy 214.780114 -287.580324) (xy 214.770051 -287.580763) (xy 214.751472 -287.588502)
			(xy 214.744046 -287.59531) (xy 213.634066 -288.70529) (xy 213.627211 -288.712685) (xy 213.619462 -288.731283)
			(xy 213.61908 -288.741358) (xy 213.61908 -315.733684) (xy 222.0595 -315.733684) (xy 222.0595 -310.008524)
			(xy 222.059912 -309.998453) (xy 222.067639 -309.979853) (xy 222.074486 -309.972456) (xy 223.259904 -308.787038)
			(xy 223.267313 -308.780209) (xy 223.285905 -308.772482) (xy 223.295972 -308.772052) (xy 234.396534 -308.772052)
			(xy 234.406607 -308.772446) (xy 234.425205 -308.780187) (xy 234.432602 -308.787038) (xy 235.381546 -309.735728)
			(xy 235.388397 -309.743119) (xy 235.396109 -309.761725) (xy 235.396532 -309.771796) (xy 235.396532 -315.691266)
			(xy 235.396107 -315.701336) (xy 235.388388 -315.719935) (xy 235.381546 -315.727334) (xy 235.103416 -316.00521)
			(xy 235.096006 -316.012037) (xy 235.077414 -316.019764) (xy 235.067348 -316.020196) (xy 222.346012 -316.020196)
			(xy 222.33594 -316.019792) (xy 222.31734 -316.012059) (xy 222.309944 -316.00521) (xy 222.074486 -315.769752)
			(xy 222.067674 -315.76233) (xy 222.059939 -315.743747) (xy 222.0595 -315.733684) (xy 213.61908 -315.733684)
			(xy 213.61908 -315.849254) (xy 213.619512 -315.85932) (xy 213.627238 -315.877912) (xy 213.634066 -315.885322)
			(xy 213.940644 -316.1919) (xy 213.948045 -316.19874) (xy 213.966643 -316.206458) (xy 213.976712 -316.206886)
			(xy 219.167964 -316.206886) (xy 219.178029 -316.20732) (xy 219.196618 -316.215049) (xy 219.204032 -316.221872)
			(xy 220.909896 -317.927736) (xy 220.916737 -317.935136) (xy 220.924459 -317.953734) (xy 220.924882 -317.963804)
			(xy 220.924882 -319.372488) (xy 220.925302 -319.38256) (xy 220.933012 -319.401169) (xy 220.939868 -319.408556)
			(xy 221.346776 -319.815464) (xy 221.354177 -319.822302) (xy 221.372776 -319.830015) (xy 221.382844 -319.83045)
		)
		(stroke
			(width 0)
			(type solid)
		)
		(fill yes)
		(layer "B.Cu")
		(net "GND")
	)
	(gr_poly
		(pts
			(xy 57.119012 -337.921854) (xy 57.12908 -337.921427) (xy 57.147677 -337.913705) (xy 57.15508 -337.906868)
			(xy 57.290716 -337.771232) (xy 57.297561 -337.763834) (xy 57.305284 -337.745235) (xy 57.305702 -337.735164)
			(xy 57.305702 -337.35645) (xy 57.305252 -337.342136) (xy 57.297375 -337.314615) (xy 57.282169 -337.290362)
			(xy 57.26083 -337.271281) (xy 57.235034 -337.258873) (xy 57.206807 -337.254111) (xy 57.178367 -337.25737)
			(xy 57.164986 -337.26247) (xy 57.141642 -337.271783) (xy 57.093123 -337.284895) (xy 57.043303 -337.291526)
			(xy 57.018174 -337.291934) (xy 56.989443 -337.291441) (xy 56.932623 -337.282875) (xy 56.877732 -337.265882)
			(xy 56.826012 -337.240845) (xy 56.778634 -337.208331) (xy 56.757316 -337.189064) (xy 56.745782 -337.178992)
			(xy 56.718236 -337.16565) (xy 56.687974 -337.161065) (xy 56.657712 -337.16565) (xy 56.630166 -337.178992)
			(xy 56.618632 -337.189064) (xy 56.597285 -337.208294) (xy 56.5499 -337.240783) (xy 56.498185 -337.265811)
			(xy 56.443307 -337.282815) (xy 56.386501 -337.291413) (xy 56.357774 -337.291934) (xy 56.330505 -337.291469)
			(xy 56.276522 -337.283703) (xy 56.224194 -337.268335) (xy 56.174586 -337.245675) (xy 56.128708 -337.216186)
			(xy 56.087493 -337.180469) (xy 56.051781 -337.139249) (xy 56.022299 -337.093366) (xy 55.999646 -337.043755)
			(xy 55.984285 -336.991425) (xy 55.976527 -336.937441) (xy 55.976012 -336.910172) (xy 55.976485 -336.88278)
			(xy 55.984313 -336.828558) (xy 55.999805 -336.77601) (xy 56.022644 -336.726213) (xy 56.05236 -336.680189)
			(xy 56.069992 -336.65922) (xy 56.0792 -336.647906) (xy 56.091337 -336.621394) (xy 56.095502 -336.592534)
			(xy 56.091357 -336.563672) (xy 56.079237 -336.537151) (xy 56.069992 -336.52587) (xy 56.052386 -336.504923)
			(xy 56.022729 -336.458938) (xy 55.999946 -336.409188) (xy 55.984504 -336.356694) (xy 55.976719 -336.302532)
			(xy 55.976266 -336.275172) (xy 55.976744 -336.247709) (xy 55.984616 -336.193351) (xy 56.000194 -336.14068)
			(xy 56.023155 -336.090785) (xy 56.053027 -336.044693) (xy 56.070754 -336.023712) (xy 56.076596 -336.017108)
			(xy 56.079898 -336.00898) (xy 56.08161 -336.004408) (xy 56.083405 -335.994812) (xy 56.083454 -335.98993)
			(xy 56.083454 -335.925414) (xy 56.083355 -335.920537) (xy 56.08156 -335.91095) (xy 56.079898 -335.906364)
			(xy 56.076596 -335.898236) (xy 56.070754 -335.891632) (xy 56.053026 -335.870653) (xy 56.02315 -335.824564)
			(xy 56.000191 -335.774667) (xy 55.984622 -335.721995) (xy 55.976766 -335.667635) (xy 55.976266 -335.640172)
			(xy 55.976754 -335.612921) (xy 55.984513 -335.558975) (xy 55.999871 -335.506682) (xy 56.022513 -335.457107)
			(xy 56.05198 -335.411258) (xy 56.087671 -335.370069) (xy 56.12886 -335.334378) (xy 56.174709 -335.304912)
			(xy 56.224284 -335.28227) (xy 56.276577 -335.266913) (xy 56.330523 -335.259154) (xy 56.357774 -335.258664)
			(xy 56.358028 -335.258664) (xy 56.38684 -335.259186) (xy 56.443809 -335.267845) (xy 56.498826 -335.284977)
			(xy 56.55064 -335.310191) (xy 56.59807 -335.342915) (xy 56.619394 -335.362296) (xy 56.626506 -335.3689)
			(xy 56.644286 -335.376012) (xy 56.731662 -335.376012) (xy 56.749442 -335.3689) (xy 56.756554 -335.362296)
			(xy 56.777824 -335.343011) (xy 56.825072 -335.310395) (xy 56.876672 -335.285222) (xy 56.931459 -335.268062)
			(xy 56.988199 -335.259301) (xy 57.016904 -335.258664) (xy 57.018936 -335.258664) (xy 57.044208 -335.259126)
			(xy 57.094299 -335.265892) (xy 57.143063 -335.279197) (xy 57.16651 -335.288636) (xy 57.178448 -335.293716)
			(xy 57.203848 -335.291176) (xy 57.283096 -335.238598) (xy 57.29315 -335.231077) (xy 57.304992 -335.20897)
			(xy 57.305702 -335.196434) (xy 57.305702 -328.89317) (xy 57.305273 -328.883102) (xy 57.297551 -328.864506)
			(xy 57.290716 -328.857102) (xy 56.805576 -328.371962) (xy 56.798179 -328.365113) (xy 56.77958 -328.357377)
			(xy 56.769508 -328.356976) (xy 23.835868 -328.356976) (xy 23.831804 -328.352912) (xy 23.168102 -329.016614)
			(xy 23.160708 -329.02347) (xy 23.142109 -329.031219) (xy 23.132034 -329.0316) (xy 20.355306 -329.0316)
			(xy 20.345235 -329.032022) (xy 20.326629 -329.039735) (xy 20.319238 -329.046586) (xy 19.307048 -330.058776)
			(xy 19.300208 -330.066176) (xy 19.292494 -330.084775) (xy 19.292062 -330.094844) (xy 19.292062 -332.132178)
			(xy 20.3073 -332.132178) (xy 20.30779 -332.09352) (xy 20.315612 -332.0166) (xy 20.331175 -331.940867)
			(xy 20.354321 -331.867097) (xy 20.384811 -331.796046) (xy 20.422333 -331.728445) (xy 20.466501 -331.664987)
			(xy 20.516862 -331.606323) (xy 20.572901 -331.553054) (xy 20.63404 -331.505729) (xy 20.699654 -331.464831)
			(xy 20.769069 -331.430782) (xy 20.841572 -331.403929) (xy 20.916421 -331.38455) (xy 20.992845 -331.372842)
			(xy 21.070062 -331.368926) (xy 21.147279 -331.372842) (xy 21.223703 -331.38455) (xy 21.298552 -331.403929)
			(xy 21.371055 -331.430782) (xy 21.44047 -331.464831) (xy 21.506084 -331.505729) (xy 21.567223 -331.553054)
			(xy 21.623262 -331.606323) (xy 21.673623 -331.664987) (xy 21.717791 -331.728445) (xy 21.755313 -331.796046)
			(xy 21.785803 -331.867097) (xy 21.808949 -331.940867) (xy 21.824512 -332.0166) (xy 21.832334 -332.09352)
			(xy 21.832824 -332.132178) (xy 21.832824 -332.132432) (xy 21.832226 -332.17418) (xy 21.823091 -332.257175)
			(xy 21.804943 -332.338675) (xy 21.778001 -332.417705) (xy 21.742586 -332.493319) (xy 21.699124 -332.564611)
			(xy 21.674074 -332.598014) (xy 21.667644 -332.607539) (xy 21.662982 -332.630006) (xy 21.668515 -332.652273)
			(xy 21.675344 -332.661514) (xy 21.699033 -332.690847) (xy 21.741143 -332.753396) (xy 21.77688 -332.819792)
			(xy 21.805898 -332.889387) (xy 21.827913 -332.961505) (xy 21.842711 -333.035441) (xy 21.850147 -333.110477)
			(xy 21.850604 -333.148178) (xy 21.850114 -333.186836) (xy 21.842292 -333.263756) (xy 21.826729 -333.339489)
			(xy 21.803583 -333.413259) (xy 21.773093 -333.48431) (xy 21.735571 -333.551911) (xy 21.691403 -333.615369)
			(xy 21.641042 -333.674033) (xy 21.585003 -333.727302) (xy 21.523864 -333.774627) (xy 21.45825 -333.815525)
			(xy 21.388835 -333.849574) (xy 21.316332 -333.876427) (xy 21.241483 -333.895806) (xy 21.165059 -333.907514)
			(xy 21.087842 -333.91143) (xy 21.010625 -333.907514) (xy 20.934201 -333.895806) (xy 20.859352 -333.876427)
			(xy 20.786849 -333.849574) (xy 20.717434 -333.815525) (xy 20.65182 -333.774627) (xy 20.590681 -333.727302)
			(xy 20.534642 -333.674033) (xy 20.484281 -333.615369) (xy 20.440113 -333.551911) (xy 20.402591 -333.48431)
			(xy 20.372101 -333.413259) (xy 20.348955 -333.339489) (xy 20.333392 -333.263756) (xy 20.32557 -333.186836)
			(xy 20.32508 -333.148178) (xy 20.32566 -333.106409) (xy 20.334781 -333.02337) (xy 20.352922 -332.941825)
			(xy 20.379866 -332.86275) (xy 20.41529 -332.787094) (xy 20.458769 -332.715763) (xy 20.48383 -332.682342)
			(xy 20.49041 -332.672889) (xy 20.495078 -332.650357) (xy 20.489504 -332.628031) (xy 20.48256 -332.618842)
			(xy 20.458851 -332.589525) (xy 20.416743 -332.526973) (xy 20.381008 -332.460574) (xy 20.351993 -332.390976)
			(xy 20.329981 -332.318856) (xy 20.315187 -332.244917) (xy 20.307755 -332.16988) (xy 20.3073 -332.132178)
			(xy 19.292062 -332.132178) (xy 19.292062 -333.928208) (xy 22.440882 -333.928208) (xy 22.440882 -333.868272)
			(xy 22.448705 -333.80885) (xy 22.464218 -333.750957) (xy 22.487154 -333.695584) (xy 22.517121 -333.643678)
			(xy 22.553608 -333.596128) (xy 22.595988 -333.553748) (xy 22.643538 -333.517261) (xy 22.695444 -333.487294)
			(xy 22.750817 -333.464358) (xy 22.80871 -333.448845) (xy 22.868132 -333.441022) (xy 22.928068 -333.441022)
			(xy 22.98749 -333.448845) (xy 23.045383 -333.464358) (xy 23.100756 -333.487294) (xy 23.152662 -333.517261)
			(xy 23.200212 -333.553748) (xy 23.242592 -333.596128) (xy 23.279079 -333.643678) (xy 23.309046 -333.695584)
			(xy 23.331982 -333.750957) (xy 23.347495 -333.80885) (xy 23.355318 -333.868272) (xy 23.355808 -333.89824)
			(xy 23.355318 -333.928208) (xy 23.347495 -333.98763) (xy 23.331982 -334.045523) (xy 23.309046 -334.100896)
			(xy 23.279079 -334.152802) (xy 23.242592 -334.200352) (xy 23.200212 -334.242732) (xy 23.152662 -334.279219)
			(xy 23.100756 -334.309186) (xy 23.045383 -334.332122) (xy 22.98749 -334.347635) (xy 22.928068 -334.355458)
			(xy 22.868132 -334.355458) (xy 22.80871 -334.347635) (xy 22.750817 -334.332122) (xy 22.695444 -334.309186)
			(xy 22.643538 -334.279219) (xy 22.595988 -334.242732) (xy 22.553608 -334.200352) (xy 22.517121 -334.152802)
			(xy 22.487154 -334.100896) (xy 22.464218 -334.045523) (xy 22.448705 -333.98763) (xy 22.440882 -333.928208)
			(xy 19.292062 -333.928208) (xy 19.292062 -336.678016) (xy 19.292538 -336.687983) (xy 19.300109 -336.706424)
			(xy 19.306794 -336.71383) (xy 20.499832 -337.906868) (xy 20.500086 -337.907122) (xy 20.507496 -337.913806)
			(xy 20.525932 -337.92139) (xy 20.5359 -337.921854)
		)
		(stroke
			(width 0)
			(type solid)
		)
		(fill yes)
		(layer "B.Cu")
		(net "PVDDIO_P1")
	)
	(gr_poly
		(pts
			(arc
				(start 82.448908 -353.519994)
				(mid 82.468431 -353.516093)
				(end 82.484976 -353.505008)
			)
			(arc
				(start 86.514178 -349.475806)
				(mid 86.525289 -349.459272)
				(end 86.529164 -349.439738)
			)
			(xy 86.529164 -349.439484)
			(arc
				(start 87.020654 -348.947994)
				(mid 87.037188 -348.936883)
				(end 87.056722 -348.933008)
			)
			(xy 103.968296 -348.933008)
			(arc
				(start 103.978456 -348.928182)
				(mid 103.999905 -348.918873)
				(end 104.02189 -348.91091)
			)
			(xy 104.027732 -348.909132) (xy 104.037638 -348.903036)
			(arc
				(start 104.66451 -348.276164)
				(mid 104.681044 -348.265053)
				(end 104.700578 -348.261178)
			)
			(arc
				(start 104.918764 -348.261178)
				(mid 104.935598 -348.258308)
				(end 104.950514 -348.250002)
			)
			(arc
				(start 104.950514 -348.250002)
				(mid 105.189528 -348.165923)
				(end 105.428542 -348.250002)
			)
			(arc
				(start 105.428542 -348.250002)
				(mid 105.443466 -348.258284)
				(end 105.460292 -348.261178)
			)
			(arc
				(start 108.414058 -348.261178)
				(mid 108.433581 -348.257277)
				(end 108.450126 -348.246192)
			)
			(arc
				(start 109.106462 -347.589856)
				(mid 109.117573 -347.573322)
				(end 109.121448 -347.553788)
			)
			(xy 109.121448 -341.80907) (xy 109.117638 -341.795862)
			(arc
				(start 109.114082 -341.789766)
				(mid 109.108439 -341.776958)
				(end 109.106462 -341.763096)
			)
			(arc
				(start 109.106462 -340.636606)
				(mid 109.102512 -340.617219)
				(end 109.091476 -340.600792)
			)
			(arc
				(start 108.70946 -340.218522)
				(mid 108.692926 -340.207411)
				(end 108.673392 -340.203536)
			)
			(arc
				(start 104.234742 -340.203536)
				(mid 104.215355 -340.207486)
				(end 104.198928 -340.218522)
			)
			(xy 104.126284 -340.291166) (xy 104.118918 -340.298278) (xy 104.111298 -340.317074)
			(arc
				(start 104.111298 -343.42705)
				(mid 104.115063 -343.446241)
				(end 104.125776 -343.46261)
			)
			(xy 104.12603 -343.462864) (xy 104.182926 -343.51976)
			(arc
				(start 104.183434 -343.520268)
				(mid 104.199791 -343.53101)
				(end 104.218994 -343.534746)
			)
			(arc
				(start 105.42778 -343.534746)
				(mid 105.447303 -343.538647)
				(end 105.463848 -343.549732)
			)
			(arc
				(start 105.906062 -343.991946)
				(mid 105.917173 -344.00848)
				(end 105.921048 -344.028014)
			)
			(arc
				(start 105.921048 -345.63431)
				(mid 105.917147 -345.653833)
				(end 105.906062 -345.670378)
			)
			(arc
				(start 105.676954 -345.899486)
				(mid 105.66042 -345.910597)
				(end 105.640886 -345.914472)
			)
			(arc
				(start 99.677982 -345.914472)
				(mid 99.658459 -345.910571)
				(end 99.641914 -345.899486)
			)
			(arc
				(start 99.496372 -345.753944)
				(mid 99.485261 -345.73741)
				(end 99.481386 -345.717876)
			)
			(xy 99.481386 -335.449418) (xy 99.473766 -335.430622) (xy 99.4664 -335.42351) (xy 99.352608 -335.309718)
			(xy 99.352608 -335.30921) (xy 99.333558 -335.29016) (xy 99.326446 -335.282794) (xy 99.30765 -335.275174)
			(xy 95.90405 -335.275174) (xy 95.885254 -335.282794) (xy 95.878142 -335.29016) (xy 95.850456 -335.317846)
			(xy 95.84309 -335.324958) (xy 95.83547 -335.343754)
			(arc
				(start 95.83547 -338.528406)
				(mid 95.839235 -338.547597)
				(end 95.849948 -338.563966)
			)
			(xy 95.850202 -338.56422) (xy 95.89262 -338.606638)
			(arc
				(start 95.893128 -338.607146)
				(mid 95.909485 -338.617888)
				(end 95.928688 -338.621624)
			)
			(arc
				(start 97.540318 -338.621624)
				(mid 97.559841 -338.625525)
				(end 97.576386 -338.63661)
			)
			(arc
				(start 97.790508 -338.850732)
				(mid 97.801619 -338.867266)
				(end 97.805494 -338.8868)
			)
			(arc
				(start 97.805494 -341.06866)
				(mid 97.801593 -341.088183)
				(end 97.790508 -341.104728)
			)
			(arc
				(start 97.335086 -341.56015)
				(mid 97.318552 -341.571261)
				(end 97.299018 -341.575136)
			)
			(arc
				(start 91.476576 -341.575136)
				(mid 91.457053 -341.571235)
				(end 91.440508 -341.56015)
			)
			(arc
				(start 91.116404 -341.236046)
				(mid 91.105293 -341.219512)
				(end 91.101418 -341.199978)
			)
			(xy 91.101418 -340.720172) (xy 91.099386 -340.706202) (xy 91.097608 -340.699852) (xy 91.094052 -340.693756)
			(arc
				(start 91.093798 -340.693502)
				(mid 91.088519 -340.681155)
				(end 91.086686 -340.667848)
			)
			(xy 91.086686 -335.335118) (xy 91.079066 -335.316322) (xy 91.0717 -335.30921)
			(arc
				(start 91.004136 -335.241646)
				(mid 90.987719 -335.230584)
				(end 90.968322 -335.22666)
			)
			(arc
				(start 87.579708 -335.22666)
				(mid 87.562063 -335.231159)
				(end 87.547196 -335.241646)
			)
			(xy 87.519256 -335.269586) (xy 87.51189 -335.276698) (xy 87.50427 -335.295494)
			(arc
				(start 87.50427 -338.474558)
				(mid 87.508035 -338.493749)
				(end 87.518748 -338.510118)
			)
			(xy 87.519002 -338.510372) (xy 87.545418 -338.536788)
			(arc
				(start 87.545926 -338.537296)
				(mid 87.562283 -338.548038)
				(end 87.581486 -338.551774)
			)
			(arc
				(start 89.13114 -338.551774)
				(mid 89.150663 -338.555675)
				(end 89.167208 -338.56676)
			)
			(arc
				(start 89.398856 -338.798408)
				(mid 89.409967 -338.814942)
				(end 89.413842 -338.834476)
			)
			(xy 89.413842 -340.278466) (xy 89.410286 -340.282022)
			(arc
				(start 89.410286 -340.972648)
				(mid 89.406394 -340.991743)
				(end 89.395554 -341.007954)
			)
			(arc
				(start 89.120218 -341.28329)
				(mid 89.104035 -341.294196)
				(end 89.084912 -341.298022)
			)
			(arc
				(start 83.46186 -341.298022)
				(mid 83.442765 -341.29413)
				(end 83.426554 -341.28329)
			)
			(arc
				(start 82.744818 -340.601554)
				(mid 82.733912 -340.585371)
				(end 82.730086 -340.566248)
			)
			(arc
				(start 82.730086 -335.430622)
				(mid 82.726185 -335.411099)
				(end 82.7151 -335.394554)
			)
			(xy 82.547206 -335.22666) (xy 82.540094 -335.219294) (xy 82.521298 -335.211674)
			(arc
				(start 79.249778 -335.211674)
				(mid 79.234148 -335.214138)
				(end 79.22006 -335.221326)
			)
			(xy 79.198724 -335.242916) (xy 79.197708 -335.242916) (xy 79.15275 -335.28762) (xy 79.146654 -335.29397)
			(arc
				(start 79.146654 -338.475828)
				(mid 79.150419 -338.495019)
				(end 79.161132 -338.511388)
			)
			(xy 79.161386 -338.511642) (xy 79.2099 -338.560156)
			(arc
				(start 79.210408 -338.560664)
				(mid 79.226765 -338.571406)
				(end 79.245968 -338.575142)
			)
			(arc
				(start 80.843374 -338.575142)
				(mid 80.862897 -338.579043)
				(end 80.879442 -338.590128)
			)
			(arc
				(start 81.04124 -338.751926)
				(mid 81.052351 -338.76846)
				(end 81.056226 -338.787994)
			)
			(xy 81.056226 -340.203282) (xy 81.053686 -340.205822)
			(arc
				(start 81.053686 -340.998048)
				(mid 81.049794 -341.017143)
				(end 81.038954 -341.033354)
			)
			(arc
				(start 80.662018 -341.41029)
				(mid 80.645835 -341.421196)
				(end 80.626712 -341.425022)
			)
			(arc
				(start 75.391518 -341.425022)
				(mid 75.372423 -341.42113)
				(end 75.356212 -341.41029)
			)
			(arc
				(start 74.482706 -340.536784)
				(mid 74.4718 -340.520601)
				(end 74.467974 -340.501478)
			)
			(xy 74.467974 -335.404714) (xy 74.460354 -335.385918) (xy 74.452988 -335.378806) (xy 74.319892 -335.24571)
			(xy 74.31278 -335.238344) (xy 74.293984 -335.230724) (xy 70.883272 -335.230724) (xy 70.864476 -335.238344)
			(xy 70.857364 -335.24571) (xy 70.806056 -335.297018) (xy 70.79869 -335.30413) (xy 70.79107 -335.322926)
			(arc
				(start 70.79107 -338.492084)
				(mid 70.794835 -338.511275)
				(end 70.805548 -338.527644)
			)
			(xy 70.805802 -338.527898) (xy 70.851776 -338.573872)
			(arc
				(start 70.852284 -338.57438)
				(mid 70.868641 -338.585122)
				(end 70.887844 -338.588858)
			)
			(arc
				(start 72.556878 -338.588858)
				(mid 72.576401 -338.592759)
				(end 72.592946 -338.603844)
			)
			(arc
				(start 72.720962 -338.73186)
				(mid 72.731868 -338.748043)
				(end 72.735694 -338.767166)
			)
			(arc
				(start 72.735694 -342.141048)
				(mid 72.739459 -342.160239)
				(end 72.750172 -342.176608)
			)
			(xy 72.750426 -342.176862)
			(arc
				(start 73.572624 -342.99906)
				(mid 73.583735 -343.015594)
				(end 73.58761 -343.035128)
			)
			(arc
				(start 73.58761 -346.248228)
				(mid 73.583709 -346.267751)
				(end 73.572624 -346.284296)
			)
			(arc
				(start 71.709788 -348.147132)
				(mid 71.693254 -348.158243)
				(end 71.67372 -348.162118)
			)
			(arc
				(start 68.688204 -348.162118)
				(mid 68.668681 -348.158217)
				(end 68.652136 -348.147132)
			)
			(xy 67.518026 -347.013022) (xy 67.510914 -347.005656) (xy 67.492118 -346.998036) (xy 62.332616 -346.998036)
			(xy 62.31382 -347.005656) (xy 62.306708 -347.013022) (xy 62.271656 -347.048074) (xy 62.26429 -347.055186)
			(xy 62.25667 -347.073982)
			(arc
				(start 62.25667 -350.243902)
				(mid 62.271549 -350.279823)
				(end 62.30747 -350.294702)
			)
			(arc
				(start 63.575438 -350.294702)
				(mid 63.594961 -350.298603)
				(end 63.611506 -350.309688)
			)
			(arc
				(start 64.136524 -350.834706)
				(mid 64.147635 -350.85124)
				(end 64.15151 -350.870774)
			)
			(xy 64.15151 -350.875854) (xy 64.15913 -350.894396)
			(arc
				(start 66.769742 -353.505008)
				(mid 66.786276 -353.516119)
				(end 66.80581 -353.519994)
			)
		)
		(stroke
			(width 0)
			(type solid)
		)
		(fill yes)
		(layer "B.Cu")
		(net "SW_P12V_AUX_PVDDCR_CPU1_P1_FLT")
	)
	(gr_poly
		(pts
			(xy 409.684474 -188.977016) (xy 409.690316 -188.977016) (xy 410.026358 -188.640974) (xy 420.909242 -188.640974)
			(xy 421.099742 -188.450474) (xy 421.099742 -187.625482) (xy 421.051482 -187.575444) (xy 421.006746 -187.573396)
			(xy 420.917886 -187.56223) (xy 420.830395 -187.543091) (xy 420.744989 -187.516135) (xy 420.662364 -187.481582)
			(xy 420.583193 -187.439714) (xy 420.508124 -187.390872) (xy 420.437769 -187.335455) (xy 420.372701 -187.273916)
			(xy 420.313452 -187.206756) (xy 420.260505 -187.134524) (xy 420.214293 -187.057808) (xy 420.175192 -186.977236)
			(xy 420.143521 -186.893463) (xy 420.119539 -186.807174) (xy 420.103441 -186.719074) (xy 420.095359 -186.62988)
			(xy 420.095359 -186.54032) (xy 420.103441 -186.451126) (xy 420.119539 -186.363026) (xy 420.143521 -186.276737)
			(xy 420.175192 -186.192964) (xy 420.214293 -186.112392) (xy 420.260505 -186.035676) (xy 420.313452 -185.963444)
			(xy 420.372701 -185.896284) (xy 420.437769 -185.834744) (xy 420.508124 -185.779328) (xy 420.583193 -185.730486)
			(xy 420.662364 -185.688618) (xy 420.744989 -185.654065) (xy 420.830396 -185.627109) (xy 420.917886 -185.60797)
			(xy 421.006747 -185.596804) (xy 421.051482 -185.594752) (xy 421.099742 -185.544714) (xy 421.099742 -172.688504)
			(xy 421.099202 -172.678668) (xy 421.091614 -172.660509) (xy 421.08501 -172.653198) (xy 420.907464 -172.475652)
			(xy 420.900223 -172.468947) (xy 420.882018 -172.461367) (xy 420.872158 -172.46092) (xy 411.46857 -172.46092)
			(xy 411.45873 -172.461449) (xy 411.44056 -172.469028) (xy 411.433264 -172.475652) (xy 411.17901 -172.729906)
			(xy 411.172293 -172.737143) (xy 411.164694 -172.755348) (xy 411.164278 -172.765212) (xy 411.164278 -175.2092)
			(xy 419.215314 -175.2092) (xy 419.219387 -175.153541) (xy 419.231522 -175.099068) (xy 419.251458 -175.046942)
			(xy 419.278772 -174.998274) (xy 419.31288 -174.954102) (xy 419.353057 -174.915367) (xy 419.398445 -174.882895)
			(xy 419.448077 -174.857377) (xy 419.500897 -174.839358) (xy 419.555776 -174.829221) (xy 419.611547 -174.827183)
			(xy 419.667021 -174.833286) (xy 419.721014 -174.847402) (xy 419.772377 -174.869229) (xy 419.820015 -174.898302)
			(xy 419.862911 -174.934001) (xy 419.900153 -174.975565) (xy 419.930947 -175.022109) (xy 419.954635 -175.07264)
			(xy 419.970713 -175.126082) (xy 419.978839 -175.181296) (xy 419.979348 -175.2092) (xy 419.978839 -175.237104)
			(xy 419.970713 -175.292318) (xy 419.954635 -175.34576) (xy 419.930947 -175.396291) (xy 419.900153 -175.442835)
			(xy 419.862911 -175.484399) (xy 419.820015 -175.520098) (xy 419.772377 -175.549171) (xy 419.721014 -175.570998)
			(xy 419.667021 -175.585114) (xy 419.611547 -175.591217) (xy 419.555776 -175.589179) (xy 419.500897 -175.579042)
			(xy 419.448077 -175.561023) (xy 419.398445 -175.535505) (xy 419.353057 -175.503033) (xy 419.31288 -175.464298)
			(xy 419.278772 -175.420126) (xy 419.251458 -175.371458) (xy 419.231522 -175.319332) (xy 419.219387 -175.264859)
			(xy 419.215314 -175.2092) (xy 411.164278 -175.2092) (xy 411.164278 -176.915064) (xy 411.163743 -176.924901)
			(xy 411.156155 -176.943062) (xy 411.149546 -176.95037) (xy 410.827728 -177.272188) (xy 410.820493 -177.27891)
			(xy 410.802288 -177.286522) (xy 410.792422 -177.28692) (xy 405.234648 -177.28692) (xy 405.22481 -177.287453)
			(xy 405.206646 -177.295038) (xy 405.199342 -177.301652) (xy 404.799546 -177.701448) (xy 404.792843 -177.70869)
			(xy 404.785269 -177.726895) (xy 404.784814 -177.736754) (xy 404.784814 -178.341528) (xy 404.784286 -178.351369)
			(xy 404.776711 -178.369543) (xy 404.770082 -178.376834) (xy 404.32101 -178.825906) (xy 404.313773 -178.832623)
			(xy 404.295568 -178.840226) (xy 404.285704 -178.840638) (xy 402.675852 -178.840638) (xy 402.666011 -178.841168)
			(xy 402.647839 -178.848743) (xy 402.640546 -178.85537) (xy 402.41601 -179.079906) (xy 402.409293 -179.087143)
			(xy 402.401694 -179.105348) (xy 402.401278 -179.115212) (xy 402.401278 -185.297064) (xy 402.400743 -185.306901)
			(xy 402.393155 -185.325062) (xy 402.386546 -185.33237) (xy 402.034756 -185.68416) (xy 402.027509 -185.690718)
			(xy 402.009466 -185.698176) (xy 401.999704 -185.698638) (xy 393.912852 -185.698638) (xy 393.903011 -185.699168)
			(xy 393.884839 -185.706743) (xy 393.877546 -185.71337) (xy 393.654026 -185.93689) (xy 393.647305 -185.944125)
			(xy 393.639697 -185.96233) (xy 393.639294 -185.972196) (xy 393.639294 -186.5851) (xy 412.55033 -186.5851)
			(xy 412.554321 -186.496233) (xy 412.566262 -186.408082) (xy 412.586057 -186.321356) (xy 412.613546 -186.236754)
			(xy 412.648509 -186.154956) (xy 412.690663 -186.076622) (xy 412.739669 -186.002382) (xy 412.795133 -185.932833)
			(xy 412.856608 -185.868536) (xy 412.923599 -185.810009) (xy 412.995567 -185.757723) (xy 413.071932 -185.712098)
			(xy 413.152079 -185.673502) (xy 413.235364 -185.642247) (xy 413.321114 -185.618582) (xy 413.408641 -185.6027)
			(xy 413.49724 -185.594727) (xy 413.541718 -185.594244) (xy 415.294318 -185.594244) (xy 415.338794 -185.594748)
			(xy 415.427389 -185.602723) (xy 415.514912 -185.618607) (xy 415.600658 -185.642273) (xy 415.683938 -185.67353)
			(xy 415.764081 -185.712126) (xy 415.840442 -185.757751) (xy 415.912406 -185.810037) (xy 415.979393 -185.868563)
			(xy 416.040864 -185.932858) (xy 416.096324 -186.002404) (xy 416.145328 -186.076642) (xy 416.187479 -186.154973)
			(xy 416.222439 -186.236768) (xy 416.249927 -186.321367) (xy 416.26972 -186.408089) (xy 416.281661 -186.496237)
			(xy 416.285652 -186.5851) (xy 416.281661 -186.673963) (xy 416.26972 -186.762111) (xy 416.249927 -186.848833)
			(xy 416.222439 -186.933432) (xy 416.187479 -187.015227) (xy 416.145328 -187.093558) (xy 416.096324 -187.167796)
			(xy 416.040864 -187.237342) (xy 415.979393 -187.301637) (xy 415.912406 -187.360163) (xy 415.840442 -187.412449)
			(xy 415.764081 -187.458074) (xy 415.683938 -187.49667) (xy 415.600658 -187.527927) (xy 415.514912 -187.551593)
			(xy 415.427389 -187.567477) (xy 415.338794 -187.575452) (xy 415.294318 -187.575952) (xy 413.541718 -187.575952)
			(xy 413.49724 -187.575473) (xy 413.408641 -187.5675) (xy 413.321114 -187.551618) (xy 413.235364 -187.527953)
			(xy 413.152079 -187.496698) (xy 413.071932 -187.458102) (xy 412.995567 -187.412477) (xy 412.923599 -187.360191)
			(xy 412.856608 -187.301664) (xy 412.795133 -187.237367) (xy 412.739669 -187.167818) (xy 412.690663 -187.093578)
			(xy 412.648509 -187.015244) (xy 412.613546 -186.933446) (xy 412.586057 -186.848844) (xy 412.566262 -186.762118)
			(xy 412.554321 -186.673967) (xy 412.55033 -186.5851) (xy 393.639294 -186.5851) (xy 393.639294 -187.466986)
			(xy 394.345668 -187.466986) (xy 394.346165 -187.439735) (xy 394.353922 -187.385789) (xy 394.369278 -187.333496)
			(xy 394.391919 -187.283921) (xy 394.421385 -187.238071) (xy 394.457075 -187.196882) (xy 394.498263 -187.161191)
			(xy 394.544112 -187.131724) (xy 394.593687 -187.109082) (xy 394.64598 -187.093725) (xy 394.699926 -187.085965)
			(xy 394.727176 -187.085478) (xy 394.75465 -187.085984) (xy 394.809028 -187.093872) (xy 394.86171 -187.109488)
			(xy 394.911603 -187.132508) (xy 394.957673 -187.162455) (xy 394.978636 -187.18022) (xy 394.985494 -187.186062)
			(xy 395.002512 -187.192666) (xy 395.08684 -187.192666) (xy 395.103858 -187.186062) (xy 395.110716 -187.18022)
			(xy 395.131677 -187.162455) (xy 395.17776 -187.132533) (xy 395.227655 -187.109522) (xy 395.280332 -187.093896)
			(xy 395.334704 -187.085978) (xy 395.362176 -187.085478) (xy 395.389428 -187.085978) (xy 395.443377 -187.093731)
			(xy 395.495673 -187.109083) (xy 395.545252 -187.131722) (xy 395.591105 -187.161186) (xy 395.632297 -187.196876)
			(xy 395.667991 -187.238065) (xy 395.69746 -187.283915) (xy 395.720103 -187.333492) (xy 395.735461 -187.385786)
			(xy 395.74322 -187.439734) (xy 395.743684 -187.466986) (xy 395.743186 -187.495074) (xy 395.734941 -187.550642)
			(xy 395.718628 -187.604398) (xy 395.694599 -187.655176) (xy 395.663377 -187.701876) (xy 395.644878 -187.723018)
			(xy 395.638528 -187.73013) (xy 395.631924 -187.747402) (xy 395.632178 -187.834016) (xy 395.639036 -187.851034)
			(xy 395.645386 -187.858146) (xy 395.664282 -187.879394) (xy 395.696216 -187.92644) (xy 395.720807 -187.977707)
			(xy 395.73751 -188.032058) (xy 395.745954 -188.088288) (xy 395.746478 -188.116718) (xy 395.746062 -188.143973)
			(xy 395.738302 -188.197927) (xy 395.722942 -188.250228) (xy 395.700295 -188.29981) (xy 395.670822 -188.345664)
			(xy 395.635124 -188.386858) (xy 395.593926 -188.422551) (xy 395.548068 -188.452018) (xy 395.498482 -188.474659)
			(xy 395.44618 -188.490012) (xy 395.392225 -188.497765) (xy 395.36497 -188.498226) (xy 395.337495 -188.497751)
			(xy 395.283115 -188.489855) (xy 395.230433 -188.474232) (xy 395.18054 -188.451205) (xy 395.134472 -188.421252)
			(xy 395.11351 -188.403484) (xy 395.106652 -188.397642) (xy 395.089634 -188.391038) (xy 395.005306 -188.391038)
			(xy 394.988288 -188.397642) (xy 394.98143 -188.403484) (xy 394.960452 -188.421228) (xy 394.914373 -188.451153)
			(xy 394.864483 -188.474168) (xy 394.81181 -188.489799) (xy 394.757441 -188.497723) (xy 394.72997 -188.498226)
			(xy 394.702719 -188.49775) (xy 394.648772 -188.48999) (xy 394.596478 -188.474632) (xy 394.546902 -188.451989)
			(xy 394.501052 -188.422521) (xy 394.459863 -188.386829) (xy 394.424172 -188.345638) (xy 394.394706 -188.299788)
			(xy 394.372064 -188.250211) (xy 394.356707 -188.197917) (xy 394.348949 -188.143969) (xy 394.348462 -188.116718)
			(xy 394.348951 -188.088629) (xy 394.357197 -188.033061) (xy 394.373511 -187.979305) (xy 394.397542 -187.928527)
			(xy 394.428767 -187.881827) (xy 394.447268 -187.860686) (xy 394.453618 -187.853574) (xy 394.460222 -187.836302)
			(xy 394.459968 -187.749688) (xy 394.45311 -187.73267) (xy 394.44676 -187.725558) (xy 394.427857 -187.704316)
			(xy 394.395926 -187.657268) (xy 394.371337 -187.605999) (xy 394.354636 -187.551646) (xy 394.346193 -187.495416)
			(xy 394.345668 -187.466986) (xy 393.639294 -187.466986) (xy 393.639294 -199.59574) (xy 393.934442 -199.890888)
			(xy 398.770348 -199.890888)
		)
		(stroke
			(width 0)
			(type solid)
		)
		(fill yes)
		(layer "B.Cu")
		(net "PVDDCR_SOC_P0")
	)
	(gr_poly
		(pts
			(xy 58.746644 -163.666932) (xy 58.756711 -163.666502) (xy 58.775307 -163.65878) (xy 58.782712 -163.651946)
			(xy 59.301634 -163.133024) (xy 59.308475 -163.125624) (xy 59.316193 -163.107025) (xy 59.31662 -163.096956)
			(xy 59.31662 -158.928562) (xy 59.317051 -158.918495) (xy 59.324777 -158.899903) (xy 59.331606 -158.892494)
			(xy 60.948824 -157.275276) (xy 60.95622 -157.268425) (xy 60.974819 -157.260687) (xy 60.984892 -157.26029)
			(xy 82.483706 -157.26029) (xy 82.493775 -157.259865) (xy 82.512377 -157.252148) (xy 82.519774 -157.245304)
			(xy 82.720434 -157.044644) (xy 82.727279 -157.037246) (xy 82.735003 -157.018647) (xy 82.73542 -157.008576)
			(xy 82.73542 -149.964648) (xy 82.734988 -149.954582) (xy 82.727263 -149.935989) (xy 82.720434 -149.92858)
			(xy 82.534252 -149.742398) (xy 82.526851 -149.735559) (xy 82.508253 -149.727843) (xy 82.498184 -149.727412)
			(xy 74.737976 -149.727412) (xy 74.727907 -149.726985) (xy 74.709308 -149.719266) (xy 74.701908 -149.712426)
			(xy 74.173588 -149.184106) (xy 74.166242 -149.177297) (xy 74.14778 -149.169568) (xy 74.137774 -149.16912)
			(xy 71.925942 -149.16912) (xy 71.915951 -149.16965) (xy 71.89751 -149.177355) (xy 71.890128 -149.184106)
			(xy 68.303394 -152.77084) (xy 68.29659 -152.778188) (xy 68.288873 -152.79665) (xy 68.288408 -152.806654)
			(xy 68.288408 -154.177746) (xy 68.288836 -154.187445) (xy 68.296016 -154.205465) (xy 68.302378 -154.212798)
			(xy 68.322038 -154.234111) (xy 68.356376 -154.280835) (xy 68.384532 -154.331525) (xy 68.406053 -154.385368)
			(xy 68.420595 -154.4415) (xy 68.427924 -154.49902) (xy 68.428362 -154.528012) (xy 68.427872 -154.55798)
			(xy 68.420049 -154.617402) (xy 68.404536 -154.675295) (xy 68.3816 -154.730668) (xy 68.351633 -154.782574)
			(xy 68.315146 -154.830124) (xy 68.272766 -154.872504) (xy 68.225216 -154.908991) (xy 68.17331 -154.938958)
			(xy 68.117937 -154.961894) (xy 68.060044 -154.977407) (xy 68.000622 -154.98523) (xy 67.940686 -154.98523)
			(xy 67.881264 -154.977407) (xy 67.823371 -154.961894) (xy 67.767998 -154.938958) (xy 67.716092 -154.908991)
			(xy 67.668542 -154.872504) (xy 67.626162 -154.830124) (xy 67.589675 -154.782574) (xy 67.559708 -154.730668)
			(xy 67.536772 -154.675295) (xy 67.521259 -154.617402) (xy 67.513436 -154.55798) (xy 67.512946 -154.528012)
			(xy 67.513416 -154.499024) (xy 67.520779 -154.441518) (xy 67.535338 -154.3854) (xy 67.556861 -154.331567)
			(xy 67.585003 -154.280879) (xy 67.619315 -154.234147) (xy 67.63893 -154.212798) (xy 67.645318 -154.205479)
			(xy 67.652513 -154.187452) (xy 67.6529 -154.177746) (xy 67.6529 -152.654) (xy 67.653342 -152.629022)
			(xy 67.661119 -152.579675) (xy 67.676527 -152.532154) (xy 67.699187 -152.487633) (xy 67.72854 -152.44721)
			(xy 67.745864 -152.42921) (xy 71.548498 -148.626576) (xy 71.566516 -148.609275) (xy 71.606945 -148.57994)
			(xy 71.651463 -148.557288) (xy 71.698975 -148.541874) (xy 71.748313 -148.534078) (xy 71.773288 -148.533612)
			(xy 73.932034 -148.533612) (xy 73.942038 -148.533118) (xy 73.96052 -148.525453) (xy 73.974665 -148.511302)
			(xy 73.982322 -148.492816) (xy 73.982834 -148.482812) (xy 73.982834 -147.503642) (xy 73.980802 -147.49653)
			(xy 73.97369 -147.470435) (xy 73.966035 -147.416893) (xy 73.965562 -147.38985) (xy 73.966034 -147.362807)
			(xy 73.973687 -147.309265) (xy 73.980802 -147.28317) (xy 73.982834 -147.276058) (xy 73.982834 -146.324574)
			(xy 73.982404 -146.314507) (xy 73.974676 -146.295916) (xy 73.967848 -146.288506) (xy 73.945242 -146.2659)
			(xy 73.936427 -146.257922) (xy 73.913908 -146.25039) (xy 73.902062 -146.251422) (xy 73.871074 -146.255994)
			(xy 73.860206 -146.25808) (xy 73.841625 -146.270056) (xy 73.83526 -146.279108) (xy 73.820164 -146.302014)
			(xy 73.784449 -146.343651) (xy 73.743143 -146.37975) (xy 73.697097 -146.409567) (xy 73.647258 -146.43249)
			(xy 73.594652 -146.448045) (xy 73.540362 -146.455913) (xy 73.512934 -146.4564) (xy 73.482881 -146.455838)
			(xy 73.42352 -146.446414) (xy 73.366372 -146.427793) (xy 73.312853 -146.400437) (xy 73.264289 -146.365023)
			(xy 73.242678 -146.344132) (xy 73.235307 -146.33739) (xy 73.216846 -146.329801) (xy 73.206864 -146.3294)
			(xy 72.08774 -146.3294) (xy 72.062744 -146.328762) (xy 72.01372 -146.318962) (xy 71.967548 -146.29979)
			(xy 71.926003 -146.271981) (xy 71.907908 -146.254724) (xy 71.580502 -145.927318) (xy 71.573055 -145.92063)
			(xy 71.554559 -145.913034) (xy 71.534563 -145.913034) (xy 71.516067 -145.92063) (xy 71.50862 -145.927318)
			(xy 71.282814 -146.153124) (xy 71.264719 -146.170382) (xy 71.223174 -146.198194) (xy 71.177003 -146.217371)
			(xy 71.127979 -146.227175) (xy 71.102982 -146.2278) (xy 69.926454 -146.2278) (xy 69.91649 -146.228283)
			(xy 69.898061 -146.235865) (xy 69.89064 -146.242532) (xy 69.869031 -146.263424) (xy 69.82046 -146.298827)
			(xy 69.76694 -146.326179) (xy 69.709795 -146.344802) (xy 69.650436 -146.354237) (xy 69.620384 -146.3548)
			(xy 69.593134 -146.354313) (xy 69.539189 -146.346555) (xy 69.486897 -146.331199) (xy 69.437323 -146.308557)
			(xy 69.391476 -146.279091) (xy 69.350288 -146.2434) (xy 69.314599 -146.202211) (xy 69.285135 -146.156363)
			(xy 69.262496 -146.106788) (xy 69.247142 -146.054495) (xy 69.239386 -146.00055) (xy 69.239386 -145.94605)
			(xy 69.247142 -145.892105) (xy 69.262496 -145.839812) (xy 69.285135 -145.790237) (xy 69.314599 -145.744389)
			(xy 69.350288 -145.7032) (xy 69.391476 -145.667509) (xy 69.437323 -145.638043) (xy 69.486897 -145.615401)
			(xy 69.539189 -145.600045) (xy 69.593134 -145.592287) (xy 69.620384 -145.591784) (xy 69.650436 -145.592346)
			(xy 69.709797 -145.601773) (xy 69.766943 -145.620395) (xy 69.820461 -145.647752) (xy 69.869024 -145.683166)
			(xy 69.89064 -145.704052) (xy 69.898054 -145.710724) (xy 69.91649 -145.718284) (xy 69.926454 -145.718784)
			(xy 70.97649 -145.718784) (xy 70.986519 -145.718339) (xy 71.005083 -145.710753) (xy 71.012558 -145.704052)
			(xy 71.087742 -145.628868) (xy 71.09459 -145.62147) (xy 71.102322 -145.602872) (xy 71.102728 -145.5928)
			(xy 71.102728 -144.150334) (xy 71.102225 -144.140282) (xy 71.094507 -144.121718) (xy 71.087742 -144.114266)
			(xy 71.032116 -144.058894) (xy 71.024766 -144.052097) (xy 71.006303 -144.044396) (xy 70.996302 -144.043908)
			(xy 68.984368 -144.043908) (xy 68.965826 -144.051528) (xy 68.959476 -144.057878) (xy 67.780662 -144.057878)
			(xy 67.770595 -144.057447) (xy 67.752003 -144.049721) (xy 67.744594 -144.042892) (xy 49.507902 -144.042892)
			(xy 49.497831 -144.043314) (xy 49.479226 -144.051027) (xy 49.471834 -144.057878) (xy 49.088802 -144.44091)
			(xy 49.081957 -144.448309) (xy 49.074226 -144.466907) (xy 49.073816 -144.476978) (xy 49.073816 -146.146266)
			(xy 52.217828 -146.146266) (xy 52.217828 -145.318734) (xy 52.218278 -145.308728) (xy 52.226005 -145.290266)
			(xy 52.232814 -145.28292) (xy 52.901088 -144.614646) (xy 52.908489 -144.607918) (xy 52.926916 -144.600199)
			(xy 52.936902 -144.59966) (xy 58.32094 -144.59966) (xy 58.330945 -144.600115) (xy 58.349408 -144.607838)
			(xy 58.356754 -144.614646) (xy 58.67781 -144.935702) (xy 58.684551 -144.943091) (xy 58.692261 -144.961527)
			(xy 58.692796 -144.971516) (xy 58.692796 -145.517362) (xy 58.69432 -145.518886) (xy 58.69432 -149.412198)
			(xy 69.012814 -149.412198) (xy 69.016885 -149.356576) (xy 69.029011 -149.302139) (xy 69.048934 -149.250048)
			(xy 69.07623 -149.201413) (xy 69.110316 -149.15727) (xy 69.150465 -149.118561) (xy 69.195823 -149.08611)
			(xy 69.245423 -149.060609) (xy 69.298207 -149.042602) (xy 69.35305 -149.032472) (xy 69.408784 -149.030435)
			(xy 69.464221 -149.036535) (xy 69.518178 -149.050641) (xy 69.569507 -149.072453) (xy 69.617113 -149.101507)
			(xy 69.659981 -149.137182) (xy 69.697198 -149.178719) (xy 69.727971 -149.225232) (xy 69.751643 -149.275729)
			(xy 69.767711 -149.329136) (xy 69.775831 -149.384312) (xy 69.77634 -149.412198) (xy 69.775831 -149.440084)
			(xy 69.767711 -149.49526) (xy 69.751643 -149.548667) (xy 69.727971 -149.599164) (xy 69.697198 -149.645677)
			(xy 69.659981 -149.687214) (xy 69.617113 -149.722889) (xy 69.569507 -149.751943) (xy 69.518178 -149.773755)
			(xy 69.464221 -149.787861) (xy 69.408784 -149.793961) (xy 69.35305 -149.791924) (xy 69.298207 -149.781794)
			(xy 69.245423 -149.763787) (xy 69.195823 -149.738286) (xy 69.150465 -149.705835) (xy 69.110316 -149.667126)
			(xy 69.07623 -149.622983) (xy 69.048934 -149.574348) (xy 69.029011 -149.522257) (xy 69.016885 -149.46782)
			(xy 69.012814 -149.412198) (xy 58.69432 -149.412198) (xy 58.69432 -160.89503) (xy 58.693866 -160.905036)
			(xy 58.686143 -160.923499) (xy 58.679334 -160.930844) (xy 58.119264 -161.490914) (xy 58.111887 -161.497671)
			(xy 58.093442 -161.505371) (xy 58.08345 -161.5059) (xy 54.181502 -161.5059) (xy 54.171492 -161.505486)
			(xy 54.153028 -161.497736) (xy 54.145688 -161.490914) (xy 53.517292 -160.862518) (xy 53.510601 -160.855116)
			(xy 53.503034 -160.836672) (xy 53.50256 -160.826704) (xy 53.50256 -158.538164) (xy 53.502164 -158.528091)
			(xy 53.494424 -158.509493) (xy 53.487574 -158.502096) (xy 52.247292 -157.261814) (xy 52.2406 -157.254414)
			(xy 52.233033 -157.235968) (xy 52.23256 -157.226) (xy 52.23256 -147.399502) (xy 52.23637 -147.395692)
			(xy 52.243202 -147.388285) (xy 52.250927 -147.369691) (xy 52.251356 -147.359624) (xy 52.251356 -146.221704)
			(xy 52.25094 -146.211633) (xy 52.243214 -146.193035) (xy 52.23637 -146.185636) (xy 52.232814 -146.18208)
			(xy 52.226068 -146.174694) (xy 52.21836 -146.156256) (xy 52.217828 -146.146266) (xy 49.073816 -146.146266)
			(xy 49.073816 -163.363148) (xy 49.074248 -163.373214) (xy 49.081977 -163.391804) (xy 49.088802 -163.399216)
			(xy 49.295812 -163.606226) (xy 49.303208 -163.613078) (xy 49.321806 -163.62082) (xy 49.33188 -163.621212)
			(xy 52.71389 -163.621212) (xy 52.723961 -163.621634) (xy 52.742567 -163.629347) (xy 52.749958 -163.636198)
			(xy 52.765706 -163.651946) (xy 52.773102 -163.658797) (xy 52.791701 -163.666538) (xy 52.801774 -163.666932)
		)
		(stroke
			(width 0)
			(type solid)
		)
		(fill yes)
		(layer "B.Cu")
		(net "GND")
	)
	(gr_poly
		(pts
			(xy 426.024548 -156.817314) (xy 426.034615 -156.816883) (xy 426.053208 -156.809158) (xy 426.060616 -156.802328)
			(xy 426.623226 -156.239718) (xy 426.630068 -156.232319) (xy 426.637784 -156.213719) (xy 426.638212 -156.20365)
			(xy 426.638212 -143.48333) (xy 426.637777 -143.473265) (xy 426.630046 -143.454678) (xy 426.623226 -143.447262)
			(xy 415.30524 -132.129276) (xy 415.297842 -132.122431) (xy 415.279243 -132.114706) (xy 415.269172 -132.11429)
			(xy 411.563058 -132.11429) (xy 411.55874 -132.118608) (xy 410.882592 -132.118608) (xy 410.872523 -132.119033)
			(xy 410.853921 -132.12675) (xy 410.846524 -132.133594) (xy 410.639514 -132.340604) (xy 410.632667 -132.348002)
			(xy 410.624932 -132.3666) (xy 410.624528 -132.376672) (xy 410.624528 -136.656318) (xy 410.624102 -136.666387)
			(xy 410.616387 -136.68499) (xy 410.609542 -136.692386) (xy 409.425648 -137.87628) (xy 410.732478 -137.87628)
			(xy 410.732968 -137.846312) (xy 410.740791 -137.78689) (xy 410.756304 -137.728997) (xy 410.77924 -137.673624)
			(xy 410.809207 -137.621718) (xy 410.845694 -137.574168) (xy 410.888074 -137.531788) (xy 410.935624 -137.495301)
			(xy 410.98753 -137.465334) (xy 411.042903 -137.442398) (xy 411.100796 -137.426885) (xy 411.160218 -137.419062)
			(xy 411.220154 -137.419062) (xy 411.279576 -137.426885) (xy 411.337469 -137.442398) (xy 411.392842 -137.465334)
			(xy 411.444748 -137.495301) (xy 411.492298 -137.531788) (xy 411.534678 -137.574168) (xy 411.571165 -137.621718)
			(xy 411.601132 -137.673624) (xy 411.624068 -137.728997) (xy 411.639581 -137.78689) (xy 411.647404 -137.846312)
			(xy 411.647894 -137.87628) (xy 411.647424 -137.906368) (xy 411.639536 -137.966023) (xy 411.623894 -138.02413)
			(xy 411.600767 -138.079683) (xy 411.570556 -138.131724) (xy 411.533781 -138.179355) (xy 411.512766 -138.200892)
			(xy 411.505932 -138.208297) (xy 411.49821 -138.226893) (xy 411.49778 -138.23696) (xy 411.49778 -138.49477)
			(xy 411.4982 -138.50484) (xy 411.505922 -138.523439) (xy 411.512766 -138.530838) (xy 411.640528 -138.6586)
			(xy 411.648002 -138.665302) (xy 411.666567 -138.672886) (xy 411.676596 -138.673332) (xy 411.725872 -138.673332)
			(xy 411.748184 -138.673716) (xy 411.791996 -138.682162) (xy 411.833305 -138.699027) (xy 411.870508 -138.723658)
			(xy 411.902166 -138.755101) (xy 411.927049 -138.792136) (xy 411.944195 -138.833329) (xy 411.952938 -138.877083)
			(xy 411.953456 -138.899392) (xy 411.953456 -139.167108) (xy 411.944312 -139.167108) (xy 411.93429 -139.167529)
			(xy 411.915772 -139.175197) (xy 411.901599 -139.189369) (xy 411.89393 -139.207886) (xy 411.893512 -139.217908)
			(xy 411.893512 -139.603226) (xy 411.893777 -139.610259) (xy 411.897634 -139.623789) (xy 411.901132 -139.629896)
			(xy 411.91942 -139.663424) (xy 411.926024 -139.676632) (xy 411.950408 -139.691872) (xy 411.953456 -139.691872)
			(xy 411.953456 -139.773914) (xy 411.953964 -139.77747) (xy 411.955623 -139.790424) (xy 411.957405 -139.816481)
			(xy 411.95752 -139.82954) (xy 411.95752 -140.05179) (xy 411.957945 -140.061859) (xy 411.965665 -140.080457)
			(xy 411.972506 -140.087858) (xy 414.04667 -142.162022) (xy 414.054084 -142.168845) (xy 414.072673 -142.176574)
			(xy 414.082738 -142.177008) (xy 415.467038 -142.177008) (xy 415.494267 -142.177572) (xy 415.548169 -142.185327)
			(xy 415.600419 -142.200674) (xy 415.649954 -142.2233) (xy 415.695764 -142.252744) (xy 415.736918 -142.288409)
			(xy 415.772578 -142.329566) (xy 415.802019 -142.37538) (xy 415.82464 -142.424917) (xy 415.839981 -142.477168)
			(xy 415.847731 -142.531071) (xy 415.847731 -142.585529) (xy 415.839981 -142.639432) (xy 415.82464 -142.691683)
			(xy 415.802019 -142.74122) (xy 415.772578 -142.787034) (xy 415.736918 -142.828191) (xy 415.695764 -142.863856)
			(xy 415.649954 -142.8933) (xy 415.600419 -142.915926) (xy 415.548169 -142.931273) (xy 415.494267 -142.939028)
			(xy 415.467038 -142.939516) (xy 413.903668 -142.939516) (xy 413.873697 -142.938959) (xy 413.814483 -142.929646)
			(xy 413.757459 -142.911175) (xy 413.704031 -142.884002) (xy 413.655517 -142.848798) (xy 413.63392 -142.82801)
			(xy 411.306518 -140.500608) (xy 411.285736 -140.479008) (xy 411.250553 -140.430483) (xy 411.22339 -140.377054)
			(xy 411.204914 -140.320035) (xy 411.19558 -140.260829) (xy 411.195012 -140.23086) (xy 411.195012 -139.82954)
			(xy 411.19511 -139.81648) (xy 411.19689 -139.790422) (xy 411.198568 -139.77747) (xy 411.199076 -139.773914)
			(xy 411.199076 -139.691872) (xy 411.202124 -139.691872) (xy 411.226508 -139.676632) (xy 411.233112 -139.663424)
			(xy 411.2514 -139.629896) (xy 411.254928 -139.623801) (xy 411.258795 -139.610265) (xy 411.25902 -139.603226)
			(xy 411.25902 -139.167108) (xy 411.249876 -139.167108) (xy 411.239868 -139.166632) (xy 411.221377 -139.158966)
			(xy 411.207225 -139.14481) (xy 411.199565 -139.126316) (xy 411.199076 -139.116308) (xy 411.199076 -139.108434)
			(xy 411.198639 -139.098366) (xy 411.190927 -139.079768) (xy 411.18409 -139.072366) (xy 410.972508 -138.861038)
			(xy 410.955789 -138.843565) (xy 410.927409 -138.804412) (xy 410.905496 -138.761306) (xy 410.890589 -138.715304)
			(xy 410.883054 -138.667538) (xy 410.882592 -138.64336) (xy 410.882592 -138.23696) (xy 410.882189 -138.226888)
			(xy 410.874453 -138.20829) (xy 410.867606 -138.200892) (xy 410.846573 -138.179373) (xy 410.809805 -138.131735)
			(xy 410.7796 -138.079689) (xy 410.756479 -138.024133) (xy 410.74084 -137.966025) (xy 410.732954 -137.906368)
			(xy 410.732478 -137.87628) (xy 409.425648 -137.87628) (xy 407.829258 -139.47267) (xy 410.103318 -139.47267)
			(xy 410.107389 -139.417048) (xy 410.119515 -139.362611) (xy 410.139438 -139.31052) (xy 410.166734 -139.261885)
			(xy 410.20082 -139.217742) (xy 410.240969 -139.179033) (xy 410.286327 -139.146582) (xy 410.335927 -139.121081)
			(xy 410.388711 -139.103074) (xy 410.443554 -139.092944) (xy 410.499288 -139.090907) (xy 410.554725 -139.097007)
			(xy 410.608682 -139.111113) (xy 410.660011 -139.132925) (xy 410.707617 -139.161979) (xy 410.750485 -139.197654)
			(xy 410.787702 -139.239191) (xy 410.818475 -139.285704) (xy 410.842147 -139.336201) (xy 410.858215 -139.389608)
			(xy 410.866335 -139.444784) (xy 410.866844 -139.47267) (xy 410.866335 -139.500556) (xy 410.858215 -139.555732)
			(xy 410.842147 -139.609139) (xy 410.818475 -139.659636) (xy 410.787702 -139.706149) (xy 410.750485 -139.747686)
			(xy 410.707617 -139.783361) (xy 410.660011 -139.812415) (xy 410.608682 -139.834227) (xy 410.554725 -139.848333)
			(xy 410.499288 -139.854433) (xy 410.443554 -139.852396) (xy 410.388711 -139.842266) (xy 410.335927 -139.824259)
			(xy 410.286327 -139.798758) (xy 410.240969 -139.766307) (xy 410.20082 -139.727598) (xy 410.166734 -139.683455)
			(xy 410.139438 -139.63482) (xy 410.119515 -139.582729) (xy 410.107389 -139.528292) (xy 410.103318 -139.47267)
			(xy 407.829258 -139.47267) (xy 407.826972 -139.474956) (xy 407.81732 -139.474956) (xy 407.81732 -141.67612)
			(xy 408.669236 -141.67612) (xy 408.669236 -141.14272) (xy 408.669752 -141.132727) (xy 408.677455 -141.114279)
			(xy 408.691593 -141.100145) (xy 408.710043 -141.092449) (xy 408.720036 -141.09192) (xy 408.934412 -141.09192)
			(xy 408.934412 -141.082776) (xy 408.934869 -141.072765) (xy 408.942538 -141.054271) (xy 408.956701 -141.040118)
			(xy 408.975201 -141.032461) (xy 408.985212 -141.031976) (xy 409.201874 -141.031976) (xy 409.224283 -141.032507)
			(xy 409.268212 -141.041395) (xy 409.309534 -141.058751) (xy 409.346636 -141.083896) (xy 409.378066 -141.115847)
			(xy 409.402598 -141.153357) (xy 409.411424 -141.173962) (xy 409.41752 -141.188694) (xy 409.44292 -141.205712)
			(xy 410.04871 -141.205712) (xy 410.075126 -141.186916) (xy 410.080206 -141.171168) (xy 410.090762 -141.141225)
			(xy 410.119056 -141.084388) (xy 410.154931 -141.032005) (xy 410.1977 -140.985081) (xy 410.246542 -140.944516)
			(xy 410.30052 -140.911089) (xy 410.3586 -140.885441) (xy 410.419666 -140.868064) (xy 410.482547 -140.85929)
			(xy 410.514292 -140.858748) (xy 410.544258 -140.859304) (xy 410.603679 -140.867126) (xy 410.66157 -140.882637)
			(xy 410.716941 -140.905572) (xy 410.768845 -140.935538) (xy 410.816393 -140.972022) (xy 410.858773 -141.014401)
			(xy 410.895258 -141.061949) (xy 410.925225 -141.113852) (xy 410.94816 -141.169223) (xy 410.963672 -141.227113)
			(xy 410.971495 -141.286534) (xy 410.971495 -141.346466) (xy 410.963672 -141.405887) (xy 410.94816 -141.463777)
			(xy 410.925225 -141.519148) (xy 410.895258 -141.571051) (xy 410.858773 -141.618599) (xy 410.816393 -141.660978)
			(xy 410.768845 -141.697462) (xy 410.716941 -141.727428) (xy 410.66157 -141.750363) (xy 410.603679 -141.765874)
			(xy 410.544258 -141.773696) (xy 410.514292 -141.774164) (xy 410.48305 -141.773652) (xy 410.421146 -141.76515)
			(xy 410.360974 -141.748306) (xy 410.303654 -141.723431) (xy 410.25025 -141.69099) (xy 410.201757 -141.651585)
			(xy 410.180028 -141.62913) (xy 410.172524 -141.621876) (xy 410.153371 -141.613627) (xy 410.142944 -141.613128)
			(xy 409.44292 -141.613128) (xy 409.41752 -141.630146) (xy 409.411424 -141.644878) (xy 409.402649 -141.665508)
			(xy 409.378118 -141.703026) (xy 409.34668 -141.73498) (xy 409.309566 -141.760119) (xy 409.268229 -141.777458)
			(xy 409.224287 -141.786318) (xy 409.201874 -141.786864) (xy 408.934412 -141.786864) (xy 408.934412 -141.77772)
			(xy 408.933964 -141.767702) (xy 408.926303 -141.749187) (xy 408.912139 -141.735015) (xy 408.89363 -141.727342)
			(xy 408.883612 -141.72692) (xy 408.720036 -141.72692) (xy 408.710001 -141.726565) (xy 408.691453 -141.718906)
			(xy 408.677269 -141.70471) (xy 408.669627 -141.686155) (xy 408.669236 -141.67612) (xy 407.81732 -141.67612)
			(xy 407.81732 -150.69693) (xy 407.817749 -150.706997) (xy 407.825473 -150.725592) (xy 407.832306 -150.732998)
			(xy 408.563826 -151.464518) (xy 408.571222 -151.471369) (xy 408.589821 -151.479107) (xy 408.599894 -151.479504)
			(xy 422.464484 -151.479504) (xy 422.474547 -151.479943) (xy 422.493129 -151.487679) (xy 422.500552 -151.49449)
			(xy 422.926764 -151.920702) (xy 422.933614 -151.928099) (xy 422.941353 -151.946697) (xy 422.94175 -151.95677)
			(xy 422.94175 -156.14396) (xy 422.942186 -156.154024) (xy 422.949921 -156.172608) (xy 422.956736 -156.180028)
			(xy 423.579036 -156.802328) (xy 423.586433 -156.809177) (xy 423.605032 -156.816909) (xy 423.615104 -156.817314)
		)
		(stroke
			(width 0)
			(type solid)
		)
		(fill yes)
		(layer "B.Cu")
		(net "GND")
	)
	(gr_poly
		(pts
			(arc
				(start 256.800604 -37.135308)
				(mid 258.932532 -36.252077)
				(end 259.815584 -34.120074)
			)
			(arc
				(start 259.815584 -13.780008)
				(mid 260.103939 -13.083859)
				(end 260.800088 -12.795504)
			)
			(arc
				(start 385.601972 -12.795504)
				(mid 387.734244 -11.912288)
				(end 388.61746 -9.780016)
			)
			(arc
				(start 388.61746 -3.976878)
				(mid 388.611809 -3.953593)
				(end 388.596124 -3.935476)
			)
			(arc
				(start 388.596124 -3.935476)
				(mid 388.428347 -3.782165)
				(end 388.302246 -3.593084)
			)
			(xy 388.294372 -3.577336) (xy 388.262368 -3.56235)
			(arc
				(start 388.149084 -3.589528)
				(mid 388.120945 -3.607374)
				(end 388.109968 -3.638804)
			)
			(arc
				(start 388.109968 -9.780016)
				(mid 387.375393 -11.553437)
				(end 385.601972 -12.288012)
			)
			(arc
				(start 260.800088 -12.288012)
				(mid 259.745088 -12.725008)
				(end 259.308092 -13.780008)
			)
			(arc
				(start 259.308092 -34.120074)
				(mid 258.573517 -35.893495)
				(end 256.800096 -36.62807)
			)
			(arc
				(start 225.300032 -36.62807)
				(mid 223.526611 -35.893495)
				(end 222.792036 -34.120074)
			)
			(arc
				(start 222.792036 -13.780008)
				(mid 222.35504 -12.725008)
				(end 221.30004 -12.288012)
			)
			(arc
				(start 196.701918 -12.288012)
				(mid 194.928497 -11.553437)
				(end 194.193922 -9.780016)
			)
			(arc
				(start 194.193922 -8.918702)
				(mid 194.182875 -8.887327)
				(end 194.154806 -8.869426)
			)
			(xy 194.041522 -8.842248) (xy 194.009518 -8.857234)
			(arc
				(start 194.001644 -8.872982)
				(mid 193.875648 -9.062025)
				(end 193.70802 -9.215374)
			)
			(arc
				(start 193.70802 -9.215374)
				(mid 193.69232 -9.233484)
				(end 193.686684 -9.256776)
			)
			(arc
				(start 193.686684 -9.780524)
				(mid 194.569915 -11.912452)
				(end 196.701918 -12.795504)
			)
			(arc
				(start 221.30004 -12.795504)
				(mid 221.996189 -13.083859)
				(end 222.284544 -13.780008)
			)
			(arc
				(start 222.284544 -34.120074)
				(mid 223.16785 -36.252182)
				(end 225.300032 -37.135308)
			)
		)
		(stroke
			(width 0)
			(type solid)
		)
		(fill yes)
		(layer "B.Cu")
		(net "GND")
	)
	(gr_poly
		(pts
			(xy 65.93332 -337.765136) (xy 65.943162 -337.76461) (xy 65.96134 -337.75704) (xy 65.968626 -337.750404)
			(xy 66.066162 -337.652868) (xy 66.072866 -337.645626) (xy 66.080445 -337.627422) (xy 66.080894 -337.617562)
			(xy 66.080894 -333.210408) (xy 66.081315 -333.200337) (xy 66.089027 -333.18173) (xy 66.09588 -333.17434)
			(xy 68.121276 -331.148944) (xy 68.128116 -331.141543) (xy 68.135834 -331.122945) (xy 68.136262 -331.112876)
			(xy 68.136262 -328.192384) (xy 68.13669 -328.182316) (xy 68.144415 -328.163722) (xy 68.151248 -328.156316)
			(xy 70.008496 -326.299068) (xy 70.015891 -326.292213) (xy 70.03449 -326.284467) (xy 70.044564 -326.284082)
			(xy 97.797112 -326.284082) (xy 97.806955 -326.284607) (xy 97.825132 -326.292177) (xy 97.832418 -326.298814)
			(xy 98.3107 -326.777096) (xy 98.318098 -326.783943) (xy 98.336696 -326.791678) (xy 98.346768 -326.792082)
			(xy 99.625912 -326.792082) (xy 99.635755 -326.792607) (xy 99.653932 -326.800177) (xy 99.661218 -326.806814)
			(xy 99.949762 -327.095358) (xy 99.956478 -327.102595) (xy 99.964084 -327.1208) (xy 99.964494 -327.130664)
			(xy 99.964494 -328.103738) (xy 108.139736 -328.103738) (xy 108.143807 -328.048116) (xy 108.155933 -327.993679)
			(xy 108.175856 -327.941588) (xy 108.203152 -327.892953) (xy 108.237238 -327.84881) (xy 108.277387 -327.810101)
			(xy 108.322745 -327.77765) (xy 108.372345 -327.752149) (xy 108.425129 -327.734142) (xy 108.479972 -327.724012)
			(xy 108.535706 -327.721975) (xy 108.591143 -327.728075) (xy 108.6451 -327.742181) (xy 108.696429 -327.763993)
			(xy 108.744035 -327.793047) (xy 108.786903 -327.828722) (xy 108.82412 -327.870259) (xy 108.854893 -327.916772)
			(xy 108.878565 -327.967269) (xy 108.894633 -328.020676) (xy 108.902753 -328.075852) (xy 108.903262 -328.103738)
			(xy 108.902753 -328.131624) (xy 108.894633 -328.1868) (xy 108.878565 -328.240207) (xy 108.854893 -328.290704)
			(xy 108.82412 -328.337217) (xy 108.786903 -328.378754) (xy 108.744035 -328.414429) (xy 108.696429 -328.443483)
			(xy 108.6451 -328.465295) (xy 108.591143 -328.479401) (xy 108.535706 -328.485501) (xy 108.479972 -328.483464)
			(xy 108.425129 -328.473334) (xy 108.372345 -328.455327) (xy 108.322745 -328.429826) (xy 108.277387 -328.397375)
			(xy 108.237238 -328.358666) (xy 108.203152 -328.314523) (xy 108.175856 -328.265888) (xy 108.155933 -328.213797)
			(xy 108.143807 -328.15936) (xy 108.139736 -328.103738) (xy 99.964494 -328.103738) (xy 99.964494 -330.908152)
			(xy 99.972114 -330.926948) (xy 99.97948 -330.93406) (xy 100.350066 -331.304646) (xy 100.357412 -331.311452)
			(xy 100.375875 -331.319169) (xy 100.38588 -331.319632) (xy 109.630972 -331.319632) (xy 109.639954 -331.318615)
			(xy 109.656358 -331.311057) (xy 109.662976 -331.3049) (xy 109.726476 -331.2414) (xy 109.733195 -331.234165)
			(xy 109.740799 -331.215959) (xy 109.741208 -331.206094) (xy 109.741208 -327.95337) (xy 109.74078 -327.943302)
			(xy 109.733059 -327.924705) (xy 109.726222 -327.917302) (xy 107.139486 -325.330566) (xy 107.132635 -325.32317)
			(xy 107.1249 -325.304571) (xy 107.1245 -325.294498) (xy 107.1245 -314.950602) (xy 107.124077 -314.940532)
			(xy 107.116363 -314.921927) (xy 107.109514 -314.914534) (xy 106.398314 -314.203588) (xy 106.391202 -314.196222)
			(xy 106.372406 -314.188602) (xy 99.204272 -314.188602) (xy 99.176332 -314.211208) (xy 99.172776 -314.228988)
			(xy 99.166137 -314.258724) (xy 99.146208 -314.316301) (xy 99.119022 -314.370828) (xy 99.102418 -314.396374)
			(xy 99.098368 -314.402783) (xy 99.09385 -314.417247) (xy 99.093528 -314.424822) (xy 99.093528 -314.706254)
			(xy 99.093845 -314.71383) (xy 99.098365 -314.728294) (xy 99.102418 -314.734702) (xy 99.117618 -314.758063)
			(xy 99.143019 -314.807674) (xy 99.162383 -314.859938) (xy 99.175439 -314.914123) (xy 99.182005 -314.96947)
			(xy 99.182428 -314.997338) (xy 99.181922 -315.028136) (xy 99.173878 -315.089205) (xy 99.157932 -315.148701)
			(xy 99.134357 -315.205607) (xy 99.103557 -315.25895) (xy 99.066058 -315.307816) (xy 99.022502 -315.35137)
			(xy 98.973635 -315.388867) (xy 98.920291 -315.419665) (xy 98.863384 -315.443238) (xy 98.803887 -315.459181)
			(xy 98.742818 -315.467223) (xy 98.71202 -315.467746) (xy 98.683372 -315.467326) (xy 98.626499 -315.46037)
			(xy 98.570895 -315.446546) (xy 98.517385 -315.426061) (xy 98.466765 -315.399218) (xy 98.443034 -315.383164)
			(xy 98.435588 -315.378445) (xy 98.418568 -315.373902) (xy 98.40976 -315.374274) (xy 98.379534 -315.376814)
			(xy 98.370984 -315.377837) (xy 98.35527 -315.384849) (xy 98.3488 -315.39053) (xy 98.330241 -315.407499)
			(xy 98.288951 -315.436202) (xy 98.243795 -315.458329) (xy 98.195811 -315.473373) (xy 98.146105 -315.480988)
			(xy 98.120962 -315.481462) (xy 98.09498 -315.480949) (xy 98.043658 -315.472815) (xy 97.994239 -315.456753)
			(xy 97.947941 -315.433158) (xy 97.905904 -315.402612) (xy 97.869163 -315.365867) (xy 97.838622 -315.323826)
			(xy 97.815032 -315.277526) (xy 97.798976 -315.228105) (xy 97.790848 -315.176782) (xy 97.790848 -315.124818)
			(xy 97.798976 -315.073495) (xy 97.815032 -315.024074) (xy 97.838622 -314.977774) (xy 97.869163 -314.935733)
			(xy 97.905904 -314.898988) (xy 97.947941 -314.868442) (xy 97.994239 -314.844847) (xy 98.043658 -314.828785)
			(xy 98.09498 -314.820651) (xy 98.120962 -314.820046) (xy 98.141763 -314.820359) (xy 98.183036 -314.825579)
			(xy 98.203258 -314.83046) (xy 98.211725 -314.832331) (xy 98.228995 -314.830903) (xy 98.23704 -314.827666)
			(xy 98.264472 -314.814966) (xy 98.272421 -314.811098) (xy 98.285173 -314.798872) (xy 98.289364 -314.79109)
			(xy 98.296564 -314.776515) (xy 98.312709 -314.748297) (xy 98.321622 -314.734702) (xy 98.325673 -314.728293)
			(xy 98.33019 -314.713829) (xy 98.330512 -314.706254) (xy 98.330512 -314.424822) (xy 98.330191 -314.417248)
			(xy 98.325661 -314.40279) (xy 98.321622 -314.396374) (xy 98.300838 -314.364027) (xy 98.268923 -314.294082)
			(xy 98.258122 -314.257182) (xy 98.255427 -314.248787) (xy 98.245293 -314.234373) (xy 98.23831 -314.228988)
			(xy 98.213672 -314.211716) (xy 98.206477 -314.207052) (xy 98.189988 -314.202386) (xy 98.181414 -314.202572)
			(xy 98.161094 -314.20308) (xy 98.138256 -314.202711) (xy 98.093009 -314.196464) (xy 98.070924 -314.190634)
			(xy 98.064066 -314.188602) (xy 70.889114 -314.188602) (xy 70.879051 -314.189041) (xy 70.860469 -314.196778)
			(xy 70.853046 -314.203588) (xy 62.62751 -322.429124) (xy 62.620666 -322.436523) (xy 62.612939 -322.455121)
			(xy 62.612524 -322.465192) (xy 62.612524 -326.068182) (xy 62.612018 -326.078232) (xy 62.604296 -326.096792)
			(xy 62.597538 -326.10425) (xy 60.347352 -328.354436) (xy 60.339954 -328.361282) (xy 60.321355 -328.369009)
			(xy 60.311284 -328.369422) (xy 57.826656 -328.369422) (xy 57.81659 -328.369854) (xy 57.797999 -328.377582)
			(xy 57.790588 -328.384408) (xy 57.696608 -328.478388) (xy 57.689759 -328.485785) (xy 57.682019 -328.504383)
			(xy 57.681622 -328.514456) (xy 57.681622 -336.271616) (xy 58.081926 -336.271616) (xy 58.082395 -336.244246)
			(xy 58.090211 -336.190067) (xy 58.105699 -336.137563) (xy 58.12854 -336.087816) (xy 58.158265 -336.04185)
			(xy 58.175906 -336.020918) (xy 58.182002 -336.013806) (xy 58.188352 -335.996788) (xy 58.188352 -335.911444)
			(xy 58.182002 -335.894426) (xy 58.175906 -335.887314) (xy 58.158261 -335.866387) (xy 58.12855 -335.820413)
			(xy 58.105715 -335.770664) (xy 58.090225 -335.718162) (xy 58.082399 -335.663986) (xy 58.081926 -335.636616)
			(xy 58.08237 -335.609362) (xy 58.090126 -335.555409) (xy 58.105482 -335.503108) (xy 58.128125 -335.453526)
			(xy 58.157594 -335.407671) (xy 58.19329 -335.366477) (xy 58.234486 -335.330784) (xy 58.280342 -335.301316)
			(xy 58.329925 -335.278675) (xy 58.382226 -335.263322) (xy 58.43618 -335.255569) (xy 58.463434 -335.255108)
			(xy 58.489629 -335.255538) (xy 58.541526 -335.262706) (xy 58.591956 -335.276902) (xy 58.639971 -335.297861)
			(xy 58.68467 -335.325188) (xy 58.725212 -335.358369) (xy 58.743342 -335.377282) (xy 58.750843 -335.384574)
			(xy 58.769981 -335.39297) (xy 58.780426 -335.393538) (xy 58.855102 -335.393538) (xy 58.86556 -335.393015)
			(xy 58.884716 -335.384619) (xy 58.892186 -335.377282) (xy 58.910325 -335.358378) (xy 58.950863 -335.325193)
			(xy 58.995559 -335.297863) (xy 59.043573 -335.276903) (xy 59.094002 -335.262707) (xy 59.145899 -335.255541)
			(xy 59.172094 -335.255108) (xy 59.199347 -335.255561) (xy 59.2533 -335.263318) (xy 59.305599 -335.278674)
			(xy 59.35518 -335.301317) (xy 59.401034 -335.330785) (xy 59.442227 -335.36648) (xy 59.477921 -335.407674)
			(xy 59.507388 -335.453529) (xy 59.53003 -335.503111) (xy 59.545385 -335.55541) (xy 59.55314 -335.609363)
			(xy 59.553602 -335.636616) (xy 59.553145 -335.663987) (xy 59.545325 -335.718166) (xy 59.529834 -335.770669)
			(xy 59.50699 -335.820416) (xy 59.477264 -335.866382) (xy 59.459622 -335.887314) (xy 59.453526 -335.894426)
			(xy 59.447176 -335.911444) (xy 59.447176 -335.996788) (xy 59.453526 -336.013806) (xy 59.459622 -336.020918)
			(xy 59.47724 -336.041867) (xy 59.506954 -336.087836) (xy 59.529794 -336.137579) (xy 59.54529 -336.190076)
			(xy 59.553124 -336.244248) (xy 59.553602 -336.271616) (xy 59.553137 -336.298868) (xy 59.545378 -336.352817)
			(xy 59.530021 -336.405112) (xy 59.507377 -336.45469) (xy 59.477909 -336.500541) (xy 59.442215 -336.541731)
			(xy 59.401023 -336.577422) (xy 59.355171 -336.606888) (xy 59.305592 -336.629528) (xy 59.253295 -336.644883)
			(xy 59.199346 -336.652639) (xy 59.172094 -336.653124) (xy 59.1459 -336.652665) (xy 59.094004 -336.645502)
			(xy 59.043575 -336.63131) (xy 58.99556 -336.610357) (xy 58.950861 -336.583036) (xy 58.910317 -336.54986)
			(xy 58.892186 -336.53095) (xy 58.884707 -336.523631) (xy 58.865553 -336.51525) (xy 58.855102 -336.514694)
			(xy 58.780426 -336.514694) (xy 58.769973 -336.515252) (xy 58.750818 -336.523626) (xy 58.743342 -336.53095)
			(xy 58.725196 -336.549846) (xy 58.684658 -336.583031) (xy 58.639964 -336.610361) (xy 58.591951 -336.631322)
			(xy 58.541524 -336.64552) (xy 58.489628 -336.652689) (xy 58.463434 -336.653124) (xy 58.436183 -336.652613)
			(xy 58.382234 -336.644861) (xy 58.329938 -336.62951) (xy 58.280359 -336.606873) (xy 58.234507 -336.57741)
			(xy 58.193314 -336.541721) (xy 58.15762 -336.500533) (xy 58.128151 -336.454685) (xy 58.105507 -336.405109)
			(xy 58.090149 -336.352815) (xy 58.08239 -336.298867) (xy 58.081926 -336.271616) (xy 57.681622 -336.271616)
			(xy 57.681622 -337.678776) (xy 57.689242 -337.697572) (xy 57.696608 -337.704684) (xy 57.742074 -337.75015)
			(xy 57.749474 -337.75699) (xy 57.768073 -337.764706) (xy 57.778142 -337.765136)
		)
		(stroke
			(width 0)
			(type solid)
		)
		(fill yes)
		(layer "B.Cu")
		(net "PVDDCR_CPU1_P1")
	)
	(gr_poly
		(pts
			(xy 460.208376 -27.943302) (xy 460.218401 -27.942887) (xy 460.236926 -27.935221) (xy 460.251106 -27.921048)
			(xy 460.258782 -27.902526) (xy 460.259176 -27.892502) (xy 460.259176 -25.58542) (xy 460.197217 -25.498938)
			(xy 460.079118 -25.321952) (xy 459.967821 -25.140612) (xy 459.863487 -24.955178) (xy 459.766266 -24.765917)
			(xy 459.676299 -24.573104) (xy 459.593714 -24.377014) (xy 459.518631 -24.177932) (xy 459.451158 -23.976143)
			(xy 459.391392 -23.771938) (xy 459.339419 -23.565613) (xy 459.295315 -23.357464) (xy 459.259143 -23.14779)
			(xy 459.230954 -22.936895) (xy 459.21079 -22.725082) (xy 459.19868 -22.512657) (xy 459.19464 -22.299924)
			(xy 459.198678 -22.087192) (xy 459.210786 -21.874766) (xy 459.230949 -21.662953) (xy 459.259135 -21.452058)
			(xy 459.295306 -21.242384) (xy 459.339408 -21.034234) (xy 459.391379 -20.827908) (xy 459.451143 -20.623704)
			(xy 459.518615 -20.421914) (xy 459.593696 -20.222831) (xy 459.676279 -20.026741) (xy 459.766245 -19.833926)
			(xy 459.863464 -19.644665) (xy 459.967797 -19.45923) (xy 460.079092 -19.277889) (xy 460.197189 -19.100902)
			(xy 460.259176 -19.01444) (xy 460.259176 -13.959078) (xy 460.258752 -13.949061) (xy 460.251077 -13.930556)
			(xy 460.236905 -13.916397) (xy 460.218393 -13.908739) (xy 460.208376 -13.908278) (xy 456.830938 -13.908278)
			(xy 456.820873 -13.907843) (xy 456.802287 -13.90011) (xy 456.79487 -13.893292) (xy 456.140566 -13.238988)
			(xy 456.13317 -13.232137) (xy 456.114571 -13.224401) (xy 456.104498 -13.224002) (xy 454.853802 -13.224002)
			(xy 454.843732 -13.224425) (xy 454.825127 -13.232139) (xy 454.817734 -13.238988) (xy 454.75906 -13.297662)
			(xy 454.752217 -13.305061) (xy 454.744495 -13.32366) (xy 454.744074 -13.33373) (xy 454.744074 -19.102324)
			(xy 454.743646 -19.112392) (xy 454.735922 -19.130987) (xy 454.729088 -19.138392) (xy 454.457054 -19.410426)
			(xy 454.450139 -19.418068) (xy 454.442542 -19.437206) (xy 454.442322 -19.44751) (xy 454.444354 -19.531584)
			(xy 454.452736 -19.550126) (xy 454.46061 -19.557238) (xy 454.479892 -19.575393) (xy 454.513757 -19.61611)
			(xy 454.541662 -19.661122) (xy 454.56307 -19.709562) (xy 454.577568 -19.760499) (xy 454.584879 -19.812952)
			(xy 454.585324 -19.839432) (xy 454.584836 -19.866682) (xy 454.577076 -19.920627) (xy 454.561718 -19.972919)
			(xy 454.539075 -20.022493) (xy 454.509609 -20.068341) (xy 454.473917 -20.109529) (xy 454.432728 -20.145218)
			(xy 454.386879 -20.174683) (xy 454.337304 -20.197324) (xy 454.285012 -20.212679) (xy 454.231066 -20.220437)
			(xy 454.203816 -20.22094) (xy 454.177222 -20.22048) (xy 454.12455 -20.213095) (xy 454.073414 -20.198465)
			(xy 454.024805 -20.176875) (xy 453.979667 -20.148743) (xy 453.938873 -20.114613) (xy 453.903215 -20.075149)
			(xy 453.873385 -20.031114) (xy 453.849959 -19.983363) (xy 453.833393 -19.932821) (xy 453.824008 -19.880468)
			(xy 453.822562 -19.85391) (xy 453.8218 -19.833336) (xy 453.79259 -19.805142) (xy 450.907658 -19.805142)
			(xy 450.897592 -19.805574) (xy 450.879003 -19.813304) (xy 450.87159 -19.820128) (xy 450.647562 -20.044156)
			(xy 450.640718 -20.051554) (xy 450.632994 -20.070153) (xy 450.632576 -20.080224) (xy 450.632576 -21.635212)
			(xy 453.632316 -21.635212) (xy 453.632777 -21.606466) (xy 453.639982 -21.549428) (xy 453.654268 -21.49374)
			(xy 453.67541 -21.440278) (xy 453.703076 -21.389881) (xy 453.736831 -21.343342) (xy 453.776144 -21.301393)
			(xy 453.820398 -21.264694) (xy 453.844406 -21.248878) (xy 453.853042 -21.243544) (xy 453.864472 -21.227542)
			(xy 453.8853 -21.138896) (xy 453.882252 -21.119338) (xy 453.876918 -21.110702) (xy 453.863954 -21.088356)
			(xy 453.843528 -21.040904) (xy 453.829703 -20.991126) (xy 453.822732 -20.939937) (xy 453.822308 -20.914106)
			(xy 453.822308 -20.913852) (xy 453.822794 -20.886601) (xy 453.83055 -20.832653) (xy 453.845905 -20.780358)
			(xy 453.868547 -20.730781) (xy 453.898013 -20.684931) (xy 453.933704 -20.64374) (xy 453.974895 -20.608049)
			(xy 454.020745 -20.578583) (xy 454.070322 -20.555941) (xy 454.122617 -20.540586) (xy 454.176565 -20.53283)
			(xy 454.231067 -20.53283) (xy 454.285015 -20.540586) (xy 454.33731 -20.555941) (xy 454.386887 -20.578583)
			(xy 454.432737 -20.608049) (xy 454.473928 -20.64374) (xy 454.509619 -20.684931) (xy 454.539085 -20.730781)
			(xy 454.561727 -20.780358) (xy 454.577082 -20.832653) (xy 454.584838 -20.886601) (xy 454.585324 -20.913852)
			(xy 454.584851 -20.941066) (xy 454.577121 -20.994943) (xy 454.56181 -21.047174) (xy 454.539231 -21.096698)
			(xy 454.50984 -21.14251) (xy 454.474236 -21.183678) (xy 454.454006 -21.201888) (xy 454.44664 -21.208238)
			(xy 454.43775 -21.226018) (xy 454.43013 -21.316696) (xy 454.436226 -21.335492) (xy 454.442576 -21.343366)
			(xy 454.462326 -21.368118) (xy 454.495607 -21.421986) (xy 454.521143 -21.479929) (xy 454.538448 -21.540838)
			(xy 454.547189 -21.603552) (xy 454.547732 -21.635212) (xy 454.547242 -21.66518) (xy 454.539419 -21.724602)
			(xy 454.523906 -21.782495) (xy 454.50097 -21.837868) (xy 454.471003 -21.889774) (xy 454.434516 -21.937324)
			(xy 454.392136 -21.979704) (xy 454.344586 -22.016191) (xy 454.29268 -22.046158) (xy 454.237307 -22.069094)
			(xy 454.179414 -22.084607) (xy 454.119992 -22.09243) (xy 454.060056 -22.09243) (xy 454.000634 -22.084607)
			(xy 453.942741 -22.069094) (xy 453.887368 -22.046158) (xy 453.835462 -22.016191) (xy 453.787912 -21.979704)
			(xy 453.745532 -21.937324) (xy 453.709045 -21.889774) (xy 453.679078 -21.837868) (xy 453.656142 -21.782495)
			(xy 453.640629 -21.724602) (xy 453.632806 -21.66518) (xy 453.632316 -21.635212) (xy 450.632576 -21.635212)
			(xy 450.632576 -21.983954) (xy 450.649594 -22.009354) (xy 450.663818 -22.015196) (xy 450.691303 -22.027133)
			(xy 450.743179 -22.057126) (xy 450.790699 -22.093631) (xy 450.833051 -22.136022) (xy 450.869511 -22.183576)
			(xy 450.899456 -22.23548) (xy 450.922375 -22.290847) (xy 450.937875 -22.34873) (xy 450.945691 -22.408141)
			(xy 450.945691 -22.44242) (xy 452.031336 -22.44242) (xy 452.031336 -22.382484) (xy 452.039159 -22.323062)
			(xy 452.054672 -22.265169) (xy 452.077608 -22.209796) (xy 452.107575 -22.15789) (xy 452.144062 -22.11034)
			(xy 452.186442 -22.06796) (xy 452.233992 -22.031473) (xy 452.285898 -22.001506) (xy 452.341271 -21.97857)
			(xy 452.399164 -21.963057) (xy 452.458586 -21.955234) (xy 452.518522 -21.955234) (xy 452.577944 -21.963057)
			(xy 452.635837 -21.97857) (xy 452.69121 -22.001506) (xy 452.743116 -22.031473) (xy 452.790666 -22.06796)
			(xy 452.833046 -22.11034) (xy 452.869533 -22.15789) (xy 452.8995 -22.209796) (xy 452.922436 -22.265169)
			(xy 452.937949 -22.323062) (xy 452.945772 -22.382484) (xy 452.946262 -22.412452) (xy 452.945772 -22.44242)
			(xy 452.937949 -22.501842) (xy 452.922436 -22.559735) (xy 452.8995 -22.615108) (xy 452.869533 -22.667014)
			(xy 452.833046 -22.714564) (xy 452.790666 -22.756944) (xy 452.743116 -22.793431) (xy 452.69121 -22.823398)
			(xy 452.635837 -22.846334) (xy 452.577944 -22.861847) (xy 452.518522 -22.86967) (xy 452.458586 -22.86967)
			(xy 452.399164 -22.861847) (xy 452.341271 -22.846334) (xy 452.285898 -22.823398) (xy 452.233992 -22.793431)
			(xy 452.186442 -22.756944) (xy 452.144062 -22.714564) (xy 452.107575 -22.667014) (xy 452.077608 -22.615108)
			(xy 452.054672 -22.559735) (xy 452.039159 -22.501842) (xy 452.031336 -22.44242) (xy 450.945691 -22.44242)
			(xy 450.945691 -22.468064) (xy 450.937874 -22.527474) (xy 450.922373 -22.585357) (xy 450.899454 -22.640724)
			(xy 450.869509 -22.692627) (xy 450.833048 -22.740181) (xy 450.790696 -22.782572) (xy 450.743175 -22.819076)
			(xy 450.691299 -22.849069) (xy 450.663818 -22.861016) (xy 450.649594 -22.866858) (xy 450.632576 -22.892258)
			(xy 450.632576 -23.109428) (xy 451.282308 -23.109428) (xy 451.282883 -23.079209) (xy 451.292396 -23.019524)
			(xy 451.311188 -22.962082) (xy 451.338792 -22.908316) (xy 451.374517 -22.859567) (xy 451.395592 -22.837902)
			(xy 451.410436 -22.813722) (xy 451.446078 -22.769582) (xy 451.487861 -22.731204) (xy 451.534865 -22.699434)
			(xy 451.586055 -22.674972) (xy 451.640301 -22.658357) (xy 451.696409 -22.649955) (xy 451.724776 -22.649434)
			(xy 451.75203 -22.649878) (xy 451.805984 -22.657633) (xy 451.858285 -22.672988) (xy 451.907868 -22.69563)
			(xy 451.953723 -22.7251) (xy 451.994917 -22.760796) (xy 452.030611 -22.801992) (xy 452.060078 -22.847848)
			(xy 452.082719 -22.897432) (xy 452.098071 -22.949734) (xy 452.105824 -23.003688) (xy 452.106284 -23.030942)
			(xy 452.105736 -23.060958) (xy 452.096317 -23.120247) (xy 452.077733 -23.177331) (xy 452.050442 -23.230802)
			(xy 452.015118 -23.279342) (xy 451.99427 -23.300944) (xy 451.979498 -23.325339) (xy 451.943879 -23.369875)
			(xy 451.902029 -23.408614) (xy 451.854879 -23.440694) (xy 451.80348 -23.465399) (xy 451.748977 -23.482179)
			(xy 451.692584 -23.490662) (xy 451.66407 -23.49119) (xy 451.636801 -23.490704) (xy 451.582819 -23.482939)
			(xy 451.530491 -23.467571) (xy 451.480883 -23.444913) (xy 451.435003 -23.415427) (xy 451.393787 -23.379712)
			(xy 451.358072 -23.338495) (xy 451.328586 -23.292615) (xy 451.305929 -23.243007) (xy 451.290561 -23.190679)
			(xy 451.282796 -23.136697) (xy 451.282308 -23.109428) (xy 450.632576 -23.109428) (xy 450.632576 -24.05634)
			(xy 450.633006 -24.066408) (xy 450.640728 -24.085004) (xy 450.647562 -24.092408) (xy 451.26402 -24.708866)
			(xy 451.272652 -24.716516) (xy 451.294419 -24.724046) (xy 451.30593 -24.723344) (xy 451.39737 -24.711914)
			(xy 451.416674 -24.699214) (xy 451.42277 -24.689054) (xy 451.437659 -24.665196) (xy 451.473343 -24.621731)
			(xy 451.515016 -24.583971) (xy 451.561777 -24.552732) (xy 451.612616 -24.52869) (xy 451.666431 -24.512366)
			(xy 451.722058 -24.504114) (xy 451.750176 -24.503634) (xy 451.777429 -24.504096) (xy 451.83138 -24.51185)
			(xy 451.883678 -24.527205) (xy 451.933259 -24.549846) (xy 451.979112 -24.579314) (xy 452.020304 -24.615009)
			(xy 452.055997 -24.656202) (xy 452.085462 -24.702057) (xy 452.108102 -24.751638) (xy 452.123454 -24.803937)
			(xy 452.131206 -24.857889) (xy 452.131684 -24.885142) (xy 452.131181 -24.913258) (xy 452.122927 -24.968881)
			(xy 452.106603 -25.022692) (xy 452.082562 -25.073526) (xy 452.051325 -25.120284) (xy 452.013567 -25.161954)
			(xy 451.970105 -25.197635) (xy 451.946264 -25.212548) (xy 451.936104 -25.218644) (xy 451.923404 -25.237948)
			(xy 451.911974 -25.329388) (xy 451.911134 -25.340916) (xy 451.918684 -25.362737) (xy 451.926452 -25.371298)
			(xy 454.48347 -27.928316) (xy 454.490868 -27.93516) (xy 454.509468 -27.942883) (xy 454.519538 -27.943302)
		)
		(stroke
			(width 0)
			(type solid)
		)
		(fill yes)
		(layer "B.Cu")
		(net "GND")
	)
	(gr_poly
		(pts
			(xy 22.2758 -361.310936) (xy 22.28581 -361.310449) (xy 22.304308 -361.30279) (xy 22.31847 -361.288639)
			(xy 22.326141 -361.270146) (xy 22.3266 -361.260136) (xy 22.3266 -355.850444) (xy 22.326166 -355.840378)
			(xy 22.318438 -355.821789) (xy 22.311614 -355.814376) (xy 19.13763 -352.640392) (xy 16.671036 -350.173544)
			(xy 16.522446 -350.024954) (xy 16.515602 -350.017555) (xy 16.507877 -349.998957) (xy 16.50746 -349.988886)
			(xy 16.50746 -342.748362) (xy 16.507029 -342.738296) (xy 16.4993 -342.719705) (xy 16.492474 -342.712294)
			(xy 13.306298 -339.526372) (xy 13.299456 -339.518972) (xy 13.291732 -339.500374) (xy 13.291312 -339.490304)
			(xy 13.291312 -333.685896) (xy 13.290889 -333.675826) (xy 13.283175 -333.657221) (xy 13.276326 -333.649828)
			(xy 12.089384 -332.462886) (xy 12.082531 -332.455491) (xy 12.074788 -332.436892) (xy 12.074398 -332.426818)
			(xy 12.074398 -328.897234) (xy 12.073963 -328.887169) (xy 12.066231 -328.868582) (xy 12.059412 -328.861166)
			(xy 10.43305 -327.234804) (xy 10.425649 -327.227965) (xy 10.407051 -327.220248) (xy 10.396982 -327.219818)
			(xy 8.902954 -327.219818) (xy 8.892888 -327.22025) (xy 8.874297 -327.227978) (xy 8.866886 -327.234804)
			(xy 8.687054 -327.414636) (xy 8.680207 -327.422034) (xy 8.672478 -327.440633) (xy 8.672068 -327.450704)
			(xy 8.672068 -330.012294) (xy 8.672489 -330.022365) (xy 8.680198 -330.040974) (xy 8.687054 -330.048362)
			(xy 10.043922 -331.40523) (xy 10.050772 -331.412626) (xy 10.058508 -331.431225) (xy 10.058908 -331.441298)
			(xy 10.058908 -339.050884) (xy 10.059347 -339.060947) (xy 10.067083 -339.079529) (xy 10.073894 -339.086952)
			(xy 11.154215 -340.16732) (xy 12.445098 -340.16732) (xy 12.447705 -340.104291) (xy 12.458088 -340.04207)
			(xy 12.476088 -339.98161) (xy 12.501427 -339.923841) (xy 12.533718 -339.86965) (xy 12.572464 -339.81987)
			(xy 12.61707 -339.775264) (xy 12.66685 -339.736518) (xy 12.721041 -339.704227) (xy 12.77881 -339.678888)
			(xy 12.83927 -339.660888) (xy 12.901491 -339.650505) (xy 12.96452 -339.647898) (xy 13.027386 -339.653107)
			(xy 13.089126 -339.666053) (xy 13.14879 -339.686536) (xy 13.205462 -339.714241) (xy 13.258272 -339.748744)
			(xy 13.306409 -339.789514) (xy 13.349134 -339.835925) (xy 13.385789 -339.887264) (xy 13.415813 -339.942743)
			(xy 13.438744 -340.00151) (xy 13.45423 -340.062661) (xy 13.462032 -340.125259) (xy 13.462508 -340.1568)
			(xy 13.461737 -340.196316) (xy 13.449489 -340.274394) (xy 13.438124 -340.312248) (xy 13.434044 -340.326628)
			(xy 13.433561 -340.356502) (xy 13.441738 -340.385239) (xy 13.457875 -340.410384) (xy 13.480595 -340.429788)
			(xy 13.507956 -340.441793) (xy 13.537618 -340.445372) (xy 13.552424 -340.443312) (xy 13.574093 -340.439753)
			(xy 13.617842 -340.435935) (xy 13.6398 -340.435692) (xy 13.671341 -340.436168) (xy 13.733939 -340.44397)
			(xy 13.79509 -340.459456) (xy 13.853857 -340.482387) (xy 13.909336 -340.512411) (xy 13.960675 -340.549066)
			(xy 14.007086 -340.591791) (xy 14.047856 -340.639928) (xy 14.082359 -340.692738) (xy 14.110064 -340.74941)
			(xy 14.130547 -340.809074) (xy 14.143493 -340.870814) (xy 14.148702 -340.93368) (xy 14.146095 -340.996709)
			(xy 14.135712 -341.05893) (xy 14.117712 -341.11939) (xy 14.092373 -341.177159) (xy 14.060082 -341.23135)
			(xy 14.021336 -341.28113) (xy 13.97673 -341.325736) (xy 13.92695 -341.364482) (xy 13.872759 -341.396773)
			(xy 13.81499 -341.422112) (xy 13.75453 -341.440112) (xy 13.692309 -341.450495) (xy 13.62928 -341.453102)
			(xy 13.566414 -341.447893) (xy 13.504674 -341.434947) (xy 13.44501 -341.414464) (xy 13.388338 -341.386759)
			(xy 13.335528 -341.352256) (xy 13.287391 -341.311486) (xy 13.244666 -341.265075) (xy 13.208011 -341.213736)
			(xy 13.177987 -341.158257) (xy 13.155056 -341.09949) (xy 13.13957 -341.038339) (xy 13.131768 -340.975741)
			(xy 13.131292 -340.9442) (xy 13.132063 -340.904684) (xy 13.144311 -340.826606) (xy 13.155676 -340.788752)
			(xy 13.159756 -340.774372) (xy 13.160239 -340.744498) (xy 13.152062 -340.715761) (xy 13.135925 -340.690616)
			(xy 13.113205 -340.671212) (xy 13.085844 -340.659207) (xy 13.056182 -340.655628) (xy 13.041376 -340.657688)
			(xy 13.019707 -340.661247) (xy 12.975958 -340.665065) (xy 12.954 -340.665308) (xy 12.922459 -340.664832)
			(xy 12.859861 -340.65703) (xy 12.79871 -340.641544) (xy 12.739943 -340.618613) (xy 12.684464 -340.588589)
			(xy 12.633125 -340.551934) (xy 12.586714 -340.509209) (xy 12.545944 -340.461072) (xy 12.511441 -340.408262)
			(xy 12.483736 -340.35159) (xy 12.463253 -340.291926) (xy 12.450307 -340.230186) (xy 12.445098 -340.16732)
			(xy 11.154215 -340.16732) (xy 15.929356 -344.942668) (xy 15.936197 -344.950068) (xy 15.943913 -344.968667)
			(xy 15.944342 -344.978736) (xy 15.944342 -352.039936) (xy 15.944773 -352.050002) (xy 15.952501 -352.068593)
			(xy 15.959328 -352.076004) (xy 20.381214 -356.49789) (xy 20.388071 -356.505284) (xy 20.395823 -356.523883)
			(xy 20.3962 -356.533958) (xy 20.3962 -356.717092) (xy 20.396662 -356.726726) (xy 20.403837 -356.744615)
			(xy 20.41017 -356.75189) (xy 20.430744 -356.773734) (xy 20.437325 -356.780184) (xy 20.453868 -356.788267)
			(xy 20.463002 -356.789482) (xy 20.495716 -356.793046) (xy 20.559905 -356.80754) (xy 20.62169 -356.830192)
			(xy 20.680036 -356.860624) (xy 20.733971 -356.898327) (xy 20.782592 -356.942672) (xy 20.825087 -356.992917)
			(xy 20.860747 -357.048223) (xy 20.888976 -357.107667) (xy 20.909303 -357.170255) (xy 20.921387 -357.234942)
			(xy 20.923758 -357.267764) (xy 20.92452 -357.282242) (xy 20.940776 -357.305864) (xy 21.051012 -357.353362)
			(xy 21.07946 -357.349298) (xy 21.090636 -357.3399) (xy 21.111341 -357.323092) (xy 21.156557 -357.294815)
			(xy 21.205268 -357.273108) (xy 21.256527 -357.258392) (xy 21.309335 -357.250955) (xy 21.336 -357.250492)
			(xy 21.363251 -357.250978) (xy 21.417199 -357.258734) (xy 21.469494 -357.274089) (xy 21.519071 -357.296731)
			(xy 21.564921 -357.326197) (xy 21.606112 -357.361888) (xy 21.641803 -357.403079) (xy 21.671269 -357.448929)
			(xy 21.693911 -357.498506) (xy 21.709266 -357.550801) (xy 21.717022 -357.604749) (xy 21.717022 -357.659251)
			(xy 21.709266 -357.713199) (xy 21.693911 -357.765494) (xy 21.671269 -357.815071) (xy 21.641803 -357.860921)
			(xy 21.606112 -357.902112) (xy 21.564921 -357.937803) (xy 21.519071 -357.967269) (xy 21.469494 -357.989911)
			(xy 21.417199 -358.005266) (xy 21.363251 -358.013022) (xy 21.336 -358.013508) (xy 21.309291 -358.013061)
			(xy 21.256396 -358.005609) (xy 21.205058 -357.990852) (xy 21.15628 -357.969077) (xy 21.111016 -357.940712)
			(xy 21.070152 -357.906309) (xy 21.034487 -357.866543) (xy 21.004717 -357.82219) (xy 20.981425 -357.774118)
			(xy 20.965067 -357.723267) (xy 20.96008 -357.697024) (xy 20.95754 -357.682546) (xy 20.938744 -357.66121)
			(xy 20.823682 -357.626412) (xy 20.795996 -357.633778) (xy 20.78609 -357.644446) (xy 20.764747 -357.66641)
			(xy 20.717679 -357.705599) (xy 20.666247 -357.738852) (xy 20.611194 -357.76569) (xy 20.553317 -357.785723)
			(xy 20.493454 -357.798663) (xy 20.463002 -357.801926) (xy 20.453884 -357.803195) (xy 20.43735 -357.811263)
			(xy 20.430744 -357.817674) (xy 20.41017 -357.839518) (xy 20.403819 -357.846784) (xy 20.396631 -357.864676)
			(xy 20.3962 -357.874316) (xy 20.3962 -358.775) (xy 20.953982 -358.775) (xy 20.958053 -358.719378)
			(xy 20.970179 -358.664941) (xy 20.990102 -358.61285) (xy 21.017398 -358.564215) (xy 21.051484 -358.520072)
			(xy 21.091633 -358.481363) (xy 21.136991 -358.448912) (xy 21.186591 -358.423411) (xy 21.239375 -358.405404)
			(xy 21.294218 -358.395274) (xy 21.349952 -358.393237) (xy 21.405389 -358.399337) (xy 21.459346 -358.413443)
			(xy 21.510675 -358.435255) (xy 21.558281 -358.464309) (xy 21.601149 -358.499984) (xy 21.638366 -358.541521)
			(xy 21.669139 -358.588034) (xy 21.692811 -358.638531) (xy 21.708879 -358.691938) (xy 21.716999 -358.747114)
			(xy 21.717508 -358.775) (xy 21.716999 -358.802886) (xy 21.708879 -358.858062) (xy 21.692811 -358.911469)
			(xy 21.669139 -358.961966) (xy 21.638366 -359.008479) (xy 21.601149 -359.050016) (xy 21.558281 -359.085691)
			(xy 21.510675 -359.114745) (xy 21.459346 -359.136557) (xy 21.405389 -359.150663) (xy 21.349952 -359.156763)
			(xy 21.294218 -359.154726) (xy 21.239375 -359.144596) (xy 21.186591 -359.126589) (xy 21.136991 -359.101088)
			(xy 21.091633 -359.068637) (xy 21.051484 -359.029928) (xy 21.017398 -358.985785) (xy 20.990102 -358.93715)
			(xy 20.970179 -358.885059) (xy 20.958053 -358.830622) (xy 20.953982 -358.775) (xy 20.3962 -358.775)
			(xy 20.3962 -359.918) (xy 20.953982 -359.918) (xy 20.958053 -359.862378) (xy 20.970179 -359.807941)
			(xy 20.990102 -359.75585) (xy 21.017398 -359.707215) (xy 21.051484 -359.663072) (xy 21.091633 -359.624363)
			(xy 21.136991 -359.591912) (xy 21.186591 -359.566411) (xy 21.239375 -359.548404) (xy 21.294218 -359.538274)
			(xy 21.349952 -359.536237) (xy 21.405389 -359.542337) (xy 21.459346 -359.556443) (xy 21.510675 -359.578255)
			(xy 21.558281 -359.607309) (xy 21.601149 -359.642984) (xy 21.638366 -359.684521) (xy 21.669139 -359.731034)
			(xy 21.692811 -359.781531) (xy 21.708879 -359.834938) (xy 21.716999 -359.890114) (xy 21.717508 -359.918)
			(xy 21.716999 -359.945886) (xy 21.708879 -360.001062) (xy 21.692811 -360.054469) (xy 21.669139 -360.104966)
			(xy 21.638366 -360.151479) (xy 21.601149 -360.193016) (xy 21.558281 -360.228691) (xy 21.510675 -360.257745)
			(xy 21.459346 -360.279557) (xy 21.405389 -360.293663) (xy 21.349952 -360.299763) (xy 21.294218 -360.297726)
			(xy 21.239375 -360.287596) (xy 21.186591 -360.269589) (xy 21.136991 -360.244088) (xy 21.091633 -360.211637)
			(xy 21.051484 -360.172928) (xy 21.017398 -360.128785) (xy 20.990102 -360.08015) (xy 20.970179 -360.028059)
			(xy 20.958053 -359.973622) (xy 20.953982 -359.918) (xy 20.3962 -359.918) (xy 20.3962 -360.72191)
			(xy 20.396625 -360.731979) (xy 20.404342 -360.750581) (xy 20.411186 -360.757978) (xy 20.78101 -361.127802)
			(xy 20.788334 -361.134605) (xy 20.806756 -361.142329) (xy 20.826732 -361.142391) (xy 20.836128 -361.138978)
			(xy 20.93722 -361.09783) (xy 20.954238 -361.07243) (xy 20.954492 -361.05719) (xy 20.955236 -361.030116)
			(xy 20.96343 -360.976581) (xy 20.979112 -360.924742) (xy 21.001968 -360.875641) (xy 21.031538 -360.830267)
			(xy 21.067227 -360.78953) (xy 21.108319 -360.754249) (xy 21.153986 -360.725134) (xy 21.203312 -360.70277)
			(xy 21.255305 -360.687605) (xy 21.30892 -360.679946) (xy 21.336 -360.679492) (xy 21.363251 -360.679978)
			(xy 21.417199 -360.687734) (xy 21.469494 -360.703089) (xy 21.519071 -360.725731) (xy 21.564921 -360.755197)
			(xy 21.606112 -360.790888) (xy 21.641803 -360.832079) (xy 21.671269 -360.877929) (xy 21.693911 -360.927506)
			(xy 21.709266 -360.979801) (xy 21.717022 -361.033749) (xy 21.717508 -361.061) (xy 21.716906 -361.090836)
			(xy 21.707588 -361.149778) (xy 21.698966 -361.178348) (xy 21.695156 -361.190032) (xy 21.698966 -361.213654)
			(xy 21.754592 -361.290108) (xy 21.762243 -361.299417) (xy 21.783709 -361.310291) (xy 21.79574 -361.310936)
		)
		(stroke
			(width 0)
			(type solid)
		)
		(fill yes)
		(layer "B.Cu")
		(net "PVDD18_S5_P1")
	)
	(gr_poly
		(pts
			(xy 81.906872 -182.544212) (xy 81.916937 -182.543776) (xy 81.935523 -182.536045) (xy 81.94294 -182.529226)
			(xy 81.951068 -182.521098) (xy 81.957918 -182.513701) (xy 81.965656 -182.495103) (xy 81.966054 -182.48503)
			(xy 81.966054 -179.402994) (xy 81.965628 -179.392925) (xy 81.957907 -179.374327) (xy 81.951068 -179.366926)
			(xy 81.84134 -179.257198) (xy 81.834228 -179.249832) (xy 81.815432 -179.242212) (xy 80.221836 -179.242212)
			(xy 80.211771 -179.241778) (xy 80.193182 -179.234048) (xy 80.185768 -179.227226) (xy 80.03794 -179.079398)
			(xy 80.03109 -179.072001) (xy 80.023349 -179.053403) (xy 80.022954 -179.04333) (xy 80.022954 -176.74209)
			(xy 80.02338 -176.732022) (xy 80.031103 -176.713425) (xy 80.03794 -176.706022) (xy 80.415892 -176.32807)
			(xy 80.423287 -176.321215) (xy 80.441885 -176.313466) (xy 80.45196 -176.313084) (xy 85.743796 -176.313084)
			(xy 85.753867 -176.313506) (xy 85.772474 -176.321217) (xy 85.779864 -176.32807) (xy 86.510368 -177.058574)
			(xy 86.517206 -177.065975) (xy 86.524919 -177.084574) (xy 86.525354 -177.094642) (xy 86.525354 -182.121556)
			(xy 86.525789 -182.13162) (xy 86.533524 -182.150205) (xy 86.54034 -182.157624) (xy 86.789768 -182.407052)
			(xy 86.797168 -182.413893) (xy 86.815767 -182.42161) (xy 86.825836 -182.422038) (xy 90.238834 -182.422038)
			(xy 90.2489 -182.421607) (xy 90.26749 -182.413877) (xy 90.274902 -182.407052) (xy 90.282268 -182.399686)
			(xy 90.289116 -182.392288) (xy 90.29685 -182.37369) (xy 90.297254 -182.363618) (xy 90.297254 -179.174394)
			(xy 90.296828 -179.164325) (xy 90.289107 -179.145727) (xy 90.282268 -179.138326) (xy 90.17254 -179.028598)
			(xy 90.165428 -179.021232) (xy 90.146632 -179.013612) (xy 88.705436 -179.013612) (xy 88.695371 -179.013178)
			(xy 88.676782 -179.005448) (xy 88.669368 -178.998626) (xy 88.365584 -178.694842) (xy 88.358738 -178.687444)
			(xy 88.351011 -178.668845) (xy 88.350598 -178.658774) (xy 88.350598 -176.65065) (xy 88.35103 -176.640584)
			(xy 88.358757 -176.621992) (xy 88.365584 -176.614582) (xy 88.643968 -176.336198) (xy 88.65137 -176.329362)
			(xy 88.669968 -176.321653) (xy 88.680036 -176.321212) (xy 94.276672 -176.321212) (xy 94.286736 -176.321649)
			(xy 94.30532 -176.329383) (xy 94.31274 -176.336198) (xy 94.955868 -176.979326) (xy 94.962714 -176.986724)
			(xy 94.970444 -177.005323) (xy 94.970854 -177.015394) (xy 94.970854 -182.30723) (xy 94.971284 -182.317297)
			(xy 94.979012 -182.335888) (xy 94.98584 -182.343298) (xy 95.070168 -182.427626) (xy 95.077567 -182.43447)
			(xy 95.096166 -182.442191) (xy 95.106236 -182.442612) (xy 98.641154 -182.442612) (xy 98.651182 -182.4422)
			(xy 98.669717 -182.434539) (xy 98.683907 -182.420366) (xy 98.691589 -182.40184) (xy 98.691954 -182.391812)
			(xy 98.691954 -179.339494) (xy 98.691528 -179.329425) (xy 98.683807 -179.310827) (xy 98.676968 -179.303426)
			(xy 98.55454 -179.180998) (xy 98.547428 -179.173632) (xy 98.528632 -179.166012) (xy 96.912176 -179.166012)
			(xy 96.902107 -179.165585) (xy 96.883508 -179.157866) (xy 96.876108 -179.151026) (xy 96.7232 -178.998118)
			(xy 96.716367 -178.990715) (xy 96.708662 -178.972117) (xy 96.708214 -178.96205) (xy 96.708214 -177.415952)
			(xy 96.710754 -177.413412) (xy 96.710754 -176.621694) (xy 96.71118 -176.611625) (xy 96.718902 -176.593028)
			(xy 96.72574 -176.585626) (xy 97.102168 -176.209198) (xy 97.10957 -176.202362) (xy 97.128168 -176.194653)
			(xy 97.138236 -176.194212) (xy 102.6922 -176.194212) (xy 102.70227 -176.194635) (xy 102.720873 -176.202351)
			(xy 102.728268 -176.209198) (xy 103.248968 -176.729898) (xy 103.249222 -176.730152) (xy 103.558848 -177.039778)
			(xy 103.558848 -177.785268) (xy 103.745792 -177.972212) (xy 107.048554 -177.972212) (xy 107.058582 -177.9718)
			(xy 107.077117 -177.964139) (xy 107.091307 -177.949966) (xy 107.098989 -177.93144) (xy 107.099354 -177.921412)
			(xy 107.099354 -174.792894) (xy 107.098928 -174.782825) (xy 107.091207 -174.764227) (xy 107.084368 -174.756826)
			(xy 106.96194 -174.634398) (xy 106.954828 -174.627032) (xy 106.936032 -174.619412) (xy 105.344976 -174.619412)
			(xy 105.334907 -174.618985) (xy 105.316308 -174.611266) (xy 105.308908 -174.604426) (xy 105.083864 -174.379382)
			(xy 105.077014 -174.371985) (xy 105.069276 -174.353387) (xy 105.068878 -174.343314) (xy 105.068878 -169.953178)
			(xy 105.06845 -169.94311) (xy 105.060728 -169.924513) (xy 105.053892 -169.91711) (xy 103.051864 -167.915082)
			(xy 103.045014 -167.907685) (xy 103.037276 -167.889087) (xy 103.036878 -167.879014) (xy 103.036878 -159.780478)
			(xy 102.362 -159.1056) (xy 82.1944 -159.1056) (xy 81.5086 -158.4198) (xy 60.542678 -158.4198) (xy 59.602878 -159.3596)
			(xy 59.602878 -168.412414) (xy 59.603303 -168.422484) (xy 59.611019 -168.441086) (xy 59.617864 -168.448482)
			(xy 59.84748 -168.678098) (xy 59.854883 -168.684932) (xy 59.873481 -168.692637) (xy 59.883548 -168.693084)
			(xy 65.169796 -168.693084) (xy 65.179866 -168.692661) (xy 65.19847 -168.684946) (xy 65.205864 -168.678098)
			(xy 65.339468 -168.544494) (xy 65.346317 -168.537097) (xy 65.354054 -168.518498) (xy 65.354454 -168.508426)
			(xy 65.354454 -165.610794) (xy 65.354028 -165.600725) (xy 65.346307 -165.582127) (xy 65.339468 -165.574726)
			(xy 65.20434 -165.439598) (xy 65.197228 -165.432232) (xy 65.178432 -165.424612) (xy 63.483236 -165.424612)
			(xy 63.473171 -165.424178) (xy 63.454582 -165.416448) (xy 63.447168 -165.409626) (xy 63.300864 -165.263322)
			(xy 63.294023 -165.255922) (xy 63.286307 -165.237323) (xy 63.285878 -165.227254) (xy 63.285878 -162.745166)
			(xy 63.286307 -162.735098) (xy 63.294027 -162.7165) (xy 63.300864 -162.709098) (xy 63.524892 -162.48507)
			(xy 63.532287 -162.478215) (xy 63.550885 -162.470466) (xy 63.56096 -162.470084) (xy 69.487796 -162.470084)
			(xy 69.497867 -162.470506) (xy 69.516474 -162.478217) (xy 69.523864 -162.48507) (xy 69.874892 -162.836098)
			(xy 69.88174 -162.843496) (xy 69.889476 -162.862094) (xy 69.889878 -162.872166) (xy 69.889878 -168.504559)
			(xy 82.100416 -168.504559) (xy 82.100416 -168.419837) (xy 82.108469 -168.3355) (xy 82.124503 -168.25231)
			(xy 82.148371 -168.17102) (xy 82.179859 -168.092368) (xy 82.218681 -168.017065) (xy 82.264484 -167.945793)
			(xy 82.316855 -167.879197) (xy 82.37532 -167.817882) (xy 82.439348 -167.762401) (xy 82.50836 -167.713258)
			(xy 82.58173 -167.670898) (xy 82.658795 -167.635703) (xy 82.738857 -167.607994) (xy 82.82119 -167.58802)
			(xy 82.905049 -167.575963) (xy 82.989674 -167.571932) (xy 83.074299 -167.575963) (xy 83.158158 -167.58802)
			(xy 83.240491 -167.607994) (xy 83.320553 -167.635703) (xy 83.397618 -167.670898) (xy 83.470988 -167.713258)
			(xy 83.54 -167.762401) (xy 83.604028 -167.817882) (xy 83.662493 -167.879197) (xy 83.714864 -167.945793)
			(xy 83.760667 -168.017065) (xy 83.799489 -168.092368) (xy 83.830977 -168.17102) (xy 83.854845 -168.25231)
			(xy 83.870879 -168.3355) (xy 83.878932 -168.419837) (xy 83.879436 -168.462198) (xy 83.878932 -168.504559)
			(xy 91.498416 -168.504559) (xy 91.498416 -168.419837) (xy 91.506469 -168.3355) (xy 91.522503 -168.25231)
			(xy 91.546371 -168.17102) (xy 91.577859 -168.092368) (xy 91.616681 -168.017065) (xy 91.662484 -167.945793)
			(xy 91.714855 -167.879197) (xy 91.77332 -167.817882) (xy 91.837348 -167.762401) (xy 91.90636 -167.713258)
			(xy 91.97973 -167.670898) (xy 92.056795 -167.635703) (xy 92.136857 -167.607994) (xy 92.21919 -167.58802)
			(xy 92.303049 -167.575963) (xy 92.387674 -167.571932) (xy 92.472299 -167.575963) (xy 92.556158 -167.58802)
			(xy 92.638491 -167.607994) (xy 92.718553 -167.635703) (xy 92.795618 -167.670898) (xy 92.868988 -167.713258)
			(xy 92.938 -167.762401) (xy 93.002028 -167.817882) (xy 93.060493 -167.879197) (xy 93.112864 -167.945793)
			(xy 93.158667 -168.017065) (xy 93.197489 -168.092368) (xy 93.228977 -168.17102) (xy 93.252845 -168.25231)
			(xy 93.268879 -168.3355) (xy 93.276932 -168.419837) (xy 93.277436 -168.462198) (xy 93.276932 -168.504559)
			(xy 93.268879 -168.588896) (xy 93.252845 -168.672086) (xy 93.228977 -168.753376) (xy 93.197489 -168.832028)
			(xy 93.158667 -168.907331) (xy 93.112864 -168.978603) (xy 93.060493 -169.045199) (xy 93.002028 -169.106514)
			(xy 92.938 -169.161995) (xy 92.868988 -169.211138) (xy 92.795618 -169.253498) (xy 92.718553 -169.288693)
			(xy 92.638491 -169.316402) (xy 92.556158 -169.336376) (xy 92.472299 -169.348433) (xy 92.387674 -169.352465)
			(xy 92.303049 -169.348433) (xy 92.21919 -169.336376) (xy 92.136857 -169.316402) (xy 92.056795 -169.288693)
			(xy 91.97973 -169.253498) (xy 91.90636 -169.211138) (xy 91.837348 -169.161995) (xy 91.77332 -169.106514)
			(xy 91.714855 -169.045199) (xy 91.662484 -168.978603) (xy 91.616681 -168.907331) (xy 91.577859 -168.832028)
			(xy 91.546371 -168.753376) (xy 91.522503 -168.672086) (xy 91.506469 -168.588896) (xy 91.498416 -168.504559)
			(xy 83.878932 -168.504559) (xy 83.870879 -168.588896) (xy 83.854845 -168.672086) (xy 83.830977 -168.753376)
			(xy 83.799489 -168.832028) (xy 83.760667 -168.907331) (xy 83.714864 -168.978603) (xy 83.662493 -169.045199)
			(xy 83.604028 -169.106514) (xy 83.54 -169.161995) (xy 83.470988 -169.211138) (xy 83.397618 -169.253498)
			(xy 83.320553 -169.288693) (xy 83.240491 -169.316402) (xy 83.158158 -169.336376) (xy 83.074299 -169.348433)
			(xy 82.989674 -169.352465) (xy 82.905049 -169.348433) (xy 82.82119 -169.336376) (xy 82.738857 -169.316402)
			(xy 82.658795 -169.288693) (xy 82.58173 -169.253498) (xy 82.50836 -169.211138) (xy 82.439348 -169.161995)
			(xy 82.37532 -169.106514) (xy 82.316855 -169.045199) (xy 82.264484 -168.978603) (xy 82.218681 -168.907331)
			(xy 82.179859 -168.832028) (xy 82.148371 -168.753376) (xy 82.124503 -168.672086) (xy 82.108469 -168.588896)
			(xy 82.100416 -168.504559) (xy 69.889878 -168.504559) (xy 69.889878 -177.206402) (xy 69.890301 -177.216473)
			(xy 69.898013 -177.235079) (xy 69.904864 -177.24247) (xy 70.027292 -177.364898) (xy 70.03469 -177.371746)
			(xy 70.053288 -177.379484) (xy 70.06336 -177.379884) (xy 73.500996 -177.379884) (xy 73.511066 -177.379461)
			(xy 73.52967 -177.371746) (xy 73.537064 -177.364898) (xy 73.608692 -177.29327) (xy 73.615535 -177.28587)
			(xy 73.623259 -177.267272) (xy 73.623678 -177.257202) (xy 73.623678 -174.212758) (xy 73.623247 -174.202692)
			(xy 73.615519 -174.1841) (xy 73.608692 -174.17669) (xy 73.4695 -174.037498) (xy 73.462388 -174.030132)
			(xy 73.443592 -174.022512) (xy 72.065388 -174.022512) (xy 72.055318 -174.022087) (xy 72.036716 -174.014371)
			(xy 72.02932 -174.007526) (xy 71.555864 -173.53407) (xy 71.549015 -173.526673) (xy 71.541282 -173.508074)
			(xy 71.540878 -173.498002) (xy 71.540878 -171.127166) (xy 71.541307 -171.117098) (xy 71.549027 -171.0985)
			(xy 71.555864 -171.091098) (xy 71.779892 -170.86707) (xy 71.787287 -170.860215) (xy 71.805885 -170.852466)
			(xy 71.81596 -170.852084) (xy 77.488796 -170.852084) (xy 77.498867 -170.852506) (xy 77.517474 -170.860217)
			(xy 77.524864 -170.86707) (xy 78.256892 -171.599098) (xy 78.26374 -171.606496) (xy 78.271476 -171.625094)
			(xy 78.271878 -171.635166) (xy 78.271878 -182.388002) (xy 78.272301 -182.398073) (xy 78.280013 -182.416679)
			(xy 78.286864 -182.42407) (xy 78.39202 -182.529226) (xy 78.399416 -182.536077) (xy 78.418015 -182.543816)
			(xy 78.428088 -182.544212)
		)
		(stroke
			(width 0)
			(type solid)
		)
		(fill yes)
		(layer "B.Cu")
		(net "SW_P12V_AUX_PVDDCR_CPU0_P1_FLT")
	)
	(gr_poly
		(pts
			(xy 357.04526 -351.585022) (xy 357.04526 -341.727028) (xy 357.04018 -341.705184) (xy 357.006224 -341.632915)
			(xy 356.944649 -341.48557) (xy 356.890438 -341.335359) (xy 356.843725 -341.18265) (xy 356.804623 -341.027818)
			(xy 356.773229 -340.87124) (xy 356.749619 -340.713301) (xy 356.733851 -340.554388) (xy 356.725963 -340.394889)
			(xy 356.725474 -340.315042) (xy 356.725474 -340.314026) (xy 356.725037 -340.303962) (xy 356.717301 -340.28538)
			(xy 356.710488 -340.277958) (xy 356.646226 -340.213696) (xy 356.638823 -340.206861) (xy 356.620225 -340.199155)
			(xy 356.610158 -340.19871) (xy 352.161602 -340.19871) (xy 352.142806 -340.20633) (xy 352.135694 -340.213696)
			(xy 352.06305 -340.28634) (xy 352.056205 -340.293738) (xy 352.048477 -340.312337) (xy 352.048064 -340.322408)
			(xy 352.048064 -343.432384) (xy 352.055684 -343.45118) (xy 352.06305 -343.458292) (xy 352.119692 -343.514934)
			(xy 352.127087 -343.521789) (xy 352.145686 -343.529537) (xy 352.15576 -343.52992) (xy 353.517454 -343.52992)
			(xy 353.527519 -343.530353) (xy 353.546108 -343.538084) (xy 353.553522 -343.544906) (xy 353.859338 -343.850722)
			(xy 353.866188 -343.858119) (xy 353.873924 -343.876718) (xy 353.874324 -343.88679) (xy 353.874324 -345.386406)
			(xy 353.8739 -345.396476) (xy 353.866187 -345.415081) (xy 353.859338 -345.422474) (xy 353.23653 -346.045282)
			(xy 353.229128 -346.052119) (xy 353.21053 -346.059831) (xy 353.200462 -346.060268) (xy 347.860366 -346.060268)
			(xy 347.850299 -346.059838) (xy 347.831707 -346.052111) (xy 347.824298 -346.045282) (xy 347.776546 -345.99753)
			(xy 347.657166 -345.99753) (xy 347.262704 -345.603068) (xy 347.262704 -344.685112) (xy 347.418152 -344.529664)
			(xy 347.418152 -335.444592) (xy 347.410532 -335.425796) (xy 347.403166 -335.418684) (xy 347.289374 -335.304892)
			(xy 347.289374 -335.304384) (xy 347.270324 -335.285334) (xy 347.262923 -335.278496) (xy 347.244324 -335.270784)
			(xy 347.234256 -335.270348) (xy 343.840816 -335.270348) (xy 343.82202 -335.277968) (xy 343.814908 -335.285334)
			(xy 343.787222 -335.31302) (xy 343.780376 -335.320419) (xy 343.772646 -335.339017) (xy 343.772236 -335.349088)
			(xy 343.772236 -338.53374) (xy 343.779856 -338.552536) (xy 343.787222 -338.559648) (xy 343.829386 -338.601812)
			(xy 343.836785 -338.608655) (xy 343.855384 -338.616371) (xy 343.865454 -338.616798) (xy 345.477084 -338.616798)
			(xy 345.487147 -338.617237) (xy 345.50573 -338.624972) (xy 345.513152 -338.631784) (xy 345.727274 -338.845906)
			(xy 345.734122 -338.853304) (xy 345.741859 -338.871902) (xy 345.74226 -338.881974) (xy 345.74226 -341.05215)
			(xy 345.741826 -341.062215) (xy 345.734095 -341.080803) (xy 345.727274 -341.088218) (xy 345.260168 -341.555324)
			(xy 345.252771 -341.562174) (xy 345.234172 -341.569908) (xy 345.2241 -341.57031) (xy 339.413342 -341.57031)
			(xy 339.403276 -341.569877) (xy 339.384686 -341.562149) (xy 339.377274 -341.555324) (xy 339.05317 -341.23122)
			(xy 339.046329 -341.22382) (xy 339.038612 -341.205221) (xy 339.038184 -341.195152) (xy 339.038184 -340.7156)
			(xy 339.036406 -340.701884) (xy 339.034374 -340.694772) (xy 339.030818 -340.68893) (xy 339.027418 -340.682998)
			(xy 339.023668 -340.669855) (xy 339.023452 -340.663022) (xy 339.023452 -335.330292) (xy 339.015832 -335.311496)
			(xy 339.008466 -335.304384) (xy 338.940902 -335.23682) (xy 338.933504 -335.229971) (xy 338.914906 -335.222233)
			(xy 338.904834 -335.221834) (xy 335.50987 -335.221834) (xy 335.491074 -335.229454) (xy 335.483962 -335.23682)
			(xy 335.456022 -335.26476) (xy 335.449183 -335.272161) (xy 335.441467 -335.290759) (xy 335.441036 -335.300828)
			(xy 335.441036 -338.479892) (xy 335.448656 -338.498688) (xy 335.456022 -338.5058) (xy 335.482184 -338.531962)
			(xy 335.489585 -338.538799) (xy 335.508184 -338.546509) (xy 335.518252 -338.546948) (xy 337.067906 -338.546948)
			(xy 337.077975 -338.547374) (xy 337.096573 -338.555095) (xy 337.103974 -338.561934) (xy 337.335622 -338.793582)
			(xy 337.342464 -338.800981) (xy 337.350181 -338.81958) (xy 337.350608 -338.82965) (xy 337.350608 -340.27364)
			(xy 337.347052 -340.277196) (xy 337.347052 -340.967822) (xy 337.346526 -340.977664) (xy 337.338957 -340.995843)
			(xy 337.33232 -341.003128) (xy 337.056984 -341.278464) (xy 337.049748 -341.285182) (xy 337.031542 -341.292782)
			(xy 337.021678 -341.293196) (xy 331.398626 -341.293196) (xy 331.388789 -341.292659) (xy 331.370629 -341.285071)
			(xy 331.36332 -341.278464) (xy 330.681584 -340.596728) (xy 330.674865 -340.589492) (xy 330.667257 -340.571287)
			(xy 330.666852 -340.561422) (xy 330.666852 -335.31937) (xy 330.659232 -335.300574) (xy 330.651866 -335.293462)
			(xy 330.580238 -335.221834) (xy 330.572838 -335.214994) (xy 330.554239 -335.207276) (xy 330.54417 -335.206848)
			(xy 327.176384 -335.206848) (xy 327.157588 -335.214468) (xy 327.150476 -335.221834) (xy 327.104502 -335.267808)
			(xy 327.104502 -335.268062) (xy 327.098406 -335.274158) (xy 327.09104 -335.28127) (xy 327.08342 -335.300066)
			(xy 327.08342 -338.481162) (xy 327.09104 -338.499958) (xy 327.098406 -338.50707) (xy 327.146666 -338.55533)
			(xy 327.154065 -338.562174) (xy 327.172664 -338.569895) (xy 327.182734 -338.570316) (xy 328.78014 -338.570316)
			(xy 328.790207 -338.570747) (xy 328.808799 -338.578473) (xy 328.816208 -338.585302) (xy 328.978006 -338.7471)
			(xy 328.984852 -338.754499) (xy 328.992585 -338.773097) (xy 328.992992 -338.783168) (xy 328.992992 -340.198456)
			(xy 328.990452 -340.200996) (xy 328.990452 -340.993222) (xy 328.989926 -341.003064) (xy 328.982357 -341.021243)
			(xy 328.97572 -341.028528) (xy 328.598784 -341.405464) (xy 328.591548 -341.412182) (xy 328.573342 -341.419782)
			(xy 328.563478 -341.420196) (xy 323.328284 -341.420196) (xy 323.318442 -341.41967) (xy 323.300268 -341.412096)
			(xy 323.292978 -341.405464) (xy 322.419472 -340.531958) (xy 322.412765 -340.524718) (xy 322.405185 -340.506513)
			(xy 322.40474 -340.496652) (xy 322.40474 -335.399888) (xy 322.39712 -335.381092) (xy 322.389754 -335.37398)
			(xy 322.256658 -335.240884) (xy 322.249261 -335.234035) (xy 322.230662 -335.226302) (xy 322.22059 -335.225898)
			(xy 318.820038 -335.225898) (xy 318.801242 -335.233518) (xy 318.79413 -335.240884) (xy 318.742822 -335.292192)
			(xy 318.735972 -335.299589) (xy 318.728231 -335.318187) (xy 318.727836 -335.32826) (xy 318.727836 -338.497418)
			(xy 318.735456 -338.516214) (xy 318.742822 -338.523326) (xy 318.788542 -338.569046) (xy 318.79594 -338.575892)
			(xy 318.814539 -338.583619) (xy 318.82461 -338.584032) (xy 320.495422 -338.584032) (xy 320.50549 -338.58446)
			(xy 320.524085 -338.592183) (xy 320.53149 -338.599018) (xy 320.669158 -338.736686) (xy 320.675996 -338.744087)
			(xy 320.683705 -338.762686) (xy 320.684144 -338.772754) (xy 320.684144 -342.60663) (xy 320.691764 -342.625426)
			(xy 320.69913 -342.632538) (xy 321.476878 -343.410286) (xy 321.483713 -343.417688) (xy 321.49142 -343.436287)
			(xy 321.491864 -343.446354) (xy 321.491864 -346.248736) (xy 321.491434 -346.258803) (xy 321.483706 -346.277394)
			(xy 321.476878 -346.284804) (xy 319.596516 -348.165166) (xy 319.589115 -348.172003) (xy 319.570516 -348.179712)
			(xy 319.560448 -348.180152) (xy 314.343542 -348.180152) (xy 313.1566 -346.99321) (xy 309.164228 -346.99321)
			(xy 309.154164 -346.993647) (xy 309.135579 -347.00138) (xy 309.12816 -347.008196) (xy 309.093108 -347.043248)
			(xy 309.086268 -347.050649) (xy 309.07855 -347.069247) (xy 309.078122 -347.079316) (xy 309.078122 -350.23933)
			(xy 309.078551 -350.249397) (xy 309.086276 -350.267992) (xy 309.093108 -350.275398) (xy 309.099966 -350.282256)
			(xy 309.118508 -350.289876) (xy 310.39689 -350.289876) (xy 310.406962 -350.290297) (xy 310.425571 -350.298006)
			(xy 310.432958 -350.304862) (xy 311.664096 -351.536) (xy 315.548518 -351.536) (xy 315.558587 -351.536427)
			(xy 315.577186 -351.544146) (xy 315.584586 -351.550986) (xy 316.007693 -351.974093) (xy 327.061826 -351.974093)
			(xy 327.061826 -351.889371) (xy 327.069879 -351.805034) (xy 327.085913 -351.721844) (xy 327.109781 -351.640554)
			(xy 327.141269 -351.561902) (xy 327.180091 -351.486599) (xy 327.225894 -351.415327) (xy 327.278265 -351.348731)
			(xy 327.33673 -351.287416) (xy 327.400758 -351.231935) (xy 327.46977 -351.182792) (xy 327.54314 -351.140432)
			(xy 327.620205 -351.105237) (xy 327.700267 -351.077528) (xy 327.7826 -351.057554) (xy 327.866459 -351.045497)
			(xy 327.951084 -351.041466) (xy 328.035709 -351.045497) (xy 328.119568 -351.057554) (xy 328.201901 -351.077528)
			(xy 328.281963 -351.105237) (xy 328.359028 -351.140432) (xy 328.432398 -351.182792) (xy 328.50141 -351.231935)
			(xy 328.565438 -351.287416) (xy 328.623903 -351.348731) (xy 328.676274 -351.415327) (xy 328.722077 -351.486599)
			(xy 328.760899 -351.561902) (xy 328.792387 -351.640554) (xy 328.816255 -351.721844) (xy 328.832289 -351.805034)
			(xy 328.840342 -351.889371) (xy 328.840846 -351.931732) (xy 328.840342 -351.974093) (xy 334.521806 -351.974093)
			(xy 334.521806 -351.889371) (xy 334.529859 -351.805034) (xy 334.545893 -351.721844) (xy 334.569761 -351.640554)
			(xy 334.601249 -351.561902) (xy 334.640071 -351.486599) (xy 334.685874 -351.415327) (xy 334.738245 -351.348731)
			(xy 334.79671 -351.287416) (xy 334.860738 -351.231935) (xy 334.92975 -351.182792) (xy 335.00312 -351.140432)
			(xy 335.080185 -351.105237) (xy 335.160247 -351.077528) (xy 335.24258 -351.057554) (xy 335.326439 -351.045497)
			(xy 335.411064 -351.041466) (xy 335.495689 -351.045497) (xy 335.579548 -351.057554) (xy 335.661881 -351.077528)
			(xy 335.741943 -351.105237) (xy 335.819008 -351.140432) (xy 335.892378 -351.182792) (xy 335.96139 -351.231935)
			(xy 336.025418 -351.287416) (xy 336.083883 -351.348731) (xy 336.136254 -351.415327) (xy 336.182057 -351.486599)
			(xy 336.220879 -351.561902) (xy 336.252367 -351.640554) (xy 336.276235 -351.721844) (xy 336.292269 -351.805034)
			(xy 336.300322 -351.889371) (xy 336.300826 -351.931732) (xy 336.300322 -351.974093) (xy 336.292269 -352.05843)
			(xy 336.276235 -352.14162) (xy 336.252367 -352.22291) (xy 336.220879 -352.301562) (xy 336.182057 -352.376865)
			(xy 336.136254 -352.448137) (xy 336.083883 -352.514733) (xy 336.025418 -352.576048) (xy 335.96139 -352.631529)
			(xy 335.892378 -352.680672) (xy 335.819008 -352.723032) (xy 335.741943 -352.758227) (xy 335.661881 -352.785936)
			(xy 335.579548 -352.80591) (xy 335.495689 -352.817967) (xy 335.411064 -352.821999) (xy 335.326439 -352.817967)
			(xy 335.24258 -352.80591) (xy 335.160247 -352.785936) (xy 335.080185 -352.758227) (xy 335.00312 -352.723032)
			(xy 334.92975 -352.680672) (xy 334.860738 -352.631529) (xy 334.79671 -352.576048) (xy 334.738245 -352.514733)
			(xy 334.685874 -352.448137) (xy 334.640071 -352.376865) (xy 334.601249 -352.301562) (xy 334.569761 -352.22291)
			(xy 334.545893 -352.14162) (xy 334.529859 -352.05843) (xy 334.521806 -351.974093) (xy 328.840342 -351.974093)
			(xy 328.832289 -352.05843) (xy 328.816255 -352.14162) (xy 328.792387 -352.22291) (xy 328.760899 -352.301562)
			(xy 328.722077 -352.376865) (xy 328.676274 -352.448137) (xy 328.623903 -352.514733) (xy 328.565438 -352.576048)
			(xy 328.50141 -352.631529) (xy 328.432398 -352.680672) (xy 328.359028 -352.723032) (xy 328.281963 -352.758227)
			(xy 328.201901 -352.785936) (xy 328.119568 -352.80591) (xy 328.035709 -352.817967) (xy 327.951084 -352.821999)
			(xy 327.866459 -352.817967) (xy 327.7826 -352.80591) (xy 327.700267 -352.785936) (xy 327.620205 -352.758227)
			(xy 327.54314 -352.723032) (xy 327.46977 -352.680672) (xy 327.400758 -352.631529) (xy 327.33673 -352.576048)
			(xy 327.278265 -352.514733) (xy 327.225894 -352.448137) (xy 327.180091 -352.376865) (xy 327.141269 -352.301562)
			(xy 327.109781 -352.22291) (xy 327.085913 -352.14162) (xy 327.069879 -352.05843) (xy 327.061826 -351.974093)
			(xy 316.007693 -351.974093) (xy 320.1416 -356.108) (xy 320.148999 -356.114847) (xy 320.167596 -356.122581)
			(xy 320.177668 -356.122986) (xy 352.507296 -356.122986)
		)
		(stroke
			(width 0)
			(type solid)
		)
		(fill yes)
		(layer "B.Cu")
		(net "SW_P12V_AUX_PVDDCR_CPU1_P0_FLT")
	)
	(gr_poly
		(pts
			(xy 353.313492 -360.429556) (xy 364.240064 -360.429556) (xy 366.157002 -358.512618) (xy 366.157002 -355.300026)
			(xy 366.157002 -335.402428) (xy 363.681264 -332.92669) (xy 362.021882 -331.267308) (xy 358.697276 -331.267308)
			(xy 358.413304 -331.55128) (xy 357.7082 -331.55128)
			(arc
				(start 357.705152 -331.554328)
				(mid 357.688969 -331.565234)
				(end 357.669846 -331.56906)
			)
			(arc
				(start 348.216982 -331.56906)
				(mid 348.197887 -331.565168)
				(end 348.181676 -331.554328)
			)
			(arc
				(start 348.178628 -331.55128)
				(mid 348.162445 -331.540374)
				(end 348.143322 -331.536548)
			)
			(arc
				(start 348.125542 -331.536548)
				(mid 348.106447 -331.532656)
				(end 348.090236 -331.521816)
			)
			(arc
				(start 347.641164 -331.072744)
				(mid 347.630258 -331.056561)
				(end 347.626432 -331.037438)
			)
			(arc
				(start 347.626432 -327.274936)
				(mid 347.62254 -327.255841)
				(end 347.6117 -327.23963)
			)
			(arc
				(start 347.509592 -327.137522)
				(mid 347.493409 -327.126616)
				(end 347.474286 -327.12279)
			)
			(arc
				(start 346.148406 -327.12279)
				(mid 346.129311 -327.118898)
				(end 346.1131 -327.108058)
			)
			(arc
				(start 345.605354 -326.600058)
				(mid 345.589171 -326.589152)
				(end 345.570048 -326.585326)
			)
			(xy 317.836804 -326.585326) (xy 316.372748 -328.049636) (xy 316.372748 -331.409548) (xy 312.978546 -334.80375)
			(xy 312.978546 -338.190078) (xy 312.715656 -338.452968) (xy 264.554716 -338.452968) (xy 263.374378 -338.452968)
			(xy 263.087866 -338.73948) (xy 263.087866 -350.824292) (xy 263.31291 -351.049336) (xy 263.943846 -351.680272)
			(xy 270.77289 -351.680272) (xy 270.93291 -351.520252) (xy 270.93291 -347.227652) (xy 271.52219 -346.638372)
			(xy 273.38401 -346.638372) (xy 273.61261 -346.866972) (xy 273.61261 -348.807532) (xy 273.88693 -349.081852)
			(xy 275.30171 -349.081852) (xy 275.55063 -348.832932) (xy 275.55063 -346.826332) (xy 275.73859 -346.638372)
			(xy 281.64917 -346.638372) (xy 281.88539 -346.874592) (xy 281.88539 -348.840552) (xy 282.12669 -349.081852)
			(xy 283.58211 -349.081852) (xy 283.83103 -348.832932) (xy 283.83103 -346.818712) (xy 284.01137 -346.638372)
			(xy 289.98799 -346.638372) (xy 290.21151 -346.861892) (xy 290.21151 -348.812612) (xy 290.48075 -349.081852)
			(xy 291.88791 -349.081852) (xy 292.13683 -348.832932) (xy 292.13683 -346.775532) (xy 292.27399 -346.638372)
			(xy 298.39031 -346.638372) (xy 298.59097 -346.839032) (xy 298.59097 -348.845632) (xy 298.82719 -349.081852)
			(xy 300.24451 -349.081852) (xy 300.49343 -348.832932) (xy 300.49343 -346.762832) (xy 300.61789 -346.638372)
			(xy 306.49545 -346.638372) (xy 306.90185 -347.044772) (xy 306.90185 -347.426026)
			(arc
				(start 306.910486 -347.434662)
				(mid 306.921597 -347.451196)
				(end 306.925472 -347.47073)
			)
			(xy 306.925472 -348.820994) (xy 307.19141 -349.086932) (xy 308.60365 -349.086932) (xy 308.775354 -348.915228)
			(xy 308.775354 -346.977208) (xy 309.11927 -346.633292) (xy 315.8617 -346.633292) (xy 316.95898 -347.730572)
			(xy 319.426844 -347.730572) (xy 320.981324 -346.176092) (xy 320.981324 -343.514172) (xy 319.165224 -341.698072)
			(xy 318.527684 -341.698072) (xy 317.892684 -341.063072) (xy 314.965334 -341.063072) (xy 314.556394 -340.654132)
			(xy 314.556394 -338.902802) (xy 314.21578 -338.562188) (xy 314.21578 -338.4169) (xy 314.21578 -335.608168)
			(xy 314.945522 -334.878426)
			(arc
				(start 316.294516 -334.878426)
				(mid 316.313611 -334.882318)
				(end 316.329822 -334.893158)
			)
			(arc
				(start 316.612778 -335.176114)
				(mid 316.623684 -335.192297)
				(end 316.62751 -335.21142)
			)
			(xy 316.62751 -337.180428) (xy 316.629034 -337.183984) (xy 316.695836 -337.250786) (xy 316.699392 -337.25231)
			(arc
				(start 318.374522 -337.25231)
				(mid 318.384239 -337.251357)
				(end 318.393572 -337.2485)
			)
			(arc
				(start 318.411352 -337.241134)
				(mid 318.420015 -337.23647)
				(end 318.427608 -337.230212)
			)
			(xy 318.466978 -337.190842) (xy 318.473328 -337.182968) (xy 318.473328 -335.201768) (xy 318.477392 -335.197958)
			(arc
				(start 318.477392 -335.036414)
				(mid 318.481284 -335.017319)
				(end 318.492124 -335.001108)
			)
			(arc
				(start 318.570864 -334.922368)
				(mid 318.587047 -334.911462)
				(end 318.60617 -334.907636)
			)
			(xy 321.713352 -334.907636) (xy 321.713352 -334.912462)
			(arc
				(start 324.641972 -334.912462)
				(mid 324.661067 -334.916354)
				(end 324.677278 -334.927194)
			)
			(arc
				(start 324.928738 -335.178654)
				(mid 324.939644 -335.194837)
				(end 324.94347 -335.21396)
			)
			(arc
				(start 324.94347 -337.11515)
				(mid 324.947362 -337.134245)
				(end 324.958202 -337.150456)
			)
			(arc
				(start 325.047864 -337.240118)
				(mid 325.064047 -337.251024)
				(end 325.08317 -337.25485)
			)
			(arc
				(start 326.690482 -337.25485)
				(mid 326.700199 -337.253897)
				(end 326.709532 -337.25104)
			)
			(arc
				(start 326.727312 -337.243674)
				(mid 326.735975 -337.23901)
				(end 326.743568 -337.232752)
			)
			(xy 326.782938 -337.193382)
			(arc
				(start 326.7837 -337.19262)
				(mid 326.789155 -337.1858)
				(end 326.793352 -337.178142)
			)
			(arc
				(start 326.793352 -335.23936)
				(mid 326.797244 -335.220265)
				(end 326.808084 -335.204054)
			)
			(xy 327.028556 -334.983582) (xy 327.029064 -334.983582)
			(arc
				(start 327.04532 -334.967072)
				(mid 327.061503 -334.956166)
				(end 327.080626 -334.95234)
			)
			(arc
				(start 330.544932 -334.95234)
				(mid 330.608454 -334.959255)
				(end 330.669138 -334.979264)
			)
			(xy 330.679044 -334.983582)
			(arc
				(start 333.034386 -334.983582)
				(mid 333.053481 -334.987474)
				(end 333.069692 -334.998314)
			)
			(arc
				(start 333.235554 -335.164176)
				(mid 333.24646 -335.180359)
				(end 333.250286 -335.199482)
			)
			(xy 333.250286 -335.553304)
			(arc
				(start 333.250794 -335.557114)
				(mid 333.255127 -335.594724)
				(end 333.256636 -335.632552)
			)
			(arc
				(start 333.256636 -335.63306)
				(mid 333.255113 -335.670887)
				(end 333.250794 -335.708498)
			)
			(xy 333.250286 -335.712308) (xy 333.250286 -336.353404)
			(arc
				(start 333.250794 -336.357214)
				(mid 333.255137 -336.394951)
				(end 333.256636 -336.432906)
			)
			(arc
				(start 333.256636 -337.056222)
				(mid 333.260528 -337.075317)
				(end 333.271368 -337.091528)
			)
			(arc
				(start 333.40548 -337.22564)
				(mid 333.421663 -337.236546)
				(end 333.440786 -337.240372)
			)
			(arc
				(start 334.997298 -337.240372)
				(mid 335.007015 -337.239419)
				(end 335.016348 -337.236562)
			)
			(arc
				(start 335.034128 -337.229196)
				(mid 335.042791 -337.224532)
				(end 335.050384 -337.218274)
			)
			(xy 335.089754 -337.178904)
			(arc
				(start 335.090516 -337.178142)
				(mid 335.095971 -337.171322)
				(end 335.100168 -337.163664)
			)
			(arc
				(start 335.100168 -335.23936)
				(mid 335.10406 -335.220265)
				(end 335.1149 -335.204054)
			)
			(arc
				(start 335.322672 -334.996282)
				(mid 335.338855 -334.985376)
				(end 335.357978 -334.98155)
			)
			(xy 335.3689 -334.98155) (xy 335.387188 -334.97393) (xy 335.393538 -334.96758)
			(arc
				(start 338.90585 -334.96758)
				(mid 338.948436 -334.970575)
				(end 338.990178 -334.979518)
			)
			(xy 338.997036 -334.98155)
			(arc
				(start 341.313008 -334.98155)
				(mid 341.332103 -334.985442)
				(end 341.348314 -334.996282)
			)
			(arc
				(start 341.592154 -335.240376)
				(mid 341.60306 -335.256559)
				(end 341.606886 -335.275682)
			)
			(arc
				(start 341.606886 -337.126072)
				(mid 341.610778 -337.145167)
				(end 341.621618 -337.161378)
			)
			(arc
				(start 341.76208 -337.30184)
				(mid 341.778263 -337.312746)
				(end 341.797386 -337.316572)
			)
			(arc
				(start 343.353898 -337.316572)
				(mid 343.363615 -337.315619)
				(end 343.372948 -337.312762)
			)
			(arc
				(start 343.390728 -337.305396)
				(mid 343.399391 -337.300732)
				(end 343.406984 -337.294474)
			)
			(xy 343.446354 -337.255104)
			(arc
				(start 343.447116 -337.254342)
				(mid 343.452571 -337.247522)
				(end 343.456768 -337.239864)
			)
			(arc
				(start 343.456768 -335.315306)
				(mid 343.460591 -335.296377)
				(end 343.471246 -335.280254)
			)
			(xy 343.517728 -335.233772) (xy 343.517728 -335.222596)
			(arc
				(start 343.709752 -335.030572)
				(mid 343.725935 -335.019666)
				(end 343.745058 -335.01584)
			)
			(arc
				(start 347.33992 -335.01584)
				(mid 347.35918 -335.019801)
				(end 347.37548 -335.030826)
			)
			(xy 347.378274 -335.03362)
			(arc
				(start 347.420946 -335.03362)
				(mid 347.440041 -335.037512)
				(end 347.456252 -335.048352)
			)
			(arc
				(start 347.758258 -335.350358)
				(mid 347.769164 -335.366541)
				(end 347.77299 -335.385664)
			)
			(arc
				(start 347.77299 -340.074758)
				(mid 347.776882 -340.093853)
				(end 347.787722 -340.110064)
			)
			(arc
				(start 347.822266 -340.144608)
				(mid 347.838449 -340.155514)
				(end 347.857572 -340.15934)
			)
			(xy 348.062296 -340.15934) (xy 348.074742 -340.156038)
			(arc
				(start 348.08033 -340.152736)
				(mid 348.2024 -340.1024)
				(end 348.333314 -340.085172)
			)
			(arc
				(start 349.355156 -340.085172)
				(mid 349.714725 -340.234111)
				(end 349.863664 -340.59368)
			)
			(arc
				(start 349.863664 -340.59368)
				(mid 349.8616 -340.638945)
				(end 349.855536 -340.68385)
			)
			(xy 349.85071 -340.709504) (xy 349.857314 -340.716108) (xy 349.857314 -341.314278)
			(arc
				(start 349.857822 -341.318088)
				(mid 349.862165 -341.355825)
				(end 349.863664 -341.39378)
			)
			(arc
				(start 349.863664 -342.017096)
				(mid 349.867556 -342.036191)
				(end 349.878396 -342.052402)
			)
			(arc
				(start 350.169988 -342.344248)
				(mid 350.250748 -342.449385)
				(end 350.30156 -342.571832)
			)
			(arc
				(start 350.30156 -342.572086)
				(mid 350.306511 -342.583933)
				(end 350.31426 -342.594184)
			)
			(arc
				(start 350.319848 -342.599772)
				(mid 350.336031 -342.610678)
				(end 350.355154 -342.614504)
			)
			(xy 350.884236 -342.614504) (xy 350.901 -342.61425)
			(arc
				(start 350.901254 -342.61425)
				(mid 351.095769 -342.652924)
				(end 351.260664 -342.763094)
			)
			(xy 351.267522 -342.769952) (xy 351.28581 -342.777572)
			(arc
				(start 351.604326 -342.777572)
				(mid 351.614043 -342.776619)
				(end 351.623376 -342.773762)
			)
			(arc
				(start 351.641156 -342.766396)
				(mid 351.649819 -342.761732)
				(end 351.657412 -342.755474)
			)
			(xy 351.696782 -342.716104)
			(arc
				(start 351.697544 -342.715342)
				(mid 351.702999 -342.708522)
				(end 351.707196 -342.700864)
			)
			(arc
				(start 351.707196 -340.561422)
				(mid 351.711019 -340.542493)
				(end 351.721674 -340.52637)
			)
			(arc
				(start 351.779078 -340.46922)
				(mid 351.789799 -340.453125)
				(end 351.793556 -340.434168)
			)
			(arc
				(start 351.793556 -340.21649)
				(mid 351.797448 -340.197395)
				(end 351.808288 -340.181184)
			)
			(arc
				(start 352.030538 -339.959188)
				(mid 352.046721 -339.948282)
				(end 352.065844 -339.944456)
			)
			(arc
				(start 356.716076 -339.944456)
				(mid 356.735171 -339.948348)
				(end 356.751382 -339.959188)
			)
			(xy 357.052118 -340.259924) (xy 357.074216 -340.259924) (xy 357.074216 -340.270084) (xy 357.435404 -340.631272)
			(xy 357.435404 -351.871534) (xy 352.581972 -356.724966) (xy 349.861886 -356.724966) (xy 346.532962 -356.724966)
			(xy 346.286582 -356.971346) (xy 346.286582 -361.037124) (xy 346.45219 -361.202732) (xy 352.540316 -361.202732)
		)
		(stroke
			(width 0)
			(type solid)
		)
		(fill yes)
		(layer "B.Cu")
		(net "GND")
	)
	(gr_poly
		(pts
			(xy 256.266188 -319.937638) (xy 256.276258 -319.937215) (xy 256.29486 -319.929497) (xy 256.302256 -319.922652)
			(xy 256.894076 -319.330832) (xy 256.900914 -319.323431) (xy 256.908628 -319.304832) (xy 256.909062 -319.294764)
			(xy 256.909062 -265.399774) (xy 256.908633 -265.389707) (xy 256.900908 -265.371113) (xy 256.894076 -265.363706)
			(xy 256.19837 -264.668) (xy 256.19097 -264.661158) (xy 256.172372 -264.653435) (xy 256.162302 -264.653014)
			(xy 233.53649 -264.653014) (xy 233.526421 -264.653439) (xy 233.50782 -264.661158) (xy 233.500422 -264.668)
			(xy 231.535478 -266.632944) (xy 231.52863 -266.640341) (xy 231.520899 -266.65894) (xy 231.520492 -266.669012)
			(xy 231.520492 -272.300954) (xy 231.52227 -272.302732) (xy 231.526636 -272.202017) (xy 231.542299 -272.001008)
			(xy 231.565845 -271.800771) (xy 231.597238 -271.601612) (xy 231.63643 -271.403841) (xy 231.683361 -271.207761)
			(xy 231.737957 -271.013676) (xy 231.800134 -270.821886) (xy 231.869797 -270.632686) (xy 231.946839 -270.446368)
			(xy 232.031139 -270.26322) (xy 232.122568 -270.083525) (xy 232.220985 -269.90756) (xy 232.326239 -269.735597)
			(xy 232.438165 -269.567901) (xy 232.556593 -269.40473) (xy 232.681338 -269.246338) (xy 232.812209 -269.092967)
			(xy 232.949003 -268.944856) (xy 233.091509 -268.802232) (xy 233.239508 -268.665316) (xy 233.39277 -268.534319)
			(xy 233.55106 -268.409443) (xy 233.714133 -268.290882) (xy 233.881737 -268.178817) (xy 234.053614 -268.073422)
			(xy 234.229498 -267.97486) (xy 234.409117 -267.883283) (xy 234.592196 -267.798832) (xy 234.77845 -267.721637)
			(xy 234.967592 -267.651818) (xy 235.159331 -267.589483) (xy 235.353371 -267.534727) (xy 235.549412 -267.487635)
			(xy 235.747151 -267.44828) (xy 235.946284 -267.416723) (xy 236.146502 -267.393012) (xy 236.347497 -267.377184)
			(xy 236.548959 -267.369263) (xy 236.649768 -267.368782) (xy 236.750525 -267.36927) (xy 236.951883 -267.37718)
			(xy 237.152776 -267.392989) (xy 237.352893 -267.416673) (xy 237.551926 -267.448196) (xy 237.749567 -267.487508)
			(xy 237.945514 -267.534549) (xy 238.139462 -267.589247) (xy 238.331113 -267.651517) (xy 238.520172 -267.721264)
			(xy 238.706346 -267.798379) (xy 238.88935 -267.882743) (xy 239.068901 -267.974228) (xy 239.244721 -268.072691)
			(xy 239.41654 -268.177981) (xy 239.584093 -268.289935) (xy 239.747122 -268.408381) (xy 239.905374 -268.533136)
			(xy 240.058607 -268.664008) (xy 240.206584 -268.800795) (xy 240.349076 -268.943286) (xy 240.485864 -269.091262)
			(xy 240.616737 -269.244493) (xy 240.741494 -269.402745) (xy 240.859941 -269.565772) (xy 240.971897 -269.733325)
			(xy 241.077188 -269.905143) (xy 241.175652 -270.080962) (xy 241.267138 -270.260512) (xy 241.351504 -270.443515)
			(xy 241.428621 -270.629689) (xy 241.498369 -270.818747) (xy 241.56064 -271.010398) (xy 241.61534 -271.204346)
			(xy 241.662383 -271.400291) (xy 241.701697 -271.597933) (xy 241.733221 -271.796966) (xy 241.756907 -271.997082)
			(xy 241.772718 -272.197975) (xy 241.78063 -272.399333) (xy 241.781076 -272.50009) (xy 241.780585 -272.600645)
			(xy 241.772706 -272.801601) (xy 241.756959 -273.002094) (xy 241.733369 -273.201816) (xy 241.701971 -273.400461)
			(xy 241.662815 -273.597722) (xy 241.63728 -273.704304) (xy 248.739152 -273.704304) (xy 248.739152 -269.271496)
			(xy 248.739561 -269.261425) (xy 248.747292 -269.242826) (xy 248.754138 -269.235428) (xy 249.403616 -268.58595)
			(xy 249.411022 -268.579117) (xy 249.429616 -268.571392) (xy 249.439684 -268.570964) (xy 252.40742 -268.570964)
			(xy 252.417493 -268.571362) (xy 252.436091 -268.5791) (xy 252.443488 -268.58595) (xy 253.092966 -269.235428)
			(xy 253.099806 -269.242828) (xy 253.107527 -269.261427) (xy 253.107952 -269.271496) (xy 253.107952 -273.45767)
			(xy 253.107524 -273.467739) (xy 253.099806 -273.486338) (xy 253.092966 -273.493738) (xy 252.456442 -274.130008)
			(xy 252.449612 -274.137416) (xy 252.441885 -274.156009) (xy 252.441456 -274.166076) (xy 252.441456 -274.2438)
			(xy 252.441079 -274.253827) (xy 252.433401 -274.272352) (xy 252.419215 -274.286526) (xy 252.400683 -274.294188)
			(xy 252.390656 -274.2946) (xy 249.329702 -274.2946) (xy 249.319629 -274.2942) (xy 249.30103 -274.286465)
			(xy 249.293634 -274.279614) (xy 248.754138 -273.740372) (xy 248.747299 -273.732971) (xy 248.739577 -273.714373)
			(xy 248.739152 -273.704304) (xy 241.63728 -273.704304) (xy 241.615959 -273.793298) (xy 241.561477 -273.986888)
			(xy 241.499452 -274.178195) (xy 241.429978 -274.366924) (xy 241.353164 -274.552787) (xy 241.269126 -274.735497)
			(xy 241.177994 -274.914774) (xy 241.079907 -275.090343) (xy 240.975017 -275.261934) (xy 240.863484 -275.429284)
			(xy 240.74548 -275.592135) (xy 240.621186 -275.750237) (xy 240.490793 -275.903348) (xy 240.354501 -276.051233)
			(xy 240.212519 -276.193664) (xy 240.065066 -276.330422) (xy 239.912368 -276.461299) (xy 239.754659 -276.586092)
			(xy 239.592181 -276.704609) (xy 239.425185 -276.81667) (xy 239.253926 -276.922102) (xy 239.078668 -277.020743)
			(xy 238.89968 -277.112441) (xy 238.717236 -277.197055) (xy 238.531617 -277.274457) (xy 238.343108 -277.344526)
			(xy 238.151998 -277.407156) (xy 237.958581 -277.462249) (xy 237.763154 -277.509722) (xy 237.566017 -277.549502)
			(xy 237.367473 -277.581527) (xy 237.167827 -277.605748) (xy 236.967384 -277.622128) (xy 236.866938 -277.626826)
			(xy 236.87278 -277.653242) (xy 238.72571 -279.506172) (xy 238.732555 -279.51357) (xy 238.740277 -279.532169)
			(xy 238.740696 -279.54224) (xy 238.740696 -287.53308) (xy 238.741134 -287.543144) (xy 238.748868 -287.561727)
			(xy 238.755682 -287.569148) (xy 239.143286 -287.957006) (xy 239.15069 -287.963838) (xy 239.169288 -287.97154)
			(xy 239.179354 -287.971992) (xy 240.105692 -287.971992) (xy 240.121212 -287.97211) (xy 240.152125 -287.974911)
			(xy 240.167414 -287.97758) (xy 240.17224 -287.978596) (xy 241.704368 -287.978596) (xy 241.714433 -287.979032)
			(xy 241.73302 -287.986763) (xy 241.740436 -287.993582) (xy 243.800376 -290.053522) (xy 243.807222 -290.060921)
			(xy 243.814952 -290.079519) (xy 243.815362 -290.08959) (xy 243.815362 -290.980297) (xy 246.674125 -290.980297)
			(xy 246.674125 -290.819403) (xy 246.682145 -290.65871) (xy 246.698165 -290.498617) (xy 246.722145 -290.33952)
			(xy 246.754025 -290.181817) (xy 246.793727 -290.025899) (xy 246.841151 -289.872154) (xy 246.89618 -289.720964)
			(xy 246.958676 -289.572705) (xy 247.028485 -289.427745) (xy 247.105433 -289.286445) (xy 247.189328 -289.149157)
			(xy 247.279963 -289.01622) (xy 247.377111 -288.887967) (xy 247.480531 -288.764716) (xy 247.589966 -288.646773)
			(xy 247.705144 -288.534431) (xy 247.825779 -288.427971) (xy 247.95157 -288.327655) (xy 248.082205 -288.233735)
			(xy 248.21736 -288.146443) (xy 248.356698 -288.065996) (xy 248.499872 -287.992595) (xy 248.646527 -287.926422)
			(xy 248.796298 -287.867641) (xy 248.948813 -287.816399) (xy 249.103693 -287.772822) (xy 249.260552 -287.73702)
			(xy 249.419001 -287.709081) (xy 249.578646 -287.689075) (xy 249.739089 -287.677052) (xy 249.899932 -287.673041)
			(xy 250.060775 -287.677052) (xy 250.221218 -287.689075) (xy 250.380863 -287.709081) (xy 250.539312 -287.73702)
			(xy 250.696171 -287.772822) (xy 250.851051 -287.816399) (xy 251.003566 -287.867641) (xy 251.153337 -287.926422)
			(xy 251.299992 -287.992595) (xy 251.443166 -288.065996) (xy 251.582504 -288.146443) (xy 251.717659 -288.233735)
			(xy 251.848294 -288.327655) (xy 251.974085 -288.427971) (xy 252.09472 -288.534431) (xy 252.209898 -288.646773)
			(xy 252.319333 -288.764716) (xy 252.422753 -288.887967) (xy 252.519901 -289.01622) (xy 252.610536 -289.149157)
			(xy 252.694431 -289.286445) (xy 252.771379 -289.427745) (xy 252.841188 -289.572705) (xy 252.903684 -289.720964)
			(xy 252.958713 -289.872154) (xy 253.006137 -290.025899) (xy 253.045839 -290.181817) (xy 253.077719 -290.33952)
			(xy 253.101699 -290.498617) (xy 253.117719 -290.65871) (xy 253.125739 -290.819403) (xy 253.12624 -290.89985)
			(xy 253.125739 -290.980297) (xy 253.117719 -291.14099) (xy 253.101699 -291.301083) (xy 253.077719 -291.46018)
			(xy 253.045839 -291.617883) (xy 253.006137 -291.773801) (xy 252.958713 -291.927546) (xy 252.903684 -292.078736)
			(xy 252.841188 -292.226995) (xy 252.771379 -292.371955) (xy 252.694431 -292.513255) (xy 252.610536 -292.650543)
			(xy 252.519901 -292.78348) (xy 252.422753 -292.911733) (xy 252.319333 -293.034984) (xy 252.209898 -293.152927)
			(xy 252.09472 -293.265269) (xy 251.974085 -293.371729) (xy 251.848294 -293.472045) (xy 251.717659 -293.565965)
			(xy 251.582504 -293.653257) (xy 251.443166 -293.733704) (xy 251.299992 -293.807105) (xy 251.153337 -293.873278)
			(xy 251.003566 -293.932059) (xy 250.851051 -293.983301) (xy 250.696171 -294.026878) (xy 250.539312 -294.06268)
			(xy 250.380863 -294.090619) (xy 250.221218 -294.110625) (xy 250.060775 -294.122648) (xy 249.899932 -294.12666)
			(xy 249.739089 -294.122648) (xy 249.578646 -294.110625) (xy 249.419001 -294.090619) (xy 249.260552 -294.06268)
			(xy 249.103693 -294.026878) (xy 248.948813 -293.983301) (xy 248.796298 -293.932059) (xy 248.646527 -293.873278)
			(xy 248.499872 -293.807105) (xy 248.356698 -293.733704) (xy 248.21736 -293.653257) (xy 248.082205 -293.565965)
			(xy 247.95157 -293.472045) (xy 247.825779 -293.371729) (xy 247.705144 -293.265269) (xy 247.589966 -293.152927)
			(xy 247.480531 -293.034984) (xy 247.377111 -292.911733) (xy 247.279963 -292.78348) (xy 247.189328 -292.650543)
			(xy 247.105433 -292.513255) (xy 247.028485 -292.371955) (xy 246.958676 -292.226995) (xy 246.89618 -292.078736)
			(xy 246.841151 -291.927546) (xy 246.793727 -291.773801) (xy 246.754025 -291.617883) (xy 246.722145 -291.46018)
			(xy 246.698165 -291.301083) (xy 246.682145 -291.14099) (xy 246.674125 -290.980297) (xy 243.815362 -290.980297)
			(xy 243.815362 -292.26129) (xy 243.815785 -292.27136) (xy 243.823504 -292.289961) (xy 243.830348 -292.297358)
			(xy 244.591332 -293.058342) (xy 244.598179 -293.065739) (xy 244.605909 -293.084338) (xy 244.606318 -293.09441)
			(xy 244.606318 -293.10711) (xy 245.929658 -293.10711) (xy 245.939723 -293.107544) (xy 245.958311 -293.115274)
			(xy 245.965726 -293.122096) (xy 246.324374 -293.480744) (xy 246.331217 -293.488144) (xy 246.338939 -293.506742)
			(xy 246.33936 -293.516812) (xy 246.33936 -293.69893) (xy 246.33893 -293.708997) (xy 246.331204 -293.72759)
			(xy 246.324374 -293.734998) (xy 245.991634 -294.067738) (xy 245.984235 -294.074581) (xy 245.965636 -294.082301)
			(xy 245.955566 -294.082724) (xy 237.160308 -294.082724) (xy 237.150287 -294.083143) (xy 237.131772 -294.090812)
			(xy 237.117603 -294.104985) (xy 237.10994 -294.123503) (xy 237.109508 -294.133524) (xy 237.109508 -309.673244)
			(xy 237.110004 -309.683245) (xy 237.117671 -309.701721) (xy 237.131823 -309.715858) (xy 237.150306 -309.723506)
			(xy 237.160308 -309.724044) (xy 237.291118 -309.724044) (xy 237.301186 -309.723616) (xy 237.31978 -309.715891)
			(xy 237.327186 -309.709058) (xy 238.19231 -308.843934) (xy 238.199707 -308.837085) (xy 238.218306 -308.829349)
			(xy 238.228378 -308.828948) (xy 248.22531 -308.828948) (xy 248.235378 -308.829374) (xy 248.253976 -308.837097)
			(xy 248.261378 -308.843934) (xy 249.313446 -309.896256) (xy 249.32029 -309.903655) (xy 249.328012 -309.922254)
			(xy 249.328432 -309.932324) (xy 249.328432 -315.684408) (xy 249.328008 -315.694478) (xy 249.320295 -315.713084)
			(xy 249.313446 -315.720476) (xy 249.028712 -316.00521) (xy 249.021318 -316.012068) (xy 249.002719 -316.019821)
			(xy 248.992644 -316.020196) (xy 237.356396 -316.020196) (xy 237.346326 -316.019772) (xy 237.327723 -316.012056)
			(xy 237.320328 -316.00521) (xy 237.144052 -315.828426) (xy 237.137276 -315.821) (xy 237.12968 -315.802404)
			(xy 237.12932 -315.792358) (xy 237.12932 -315.28893) (xy 237.128908 -315.27932) (xy 237.121864 -315.261435)
			(xy 237.115604 -315.254132) (xy 237.095284 -315.232288) (xy 237.088989 -315.226077) (xy 237.073269 -315.218007)
			(xy 237.06455 -315.21654) (xy 237.039566 -315.213006) (xy 236.990757 -315.200207) (xy 236.944056 -315.181097)
			(xy 236.900276 -315.156007) (xy 236.860178 -315.125375) (xy 236.842046 -315.107828) (xy 236.645958 -314.911486)
			(xy 236.638556 -314.904812) (xy 236.620146 -314.897227) (xy 236.600234 -314.897231) (xy 236.59084 -314.900564)
			(xy 236.576362 -314.906406) (xy 236.559344 -314.93206) (xy 236.559344 -319.385188) (xy 236.559766 -319.395258)
			(xy 236.567482 -319.413862) (xy 236.57433 -319.421256) (xy 237.075726 -319.922652) (xy 237.083124 -319.929499)
			(xy 237.101722 -319.937232) (xy 237.111794 -319.937638)
		)
		(stroke
			(width 0)
			(type solid)
		)
		(fill yes)
		(layer "B.Cu")
		(net "GND")
	)
	(gr_poly
		(pts
			(xy 380.664212 -182.594504) (xy 380.674281 -182.594079) (xy 380.692883 -182.586362) (xy 380.70028 -182.579518)
			(xy 380.721108 -182.55869) (xy 380.727952 -182.551291) (xy 380.735682 -182.532693) (xy 380.736094 -182.522622)
			(xy 380.736094 -179.578762) (xy 380.735664 -179.568695) (xy 380.727939 -179.550101) (xy 380.721108 -179.542694)
			(xy 380.485904 -179.30749) (xy 380.47851 -179.300633) (xy 380.459911 -179.292883) (xy 380.449836 -179.292504)
			(xy 379.333252 -179.292504) (xy 379.323186 -179.292072) (xy 379.304594 -179.284346) (xy 379.297184 -179.277518)
			(xy 378.87783 -178.858164) (xy 378.870986 -178.850765) (xy 378.86326 -178.832167) (xy 378.862844 -178.822096)
			(xy 378.862844 -177.01006) (xy 378.863276 -176.999994) (xy 378.871005 -176.981404) (xy 378.87783 -176.973992)
			(xy 379.460252 -176.39157) (xy 379.46765 -176.384724) (xy 379.486249 -176.376997) (xy 379.49632 -176.376584)
			(xy 384.676142 -176.376584) (xy 384.686209 -176.377014) (xy 384.704804 -176.384738) (xy 384.71221 -176.39157)
			(xy 385.293108 -176.972468) (xy 385.299943 -176.979871) (xy 385.307651 -176.998469) (xy 385.308094 -177.008536)
			(xy 385.308094 -182.342282) (xy 385.308532 -182.352346) (xy 385.316266 -182.370929) (xy 385.32308 -182.37835)
			(xy 385.519168 -182.574438) (xy 385.526567 -182.581281) (xy 385.545166 -182.589) (xy 385.555236 -182.589424)
			(xy 389.000492 -182.589424) (xy 389.010563 -182.589003) (xy 389.029172 -182.581293) (xy 389.03656 -182.574438)
			(xy 389.052308 -182.55869) (xy 389.059152 -182.551291) (xy 389.066882 -182.532693) (xy 389.067294 -182.522622)
			(xy 389.067294 -179.606702) (xy 389.066871 -179.596632) (xy 389.059156 -179.578027) (xy 389.052308 -179.570634)
			(xy 388.794244 -179.31257) (xy 388.786846 -179.305725) (xy 388.768247 -179.298) (xy 388.758176 -179.297584)
			(xy 387.645148 -179.297584) (xy 387.635082 -179.297151) (xy 387.616493 -179.289421) (xy 387.60908 -179.282598)
			(xy 387.17474 -178.848258) (xy 387.167896 -178.840859) (xy 387.160171 -178.822261) (xy 387.159754 -178.81219)
			(xy 387.159754 -175.813974) (xy 387.159325 -175.803907) (xy 387.151599 -175.785314) (xy 387.144768 -175.777906)
			(xy 386.279898 -174.913036) (xy 386.279898 -174.906432) (xy 386.175504 -174.802038) (xy 386.168667 -174.794636)
			(xy 386.160954 -174.776038) (xy 386.160518 -174.76597) (xy 386.160518 -170.597576) (xy 383.734818 -168.171876)
			(xy 383.548636 -167.985694) (xy 383.548636 -159.90824) (xy 383.276348 -159.635952) (xy 365.326422 -159.635952)
			(xy 364.534958 -158.844488) (xy 364.534958 -150.042372) (xy 363.531658 -149.039072) (xy 352.759264 -149.039072)
			(xy 349.557086 -152.24125) (xy 341.358474 -152.24125) (xy 340.844943 -152.754781) (xy 361.196124 -152.754781)
			(xy 361.196124 -152.670059) (xy 361.204177 -152.585722) (xy 361.220211 -152.502532) (xy 361.244079 -152.421242)
			(xy 361.275567 -152.34259) (xy 361.314389 -152.267287) (xy 361.360192 -152.196015) (xy 361.412563 -152.129419)
			(xy 361.471028 -152.068104) (xy 361.535056 -152.012623) (xy 361.604068 -151.96348) (xy 361.677438 -151.92112)
			(xy 361.754503 -151.885925) (xy 361.834565 -151.858216) (xy 361.916898 -151.838242) (xy 362.000757 -151.826185)
			(xy 362.085382 -151.822154) (xy 362.170007 -151.826185) (xy 362.253866 -151.838242) (xy 362.336199 -151.858216)
			(xy 362.416261 -151.885925) (xy 362.493326 -151.92112) (xy 362.566696 -151.96348) (xy 362.635708 -152.012623)
			(xy 362.699736 -152.068104) (xy 362.758201 -152.129419) (xy 362.810572 -152.196015) (xy 362.856375 -152.267287)
			(xy 362.895197 -152.34259) (xy 362.926685 -152.421242) (xy 362.950553 -152.502532) (xy 362.966587 -152.585722)
			(xy 362.97464 -152.670059) (xy 362.975144 -152.71242) (xy 362.97464 -152.754781) (xy 362.966587 -152.839118)
			(xy 362.950553 -152.922308) (xy 362.926685 -153.003598) (xy 362.895197 -153.08225) (xy 362.856375 -153.157553)
			(xy 362.810572 -153.228825) (xy 362.758201 -153.295421) (xy 362.699736 -153.356736) (xy 362.635708 -153.412217)
			(xy 362.566696 -153.46136) (xy 362.493326 -153.50372) (xy 362.416261 -153.538915) (xy 362.336199 -153.566624)
			(xy 362.253866 -153.586598) (xy 362.170007 -153.598655) (xy 362.085382 -153.602687) (xy 362.000757 -153.598655)
			(xy 361.916898 -153.586598) (xy 361.834565 -153.566624) (xy 361.754503 -153.538915) (xy 361.677438 -153.50372)
			(xy 361.604068 -153.46136) (xy 361.535056 -153.412217) (xy 361.471028 -153.356736) (xy 361.412563 -153.295421)
			(xy 361.360192 -153.228825) (xy 361.314389 -153.157553) (xy 361.275567 -153.08225) (xy 361.244079 -153.003598)
			(xy 361.220211 -152.922308) (xy 361.204177 -152.839118) (xy 361.196124 -152.754781) (xy 340.844943 -152.754781)
			(xy 340.658958 -152.940766) (xy 340.658958 -160.524952) (xy 341.09914 -160.965134) (xy 343.875614 -160.965134)
			(xy 343.878154 -160.967674) (xy 347.31706 -160.967674) (xy 347.327125 -160.967239) (xy 347.345711 -160.959507)
			(xy 347.353128 -160.952688) (xy 347.358208 -160.947608) (xy 347.365055 -160.940209) (xy 347.372791 -160.921612)
			(xy 347.373194 -160.91154) (xy 347.373194 -157.963362) (xy 347.372764 -157.953295) (xy 347.365039 -157.934701)
			(xy 347.358208 -157.927294) (xy 347.062044 -157.63113) (xy 347.054644 -157.624289) (xy 347.036045 -157.616571)
			(xy 347.025976 -157.616144) (xy 345.872308 -157.616144) (xy 345.862238 -157.615721) (xy 345.843637 -157.608002)
			(xy 345.83624 -157.601158) (xy 345.49588 -157.260798) (xy 345.489025 -157.253403) (xy 345.481279 -157.234804)
			(xy 345.480894 -157.22473) (xy 345.480894 -155.283916) (xy 345.481332 -155.273852) (xy 345.489067 -155.255269)
			(xy 345.49588 -155.247848) (xy 345.850718 -154.89301) (xy 345.858117 -154.886165) (xy 345.876715 -154.878436)
			(xy 345.886786 -154.878024) (xy 351.493582 -154.878024) (xy 351.503645 -154.878463) (xy 351.522226 -154.886201)
			(xy 351.52965 -154.89301) (xy 352.019108 -155.382468) (xy 352.025943 -155.389871) (xy 352.033651 -155.408469)
			(xy 352.034094 -155.418536) (xy 352.034094 -169.127678) (xy 352.034531 -169.137742) (xy 352.042265 -169.156327)
			(xy 352.04908 -169.163746) (xy 352.181922 -169.296588) (xy 352.189321 -169.303432) (xy 352.207919 -169.311161)
			(xy 352.21799 -169.311574) (xy 355.629972 -169.311574) (xy 355.640036 -169.311137) (xy 355.658619 -169.303401)
			(xy 355.66604 -169.296588) (xy 355.684328 -169.2783) (xy 355.691182 -169.270905) (xy 355.698928 -169.252306)
			(xy 355.699314 -169.242232) (xy 355.699314 -166.326312) (xy 355.698894 -166.31624) (xy 355.691184 -166.297631)
			(xy 355.684328 -166.290244) (xy 355.426264 -166.03218) (xy 355.418867 -166.02533) (xy 355.400268 -166.017596)
			(xy 355.390196 -166.017194) (xy 354.283518 -166.017194) (xy 354.273455 -166.016756) (xy 354.254872 -166.00902)
			(xy 354.24745 -166.002208) (xy 353.75342 -165.508178) (xy 353.746575 -165.500779) (xy 353.738845 -165.482181)
			(xy 353.738434 -165.47211) (xy 353.738434 -163.77031) (xy 353.738856 -163.76024) (xy 353.746572 -163.741636)
			(xy 353.75342 -163.734242) (xy 354.322126 -163.16579) (xy 354.329521 -163.158938) (xy 354.348121 -163.151199)
			(xy 354.358194 -163.150804) (xy 355.843332 -163.150804) (xy 355.868478 -163.134548) (xy 355.874574 -163.120832)
			(xy 355.886266 -163.096043) (xy 355.915698 -163.04981) (xy 355.951436 -163.008258) (xy 355.992746 -162.97224)
			(xy 356.03878 -162.942496) (xy 356.088592 -162.919637) (xy 356.14116 -162.904131) (xy 356.195405 -162.896298)
			(xy 356.250211 -162.896298) (xy 356.304456 -162.904131) (xy 356.357024 -162.919637) (xy 356.406836 -162.942496)
			(xy 356.45287 -162.97224) (xy 356.49418 -163.008258) (xy 356.529918 -163.04981) (xy 356.55935 -163.096043)
			(xy 356.571042 -163.120832) (xy 356.577138 -163.134548) (xy 356.602284 -163.150804) (xy 359.766362 -163.150804)
			(xy 359.776427 -163.151239) (xy 359.795015 -163.158969) (xy 359.80243 -163.16579) (xy 360.349292 -163.712652)
			(xy 360.356131 -163.720053) (xy 360.363848 -163.738651) (xy 360.364278 -163.74872) (xy 360.364278 -165.139313)
			(xy 376.9807 -165.139313) (xy 376.9807 -165.054591) (xy 376.988753 -164.970254) (xy 377.004787 -164.887064)
			(xy 377.028655 -164.805774) (xy 377.060143 -164.727122) (xy 377.098965 -164.651819) (xy 377.144768 -164.580547)
			(xy 377.197139 -164.513951) (xy 377.255604 -164.452636) (xy 377.319632 -164.397155) (xy 377.388644 -164.348012)
			(xy 377.462014 -164.305652) (xy 377.539079 -164.270457) (xy 377.619141 -164.242748) (xy 377.701474 -164.222774)
			(xy 377.785333 -164.210717) (xy 377.869958 -164.206686) (xy 377.954583 -164.210717) (xy 378.038442 -164.222774)
			(xy 378.120775 -164.242748) (xy 378.200837 -164.270457) (xy 378.277902 -164.305652) (xy 378.351272 -164.348012)
			(xy 378.420284 -164.397155) (xy 378.484312 -164.452636) (xy 378.542777 -164.513951) (xy 378.595148 -164.580547)
			(xy 378.640951 -164.651819) (xy 378.679773 -164.727122) (xy 378.711261 -164.805774) (xy 378.735129 -164.887064)
			(xy 378.751163 -164.970254) (xy 378.759216 -165.054591) (xy 378.75972 -165.096952) (xy 378.759216 -165.139313)
			(xy 378.751163 -165.22365) (xy 378.735129 -165.30684) (xy 378.711261 -165.38813) (xy 378.679773 -165.466782)
			(xy 378.640951 -165.542085) (xy 378.595148 -165.613357) (xy 378.542777 -165.679953) (xy 378.484312 -165.741268)
			(xy 378.420284 -165.796749) (xy 378.351272 -165.845892) (xy 378.277902 -165.888252) (xy 378.200837 -165.923447)
			(xy 378.120775 -165.951156) (xy 378.038442 -165.97113) (xy 377.954583 -165.983187) (xy 377.869958 -165.987219)
			(xy 377.785333 -165.983187) (xy 377.701474 -165.97113) (xy 377.619141 -165.951156) (xy 377.539079 -165.923447)
			(xy 377.462014 -165.888252) (xy 377.388644 -165.845892) (xy 377.319632 -165.796749) (xy 377.255604 -165.741268)
			(xy 377.197139 -165.679953) (xy 377.144768 -165.613357) (xy 377.098965 -165.542085) (xy 377.060143 -165.466782)
			(xy 377.028655 -165.38813) (xy 377.004787 -165.30684) (xy 376.988753 -165.22365) (xy 376.9807 -165.139313)
			(xy 360.364278 -165.139313) (xy 360.364278 -177.422556) (xy 360.364711 -177.432622) (xy 360.372437 -177.451214)
			(xy 360.379264 -177.458624) (xy 360.477308 -177.556668) (xy 360.484705 -177.563517) (xy 360.503304 -177.571253)
			(xy 360.513376 -177.571654) (xy 363.917992 -177.571654) (xy 363.928062 -177.571231) (xy 363.946664 -177.563513)
			(xy 363.95406 -177.556668) (xy 363.995208 -177.51552) (xy 364.002041 -177.508117) (xy 364.009745 -177.489519)
			(xy 364.010194 -177.479452) (xy 364.010194 -174.616872) (xy 364.009766 -174.606804) (xy 364.002043 -174.588208)
			(xy 363.995208 -174.580804) (xy 363.724444 -174.31004) (xy 363.717044 -174.303198) (xy 363.698446 -174.295478)
			(xy 363.688376 -174.295054) (xy 362.639102 -174.295054) (xy 362.629033 -174.29463) (xy 362.610432 -174.286911)
			(xy 362.603034 -174.280068) (xy 362.121704 -173.798738) (xy 362.114867 -173.791336) (xy 362.107154 -173.772738)
			(xy 362.106718 -173.76267) (xy 362.106718 -172.01896) (xy 362.107149 -172.008893) (xy 362.114876 -171.990301)
			(xy 362.121704 -171.982892) (xy 362.741972 -171.362624) (xy 362.749373 -171.355786) (xy 362.767972 -171.348074)
			(xy 362.77804 -171.347638) (xy 367.963196 -171.347638) (xy 367.973266 -171.348061) (xy 367.991868 -171.355779)
			(xy 367.999264 -171.362624) (xy 368.554508 -171.917868) (xy 368.561343 -171.925271) (xy 368.569051 -171.943869)
			(xy 368.569494 -171.953936) (xy 368.569494 -182.169308) (xy 368.569918 -182.179378) (xy 368.577634 -182.197981)
			(xy 368.58448 -182.205376) (xy 368.833908 -182.454804) (xy 368.841307 -182.461649) (xy 368.859905 -182.46938)
			(xy 368.869976 -182.46979) (xy 372.282974 -182.46979) (xy 372.293038 -182.469353) (xy 372.311622 -182.461619)
			(xy 372.319042 -182.454804) (xy 372.326408 -182.447438) (xy 372.333244 -182.440036) (xy 372.340954 -182.421438)
			(xy 372.341394 -182.41137) (xy 372.341394 -179.439062) (xy 372.340964 -179.428995) (xy 372.333239 -179.410401)
			(xy 372.326408 -179.402994) (xy 372.235984 -179.31257) (xy 372.228588 -179.305719) (xy 372.209989 -179.297979)
			(xy 372.199916 -179.297584) (xy 371.035072 -179.297584) (xy 371.025004 -179.297155) (xy 371.006409 -179.289432)
			(xy 370.999004 -179.282598) (xy 370.590064 -178.873658) (xy 370.583217 -178.86626) (xy 370.575488 -178.847661)
			(xy 370.575078 -178.83759) (xy 370.575078 -176.652174) (xy 370.575505 -176.642105) (xy 370.583224 -176.623506)
			(xy 370.590064 -176.616106) (xy 370.821966 -176.38395) (xy 370.829366 -176.377108) (xy 370.847964 -176.36939)
			(xy 370.858034 -176.368964) (xy 376.295412 -176.368964) (xy 376.30548 -176.369391) (xy 376.324075 -176.377116)
			(xy 376.33148 -176.38395) (xy 377.000008 -177.052478) (xy 377.006841 -177.059881) (xy 377.014546 -177.078479)
			(xy 377.014994 -177.088546) (xy 377.014994 -182.354982) (xy 377.015432 -182.365046) (xy 377.023166 -182.383629)
			(xy 377.02998 -182.39105) (xy 377.218448 -182.579518) (xy 377.225845 -182.586366) (xy 377.244444 -182.594096)
			(xy 377.254516 -182.594504)
		)
		(stroke
			(width 0)
			(type solid)
		)
		(fill yes)
		(layer "B.Cu")
		(net "SW_P12V_AUX_PVDDCR_CPU0_P0_FLT")
	)
	(gr_poly
		(pts
			(xy 461.558386 -417.734242) (xy 461.568448 -417.733802) (xy 461.587024 -417.726059) (xy 461.594454 -417.719256)
			(xy 463.526632 -415.787078) (xy 463.533482 -415.779682) (xy 463.541219 -415.761083) (xy 463.541618 -415.75101)
			(xy 463.541618 -408.041094) (xy 463.542043 -408.031025) (xy 463.549761 -408.012423) (xy 463.556604 -408.005026)
			(xy 466.73643 -404.8252) (xy 466.743284 -404.817805) (xy 466.75103 -404.799206) (xy 466.751416 -404.789132)
			(xy 466.751416 -399.908776) (xy 466.751416 -398.153128) (xy 466.751416 -375.08815) (xy 466.750984 -375.078083)
			(xy 466.743259 -375.059491) (xy 466.73643 -375.052082) (xy 466.531452 -374.847104) (xy 466.524051 -374.840265)
			(xy 466.505453 -374.832547) (xy 466.495384 -374.832118) (xy 464.687158 -374.832118) (xy 464.668616 -374.824498)
			(xy 464.664552 -374.820434) (xy 441.444634 -374.820434) (xy 441.43457 -374.82087) (xy 441.415986 -374.828605)
			(xy 441.408566 -374.83542) (xy 441.121038 -375.122948) (xy 441.114195 -375.130347) (xy 441.106472 -375.148946)
			(xy 441.106052 -375.159016) (xy 441.106052 -379.561852) (xy 441.106486 -379.571917) (xy 441.11422 -379.590503)
			(xy 441.121038 -379.59792) (xy 441.408566 -379.885448) (xy 441.415966 -379.89229) (xy 441.434564 -379.900008)
			(xy 441.444634 -379.900434) (xy 464.243674 -379.900434) (xy 464.253737 -379.900871) (xy 464.272319 -379.908608)
			(xy 464.279742 -379.91542) (xy 464.89112 -380.526798) (xy 464.897975 -380.534193) (xy 464.905723 -380.552791)
			(xy 464.906106 -380.562866) (xy 464.906106 -388.9756) (xy 464.905683 -388.98567) (xy 464.89797 -389.004276)
			(xy 464.89112 -389.011668) (xy 464.522312 -389.380476) (xy 464.514915 -389.387327) (xy 464.496317 -389.395069)
			(xy 464.486244 -389.395462) (xy 462.309464 -389.395462) (xy 462.299307 -389.395909) (xy 462.280571 -389.403762)
			(xy 462.273142 -389.410702) (xy 462.272888 -389.410956) (xy 462.270094 -389.408162) (xy 462.262698 -389.40131)
			(xy 462.244099 -389.393568) (xy 462.234026 -389.393176) (xy 445.117474 -389.393176) (xy 445.115696 -389.391652)
			(xy 438.22874 -389.391652) (xy 438.210198 -389.399272) (xy 438.206388 -389.403082) (xy 432.25974 -389.403082)
			(xy 432.249674 -389.403515) (xy 432.231084 -389.411243) (xy 432.223672 -389.418068) (xy 431.9651 -389.67664)
			(xy 431.9651 -389.691372) (xy 431.259996 -390.396476) (xy 431.253162 -390.403879) (xy 431.245456 -390.422477)
			(xy 431.24501 -390.432544) (xy 431.24501 -391.436371) (xy 438.100141 -391.436371) (xy 438.100141 -391.376429)
			(xy 438.107965 -391.317) (xy 438.12348 -391.2591) (xy 438.146419 -391.203721) (xy 438.176391 -391.151811)
			(xy 438.212882 -391.104256) (xy 438.255268 -391.061871) (xy 438.302824 -391.025382) (xy 438.354736 -390.995412)
			(xy 438.410116 -390.972475) (xy 438.468016 -390.956962) (xy 438.527445 -390.94914) (xy 438.557416 -390.948672)
			(xy 438.586705 -390.949117) (xy 438.644803 -390.9566) (xy 438.701472 -390.971428) (xy 438.755789 -390.993361)
			(xy 438.806866 -391.02204) (xy 438.853871 -391.056996) (xy 438.896035 -391.09766) (xy 438.93267 -391.143367)
			(xy 438.948322 -391.168128) (xy 438.956065 -391.179998) (xy 438.97689 -391.199206) (xy 439.002188 -391.211958)
			(xy 439.030016 -391.217276) (xy 439.058234 -391.21475) (xy 439.084674 -391.204574) (xy 439.107305 -391.187531)
			(xy 439.116216 -391.17651) (xy 439.134381 -391.15333) (xy 439.176581 -391.112257) (xy 439.224595 -391.078162)
			(xy 439.27728 -391.051855) (xy 439.333384 -391.033963) (xy 439.391572 -391.02491) (xy 439.421016 -391.024364)
			(xy 439.448264 -391.024907) (xy 439.502206 -391.032665) (xy 439.554495 -391.04802) (xy 439.604067 -391.070661)
			(xy 439.649912 -391.100125) (xy 439.691097 -391.135814) (xy 439.726784 -391.177001) (xy 439.756247 -391.222847)
			(xy 439.778885 -391.27242) (xy 439.794238 -391.324709) (xy 439.801994 -391.378652) (xy 439.801994 -391.433148)
			(xy 439.794238 -391.487091) (xy 439.778885 -391.53938) (xy 439.756247 -391.588953) (xy 439.726784 -391.634799)
			(xy 439.691097 -391.675986) (xy 439.649912 -391.711675) (xy 439.604067 -391.741139) (xy 439.554495 -391.76378)
			(xy 439.502206 -391.779135) (xy 439.448264 -391.786893) (xy 439.421016 -391.78738) (xy 439.391617 -391.786837)
			(xy 439.333516 -391.777799) (xy 439.277486 -391.759964) (xy 439.224852 -391.733754) (xy 439.176855 -391.699789)
			(xy 439.13463 -391.658869) (xy 439.11647 -391.635742) (xy 439.107618 -391.624661) (xy 439.084987 -391.607578)
			(xy 439.05853 -391.597379) (xy 439.030289 -391.594852) (xy 439.002442 -391.600191) (xy 438.977138 -391.612985)
			(xy 438.956329 -391.632246) (xy 438.948576 -391.644124) (xy 438.932971 -391.668955) (xy 438.896345 -391.71476)
			(xy 438.854171 -391.755514) (xy 438.807138 -391.790549) (xy 438.756016 -391.819292) (xy 438.701642 -391.841272)
			(xy 438.644908 -391.856129) (xy 438.58674 -391.863619) (xy 438.557416 -391.864088) (xy 438.527445 -391.86366)
			(xy 438.468016 -391.855838) (xy 438.410116 -391.840325) (xy 438.354736 -391.817388) (xy 438.302824 -391.787418)
			(xy 438.255268 -391.750929) (xy 438.212882 -391.708544) (xy 438.176391 -391.660989) (xy 438.146419 -391.609079)
			(xy 438.12348 -391.5537) (xy 438.107965 -391.4958) (xy 438.100141 -391.436371) (xy 431.24501 -391.436371)
			(xy 431.24501 -400.186906) (xy 431.245435 -400.196975) (xy 431.253152 -400.215577) (xy 431.259996 -400.222974)
			(xy 434.037232 -403.00021) (xy 434.686962 -403.00021) (xy 434.691033 -402.944588) (xy 434.703159 -402.890151)
			(xy 434.723082 -402.83806) (xy 434.750378 -402.789425) (xy 434.784464 -402.745282) (xy 434.824613 -402.706573)
			(xy 434.869971 -402.674122) (xy 434.919571 -402.648621) (xy 434.972355 -402.630614) (xy 435.027198 -402.620484)
			(xy 435.082932 -402.618447) (xy 435.138369 -402.624547) (xy 435.192326 -402.638653) (xy 435.243655 -402.660465)
			(xy 435.291261 -402.689519) (xy 435.334129 -402.725194) (xy 435.371346 -402.766731) (xy 435.402119 -402.813244)
			(xy 435.425791 -402.863741) (xy 435.441859 -402.917148) (xy 435.449979 -402.972324) (xy 435.450488 -403.00021)
			(xy 435.449979 -403.028096) (xy 435.441859 -403.083272) (xy 435.425791 -403.136679) (xy 435.402119 -403.187176)
			(xy 435.371346 -403.233689) (xy 435.334129 -403.275226) (xy 435.291261 -403.310901) (xy 435.243655 -403.339955)
			(xy 435.192326 -403.361767) (xy 435.138369 -403.375873) (xy 435.082932 -403.381973) (xy 435.027198 -403.379936)
			(xy 434.972355 -403.369806) (xy 434.919571 -403.351799) (xy 434.869971 -403.326298) (xy 434.824613 -403.293847)
			(xy 434.784464 -403.255138) (xy 434.750378 -403.210995) (xy 434.723082 -403.16236) (xy 434.703159 -403.110269)
			(xy 434.691033 -403.055832) (xy 434.686962 -403.00021) (xy 434.037232 -403.00021) (xy 434.92674 -403.889718)
			(xy 440.15025 -403.889718) (xy 440.15025 -397.66748) (xy 440.150652 -397.657408) (xy 440.158388 -397.638809)
			(xy 440.165236 -397.631412) (xy 440.64936 -397.147288) (xy 440.656192 -397.139881) (xy 440.663918 -397.121287)
			(xy 440.664346 -397.11122) (xy 440.664346 -397.109188) (xy 442.232796 -397.109188) (xy 442.242868 -397.109592)
			(xy 442.261467 -397.117325) (xy 442.268864 -397.124174) (xy 442.310774 -397.166084) (xy 442.317596 -397.173499)
			(xy 442.325327 -397.192087) (xy 442.32576 -397.202152) (xy 442.32576 -398.380204) (xy 442.326168 -398.390276)
			(xy 442.333899 -398.408874) (xy 442.340746 -398.416272) (xy 443.382146 -399.457672) (xy 443.389574 -399.464477)
			(xy 443.408152 -399.472218) (xy 443.418214 -399.472658) (xy 445.05245 -399.472658) (xy 445.062518 -399.472218)
			(xy 445.081116 -399.464509) (xy 445.088518 -399.457672) (xy 445.109346 -399.436844) (xy 445.116107 -399.429389)
			(xy 445.123827 -399.410827) (xy 445.124332 -399.400776) (xy 445.124332 -397.28394) (xy 445.12477 -397.273872)
			(xy 445.132481 -397.255274) (xy 445.139318 -397.247872) (xy 445.222122 -397.165068) (xy 445.229517 -397.158221)
			(xy 445.24812 -397.150506) (xy 445.25819 -397.150082) (xy 449.400422 -397.150082) (xy 449.400676 -397.150336)
			(xy 449.604384 -397.150336) (xy 449.614455 -397.149919) (xy 449.633053 -397.142194) (xy 449.640452 -397.13535)
			(xy 449.713604 -397.062198) (xy 449.721008 -397.055363) (xy 449.739604 -397.047641) (xy 449.749672 -397.047212)
			(xy 451.433184 -397.047212) (xy 451.443253 -397.047643) (xy 451.461851 -397.055359) (xy 451.469252 -397.062198)
			(xy 451.61708 -397.210026) (xy 451.623921 -397.217425) (xy 451.631641 -397.236025) (xy 451.632066 -397.246094)
			(xy 451.632066 -398.012412) (xy 451.630796 -398.013682) (xy 451.623971 -398.021094) (xy 451.616243 -398.039684)
			(xy 451.61581 -398.04975) (xy 451.61581 -398.591786) (xy 451.61624 -398.601855) (xy 451.623957 -398.620453)
			(xy 451.630796 -398.627854) (xy 452.460868 -399.457672) (xy 452.468288 -399.464486) (xy 452.486872 -399.472222)
			(xy 452.496936 -399.472658) (xy 454.131172 -399.472658) (xy 454.141241 -399.472229) (xy 454.15984 -399.464512)
			(xy 454.16724 -399.457672) (xy 454.188068 -399.436844) (xy 454.194877 -399.429419) (xy 454.202616 -399.410839)
			(xy 454.203054 -399.400776) (xy 454.203054 -397.456152) (xy 454.203492 -397.446084) (xy 454.211202 -397.427485)
			(xy 454.21804 -397.420084) (xy 454.473056 -397.165068) (xy 454.480473 -397.15825) (xy 454.49906 -397.150518)
			(xy 454.509124 -397.150082) (xy 458.619098 -397.150082) (xy 458.629103 -397.150589) (xy 458.647592 -397.158245)
			(xy 458.661744 -397.172392) (xy 458.669407 -397.190877) (xy 458.669898 -397.200882) (xy 458.669898 -411.287468)
			(xy 458.669483 -411.297539) (xy 458.661758 -411.316138) (xy 458.654912 -411.323536) (xy 458.034898 -411.94355)
			(xy 458.027487 -411.950376) (xy 458.008896 -411.958106) (xy 457.99883 -411.958536) (xy 446.980056 -411.958536)
			(xy 446.969982 -411.95815) (xy 446.951383 -411.950404) (xy 446.943988 -411.94355) (xy 446.210436 -411.209998)
			(xy 446.203608 -411.202588) (xy 446.19588 -411.183997) (xy 446.19545 -411.17393) (xy 446.19545 -410.39796)
			(xy 446.195841 -410.387887) (xy 446.203585 -410.369288) (xy 446.210436 -410.361892) (xy 446.867788 -409.70454)
			(xy 446.874601 -409.697119) (xy 446.882337 -409.678536) (xy 446.882774 -409.668472) (xy 446.882774 -405.158194)
			(xy 446.882358 -405.148124) (xy 446.874632 -405.129525) (xy 446.867788 -405.122126) (xy 446.128902 -404.38324)
			(xy 446.121491 -404.376414) (xy 446.1029 -404.368685) (xy 446.092834 -404.368254) (xy 440.628786 -404.368254)
			(xy 440.618714 -404.367848) (xy 440.600116 -404.360115) (xy 440.592718 -404.353268) (xy 440.165236 -403.925786)
			(xy 440.158402 -403.918381) (xy 440.150678 -403.899786) (xy 440.15025 -403.889718) (xy 434.92674 -403.889718)
			(xy 437.036464 -405.999442) (xy 437.04256 -406.002998) (xy 437.042814 -406.002998) (xy 437.064486 -406.015908)
			(xy 437.104546 -406.046567) (xy 437.140217 -406.082236) (xy 437.170879 -406.122293) (xy 437.183784 -406.143968)
			(xy 437.183784 -406.144222) (xy 437.18734 -406.150318) (xy 437.96458 -406.927558) (xy 437.968335 -406.931622)
			(xy 439.08929 -406.931622) (xy 439.093361 -406.876) (xy 439.105487 -406.821563) (xy 439.12541 -406.769472)
			(xy 439.152706 -406.720837) (xy 439.186792 -406.676694) (xy 439.226941 -406.637985) (xy 439.272299 -406.605534)
			(xy 439.321899 -406.580033) (xy 439.374683 -406.562026) (xy 439.429526 -406.551896) (xy 439.48526 -406.549859)
			(xy 439.540697 -406.555959) (xy 439.594654 -406.570065) (xy 439.645983 -406.591877) (xy 439.693589 -406.620931)
			(xy 439.736457 -406.656606) (xy 439.773674 -406.698143) (xy 439.804447 -406.744656) (xy 439.828119 -406.795153)
			(xy 439.844187 -406.84856) (xy 439.852307 -406.903736) (xy 439.852816 -406.931622) (xy 439.852307 -406.959508)
			(xy 439.844187 -407.014684) (xy 439.828119 -407.068091) (xy 439.804447 -407.118588) (xy 439.773674 -407.165101)
			(xy 439.736457 -407.206638) (xy 439.693589 -407.242313) (xy 439.645983 -407.271367) (xy 439.594654 -407.293179)
			(xy 439.540697 -407.307285) (xy 439.48526 -407.313385) (xy 439.429526 -407.311348) (xy 439.374683 -407.301218)
			(xy 439.321899 -407.283211) (xy 439.272299 -407.25771) (xy 439.226941 -407.225259) (xy 439.186792 -407.18655)
			(xy 439.152706 -407.142407) (xy 439.12541 -407.093772) (xy 439.105487 -407.041681) (xy 439.093361 -406.987244)
			(xy 439.08929 -406.931622) (xy 437.968335 -406.931622) (xy 437.971419 -406.934959) (xy 437.979136 -406.953557)
			(xy 437.979566 -406.963626) (xy 437.979566 -413.409384) (xy 437.980006 -413.419446) (xy 437.987749 -413.438022)
			(xy 437.994552 -413.445452) (xy 440.568842 -416.019742) (xy 449.148708 -416.019742) (xy 449.148708 -414.270952)
			(xy 449.149159 -414.260886) (xy 449.156862 -414.242287) (xy 449.163694 -414.234884) (xy 449.632832 -413.765746)
			(xy 449.640232 -413.758906) (xy 449.658831 -413.751185) (xy 449.6689 -413.75076) (xy 454.193402 -413.75076)
			(xy 454.203473 -413.751169) (xy 454.222072 -413.758899) (xy 454.22947 -413.765746) (xy 454.536302 -414.072832)
			(xy 454.543149 -414.080227) (xy 454.550865 -414.09883) (xy 454.551288 -414.1089) (xy 454.551288 -415.981896)
			(xy 454.550863 -415.991965) (xy 454.543142 -416.010563) (xy 454.536302 -416.017964) (xy 454.255632 -416.298634)
			(xy 454.248219 -416.305457) (xy 454.229629 -416.313186) (xy 454.219564 -416.31362) (xy 449.44284 -416.31362)
			(xy 449.43277 -416.313195) (xy 449.414171 -416.305476) (xy 449.406772 -416.298634) (xy 449.163694 -416.05581)
			(xy 449.156865 -416.048401) (xy 449.149139 -416.029809) (xy 449.148708 -416.019742) (xy 440.568842 -416.019742)
			(xy 442.268356 -417.719256) (xy 442.275755 -417.726098) (xy 442.294354 -417.733819) (xy 442.304424 -417.734242)
		)
		(stroke
			(width 0)
			(type solid)
		)
		(fill yes)
		(layer "B.Cu")
		(net "GND")
	)
	(gr_poly
		(pts
			(arc
				(start 28.551632 -349.515938)
				(mid 28.561349 -349.514985)
				(end 28.570682 -349.512128)
			)
			(arc
				(start 28.588462 -349.504762)
				(mid 28.597125 -349.500098)
				(end 28.604718 -349.49384)
			)
			(arc
				(start 28.63977 -349.458788)
				(mid 28.650676 -349.442605)
				(end 28.654502 -349.423482)
			)
			(arc
				(start 28.654502 -347.300042)
				(mid 28.658394 -347.280947)
				(end 28.669234 -347.264736)
			)
			(arc
				(start 28.715208 -347.218762)
				(mid 28.725929 -347.202667)
				(end 28.729686 -347.18371)
			)
			(arc
				(start 28.729686 -346.891102)
				(mid 28.733578 -346.872007)
				(end 28.744418 -346.855796)
			)
			(arc
				(start 28.90139 -346.698824)
				(mid 28.91772 -346.688006)
				(end 28.93695 -346.684346)
			)
			(arc
				(start 32.561276 -346.684346)
				(mid 32.580479 -346.688072)
				(end 32.596836 -346.698824)
			)
			(arc
				(start 32.84347 -346.945458)
				(mid 32.854376 -346.961641)
				(end 32.858202 -346.980764)
			)
			(arc
				(start 32.858202 -347.115384)
				(mid 32.872768 -347.150676)
				(end 32.907986 -347.165422)
			)
			(arc
				(start 33.023556 -347.165422)
				(mid 33.042651 -347.16153)
				(end 33.058862 -347.15069)
			)
			(arc
				(start 33.18891 -347.020896)
				(mid 33.353794 -346.910631)
				(end 33.54832 -346.871798)
			)
			(arc
				(start 34.570162 -346.871798)
				(mid 34.929731 -347.020737)
				(end 35.07867 -347.380306)
			)
			(xy 35.076892 -347.421454) (xy 35.075876 -347.43263) (xy 35.083496 -347.45295) (xy 35.08502 -347.454474)
			(arc
				(start 35.08502 -348.810072)
				(mid 35.088912 -348.829167)
				(end 35.099752 -348.845378)
			)
			(arc
				(start 35.384994 -349.130874)
				(mid 35.465754 -349.236011)
				(end 35.516566 -349.358458)
			)
			(xy 35.518344 -349.365062) (xy 35.524694 -349.376238)
			(arc
				(start 35.534854 -349.386398)
				(mid 35.551037 -349.397304)
				(end 35.57016 -349.40113)
			)
			(arc
				(start 36.116514 -349.40113)
				(mid 36.279271 -349.42798)
				(end 36.42487 -349.505524)
			)
			(xy 36.45535 -349.515938)
			(arc
				(start 36.832032 -349.515938)
				(mid 36.841749 -349.514985)
				(end 36.851082 -349.512128)
			)
			(arc
				(start 36.868862 -349.504762)
				(mid 36.877525 -349.500098)
				(end 36.885118 -349.49384)
			)
			(arc
				(start 36.92017 -349.458788)
				(mid 36.931076 -349.442605)
				(end 36.934902 -349.423482)
			)
			(arc
				(start 36.934902 -347.300042)
				(mid 36.938794 -347.280947)
				(end 36.949634 -347.264736)
			)
			(arc
				(start 36.995608 -347.218762)
				(mid 37.006329 -347.202667)
				(end 37.010086 -347.18371)
			)
			(arc
				(start 37.010086 -346.891102)
				(mid 37.013978 -346.872007)
				(end 37.024818 -346.855796)
			)
			(arc
				(start 37.18179 -346.698824)
				(mid 37.19812 -346.688006)
				(end 37.21735 -346.684346)
			)
			(arc
				(start 40.790876 -346.684346)
				(mid 40.810079 -346.688072)
				(end 40.826436 -346.698824)
			)
			(arc
				(start 41.12387 -346.996258)
				(mid 41.134776 -347.012441)
				(end 41.138602 -347.031564)
			)
			(arc
				(start 41.138602 -347.128338)
				(mid 41.153168 -347.16363)
				(end 41.188386 -347.178376)
			)
			(arc
				(start 41.316402 -347.178376)
				(mid 41.335497 -347.174484)
				(end 41.351708 -347.163644)
			)
			(arc
				(start 41.49471 -347.020896)
				(mid 41.659594 -346.910631)
				(end 41.85412 -346.871798)
			)
			(arc
				(start 42.875962 -346.871798)
				(mid 43.235531 -347.020737)
				(end 43.38447 -347.380306)
			)
			(xy 43.382692 -347.421454) (xy 43.381676 -347.43263) (xy 43.389296 -347.45295) (xy 43.39082 -347.454474)
			(arc
				(start 43.39082 -348.810072)
				(mid 43.394712 -348.829167)
				(end 43.405552 -348.845378)
			)
			(arc
				(start 43.690794 -349.130874)
				(mid 43.771554 -349.236011)
				(end 43.822366 -349.358458)
			)
			(xy 43.824144 -349.365062) (xy 43.830494 -349.376238)
			(arc
				(start 43.840654 -349.386398)
				(mid 43.856837 -349.397304)
				(end 43.87596 -349.40113)
			)
			(arc
				(start 44.422314 -349.40113)
				(mid 44.585071 -349.42798)
				(end 44.73067 -349.505524)
			)
			(xy 44.76115 -349.515938)
			(arc
				(start 45.137832 -349.515938)
				(mid 45.147549 -349.514985)
				(end 45.156882 -349.512128)
			)
			(arc
				(start 45.174662 -349.504762)
				(mid 45.183325 -349.500098)
				(end 45.190918 -349.49384)
			)
			(arc
				(start 45.22597 -349.458788)
				(mid 45.236876 -349.442605)
				(end 45.240702 -349.423482)
			)
			(arc
				(start 45.240702 -347.300042)
				(mid 45.244594 -347.280947)
				(end 45.255434 -347.264736)
			)
			(arc
				(start 45.301408 -347.218762)
				(mid 45.312129 -347.202667)
				(end 45.315886 -347.18371)
			)
			(arc
				(start 45.315886 -346.891102)
				(mid 45.319778 -346.872007)
				(end 45.330618 -346.855796)
			)
			(arc
				(start 45.48759 -346.698824)
				(mid 45.50392 -346.688006)
				(end 45.52315 -346.684346)
			)
			(arc
				(start 49.045876 -346.684346)
				(mid 49.065079 -346.688072)
				(end 49.081436 -346.698824)
			)
			(arc
				(start 49.45507 -347.072458)
				(mid 49.465976 -347.088641)
				(end 49.469802 -347.107764)
			)
			(arc
				(start 49.469802 -347.128338)
				(mid 49.484368 -347.16363)
				(end 49.519586 -347.178376)
			)
			(arc
				(start 49.694592 -347.178376)
				(mid 49.713687 -347.174484)
				(end 49.729898 -347.163644)
			)
			(arc
				(start 49.8729 -347.020896)
				(mid 50.037784 -346.910631)
				(end 50.23231 -346.871798)
			)
			(arc
				(start 51.232562 -346.871798)
				(mid 51.592131 -347.020737)
				(end 51.74107 -347.380306)
			)
			(xy 51.739292 -347.421454) (xy 51.738276 -347.43263) (xy 51.745896 -347.45295) (xy 51.74742 -347.454474)
			(arc
				(start 51.74742 -348.810072)
				(mid 51.751312 -348.829167)
				(end 51.762152 -348.845378)
			)
			(arc
				(start 52.047394 -349.130874)
				(mid 52.128154 -349.236011)
				(end 52.178966 -349.358458)
			)
			(xy 52.180744 -349.365062) (xy 52.187094 -349.376238)
			(arc
				(start 52.197254 -349.386398)
				(mid 52.213437 -349.397304)
				(end 52.23256 -349.40113)
			)
			(arc
				(start 52.778914 -349.40113)
				(mid 52.941671 -349.42798)
				(end 53.08727 -349.505524)
			)
			(xy 53.11775 -349.515938)
			(arc
				(start 53.494432 -349.515938)
				(mid 53.504149 -349.514985)
				(end 53.513482 -349.512128)
			)
			(arc
				(start 53.531262 -349.504762)
				(mid 53.539925 -349.500098)
				(end 53.547518 -349.49384)
			)
			(arc
				(start 53.58257 -349.458788)
				(mid 53.593476 -349.442605)
				(end 53.597302 -349.423482)
			)
			(arc
				(start 53.597302 -347.300042)
				(mid 53.601194 -347.280947)
				(end 53.612034 -347.264736)
			)
			(arc
				(start 53.658008 -347.218762)
				(mid 53.668729 -347.202667)
				(end 53.672486 -347.18371)
			)
			(arc
				(start 53.672486 -346.891102)
				(mid 53.676378 -346.872007)
				(end 53.687218 -346.855796)
			)
			(arc
				(start 53.84419 -346.698824)
				(mid 53.86052 -346.688006)
				(end 53.87975 -346.684346)
			)
			(arc
				(start 57.530238 -346.684346)
				(mid 57.549031 -346.688216)
				(end 57.565036 -346.698824)
			)
			(arc
				(start 57.81167 -346.945458)
				(mid 57.822576 -346.961641)
				(end 57.826402 -346.980764)
			)
			(arc
				(start 57.826402 -347.142816)
				(mid 57.840968 -347.178108)
				(end 57.876186 -347.192854)
			)
			(arc
				(start 57.989724 -347.192854)
				(mid 58.008819 -347.188962)
				(end 58.02503 -347.178122)
			)
			(arc
				(start 58.18251 -347.020896)
				(mid 58.347394 -346.910631)
				(end 58.54192 -346.871798)
			)
			(arc
				(start 59.563762 -346.871798)
				(mid 59.923331 -347.020737)
				(end 60.07227 -347.380306)
			)
			(xy 60.071762 -347.39961) (xy 60.071254 -347.410278) (xy 60.078874 -347.429328)
			(arc
				(start 60.089288 -347.439742)
				(mid 60.100194 -347.455925)
				(end 60.10402 -347.475048)
			)
			(arc
				(start 60.10402 -348.835472)
				(mid 60.107912 -348.854567)
				(end 60.118752 -348.870778)
			)
			(arc
				(start 60.378594 -349.130874)
				(mid 60.459354 -349.236011)
				(end 60.510166 -349.358458)
			)
			(xy 60.511944 -349.365062) (xy 60.518294 -349.376238)
			(arc
				(start 60.528454 -349.386398)
				(mid 60.544637 -349.397304)
				(end 60.56376 -349.40113)
			)
			(arc
				(start 61.110114 -349.40113)
				(mid 61.272871 -349.42798)
				(end 61.41847 -349.505524)
			)
			(xy 61.44895 -349.515938)
			(arc
				(start 61.851032 -349.515938)
				(mid 61.860749 -349.514985)
				(end 61.870082 -349.512128)
			)
			(arc
				(start 61.887862 -349.504762)
				(mid 61.896525 -349.500098)
				(end 61.904118 -349.49384)
			)
			(arc
				(start 61.93917 -349.458788)
				(mid 61.950076 -349.442605)
				(end 61.953902 -349.423482)
			)
			(arc
				(start 61.953902 -346.866972)
				(mid 61.957794 -346.847877)
				(end 61.968634 -346.831666)
			)
			(arc
				(start 62.11697 -346.68333)
				(mid 62.133153 -346.672424)
				(end 62.152276 -346.668598)
			)
			(xy 67.867022 -346.668598) (xy 68.893182 -347.694758) (xy 71.423022 -347.694758) (xy 73.109582 -346.008198)
			(xy 73.109582 -343.259918) (xy 72.253094 -342.40343)
			(arc
				(start 72.253094 -339.395562)
				(mid 72.249202 -339.376467)
				(end 72.238362 -339.360256)
			)
			(arc
				(start 72.140826 -339.26272)
				(mid 72.124643 -339.251814)
				(end 72.10552 -339.247988)
			)
			(arc
				(start 71.062342 -339.247988)
				(mid 71.043247 -339.25188)
				(end 71.027036 -339.26272)
			)
			(arc
				(start 70.3453 -339.944456)
				(mid 70.329117 -339.955362)
				(end 70.309994 -339.959188)
			)
			(arc
				(start 67.388994 -339.959188)
				(mid 67.369899 -339.955296)
				(end 67.353688 -339.944456)
			)
			(xy 66.399664 -338.990178) (xy 65.80505 -338.395564) (xy 24.048466 -338.395564) (xy 23.894034 -338.241132)
			(xy 22.608286 -338.241132) (xy 22.453854 -338.395564) (xy 22.0472 -338.802218) (xy 22.0472 -342.865964)
			(xy 22.492716 -343.31148) (xy 22.6187 -343.31148) (xy 24.901652 -345.594432) (xy 24.901652 -346.50553)
			(xy 25.26792 -346.871798)
			(arc
				(start 26.289762 -346.871798)
				(mid 26.649331 -347.020737)
				(end 26.79827 -347.380306)
			)
			(xy 26.796492 -347.421454) (xy 26.795476 -347.43263) (xy 26.803096 -347.45295) (xy 26.80462 -347.454474)
			(arc
				(start 26.80462 -348.810072)
				(mid 26.808512 -348.829167)
				(end 26.819352 -348.845378)
			)
			(arc
				(start 27.104594 -349.130874)
				(mid 27.185354 -349.236011)
				(end 27.236166 -349.358458)
			)
			(xy 27.237944 -349.365062) (xy 27.244294 -349.376238)
			(arc
				(start 27.254454 -349.386398)
				(mid 27.270637 -349.397304)
				(end 27.28976 -349.40113)
			)
			(arc
				(start 27.836114 -349.40113)
				(mid 27.998871 -349.42798)
				(end 28.14447 -349.505524)
			)
			(xy 28.17495 -349.515938)
		)
		(stroke
			(width 0)
			(type solid)
		)
		(fill yes)
		(layer "B.Cu")
		(net "GND")
	)
	(gr_poly
		(pts
			(xy 57.587134 -391.28065) (xy 57.597011 -391.280188) (xy 57.61531 -391.272746) (xy 57.622694 -391.266172)
			(xy 57.622948 -391.265918) (xy 57.695084 -391.193782) (xy 57.701767 -391.186372) (xy 57.709345 -391.167936)
			(xy 57.709816 -391.157968) (xy 57.709816 -389.795766) (xy 57.692036 -389.769858) (xy 57.677304 -389.76427)
			(xy 57.654078 -389.754824) (xy 57.610693 -389.729693) (xy 57.571787 -389.698067) (xy 57.538324 -389.660729)
			(xy 57.511133 -389.618605) (xy 57.490886 -389.572737) (xy 57.48401 -389.548624) (xy 57.482232 -389.542274)
			(xy 57.16651 -388.996174) (xy 57.162446 -388.991856) (xy 57.146255 -388.974148) (xy 57.118876 -388.934746)
			(xy 57.097783 -388.891651) (xy 57.083464 -388.845857) (xy 57.07625 -388.798423) (xy 57.075832 -388.774432)
			(xy 57.075927 -388.760325) (xy 57.078348 -388.732215) (xy 57.080658 -388.718298) (xy 57.081921 -388.709104)
			(xy 57.078517 -388.690877) (xy 57.074054 -388.682738) (xy 57.05729 -388.655814) (xy 57.052085 -388.648113)
			(xy 57.037359 -388.636797) (xy 57.028588 -388.633716) (xy 57.006972 -388.626943) (xy 56.965766 -388.608128)
			(xy 56.927647 -388.583656) (xy 56.893385 -388.554024) (xy 56.87822 -388.537196) (xy 56.875764 -388.534362)
			(xy 56.870152 -388.529389) (xy 56.867044 -388.52729) (xy 56.854978 -388.519235) (xy 56.835021 -388.49819)
			(xy 56.820946 -388.472831) (xy 56.813645 -388.444762) (xy 56.813196 -388.430262) (xy 56.813196 -388.418324)
			(xy 56.811672 -388.41172) (xy 56.806478 -388.391348) (xy 56.800877 -388.349682) (xy 56.800496 -388.328662)
			(xy 56.80087 -388.307642) (xy 56.806481 -388.265976) (xy 56.811672 -388.245604) (xy 56.813196 -388.239)
			(xy 56.813196 -388.125462) (xy 56.813649 -388.110419) (xy 56.821453 -388.081363) (xy 56.836517 -388.05532)
			(xy 56.857813 -388.034069) (xy 56.883888 -388.01906) (xy 56.91296 -388.011318) (xy 56.928004 -388.010908)
			(xy 57.109614 -388.010908) (xy 57.110122 -388.010654) (xy 57.118504 -388.010654) (xy 57.126886 -388.010654)
			(xy 57.127394 -388.010908) (xy 57.309004 -388.010908) (xy 57.324032 -388.011397) (xy 57.353066 -388.019167)
			(xy 57.379105 -388.034177) (xy 57.40038 -388.055408) (xy 57.415443 -388.081417) (xy 57.423272 -388.110435)
			(xy 57.423812 -388.125462) (xy 57.423812 -388.239) (xy 57.425336 -388.245604) (xy 57.430535 -388.265975)
			(xy 57.436145 -388.307641) (xy 57.436512 -388.328662) (xy 57.436381 -388.343416) (xy 57.433709 -388.372801)
			(xy 57.431178 -388.387336) (xy 57.429811 -388.396574) (xy 57.433065 -388.414947) (xy 57.437528 -388.42315)
			(xy 57.454038 -388.450074) (xy 57.45921 -388.457852) (xy 57.47393 -388.469323) (xy 57.48274 -388.472426)
			(xy 57.507588 -388.48052) (xy 57.554422 -388.503698) (xy 57.596803 -388.534266) (xy 57.633578 -388.571391)
			(xy 57.663742 -388.614062) (xy 57.686474 -388.661113) (xy 57.694322 -388.68604) (xy 57.695846 -388.691882)
			(xy 57.939686 -389.113522) (xy 57.946048 -389.123348) (xy 57.965508 -389.136308) (xy 57.977024 -389.138414)
			(xy 57.988708 -389.140192) (xy 58.010806 -389.132572) (xy 58.264806 -388.878572) (xy 58.272976 -388.869272)
			(xy 58.280256 -388.845653) (xy 58.278776 -388.83336) (xy 58.276173 -388.818767) (xy 58.273377 -388.789254)
			(xy 58.273188 -388.774432) (xy 58.273352 -388.760707) (xy 58.275765 -388.733363) (xy 58.278014 -388.719822)
			(xy 58.278268 -388.71779) (xy 58.278776 -388.712964) (xy 58.279204 -388.704784) (xy 58.275447 -388.688849)
			(xy 58.27141 -388.681722) (xy 58.25998 -388.66318) (xy 58.257474 -388.65936) (xy 58.251341 -388.65259)
			(xy 58.247788 -388.649718) (xy 58.226706 -388.633462) (xy 58.218578 -388.630668) (xy 58.191741 -388.621123)
			(xy 58.141707 -388.593912) (xy 58.097293 -388.558258) (xy 58.078116 -388.537196) (xy 58.075595 -388.534355)
			(xy 58.069857 -388.52938) (xy 58.066686 -388.52729) (xy 58.054641 -388.51923) (xy 58.034734 -388.498176)
			(xy 58.020727 -388.472812) (xy 58.013512 -388.44475) (xy 58.013092 -388.430262) (xy 58.013092 -388.418578)
			(xy 58.011314 -388.411974) (xy 58.006108 -388.39154) (xy 58.000501 -388.349746) (xy 58.000138 -388.328662)
			(xy 58.000392 -388.320788) (xy 58.001155 -388.30182) (xy 58.006634 -388.264255) (xy 58.011314 -388.245858)
			(xy 58.013092 -388.239254) (xy 58.013092 -387.78307) (xy 58.011314 -387.776466) (xy 58.006278 -387.756457)
			(xy 58.000803 -387.715561) (xy 58.000392 -387.694932) (xy 58.000392 -387.689344) (xy 58.000966 -387.669481)
			(xy 58.006439 -387.630122) (xy 58.011314 -387.610858) (xy 58.013092 -387.604508) (xy 58.013092 -387.592062)
			(xy 58.013502 -387.577621) (xy 58.020689 -387.549647) (xy 58.034625 -387.52435) (xy 58.054429 -387.503327)
			(xy 58.066432 -387.495288) (xy 58.067194 -387.490462) (xy 58.068106 -387.485287) (xy 58.067986 -387.474783)
			(xy 58.06694 -387.469634) (xy 58.047382 -387.384798) (xy 58.034682 -387.36778) (xy 58.024776 -387.362446)
			(xy 58.00054 -387.348449) (xy 57.956983 -387.313311) (xy 57.938162 -387.292596) (xy 57.935705 -387.289764)
			(xy 57.930088 -387.284797) (xy 57.926986 -387.28269) (xy 57.914941 -387.27463) (xy 57.895034 -387.253576)
			(xy 57.881027 -387.228212) (xy 57.873812 -387.20015) (xy 57.873392 -387.185662) (xy 57.873392 -387.173724)
			(xy 57.871614 -387.16712) (xy 57.866421 -387.146748) (xy 57.860821 -387.105082) (xy 57.860438 -387.084062)
			(xy 57.860812 -387.063042) (xy 57.866421 -387.021376) (xy 57.871614 -387.001004) (xy 57.873392 -386.9944)
			(xy 57.873392 -386.90423) (xy 57.865834 -386.89649) (xy 57.8461 -386.887671) (xy 57.835292 -386.887212)
			(xy 54.41061 -386.887212) (xy 54.400539 -386.887634) (xy 54.381933 -386.895347) (xy 54.374542 -386.902198)
			(xy 54.348126 -386.928614) (xy 54.34076 -386.935726) (xy 54.33314 -386.954522) (xy 54.33314 -387.0198)
			(xy 54.333543 -387.029081) (xy 54.340189 -387.046411) (xy 54.346094 -387.053582) (xy 54.350412 -387.058408)
			(xy 54.35092 -387.058916) (xy 54.357374 -387.066211) (xy 54.364702 -387.084239) (xy 54.365144 -387.093968)
			(xy 54.365144 -387.191504) (xy 54.365144 -387.931406) (xy 54.365865 -387.943361) (xy 54.376739 -387.964668)
			(xy 54.385972 -387.9723) (xy 54.450234 -388.01929) (xy 54.47538 -388.022846) (xy 54.487572 -388.01802)
			(xy 54.497319 -388.014628) (xy 54.517639 -388.011041) (xy 54.527958 -388.010908) (xy 54.709568 -388.010908)
			(xy 54.710076 -388.010654) (xy 54.718458 -388.010654) (xy 54.72684 -388.010654) (xy 54.727348 -388.010908)
			(xy 54.908958 -388.010908) (xy 54.923986 -388.011349) (xy 54.95302 -388.019118) (xy 54.979055 -388.034136)
			(xy 55.000315 -388.055381) (xy 55.015352 -388.081405) (xy 55.023141 -388.110434) (xy 55.023512 -388.125462)
			(xy 55.023512 -388.239) (xy 55.02529 -388.245604) (xy 55.03049 -388.265975) (xy 55.036101 -388.307641)
			(xy 55.036466 -388.328662) (xy 55.6006 -388.328662) (xy 55.600967 -388.307641) (xy 55.606577 -388.265975)
			(xy 55.611776 -388.245604) (xy 55.6133 -388.239) (xy 55.6133 -388.125462) (xy 55.613761 -388.11042)
			(xy 55.621564 -388.081367) (xy 55.636627 -388.055326) (xy 55.657922 -388.034077) (xy 55.683995 -388.01907)
			(xy 55.713066 -388.011329) (xy 55.728108 -388.010908) (xy 55.909718 -388.010908) (xy 55.910226 -388.010654)
			(xy 55.918608 -388.010654) (xy 55.92699 -388.010654) (xy 55.927498 -388.010908) (xy 56.109108 -388.010908)
			(xy 56.124139 -388.011373) (xy 56.153178 -388.019145) (xy 56.179222 -388.034159) (xy 56.2005 -388.055395)
			(xy 56.215566 -388.081408) (xy 56.223397 -388.110432) (xy 56.223916 -388.125462) (xy 56.223916 -388.239)
			(xy 56.22544 -388.245604) (xy 56.230632 -388.265976) (xy 56.236242 -388.307642) (xy 56.236616 -388.328662)
			(xy 56.236476 -388.343415) (xy 56.2338 -388.372799) (xy 56.231282 -388.387336) (xy 56.229935 -388.396575)
			(xy 56.233182 -388.414943) (xy 56.237632 -388.42315) (xy 56.254142 -388.450074) (xy 56.259323 -388.457844)
			(xy 56.27404 -388.469312) (xy 56.282844 -388.472426) (xy 56.307793 -388.480459) (xy 56.354778 -388.503681)
			(xy 56.397274 -388.534356) (xy 56.43411 -388.571639) (xy 56.464269 -388.614503) (xy 56.48692 -388.661766)
			(xy 56.49468 -388.686802) (xy 56.496204 -388.692644) (xy 56.81599 -389.245602) (xy 56.820054 -389.24992)
			(xy 56.836251 -389.267621) (xy 56.863614 -389.307032) (xy 56.884697 -389.35013) (xy 56.899016 -389.395923)
			(xy 56.90624 -389.443354) (xy 56.906668 -389.467344) (xy 56.90616 -389.492792) (xy 56.89799 -389.543028)
			(xy 56.881867 -389.591304) (xy 56.858211 -389.636368) (xy 56.827632 -389.677054) (xy 56.790923 -389.712309)
			(xy 56.77027 -389.727186) (xy 56.762413 -389.733124) (xy 56.75152 -389.749504) (xy 56.747591 -389.76878)
			(xy 56.751204 -389.788117) (xy 56.761828 -389.804674) (xy 56.7779 -389.816017) (xy 56.79706 -389.820478)
			(xy 56.806846 -389.819388) (xy 56.815422 -389.818081) (xy 56.832715 -389.816684) (xy 56.84139 -389.816594)
			(xy 56.841644 -389.816848) (xy 57.140856 -389.816848) (xy 57.14111 -389.816594) (xy 57.162155 -389.817024)
			(xy 57.203475 -389.825015) (xy 57.24243 -389.840942) (xy 57.277512 -389.864188) (xy 57.307363 -389.893853)
			(xy 57.330828 -389.928789) (xy 57.346999 -389.967643) (xy 57.355248 -390.008912) (xy 57.35574 -390.029954)
			(xy 57.35574 -390.284716) (xy 57.346596 -390.284716) (xy 57.336604 -390.285232) (xy 57.31816 -390.292939)
			(xy 57.304027 -390.307076) (xy 57.296328 -390.325524) (xy 57.295796 -390.335516) (xy 57.295796 -390.499092)
			(xy 57.295374 -390.509113) (xy 57.287706 -390.527631) (xy 57.273534 -390.541804) (xy 57.255017 -390.549473)
			(xy 57.244996 -390.549892) (xy 56.737504 -390.549892) (xy 56.727482 -390.549477) (xy 56.708964 -390.541807)
			(xy 56.694791 -390.527633) (xy 56.687122 -390.509114) (xy 56.686704 -390.499092) (xy 56.686704 -390.284716)
			(xy 56.67756 -390.284716) (xy 56.66752 -390.284294) (xy 56.64894 -390.276705) (xy 56.634737 -390.262524)
			(xy 56.62712 -390.243954) (xy 56.62676 -390.233916) (xy 56.62676 -390.029954) (xy 56.62743 -390.004095)
			(xy 56.63977 -389.953873) (xy 56.651144 -389.93064) (xy 56.65724 -389.91921) (xy 56.656986 -389.89381)
			(xy 56.602884 -389.796782) (xy 56.581548 -389.783066) (xy 56.568594 -389.78205) (xy 56.544695 -389.779956)
			(xy 56.497907 -389.769351) (xy 56.453266 -389.75178) (xy 56.411802 -389.727648) (xy 56.374472 -389.697514)
			(xy 56.342139 -389.662072) (xy 56.315548 -389.622141) (xy 56.295314 -389.578642) (xy 56.288178 -389.555736)
			(xy 56.286654 -389.549894) (xy 55.966106 -388.995412) (xy 55.962042 -388.991094) (xy 55.945941 -388.973435)
			(xy 55.918754 -388.934135) (xy 55.897802 -388.891186) (xy 55.883566 -388.845568) (xy 55.876371 -388.798326)
			(xy 55.875936 -388.774432) (xy 55.876049 -388.760325) (xy 55.878464 -388.732217) (xy 55.880762 -388.718298)
			(xy 55.881993 -388.709101) (xy 55.878621 -388.690872) (xy 55.874158 -388.682738) (xy 55.857394 -388.655814)
			(xy 55.852189 -388.64811) (xy 55.837473 -388.636772) (xy 55.828692 -388.633716) (xy 55.807076 -388.626939)
			(xy 55.765867 -388.608131) (xy 55.727744 -388.583663) (xy 55.693481 -388.554031) (xy 55.678324 -388.537196)
			(xy 55.675862 -388.534368) (xy 55.67025 -388.529396) (xy 55.667148 -388.52729) (xy 55.655086 -388.51923)
			(xy 55.635129 -388.498187) (xy 55.621054 -388.472829) (xy 55.613753 -388.444762) (xy 55.6133 -388.430262)
			(xy 55.6133 -388.418324) (xy 55.611776 -388.41172) (xy 55.60657 -388.391351) (xy 55.600969 -388.349683)
			(xy 55.6006 -388.328662) (xy 55.036466 -388.328662) (xy 55.036303 -388.342387) (xy 55.033889 -388.369731)
			(xy 55.03164 -388.383272) (xy 55.031386 -388.385304) (xy 55.030878 -388.39013) (xy 55.030449 -388.39831)
			(xy 55.034208 -388.414244) (xy 55.038244 -388.421372) (xy 55.049674 -388.439914) (xy 55.052181 -388.443733)
			(xy 55.058318 -388.450498) (xy 55.061866 -388.453376) (xy 55.082948 -388.469632) (xy 55.091076 -388.472426)
			(xy 55.115908 -388.481197) (xy 55.162484 -388.505768) (xy 55.204378 -388.537674) (xy 55.240447 -388.576042)
			(xy 55.269705 -388.619827) (xy 55.291354 -388.667831) (xy 55.298594 -388.693152) (xy 55.300372 -388.699756)
			(xy 55.611268 -389.237728) (xy 55.616094 -389.2423) (xy 55.633432 -389.260331) (xy 55.662835 -389.300796)
			(xy 55.685546 -389.345362) (xy 55.701009 -389.392932) (xy 55.70884 -389.442334) (xy 55.709312 -389.467344)
			(xy 55.708781 -389.494483) (xy 55.6996 -389.547977) (xy 55.681462 -389.599133) (xy 55.654894 -389.646463)
			(xy 55.620669 -389.688589) (xy 55.6006 -389.706866) (xy 55.591964 -389.713978) (xy 55.583074 -389.73379)
			(xy 55.583074 -389.757412) (xy 55.583074 -389.759952) (xy 55.583953 -389.769536) (xy 55.591906 -389.787044)
			(xy 55.598568 -389.793988) (xy 55.607204 -389.80237) (xy 55.614535 -389.808907) (xy 55.632699 -389.816335)
			(xy 55.64251 -389.816848) (xy 55.94096 -389.816848) (xy 55.941214 -389.816594) (xy 55.962262 -389.816955)
			(xy 56.003587 -389.82495) (xy 56.042545 -389.840884) (xy 56.077628 -389.86414) (xy 56.107477 -389.893817)
			(xy 56.130935 -389.928765) (xy 56.147094 -389.967631) (xy 56.155327 -390.008908) (xy 56.155844 -390.029954)
			(xy 56.155844 -390.233916) (xy 56.155469 -390.243956) (xy 56.147842 -390.262526) (xy 56.13365 -390.276726)
			(xy 56.115084 -390.284364) (xy 56.105044 -390.284716) (xy 56.0959 -390.284716) (xy 56.0959 -390.499092)
			(xy 56.095482 -390.509114) (xy 56.087813 -390.527634) (xy 56.073641 -390.541809) (xy 56.055122 -390.54948)
			(xy 56.0451 -390.549892) (xy 55.600346 -390.549892) (xy 55.592503 -390.5574) (xy 55.583528 -390.577146)
			(xy 55.583074 -390.587992) (xy 55.583074 -391.174732) (xy 55.583536 -391.184609) (xy 55.59098 -391.202906)
			(xy 55.597552 -391.210292) (xy 55.597806 -391.210546) (xy 55.652924 -391.265664) (xy 55.653432 -391.266172)
			(xy 55.660813 -391.272755) (xy 55.679112 -391.28021) (xy 55.688992 -391.28065)
		)
		(stroke
			(width 0)
			(type solid)
		)
		(fill yes)
		(layer "B.Cu")
		(net "P1V8_CPU1_RT0_1A")
	)
	(gr_poly
		(pts
			(xy 90.114882 -391.28065) (xy 90.124755 -391.28018) (xy 90.143042 -391.272726) (xy 90.150442 -391.266172)
			(xy 90.150696 -391.265918) (xy 90.222832 -391.193782) (xy 90.22951 -391.18637) (xy 90.237081 -391.167934)
			(xy 90.237564 -391.157968) (xy 90.237564 -389.795766) (xy 90.219784 -389.769858) (xy 90.205052 -389.76427)
			(xy 90.181823 -389.754827) (xy 90.138433 -389.729699) (xy 90.099522 -389.698076) (xy 90.066054 -389.66074)
			(xy 90.038858 -389.618615) (xy 90.018607 -389.572745) (xy 90.011758 -389.548624) (xy 90.00998 -389.542274)
			(xy 89.694258 -388.996174) (xy 89.690194 -388.991856) (xy 89.674005 -388.974147) (xy 89.646631 -388.934744)
			(xy 89.625542 -388.891648) (xy 89.611225 -388.845855) (xy 89.604012 -388.798422) (xy 89.60358 -388.774432)
			(xy 89.603675 -388.760325) (xy 89.606096 -388.732215) (xy 89.608406 -388.718298) (xy 89.609669 -388.709104)
			(xy 89.606268 -388.690875) (xy 89.601802 -388.682738) (xy 89.585038 -388.655814) (xy 89.579836 -388.648109)
			(xy 89.565115 -388.636779) (xy 89.556336 -388.633716) (xy 89.534718 -388.626946) (xy 89.493508 -388.608135)
			(xy 89.455384 -388.583668) (xy 89.421118 -388.554038) (xy 89.405968 -388.537196) (xy 89.403511 -388.534364)
			(xy 89.397895 -388.529396) (xy 89.394792 -388.52729) (xy 89.382731 -388.519232) (xy 89.362782 -388.498184)
			(xy 89.348715 -388.472826) (xy 89.341417 -388.44476) (xy 89.340944 -388.430262) (xy 89.340944 -388.418324)
			(xy 89.33942 -388.41172) (xy 89.334227 -388.391348) (xy 89.328627 -388.349682) (xy 89.328244 -388.328662)
			(xy 89.328618 -388.307642) (xy 89.334227 -388.265976) (xy 89.33942 -388.245604) (xy 89.340944 -388.239)
			(xy 89.340944 -388.125462) (xy 89.341397 -388.110422) (xy 89.349202 -388.08137) (xy 89.364267 -388.055334)
			(xy 89.385565 -388.03409) (xy 89.41164 -388.01909) (xy 89.44071 -388.01136) (xy 89.455752 -388.010908)
			(xy 89.637362 -388.010908) (xy 89.63787 -388.010654) (xy 89.646252 -388.010654) (xy 89.654634 -388.010654)
			(xy 89.655142 -388.010908) (xy 89.836752 -388.010908) (xy 89.851784 -388.01139) (xy 89.88083 -388.019152)
			(xy 89.906881 -388.034159) (xy 89.928167 -388.055391) (xy 89.943238 -388.081405) (xy 89.951072 -388.110431)
			(xy 89.95156 -388.125462) (xy 89.95156 -388.239) (xy 89.953084 -388.245604) (xy 89.958282 -388.265975)
			(xy 89.963892 -388.307641) (xy 89.96426 -388.328662) (xy 89.964129 -388.343416) (xy 89.961457 -388.372801)
			(xy 89.958926 -388.387336) (xy 89.957559 -388.396575) (xy 89.96081 -388.414948) (xy 89.965276 -388.42315)
			(xy 89.981786 -388.450074) (xy 89.986962 -388.457847) (xy 90.001686 -388.469305) (xy 90.010488 -388.472426)
			(xy 90.035334 -388.480523) (xy 90.082162 -388.503706) (xy 90.124537 -388.534277) (xy 90.161306 -388.571403)
			(xy 90.191465 -388.614073) (xy 90.214193 -388.661123) (xy 90.22207 -388.68604) (xy 90.223594 -388.691882)
			(xy 90.467434 -389.113522) (xy 90.473792 -389.123355) (xy 90.493249 -389.136335) (xy 90.504772 -389.138414)
			(xy 90.516456 -389.140192) (xy 90.538554 -389.132572) (xy 90.792554 -388.878572) (xy 90.800731 -388.869274)
			(xy 90.808019 -388.845652) (xy 90.806524 -388.83336) (xy 90.803921 -388.818767) (xy 90.801124 -388.789254)
			(xy 90.800936 -388.774432) (xy 90.8011 -388.760707) (xy 90.803514 -388.733363) (xy 90.805762 -388.719822)
			(xy 90.806016 -388.71779) (xy 90.806524 -388.712964) (xy 90.806952 -388.704784) (xy 90.803192 -388.688851)
			(xy 90.799158 -388.681722) (xy 90.787728 -388.66318) (xy 90.785221 -388.659362) (xy 90.779083 -388.652597)
			(xy 90.775536 -388.649718) (xy 90.754454 -388.633462) (xy 90.746326 -388.630668) (xy 90.719487 -388.621126)
			(xy 90.669448 -388.593921) (xy 90.625028 -388.55827) (xy 90.605864 -388.537196) (xy 90.603345 -388.534354)
			(xy 90.59761 -388.529373) (xy 90.594434 -388.52729) (xy 90.582393 -388.519226) (xy 90.562495 -388.49817)
			(xy 90.548495 -388.472807) (xy 90.541284 -388.444748) (xy 90.54084 -388.430262) (xy 90.54084 -388.418578)
			(xy 90.539062 -388.411974) (xy 90.533857 -388.39154) (xy 90.52825 -388.349746) (xy 90.527886 -388.328662)
			(xy 90.52814 -388.320788) (xy 90.528903 -388.30182) (xy 90.534381 -388.264255) (xy 90.539062 -388.245858)
			(xy 90.54084 -388.239254) (xy 90.54084 -387.78307) (xy 90.539062 -387.776466) (xy 90.534027 -387.756457)
			(xy 90.528553 -387.715561) (xy 90.52814 -387.694932) (xy 90.52814 -387.689344) (xy 90.528714 -387.669481)
			(xy 90.534186 -387.630122) (xy 90.539062 -387.610858) (xy 90.54084 -387.604508) (xy 90.54084 -387.592062)
			(xy 90.54125 -387.577622) (xy 90.548439 -387.549651) (xy 90.562379 -387.524357) (xy 90.582187 -387.503341)
			(xy 90.59418 -387.495288) (xy 90.594942 -387.490462) (xy 90.595854 -387.485287) (xy 90.595735 -387.474783)
			(xy 90.594688 -387.469634) (xy 90.57513 -387.384798) (xy 90.56243 -387.36778) (xy 90.552524 -387.362446)
			(xy 90.528286 -387.348451) (xy 90.484724 -387.313318) (xy 90.46591 -387.292596) (xy 90.463454 -387.289762)
			(xy 90.457841 -387.28479) (xy 90.454734 -387.28269) (xy 90.442693 -387.274626) (xy 90.422795 -387.25357)
			(xy 90.408795 -387.228207) (xy 90.401584 -387.200148) (xy 90.40114 -387.185662) (xy 90.40114 -387.173724)
			(xy 90.399362 -387.16712) (xy 90.394168 -387.146748) (xy 90.388568 -387.105082) (xy 90.388186 -387.084062)
			(xy 90.38856 -387.063042) (xy 90.39417 -387.021376) (xy 90.399362 -387.001004) (xy 90.40114 -386.9944)
			(xy 90.40114 -386.90423) (xy 90.393579 -386.896498) (xy 90.373845 -386.887699) (xy 90.36304 -386.887212)
			(xy 86.938358 -386.887212) (xy 86.928291 -386.887643) (xy 86.909699 -386.89537) (xy 86.90229 -386.902198)
			(xy 86.875874 -386.928614) (xy 86.868508 -386.935726) (xy 86.860888 -386.954522) (xy 86.860888 -387.0198)
			(xy 86.86129 -387.029082) (xy 86.867931 -387.046415) (xy 86.873842 -387.053582) (xy 86.87816 -387.058408)
			(xy 86.878668 -387.058916) (xy 86.885117 -387.066213) (xy 86.892437 -387.084241) (xy 86.892892 -387.093968)
			(xy 86.892892 -387.931152) (xy 86.892892 -387.933692) (xy 86.894082 -387.945034) (xy 86.904894 -387.965079)
			(xy 86.91372 -387.9723) (xy 86.977982 -388.01929) (xy 87.003128 -388.022846) (xy 87.01532 -388.01802)
			(xy 87.025067 -388.014632) (xy 87.045388 -388.011054) (xy 87.055706 -388.010908) (xy 87.237316 -388.010908)
			(xy 87.237824 -388.010654) (xy 87.246206 -388.010654) (xy 87.254588 -388.010654) (xy 87.255096 -388.010908)
			(xy 87.436706 -388.010908) (xy 87.451724 -388.011398) (xy 87.480737 -388.019172) (xy 87.50675 -388.034188)
			(xy 87.527992 -388.055424) (xy 87.543016 -388.081433) (xy 87.550797 -388.110444) (xy 87.55126 -388.125462)
			(xy 87.55126 -388.239) (xy 87.553038 -388.245604) (xy 87.558237 -388.265975) (xy 87.563847 -388.307641)
			(xy 87.564214 -388.328662) (xy 88.128348 -388.328662) (xy 88.128716 -388.307641) (xy 88.134326 -388.265975)
			(xy 88.139524 -388.245604) (xy 88.141048 -388.239) (xy 88.141048 -388.125462) (xy 88.141462 -388.110416)
			(xy 88.149269 -388.081356) (xy 88.164339 -388.05531) (xy 88.185645 -388.03406) (xy 88.211728 -388.019056)
			(xy 88.240809 -388.011323) (xy 88.255856 -388.010908) (xy 88.437466 -388.010908) (xy 88.437974 -388.010654)
			(xy 88.446356 -388.010654) (xy 88.454738 -388.010654) (xy 88.455246 -388.010908) (xy 88.636856 -388.010908)
			(xy 88.651884 -388.011419) (xy 88.680922 -388.019179) (xy 88.706966 -388.034182) (xy 88.728245 -388.055409)
			(xy 88.743313 -388.081416) (xy 88.751144 -388.110435) (xy 88.751664 -388.125462) (xy 88.751664 -388.239)
			(xy 88.753188 -388.245604) (xy 88.758379 -388.265977) (xy 88.76399 -388.307642) (xy 88.764364 -388.328662)
			(xy 88.764223 -388.343415) (xy 88.761548 -388.372799) (xy 88.75903 -388.387336) (xy 88.75769 -388.396575)
			(xy 88.760934 -388.414942) (xy 88.76538 -388.42315) (xy 88.78189 -388.450074) (xy 88.787054 -388.457857)
			(xy 88.801783 -388.469318) (xy 88.810592 -388.472426) (xy 88.835531 -388.480489) (xy 88.882517 -388.503702)
			(xy 88.925015 -388.534371) (xy 88.961853 -388.571649) (xy 88.992014 -388.614508) (xy 89.014668 -388.661768)
			(xy 89.022428 -388.686802) (xy 89.023952 -388.692644) (xy 89.343738 -389.245602) (xy 89.347802 -389.24992)
			(xy 89.36399 -389.267629) (xy 89.391356 -389.307037) (xy 89.412442 -389.350133) (xy 89.426762 -389.395924)
			(xy 89.433987 -389.443355) (xy 89.434416 -389.467344) (xy 89.433958 -389.492796) (xy 89.425785 -389.543038)
			(xy 89.409658 -389.591319) (xy 89.385995 -389.636388) (xy 89.355409 -389.677077) (xy 89.318692 -389.712333)
			(xy 89.298018 -389.727186) (xy 89.290194 -389.733155) (xy 89.279319 -389.749528) (xy 89.275399 -389.768789)
			(xy 89.27901 -389.78811) (xy 89.289621 -389.804656) (xy 89.305675 -389.815996) (xy 89.324815 -389.820468)
			(xy 89.334594 -389.819388) (xy 89.343171 -389.818087) (xy 89.360463 -389.816686) (xy 89.369138 -389.816594)
			(xy 89.369392 -389.816848) (xy 89.668604 -389.816848) (xy 89.668858 -389.816594) (xy 89.689905 -389.816981)
			(xy 89.731226 -389.82498) (xy 89.770181 -389.840915) (xy 89.805263 -389.864168) (xy 89.835114 -389.893839)
			(xy 89.858578 -389.928779) (xy 89.874747 -389.967638) (xy 89.882996 -390.00891) (xy 89.883488 -390.029954)
			(xy 89.883488 -390.284716) (xy 89.874344 -390.284716) (xy 89.864355 -390.285271) (xy 89.845912 -390.292962)
			(xy 89.831778 -390.307088) (xy 89.824077 -390.325527) (xy 89.823544 -390.335516) (xy 89.823544 -390.499092)
			(xy 89.823006 -390.509094) (xy 89.815358 -390.527577) (xy 89.801221 -390.541729) (xy 89.782745 -390.549396)
			(xy 89.772744 -390.549892) (xy 89.265252 -390.549892) (xy 89.25524 -390.549451) (xy 89.236746 -390.541774)
			(xy 89.222594 -390.527607) (xy 89.214938 -390.509104) (xy 89.214452 -390.499092) (xy 89.214452 -390.284716)
			(xy 89.205308 -390.284716) (xy 89.195265 -390.284337) (xy 89.176683 -390.276731) (xy 89.162482 -390.262537)
			(xy 89.154867 -390.243958) (xy 89.154508 -390.233916) (xy 89.154508 -390.029954) (xy 89.155183 -390.004096)
			(xy 89.167521 -389.953874) (xy 89.178892 -389.93064) (xy 89.184988 -389.91921) (xy 89.184734 -389.89381)
			(xy 89.130632 -389.796782) (xy 89.109296 -389.783066) (xy 89.096342 -389.78205) (xy 89.072447 -389.779917)
			(xy 89.02566 -389.769319) (xy 88.981019 -389.751755) (xy 88.939555 -389.727629) (xy 88.902225 -389.6975)
			(xy 88.86989 -389.662063) (xy 88.843298 -389.622135) (xy 88.823063 -389.57864) (xy 88.815926 -389.555736)
			(xy 88.814402 -389.549894) (xy 88.493854 -388.995412) (xy 88.48979 -388.991094) (xy 88.473697 -388.973428)
			(xy 88.446507 -388.934131) (xy 88.425553 -388.891183) (xy 88.411315 -388.845567) (xy 88.404119 -388.798325)
			(xy 88.403684 -388.774432) (xy 88.403796 -388.760325) (xy 88.406212 -388.732217) (xy 88.40851 -388.718298)
			(xy 88.409749 -388.709101) (xy 88.406373 -388.690871) (xy 88.401906 -388.682738) (xy 88.385142 -388.655814)
			(xy 88.379955 -388.648095) (xy 88.365226 -388.636766) (xy 88.35644 -388.633716) (xy 88.334818 -388.626959)
			(xy 88.293609 -388.608144) (xy 88.255489 -388.58367) (xy 88.221228 -388.554033) (xy 88.206072 -388.537196)
			(xy 88.203601 -388.534376) (xy 88.197994 -388.529401) (xy 88.194896 -388.52729) (xy 88.182844 -388.519215)
			(xy 88.162883 -388.498179) (xy 88.148805 -388.472826) (xy 88.141502 -388.444761) (xy 88.141048 -388.430262)
			(xy 88.141048 -388.418324) (xy 88.139524 -388.41172) (xy 88.134317 -388.391351) (xy 88.128717 -388.349683)
			(xy 88.128348 -388.328662) (xy 87.564214 -388.328662) (xy 87.564051 -388.342387) (xy 87.561637 -388.369732)
			(xy 87.559388 -388.383272) (xy 87.559134 -388.385304) (xy 87.558626 -388.39013) (xy 87.558197 -388.39831)
			(xy 87.561952 -388.414246) (xy 87.565992 -388.421372) (xy 87.577422 -388.439914) (xy 87.579927 -388.443734)
			(xy 87.58606 -388.450505) (xy 87.589614 -388.453376) (xy 87.610696 -388.469632) (xy 87.618824 -388.472426)
			(xy 87.643658 -388.481194) (xy 87.690241 -388.50576) (xy 87.732142 -388.537663) (xy 87.768217 -388.57603)
			(xy 87.79748 -388.619815) (xy 87.819133 -388.667821) (xy 87.826342 -388.693152) (xy 87.82812 -388.699756)
			(xy 88.139016 -389.237728) (xy 88.143842 -389.2423) (xy 88.161183 -389.26033) (xy 88.19059 -389.300794)
			(xy 88.213305 -389.345359) (xy 88.22877 -389.39293) (xy 88.236603 -389.442334) (xy 88.23706 -389.467344)
			(xy 88.236529 -389.494482) (xy 88.227347 -389.547976) (xy 88.209207 -389.59913) (xy 88.182636 -389.646457)
			(xy 88.148407 -389.688578) (xy 88.128348 -389.706866) (xy 88.119712 -389.713978) (xy 88.110822 -389.73379)
			(xy 88.110822 -389.757412) (xy 88.110822 -389.759952) (xy 88.111703 -389.769535) (xy 88.119661 -389.787038)
			(xy 88.126316 -389.793988) (xy 88.134952 -389.80237) (xy 88.14228 -389.808915) (xy 88.160444 -389.816362)
			(xy 88.170258 -389.816848) (xy 88.468708 -389.816848) (xy 88.468962 -389.816594) (xy 88.490007 -389.81696)
			(xy 88.531324 -389.824962) (xy 88.570274 -389.8409) (xy 88.605349 -389.864157) (xy 88.63519 -389.893833)
			(xy 88.658642 -389.928778) (xy 88.674796 -389.967639) (xy 88.683027 -390.008911) (xy 88.683592 -390.029954)
			(xy 88.683592 -390.233916) (xy 88.683218 -390.24396) (xy 88.675592 -390.262538) (xy 88.661402 -390.276749)
			(xy 88.642835 -390.284404) (xy 88.632792 -390.284716) (xy 88.623648 -390.284716) (xy 88.623648 -390.499092)
			(xy 88.623162 -390.509104) (xy 88.615506 -390.527607) (xy 88.601354 -390.541774) (xy 88.58286 -390.549451)
			(xy 88.572848 -390.549892) (xy 88.128094 -390.549892) (xy 88.120257 -390.557403) (xy 88.111292 -390.577148)
			(xy 88.110822 -390.587992) (xy 88.110822 -391.174732) (xy 88.111285 -391.184608) (xy 88.118734 -391.202901)
			(xy 88.1253 -391.210292) (xy 88.125554 -391.210546) (xy 88.180672 -391.265664) (xy 88.18118 -391.266172)
			(xy 88.188563 -391.272748) (xy 88.206862 -391.280186) (xy 88.21674 -391.28065)
		)
		(stroke
			(width 0)
			(type solid)
		)
		(fill yes)
		(layer "B.Cu")
		(net "P1V8_CPU1_RT1_1A")
	)
	(gr_poly
		(pts
			(xy 380.686818 -399.66265) (xy 380.696696 -399.662191) (xy 380.714999 -399.654753) (xy 380.722378 -399.648172)
			(xy 380.722632 -399.647918) (xy 380.794768 -399.575782) (xy 380.79807 -399.572226) (xy 380.803471 -399.565213)
			(xy 380.809447 -399.548561) (xy 380.809754 -399.539714) (xy 380.809754 -398.177766) (xy 380.791974 -398.151858)
			(xy 380.776988 -398.14627) (xy 380.753703 -398.136823) (xy 380.710209 -398.111661) (xy 380.671216 -398.079969)
			(xy 380.637693 -398.042538) (xy 380.610477 -398.000299) (xy 380.590245 -397.954305) (xy 380.58344 -397.930116)
			(xy 380.581662 -397.923512) (xy 380.266448 -397.378174) (xy 380.262384 -397.373856) (xy 380.246169 -397.356157)
			(xy 380.218741 -397.316767) (xy 380.197598 -397.273675) (xy 380.183229 -397.227878) (xy 380.175966 -397.180432)
			(xy 380.175516 -397.156432) (xy 380.175685 -397.14232) (xy 380.178231 -397.114211) (xy 380.180596 -397.100298)
			(xy 380.181859 -397.091104) (xy 380.178457 -397.072875) (xy 380.173992 -397.064738) (xy 380.157228 -397.037814)
			(xy 380.152025 -397.03011) (xy 380.137303 -397.018783) (xy 380.128526 -397.015716) (xy 380.106908 -397.008945)
			(xy 380.065699 -396.990134) (xy 380.027576 -396.965665) (xy 379.993312 -396.936035) (xy 379.978158 -396.919196)
			(xy 379.9757 -396.916364) (xy 379.970084 -396.911397) (xy 379.966982 -396.90929) (xy 379.954937 -396.901229)
			(xy 379.935031 -396.880176) (xy 379.921025 -396.854811) (xy 379.91381 -396.82675) (xy 379.913388 -396.812262)
			(xy 379.913388 -396.800324) (xy 379.91161 -396.79372) (xy 379.906415 -396.773349) (xy 379.900814 -396.731682)
			(xy 379.900434 -396.710662) (xy 379.900808 -396.689642) (xy 379.906419 -396.647977) (xy 379.91161 -396.627604)
			(xy 379.913388 -396.621) (xy 379.913388 -396.507462) (xy 379.913839 -396.492445) (xy 379.921622 -396.463436)
			(xy 379.936649 -396.43743) (xy 379.957894 -396.4162) (xy 379.98391 -396.401191) (xy 380.012924 -396.393428)
			(xy 380.027942 -396.392908) (xy 380.209552 -396.392908) (xy 380.21006 -396.392654) (xy 380.218442 -396.392654)
			(xy 380.226824 -396.392654) (xy 380.227332 -396.392908) (xy 380.408942 -396.392908) (xy 380.423957 -396.393403)
			(xy 380.452962 -396.401182) (xy 380.478967 -396.416201) (xy 380.500201 -396.437436) (xy 380.515219 -396.463442)
			(xy 380.522998 -396.492447) (xy 380.523496 -396.507462) (xy 380.523496 -396.621) (xy 380.525274 -396.627604)
			(xy 380.530472 -396.647975) (xy 380.536082 -396.689641) (xy 380.53645 -396.710662) (xy 380.536319 -396.725416)
			(xy 380.533647 -396.754801) (xy 380.531116 -396.769336) (xy 380.529748 -396.778574) (xy 380.533004 -396.796946)
			(xy 380.537466 -396.80515) (xy 380.553976 -396.832074) (xy 380.559151 -396.839848) (xy 380.573874 -396.851309)
			(xy 380.582678 -396.854426) (xy 380.607524 -396.862522) (xy 380.654353 -396.885704) (xy 380.69673 -396.916275)
			(xy 380.7335 -396.953401) (xy 380.76366 -396.996071) (xy 380.786389 -397.043121) (xy 380.79426 -397.06804)
			(xy 380.795784 -397.073882) (xy 381.039624 -397.495522) (xy 381.045981 -397.505357) (xy 381.065438 -397.51834)
			(xy 381.076962 -397.520414) (xy 381.088646 -397.521938) (xy 381.110744 -397.514318) (xy 381.36449 -397.260572)
			(xy 381.372662 -397.251272) (xy 381.379944 -397.227652) (xy 381.37846 -397.21536) (xy 381.375857 -397.200767)
			(xy 381.373061 -397.171254) (xy 381.372872 -397.156432) (xy 381.373036 -397.142707) (xy 381.37545 -397.115363)
			(xy 381.377698 -397.101822) (xy 381.377952 -397.09979) (xy 381.37846 -397.094964) (xy 381.378889 -397.086784)
			(xy 381.37513 -397.07085) (xy 381.371094 -397.063722) (xy 381.359664 -397.04518) (xy 381.357158 -397.04136)
			(xy 381.351023 -397.034592) (xy 381.347472 -397.031718) (xy 381.32639 -397.015462) (xy 381.318262 -397.012668)
			(xy 381.291405 -397.003099) (xy 381.241347 -396.975821) (xy 381.19694 -396.940073) (xy 381.1778 -396.918942)
			(xy 381.175319 -396.916188) (xy 381.169713 -396.911338) (xy 381.166624 -396.90929) (xy 381.154584 -396.901226)
			(xy 381.134688 -396.880169) (xy 381.120689 -396.854806) (xy 381.113479 -396.826747) (xy 381.11303 -396.812262)
			(xy 381.11303 -396.800832) (xy 381.111252 -396.794228) (xy 381.106031 -396.773732) (xy 381.100428 -396.73181)
			(xy 381.100076 -396.710662) (xy 381.100076 -396.710154) (xy 381.100435 -396.68907) (xy 381.106041 -396.647275)
			(xy 381.111252 -396.626842) (xy 381.11303 -396.620238) (xy 381.11303 -396.166086) (xy 381.111252 -396.159482)
			(xy 381.106042 -396.139049) (xy 381.100433 -396.097254) (xy 381.100076 -396.07617) (xy 381.100076 -396.075662)
			(xy 381.100426 -396.054515) (xy 381.106039 -396.012594) (xy 381.111252 -395.992096) (xy 381.11303 -395.985492)
			(xy 381.11303 -395.974062) (xy 381.113477 -395.959671) (xy 381.120601 -395.931786) (xy 381.134396 -395.906526)
			(xy 381.154008 -395.88546) (xy 381.165862 -395.877288) (xy 381.166878 -395.872462) (xy 381.16779 -395.867287)
			(xy 381.16767 -395.856783) (xy 381.166624 -395.851634) (xy 381.149606 -395.77772) (xy 381.146766 -395.767331)
			(xy 381.133883 -395.750094) (xy 381.124714 -395.744446) (xy 381.12446 -395.744446) (xy 381.100139 -395.730334)
			(xy 381.056448 -395.694947) (xy 381.037592 -395.674088) (xy 381.035109 -395.671336) (xy 381.0295 -395.666492)
			(xy 381.026416 -395.664436) (xy 381.014465 -395.656334) (xy 380.994684 -395.635315) (xy 380.980749 -395.610039)
			(xy 380.973535 -395.582093) (xy 380.973076 -395.567662) (xy 380.973076 -395.556486) (xy 380.971298 -395.549882)
			(xy 380.966062 -395.529324) (xy 380.960452 -395.487274) (xy 380.960122 -395.466062) (xy 380.960456 -395.44485)
			(xy 380.966062 -395.4028) (xy 380.971298 -395.382242) (xy 380.973076 -395.375638) (xy 380.973076 -395.286738)
			(xy 380.965526 -395.278818) (xy 380.945651 -395.269717) (xy 380.934722 -395.269212) (xy 377.510294 -395.269212)
			(xy 377.500225 -395.269637) (xy 377.481623 -395.277354) (xy 377.474226 -395.284198) (xy 377.44781 -395.310614)
			(xy 377.440444 -395.317726) (xy 377.432824 -395.336522) (xy 377.432824 -395.4018) (xy 377.433226 -395.411081)
			(xy 377.439871 -395.428412) (xy 377.445778 -395.435582) (xy 377.450096 -395.440408) (xy 377.450604 -395.440916)
			(xy 377.457162 -395.448239) (xy 377.464631 -395.466404) (xy 377.465082 -395.476222) (xy 377.465082 -396.313406)
			(xy 377.465747 -396.325434) (xy 377.476605 -396.346905) (xy 377.48591 -396.354554) (xy 377.549918 -396.40129)
			(xy 377.575064 -396.404846) (xy 377.587256 -396.400274) (xy 377.597059 -396.396823) (xy 377.617506 -396.39312)
			(xy 377.627896 -396.392908) (xy 377.809506 -396.392908) (xy 377.810014 -396.392654) (xy 377.818396 -396.392654)
			(xy 377.826778 -396.392654) (xy 377.827286 -396.392908) (xy 378.008896 -396.392908) (xy 378.023925 -396.393396)
			(xy 378.052961 -396.401164) (xy 378.079002 -396.416174) (xy 378.100278 -396.437406) (xy 378.115343 -396.463415)
			(xy 378.123172 -396.492434) (xy 378.123704 -396.507462) (xy 378.123704 -396.621) (xy 378.125228 -396.627604)
			(xy 378.130427 -396.647975) (xy 378.136037 -396.689641) (xy 378.136404 -396.710662) (xy 378.700538 -396.710662)
			(xy 378.700907 -396.689641) (xy 378.706516 -396.647975) (xy 378.711714 -396.627604) (xy 378.713492 -396.621)
			(xy 378.713492 -396.507462) (xy 378.71386 -396.492434) (xy 378.721649 -396.463404) (xy 378.736686 -396.43738)
			(xy 378.757947 -396.416135) (xy 378.783982 -396.401116) (xy 378.813018 -396.393349) (xy 378.828046 -396.392908)
			(xy 379.009656 -396.392908) (xy 379.010164 -396.392654) (xy 379.018546 -396.392654) (xy 379.026928 -396.392654)
			(xy 379.027436 -396.392908) (xy 379.209046 -396.392908) (xy 379.224062 -396.393395) (xy 379.253068 -396.401176)
			(xy 379.279074 -396.416196) (xy 379.300309 -396.437433) (xy 379.315327 -396.463439) (xy 379.323106 -396.492446)
			(xy 379.3236 -396.507462) (xy 379.3236 -396.621) (xy 379.325378 -396.627604) (xy 379.33057 -396.647976)
			(xy 379.33618 -396.689642) (xy 379.336554 -396.710662) (xy 379.336414 -396.725415) (xy 379.333738 -396.754799)
			(xy 379.33122 -396.769336) (xy 379.329881 -396.778575) (xy 379.333124 -396.796942) (xy 379.33757 -396.80515)
			(xy 379.35408 -396.832074) (xy 379.359248 -396.839854) (xy 379.373974 -396.851316) (xy 379.382782 -396.854426)
			(xy 379.407738 -396.862438) (xy 379.454723 -396.885665) (xy 379.497218 -396.916345) (xy 379.534051 -396.953632)
			(xy 379.564209 -396.9965) (xy 379.586859 -397.043765) (xy 379.594618 -397.068802) (xy 379.596142 -397.074644)
			(xy 379.915928 -397.627602) (xy 379.919992 -397.63192) (xy 379.936182 -397.64964) (xy 379.963609 -397.689027)
			(xy 379.984754 -397.732114) (xy 379.999131 -397.777906) (xy 380.006408 -397.825346) (xy 380.00686 -397.849344)
			(xy 380.006355 -397.874805) (xy 379.998158 -397.925065) (xy 379.981998 -397.973356) (xy 379.958297 -398.018427)
			(xy 379.927667 -398.059109) (xy 379.890904 -398.094346) (xy 379.870208 -398.109186) (xy 379.86239 -398.115161)
			(xy 379.851519 -398.131533) (xy 379.847601 -398.150791) (xy 379.851211 -398.170109) (xy 379.86182 -398.186652)
			(xy 379.87787 -398.197992) (xy 379.897007 -398.202466) (xy 379.906784 -398.201388) (xy 379.915361 -398.200088)
			(xy 379.932654 -398.198687) (xy 379.941328 -398.198594) (xy 379.941582 -398.198848) (xy 380.240794 -398.198848)
			(xy 380.241048 -398.198594) (xy 380.26211 -398.19901) (xy 380.303468 -398.206962) (xy 380.342466 -398.222864)
			(xy 380.377592 -398.246101) (xy 380.407484 -398.275769) (xy 380.430982 -398.31072) (xy 380.447177 -398.349598)
			(xy 380.455438 -398.390896) (xy 380.455932 -398.411954) (xy 380.455932 -398.666716) (xy 380.446788 -398.666716)
			(xy 380.436764 -398.66711) (xy 380.418244 -398.674787) (xy 380.404071 -398.688967) (xy 380.396405 -398.707492)
			(xy 380.395988 -398.717516) (xy 380.395988 -398.881092) (xy 380.395574 -398.891114) (xy 380.387904 -398.909633)
			(xy 380.37373 -398.923806) (xy 380.35521 -398.931475) (xy 380.345188 -398.931892) (xy 379.837188 -398.931892)
			(xy 379.827153 -398.931522) (xy 379.8086 -398.923875) (xy 379.794414 -398.909683) (xy 379.786774 -398.891127)
			(xy 379.786388 -398.881092) (xy 379.786388 -398.666716) (xy 379.777244 -398.666716) (xy 379.767228 -398.666245)
			(xy 379.748715 -398.658592) (xy 379.734541 -398.644436) (xy 379.726867 -398.625932) (xy 379.726444 -398.615916)
			(xy 379.726444 -398.411954) (xy 379.726786 -398.394721) (xy 379.732357 -398.360708) (xy 379.743331 -398.328035)
			(xy 379.751082 -398.31264) (xy 379.757178 -398.30121) (xy 379.756924 -398.27581) (xy 379.702822 -398.178782)
			(xy 379.681486 -398.165066) (xy 379.668532 -398.16405) (xy 379.644636 -398.161926) (xy 379.597849 -398.151326)
			(xy 379.553208 -398.13376) (xy 379.511744 -398.109633) (xy 379.474414 -398.079503) (xy 379.44208 -398.044065)
			(xy 379.415488 -398.004137) (xy 379.395252 -397.96064) (xy 379.388116 -397.937736) (xy 379.386592 -397.931894)
			(xy 379.066044 -397.377412) (xy 379.06198 -397.373094) (xy 379.045882 -397.35542) (xy 379.018632 -397.316143)
			(xy 378.997619 -397.273204) (xy 378.983326 -397.227586) (xy 378.976079 -397.180334) (xy 378.97562 -397.156432)
			(xy 378.975784 -397.14232) (xy 378.978332 -397.114211) (xy 378.9807 -397.100298) (xy 378.981926 -397.091101)
			(xy 378.978557 -397.072872) (xy 378.974096 -397.064738) (xy 378.957332 -397.037814) (xy 378.952149 -397.030092)
			(xy 378.937417 -397.018764) (xy 378.92863 -397.015716) (xy 378.907019 -397.008925) (xy 378.865809 -396.990121)
			(xy 378.827685 -396.965657) (xy 378.79342 -396.936029) (xy 378.778262 -396.919196) (xy 378.775793 -396.916375)
			(xy 378.770185 -396.9114) (xy 378.767086 -396.90929) (xy 378.75506 -396.901207) (xy 378.735169 -396.880148)
			(xy 378.72116 -396.854793) (xy 378.713919 -396.826746) (xy 378.713492 -396.812262) (xy 378.713492 -396.800324)
			(xy 378.711714 -396.79372) (xy 378.706507 -396.773351) (xy 378.700907 -396.731683) (xy 378.700538 -396.710662)
			(xy 378.136404 -396.710662) (xy 378.136259 -396.724965) (xy 378.133715 -396.753456) (xy 378.131324 -396.767558)
			(xy 378.129546 -396.776956) (xy 378.132848 -396.795244) (xy 378.149358 -396.821914) (xy 378.151865 -396.825733)
			(xy 378.158 -396.8325) (xy 378.16155 -396.835376) (xy 378.182632 -396.851632) (xy 378.19076 -396.854426)
			(xy 378.215538 -396.863186) (xy 378.262045 -396.887656) (xy 378.303898 -396.919435) (xy 378.33996 -396.957661)
			(xy 378.36925 -397.001293) (xy 378.390971 -397.049145) (xy 378.398278 -397.07439) (xy 378.400056 -397.080994)
			(xy 378.711714 -397.620236) (xy 378.716286 -397.624808) (xy 378.733532 -397.642825) (xy 378.762766 -397.68323)
			(xy 378.785339 -397.727699) (xy 378.800701 -397.775146) (xy 378.808473 -397.824408) (xy 378.808996 -397.849344)
			(xy 378.808465 -397.876483) (xy 378.799284 -397.929977) (xy 378.781145 -397.981132) (xy 378.754576 -398.028461)
			(xy 378.72035 -398.070586) (xy 378.700284 -398.088866) (xy 378.691648 -398.095978) (xy 378.682758 -398.11579)
			(xy 378.682758 -398.139412) (xy 378.682758 -398.141952) (xy 378.683637 -398.151536) (xy 378.691588 -398.169046)
			(xy 378.698252 -398.175988) (xy 378.706888 -398.18437) (xy 378.714218 -398.19091) (xy 378.732382 -398.198344)
			(xy 378.742194 -398.198848) (xy 379.040898 -398.198848) (xy 379.041152 -398.198594) (xy 379.062217 -398.198931)
			(xy 379.103583 -398.206888) (xy 379.142586 -398.222798) (xy 379.177715 -398.246045) (xy 379.207605 -398.275727)
			(xy 379.231098 -398.310692) (xy 379.247281 -398.349583) (xy 379.255527 -398.390892) (xy 379.256036 -398.411954)
			(xy 379.256036 -398.615916) (xy 379.255546 -398.625924) (xy 379.247885 -398.644417) (xy 379.233734 -398.658573)
			(xy 379.215244 -398.666242) (xy 379.205236 -398.666716) (xy 379.196092 -398.666716) (xy 379.196092 -398.881092)
			(xy 379.195674 -398.891114) (xy 379.188005 -398.909632) (xy 379.173832 -398.923805) (xy 379.155314 -398.931474)
			(xy 379.145292 -398.931892) (xy 378.70003 -398.931892) (xy 378.692189 -398.939401) (xy 378.683217 -398.959147)
			(xy 378.682758 -398.969992) (xy 378.682758 -399.556732) (xy 378.683219 -399.566609) (xy 378.690662 -399.584908)
			(xy 378.697236 -399.592292) (xy 378.69749 -399.592546) (xy 378.752608 -399.647664) (xy 378.753116 -399.648172)
			(xy 378.760496 -399.654758) (xy 378.778795 -399.662219) (xy 378.788676 -399.66265)
		)
		(stroke
			(width 0)
			(type solid)
		)
		(fill yes)
		(layer "B.Cu")
		(net "P1V8_CPU0_RT3_1A")
	)
	(gr_poly
		(pts
			(xy 413.214566 -399.66265) (xy 413.22444 -399.662183) (xy 413.242731 -399.654733) (xy 413.250126 -399.648172)
			(xy 413.25038 -399.647918) (xy 413.322516 -399.575782) (xy 413.325818 -399.572226) (xy 413.331224 -399.565215)
			(xy 413.337205 -399.548563) (xy 413.337502 -399.539714) (xy 413.337502 -398.177766) (xy 413.319722 -398.151858)
			(xy 413.304736 -398.14627) (xy 413.281449 -398.136825) (xy 413.237949 -398.111667) (xy 413.19895 -398.079979)
			(xy 413.165423 -398.042548) (xy 413.138202 -398.000309) (xy 413.117966 -397.954313) (xy 413.111188 -397.930116)
			(xy 413.10941 -397.923512) (xy 412.794196 -397.378174) (xy 412.790132 -397.373856) (xy 412.773915 -397.356158)
			(xy 412.746483 -397.316769) (xy 412.725337 -397.273678) (xy 412.710965 -397.22788) (xy 412.703701 -397.180432)
			(xy 412.703264 -397.156432) (xy 412.703433 -397.14232) (xy 412.70598 -397.114211) (xy 412.708344 -397.100298)
			(xy 412.709606 -397.091103) (xy 412.706208 -397.072874) (xy 412.70174 -397.064738) (xy 412.684976 -397.037814)
			(xy 412.679776 -397.030105) (xy 412.665058 -397.018764) (xy 412.656274 -397.015716) (xy 412.634658 -397.008942)
			(xy 412.593453 -396.990125) (xy 412.555336 -396.965653) (xy 412.521076 -396.936019) (xy 412.505906 -396.919196)
			(xy 412.50345 -396.916362) (xy 412.497836 -396.911391) (xy 412.49473 -396.90929) (xy 412.48269 -396.901226)
			(xy 412.462792 -396.88017) (xy 412.448793 -396.854806) (xy 412.441582 -396.826748) (xy 412.441136 -396.812262)
			(xy 412.441136 -396.800324) (xy 412.439358 -396.79372) (xy 412.434164 -396.773348) (xy 412.428564 -396.731682)
			(xy 412.428182 -396.710662) (xy 412.428556 -396.689642) (xy 412.434166 -396.647976) (xy 412.439358 -396.627604)
			(xy 412.441136 -396.621) (xy 412.441136 -396.507462) (xy 412.44163 -396.492448) (xy 412.44941 -396.463445)
			(xy 412.464429 -396.437442) (xy 412.485665 -396.416212) (xy 412.511671 -396.401199) (xy 412.540676 -396.393427)
			(xy 412.55569 -396.392908) (xy 412.7373 -396.392908) (xy 412.737808 -396.392654) (xy 412.74619 -396.392654)
			(xy 412.754572 -396.392654) (xy 412.75508 -396.392908) (xy 412.93669 -396.392908) (xy 412.95171 -396.393396)
			(xy 412.980726 -396.401167) (xy 413.006743 -396.416182) (xy 413.027988 -396.437419) (xy 413.043014 -396.46343)
			(xy 413.050797 -396.492443) (xy 413.051244 -396.507462) (xy 413.051244 -396.621) (xy 413.053022 -396.627604)
			(xy 413.058221 -396.647975) (xy 413.063832 -396.689641) (xy 413.064198 -396.710662) (xy 413.064067 -396.725416)
			(xy 413.061395 -396.754801) (xy 413.058864 -396.769336) (xy 413.057497 -396.778574) (xy 413.06075 -396.796948)
			(xy 413.065214 -396.80515) (xy 413.081724 -396.832074) (xy 413.086902 -396.839843) (xy 413.10163 -396.851291)
			(xy 413.110426 -396.854426) (xy 413.135275 -396.862519) (xy 413.18211 -396.885696) (xy 413.224494 -396.916263)
			(xy 413.261269 -396.953388) (xy 413.291435 -396.996058) (xy 413.314168 -397.04311) (xy 413.322008 -397.06804)
			(xy 413.323532 -397.073882) (xy 413.567372 -397.495522) (xy 413.573732 -397.50535) (xy 413.593192 -397.518315)
			(xy 413.60471 -397.520414) (xy 413.616394 -397.521938) (xy 413.638492 -397.514318) (xy 413.892238 -397.260572)
			(xy 413.900403 -397.25127) (xy 413.907679 -397.227653) (xy 413.906208 -397.21536) (xy 413.903605 -397.200767)
			(xy 413.900808 -397.171254) (xy 413.90062 -397.156432) (xy 413.900784 -397.142707) (xy 413.903198 -397.115363)
			(xy 413.905446 -397.101822) (xy 413.9057 -397.09979) (xy 413.906208 -397.094964) (xy 413.906636 -397.086784)
			(xy 413.902875 -397.070852) (xy 413.898842 -397.063722) (xy 413.887412 -397.04518) (xy 413.884908 -397.041359)
			(xy 413.878777 -397.034586) (xy 413.87522 -397.031718) (xy 413.854138 -397.015462) (xy 413.84601 -397.012668)
			(xy 413.81915 -397.003103) (xy 413.769087 -396.97583) (xy 413.724675 -396.940086) (xy 413.705548 -396.918942)
			(xy 413.703065 -396.91619) (xy 413.697457 -396.911345) (xy 413.694372 -396.90929) (xy 413.682328 -396.901229)
			(xy 413.662423 -396.880174) (xy 413.648419 -396.85481) (xy 413.641205 -396.826749) (xy 413.640778 -396.812262)
			(xy 413.640778 -396.800832) (xy 413.639 -396.794228) (xy 413.63378 -396.773732) (xy 413.628177 -396.73181)
			(xy 413.627824 -396.710662) (xy 413.627824 -396.710154) (xy 413.628183 -396.68907) (xy 413.633789 -396.647275)
			(xy 413.639 -396.626842) (xy 413.640778 -396.620238) (xy 413.640778 -396.166086) (xy 413.639 -396.159482)
			(xy 413.633789 -396.139049) (xy 413.62818 -396.097254) (xy 413.627824 -396.07617) (xy 413.627824 -396.075662)
			(xy 413.628174 -396.054515) (xy 413.633786 -396.012594) (xy 413.639 -395.992096) (xy 413.640778 -395.985492)
			(xy 413.640778 -395.974062) (xy 413.641226 -395.959672) (xy 413.648351 -395.931789) (xy 413.662151 -395.906534)
			(xy 413.681766 -395.885475) (xy 413.69361 -395.877288) (xy 413.694626 -395.872462) (xy 413.695539 -395.867287)
			(xy 413.695419 -395.856783) (xy 413.694372 -395.851634) (xy 413.677354 -395.77772) (xy 413.674511 -395.767334)
			(xy 413.661622 -395.750108) (xy 413.652462 -395.744446) (xy 413.652208 -395.744446) (xy 413.62789 -395.730331)
			(xy 413.584203 -395.69494) (xy 413.56534 -395.674088) (xy 413.562855 -395.671338) (xy 413.557243 -395.666498)
			(xy 413.554164 -395.664436) (xy 413.542209 -395.656337) (xy 413.52242 -395.635321) (xy 413.508479 -395.610044)
			(xy 413.501261 -395.582095) (xy 413.500824 -395.567662) (xy 413.500824 -395.556486) (xy 413.499046 -395.549882)
			(xy 413.493809 -395.529324) (xy 413.488199 -395.487274) (xy 413.48787 -395.466062) (xy 413.488204 -395.44485)
			(xy 413.493811 -395.4028) (xy 413.499046 -395.382242) (xy 413.500824 -395.375638) (xy 413.500824 -395.286738)
			(xy 413.493271 -395.278827) (xy 413.473395 -395.269746) (xy 413.46247 -395.269212) (xy 410.038042 -395.269212)
			(xy 410.027977 -395.269646) (xy 410.009389 -395.277377) (xy 410.001974 -395.284198) (xy 409.975558 -395.310614)
			(xy 409.968192 -395.317726) (xy 409.960572 -395.336522) (xy 409.960572 -395.4018) (xy 409.960976 -395.41108)
			(xy 409.967625 -395.428408) (xy 409.973526 -395.435582) (xy 409.977844 -395.440408) (xy 409.978352 -395.440916)
			(xy 409.984905 -395.448242) (xy 409.992367 -395.466405) (xy 409.99283 -395.476222) (xy 409.99283 -396.313406)
			(xy 409.993497 -396.325433) (xy 410.004361 -396.346896) (xy 410.013658 -396.354554) (xy 410.077666 -396.40129)
			(xy 410.102812 -396.404846) (xy 410.115004 -396.400274) (xy 410.124806 -396.396819) (xy 410.145253 -396.393106)
			(xy 410.155644 -396.392908) (xy 410.337254 -396.392908) (xy 410.337762 -396.392654) (xy 410.346144 -396.392654)
			(xy 410.354526 -396.392654) (xy 410.355034 -396.392908) (xy 410.536644 -396.392908) (xy 410.551668 -396.393401)
			(xy 410.580694 -396.401178) (xy 410.606724 -396.416191) (xy 410.62799 -396.437421) (xy 410.643047 -396.463426)
			(xy 410.650873 -396.492439) (xy 410.651452 -396.507462) (xy 410.651452 -396.621) (xy 410.652976 -396.627604)
			(xy 410.658174 -396.647975) (xy 410.663784 -396.689641) (xy 410.664152 -396.710662) (xy 411.228286 -396.710662)
			(xy 411.228653 -396.689641) (xy 411.234263 -396.647975) (xy 411.239462 -396.627604) (xy 411.24124 -396.621)
			(xy 411.24124 -396.507462) (xy 411.241703 -396.492444) (xy 411.249484 -396.463433) (xy 411.264508 -396.437424)
			(xy 411.28575 -396.416188) (xy 411.311763 -396.401172) (xy 411.340776 -396.393398) (xy 411.355794 -396.392908)
			(xy 411.537404 -396.392908) (xy 411.537912 -396.392654) (xy 411.546294 -396.392654) (xy 411.554676 -396.392654)
			(xy 411.555184 -396.392908) (xy 411.736794 -396.392908) (xy 411.751807 -396.393441) (xy 411.780812 -396.40121)
			(xy 411.806818 -396.416219) (xy 411.828054 -396.437447) (xy 411.843073 -396.463447) (xy 411.850853 -396.492449)
			(xy 411.851348 -396.507462) (xy 411.851348 -396.621) (xy 411.853126 -396.627604) (xy 411.858317 -396.647977)
			(xy 411.863928 -396.689642) (xy 411.864302 -396.710662) (xy 411.864162 -396.725415) (xy 411.861486 -396.754799)
			(xy 411.858968 -396.769336) (xy 411.857623 -396.778575) (xy 411.860869 -396.796943) (xy 411.865318 -396.80515)
			(xy 411.881828 -396.832074) (xy 411.887014 -396.83984) (xy 411.901728 -396.85131) (xy 411.91053 -396.854426)
			(xy 411.935476 -396.862467) (xy 411.982462 -396.885687) (xy 412.024959 -396.91636) (xy 412.061794 -396.953642)
			(xy 412.091954 -396.996505) (xy 412.114606 -397.043767) (xy 412.122366 -397.068802) (xy 412.12389 -397.074644)
			(xy 412.443676 -397.627602) (xy 412.44774 -397.63192) (xy 412.463938 -397.649633) (xy 412.491362 -397.689023)
			(xy 412.512505 -397.732111) (xy 412.52688 -397.777904) (xy 412.534156 -397.825346) (xy 412.534608 -397.849344)
			(xy 412.534125 -397.874807) (xy 412.525926 -397.925068) (xy 412.509764 -397.973361) (xy 412.486058 -398.018433)
			(xy 412.455423 -398.059114) (xy 412.418655 -398.094348) (xy 412.397956 -398.109186) (xy 412.390108 -398.115132)
			(xy 412.37922 -398.131511) (xy 412.375293 -398.150782) (xy 412.378906 -398.170115) (xy 412.389526 -398.186669)
			(xy 412.405594 -398.198011) (xy 412.424748 -398.202475) (xy 412.434532 -398.201388) (xy 412.443108 -398.200083)
			(xy 412.460401 -398.198685) (xy 412.469076 -398.198594) (xy 412.46933 -398.198848) (xy 412.768542 -398.198848)
			(xy 412.768796 -398.198594) (xy 412.789859 -398.198966) (xy 412.831219 -398.206927) (xy 412.870218 -398.222837)
			(xy 412.905343 -398.24608) (xy 412.935234 -398.275755) (xy 412.958732 -398.310711) (xy 412.974925 -398.349593)
			(xy 412.983186 -398.390894) (xy 412.98368 -398.411954) (xy 412.98368 -398.666716) (xy 412.974536 -398.666716)
			(xy 412.964515 -398.667149) (xy 412.945996 -398.674811) (xy 412.931822 -398.688979) (xy 412.924153 -398.707495)
			(xy 412.923736 -398.717516) (xy 412.923736 -398.881092) (xy 412.923206 -398.891095) (xy 412.915556 -398.909579)
			(xy 412.901416 -398.923731) (xy 412.882938 -398.931398) (xy 412.872936 -398.931892) (xy 412.364936 -398.931892)
			(xy 412.354898 -398.931564) (xy 412.336344 -398.923901) (xy 412.322159 -398.909696) (xy 412.314522 -398.891131)
			(xy 412.314136 -398.881092) (xy 412.314136 -398.666716) (xy 412.304992 -398.666716) (xy 412.294986 -398.666219)
			(xy 412.276497 -398.65856) (xy 412.262345 -398.64441) (xy 412.254683 -398.625922) (xy 412.254192 -398.615916)
			(xy 412.254192 -398.411954) (xy 412.25454 -398.394721) (xy 412.26011 -398.360709) (xy 412.27108 -398.328036)
			(xy 412.27883 -398.31264) (xy 412.284926 -398.30121) (xy 412.284672 -398.27581) (xy 412.23057 -398.178782)
			(xy 412.209234 -398.165066) (xy 412.19628 -398.16405) (xy 412.17238 -398.161968) (xy 412.125591 -398.15136)
			(xy 412.08095 -398.133787) (xy 412.039486 -398.109654) (xy 412.002157 -398.079518) (xy 411.969824 -398.044075)
			(xy 411.943234 -398.004142) (xy 411.923 -397.960642) (xy 411.915864 -397.937736) (xy 411.91434 -397.931894)
			(xy 411.593792 -397.377412) (xy 411.589728 -397.373094) (xy 411.573621 -397.355428) (xy 411.546374 -397.316148)
			(xy 411.525364 -397.273206) (xy 411.511073 -397.227587) (xy 411.503826 -397.180334) (xy 411.503368 -397.156432)
			(xy 411.503532 -397.14232) (xy 411.506079 -397.114211) (xy 411.508448 -397.100298) (xy 411.509681 -397.091101)
			(xy 411.506308 -397.072871) (xy 411.501844 -397.064738) (xy 411.48508 -397.037814) (xy 411.479879 -397.030106)
			(xy 411.46516 -397.018771) (xy 411.456378 -397.015716) (xy 411.43476 -397.008945) (xy 411.393551 -396.990134)
			(xy 411.355429 -396.965665) (xy 411.321167 -396.936031) (xy 411.30601 -396.919196) (xy 411.303535 -396.916381)
			(xy 411.297931 -396.911402) (xy 411.294834 -396.90929) (xy 411.282818 -396.901192) (xy 411.262923 -396.88014)
			(xy 411.248911 -396.85479) (xy 411.241668 -396.826744) (xy 411.24124 -396.812262) (xy 411.24124 -396.800324)
			(xy 411.239462 -396.79372) (xy 411.234256 -396.773351) (xy 411.228655 -396.731683) (xy 411.228286 -396.710662)
			(xy 410.664152 -396.710662) (xy 410.664007 -396.724965) (xy 410.661463 -396.753456) (xy 410.659072 -396.767558)
			(xy 410.657294 -396.776956) (xy 410.660596 -396.795244) (xy 410.677106 -396.821914) (xy 410.679611 -396.825735)
			(xy 410.685743 -396.832507) (xy 410.689298 -396.835376) (xy 410.71038 -396.851632) (xy 410.718508 -396.854426)
			(xy 410.743284 -396.863189) (xy 410.789785 -396.887663) (xy 410.831632 -396.919445) (xy 410.867688 -396.957672)
			(xy 410.896973 -397.001304) (xy 410.91869 -397.049154) (xy 410.926026 -397.07439) (xy 410.927804 -397.080994)
			(xy 411.239462 -397.620236) (xy 411.244034 -397.624808) (xy 411.261282 -397.642824) (xy 411.290521 -397.683227)
			(xy 411.313098 -397.727697) (xy 411.328462 -397.775144) (xy 411.336236 -397.824407) (xy 411.336744 -397.849344)
			(xy 411.336213 -397.876482) (xy 411.327031 -397.929975) (xy 411.30889 -397.981129) (xy 411.282318 -398.028455)
			(xy 411.248088 -398.070575) (xy 411.228032 -398.088866) (xy 411.219396 -398.095978) (xy 411.210506 -398.11579)
			(xy 411.210506 -398.139412) (xy 411.210506 -398.141952) (xy 411.211387 -398.151535) (xy 411.219343 -398.16904)
			(xy 411.226 -398.175988) (xy 411.234636 -398.18437) (xy 411.241964 -398.190918) (xy 411.260127 -398.19837)
			(xy 411.269942 -398.198848) (xy 411.568646 -398.198848) (xy 411.5689 -398.198594) (xy 411.589962 -398.198935)
			(xy 411.63132 -398.206899) (xy 411.670315 -398.222814) (xy 411.705436 -398.246063) (xy 411.735318 -398.275743)
			(xy 411.758804 -398.310705) (xy 411.774983 -398.349592) (xy 411.783227 -398.390895) (xy 411.783784 -398.411954)
			(xy 411.783784 -398.615916) (xy 411.783293 -398.62592) (xy 411.77563 -398.644404) (xy 411.761477 -398.658548)
			(xy 411.742989 -398.666199) (xy 411.732984 -398.666716) (xy 411.72384 -398.666716) (xy 411.72384 -398.881092)
			(xy 411.723354 -398.891104) (xy 411.715697 -398.909605) (xy 411.701545 -398.92377) (xy 411.683051 -398.931444)
			(xy 411.67304 -398.931892) (xy 411.227778 -398.931892) (xy 411.219943 -398.939404) (xy 411.210981 -398.959149)
			(xy 411.210506 -398.969992) (xy 411.210506 -399.556732) (xy 411.210969 -399.566608) (xy 411.218416 -399.584902)
			(xy 411.224984 -399.592292) (xy 411.225238 -399.592546) (xy 411.280356 -399.647664) (xy 411.280864 -399.648172)
			(xy 411.288247 -399.654751) (xy 411.306545 -399.662194) (xy 411.316424 -399.66265)
		)
		(stroke
			(width 0)
			(type solid)
		)
		(fill yes)
		(layer "B.Cu")
		(net "P1V8_CPU0_RT2_1A")
	)
	(gr_poly
		(pts
			(xy 124.687076 -391.28065) (xy 124.69695 -391.280181) (xy 124.715238 -391.272728) (xy 124.722636 -391.266172)
			(xy 124.72289 -391.265918) (xy 124.795026 -391.193782) (xy 124.798328 -391.190226) (xy 124.803733 -391.183214)
			(xy 124.809713 -391.166562) (xy 124.810012 -391.157714) (xy 124.810012 -389.795766) (xy 124.792232 -389.769858)
			(xy 124.777246 -389.76427) (xy 124.754018 -389.754826) (xy 124.710628 -389.729699) (xy 124.671717 -389.698075)
			(xy 124.63825 -389.660738) (xy 124.611054 -389.618614) (xy 124.590804 -389.572744) (xy 124.583952 -389.548624)
			(xy 124.582174 -389.542274) (xy 124.266452 -388.996174) (xy 124.262388 -388.991856) (xy 124.246173 -388.974157)
			(xy 124.218744 -388.934767) (xy 124.197601 -388.891676) (xy 124.183232 -388.845878) (xy 124.175969 -388.798432)
			(xy 124.17552 -388.774432) (xy 124.175689 -388.76032) (xy 124.178236 -388.732211) (xy 124.1806 -388.718298)
			(xy 124.181863 -388.709104) (xy 124.178461 -388.690875) (xy 124.173996 -388.682738) (xy 124.157232 -388.655814)
			(xy 124.152029 -388.648109) (xy 124.137308 -388.636781) (xy 124.12853 -388.633716) (xy 124.106912 -388.626945)
			(xy 124.065703 -388.608134) (xy 124.02758 -388.583666) (xy 123.993314 -388.554036) (xy 123.978162 -388.537196)
			(xy 123.975705 -388.534364) (xy 123.970088 -388.529397) (xy 123.966986 -388.52729) (xy 123.954941 -388.51923)
			(xy 123.935034 -388.498176) (xy 123.921027 -388.472812) (xy 123.913812 -388.44475) (xy 123.913392 -388.430262)
			(xy 123.913392 -388.418324) (xy 123.911614 -388.41172) (xy 123.906421 -388.391348) (xy 123.900821 -388.349682)
			(xy 123.900438 -388.328662) (xy 123.900812 -388.307642) (xy 123.906421 -388.265976) (xy 123.911614 -388.245604)
			(xy 123.913392 -388.239) (xy 123.913392 -388.125462) (xy 123.913843 -388.110445) (xy 123.921626 -388.081436)
			(xy 123.936653 -388.055431) (xy 123.957898 -388.034201) (xy 123.983914 -388.019194) (xy 124.012929 -388.011432)
			(xy 124.027946 -388.010908) (xy 124.209556 -388.010908) (xy 124.210064 -388.010654) (xy 124.218446 -388.010654)
			(xy 124.226828 -388.010654) (xy 124.227336 -388.010908) (xy 124.408946 -388.010908) (xy 124.423961 -388.011403)
			(xy 124.452965 -388.019184) (xy 124.478969 -388.034202) (xy 124.500202 -388.055437) (xy 124.51522 -388.081443)
			(xy 124.522998 -388.110447) (xy 124.5235 -388.125462) (xy 124.5235 -388.239) (xy 124.525278 -388.245604)
			(xy 124.530476 -388.265975) (xy 124.536086 -388.307641) (xy 124.536454 -388.328662) (xy 124.536323 -388.343416)
			(xy 124.533651 -388.372801) (xy 124.53112 -388.387336) (xy 124.529753 -388.396575) (xy 124.533004 -388.414949)
			(xy 124.53747 -388.42315) (xy 124.55398 -388.450074) (xy 124.559155 -388.457847) (xy 124.573879 -388.469308)
			(xy 124.582682 -388.472426) (xy 124.607528 -388.480522) (xy 124.654357 -388.503705) (xy 124.696733 -388.534275)
			(xy 124.733502 -388.571402) (xy 124.763662 -388.614072) (xy 124.78639 -388.661122) (xy 124.794264 -388.68604)
			(xy 124.795788 -388.691882) (xy 125.039628 -389.113522) (xy 125.045985 -389.123356) (xy 125.065442 -389.136338)
			(xy 125.076966 -389.138414) (xy 125.08865 -389.140192) (xy 125.110748 -389.132572) (xy 125.364748 -388.878572)
			(xy 125.372925 -388.869274) (xy 125.380214 -388.845652) (xy 125.378718 -388.83336) (xy 125.376115 -388.818767)
			(xy 125.373318 -388.789254) (xy 125.37313 -388.774432) (xy 125.373294 -388.760707) (xy 125.375708 -388.733363)
			(xy 125.377956 -388.719822) (xy 125.37821 -388.71779) (xy 125.378718 -388.712964) (xy 125.379146 -388.704784)
			(xy 125.375385 -388.688852) (xy 125.371352 -388.681722) (xy 125.359922 -388.66318) (xy 125.357414 -388.659362)
			(xy 125.351277 -388.652597) (xy 125.34773 -388.649718) (xy 125.326648 -388.633462) (xy 125.31852 -388.630668)
			(xy 125.291681 -388.621126) (xy 125.241642 -388.59392) (xy 125.197224 -388.558269) (xy 125.178058 -388.537196)
			(xy 125.175538 -388.534354) (xy 125.169803 -388.529374) (xy 125.166628 -388.52729) (xy 125.154588 -388.519226)
			(xy 125.134691 -388.498169) (xy 125.120692 -388.472806) (xy 125.113481 -388.444748) (xy 125.113034 -388.430262)
			(xy 125.113034 -388.418578) (xy 125.111256 -388.411974) (xy 125.106051 -388.39154) (xy 125.100444 -388.349746)
			(xy 125.10008 -388.328662) (xy 125.100334 -388.320788) (xy 125.101096 -388.30182) (xy 125.106575 -388.264255)
			(xy 125.111256 -388.245858) (xy 125.113034 -388.239254) (xy 125.113034 -387.78307) (xy 125.111256 -387.776466)
			(xy 125.106221 -387.756457) (xy 125.100747 -387.715561) (xy 125.100334 -387.694932) (xy 125.100334 -387.689344)
			(xy 125.100908 -387.669481) (xy 125.10638 -387.630122) (xy 125.111256 -387.610858) (xy 125.113034 -387.604508)
			(xy 125.113034 -387.592062) (xy 125.113444 -387.577622) (xy 125.120633 -387.54965) (xy 125.134572 -387.524356)
			(xy 125.15438 -387.503339) (xy 125.166374 -387.495288) (xy 125.167136 -387.490462) (xy 125.168048 -387.485287)
			(xy 125.167929 -387.474783) (xy 125.166882 -387.469634) (xy 125.147324 -387.384798) (xy 125.134624 -387.36778)
			(xy 125.124718 -387.362446) (xy 125.10048 -387.348451) (xy 125.056919 -387.313317) (xy 125.038104 -387.292596)
			(xy 125.035648 -387.289762) (xy 125.030034 -387.284791) (xy 125.026928 -387.28269) (xy 125.014864 -387.274634)
			(xy 124.994909 -387.253588) (xy 124.980837 -387.22823) (xy 124.973536 -387.200162) (xy 124.97308 -387.185662)
			(xy 124.97308 -387.173724) (xy 124.971556 -387.16712) (xy 124.966362 -387.146748) (xy 124.960762 -387.105082)
			(xy 124.96038 -387.084062) (xy 124.960754 -387.063042) (xy 124.966364 -387.021376) (xy 124.971556 -387.001004)
			(xy 124.97308 -386.9944) (xy 124.97308 -386.904484) (xy 124.965567 -386.896653) (xy 124.945821 -386.887701)
			(xy 124.93498 -386.887212) (xy 121.510552 -386.887212) (xy 121.500486 -386.887644) (xy 121.481895 -386.895372)
			(xy 121.474484 -386.902198) (xy 121.448068 -386.928614) (xy 121.440702 -386.935726) (xy 121.433082 -386.954522)
			(xy 121.433082 -387.0198) (xy 121.433483 -387.029082) (xy 121.440123 -387.046416) (xy 121.446036 -387.053582)
			(xy 121.450354 -387.058408) (xy 121.450862 -387.058916) (xy 121.457414 -387.066242) (xy 121.464874 -387.084406)
			(xy 121.46534 -387.094222) (xy 121.46534 -387.931406) (xy 121.466007 -387.943432) (xy 121.476873 -387.964894)
			(xy 121.486168 -387.972554) (xy 121.550176 -388.01929) (xy 121.575322 -388.022846) (xy 121.587514 -388.01802)
			(xy 121.597261 -388.014632) (xy 121.617582 -388.011053) (xy 121.6279 -388.010908) (xy 121.80951 -388.010908)
			(xy 121.810018 -388.010654) (xy 121.8184 -388.010654) (xy 121.826782 -388.010654) (xy 121.82729 -388.010908)
			(xy 122.0089 -388.010908) (xy 122.023928 -388.011396) (xy 122.052963 -388.019165) (xy 122.079004 -388.034176)
			(xy 122.100279 -388.055407) (xy 122.115343 -388.081416) (xy 122.123172 -388.110435) (xy 122.123708 -388.125462)
			(xy 122.123708 -388.239) (xy 122.125232 -388.245604) (xy 122.130431 -388.265975) (xy 122.136041 -388.307641)
			(xy 122.136408 -388.328662) (xy 122.700542 -388.328662) (xy 122.70091 -388.307641) (xy 122.70652 -388.265975)
			(xy 122.711718 -388.245604) (xy 122.713496 -388.239) (xy 122.713496 -388.125462) (xy 122.71386 -388.110434)
			(xy 122.721649 -388.081403) (xy 122.736687 -388.055379) (xy 122.757949 -388.034133) (xy 122.783985 -388.019115)
			(xy 122.813021 -388.011348) (xy 122.82805 -388.010908) (xy 123.00966 -388.010908) (xy 123.010168 -388.010654)
			(xy 123.01855 -388.010654) (xy 123.026932 -388.010654) (xy 123.02744 -388.010908) (xy 123.20905 -388.010908)
			(xy 123.224067 -388.011435) (xy 123.253081 -388.019197) (xy 123.279098 -388.034203) (xy 123.300343 -388.055432)
			(xy 123.31537 -388.081437) (xy 123.323153 -388.110445) (xy 123.323604 -388.125462) (xy 123.323604 -388.239)
			(xy 123.325382 -388.245604) (xy 123.330575 -388.265976) (xy 123.336184 -388.307642) (xy 123.336558 -388.328662)
			(xy 123.336417 -388.343415) (xy 123.333742 -388.372799) (xy 123.331224 -388.387336) (xy 123.329884 -388.396575)
			(xy 123.333128 -388.414942) (xy 123.337574 -388.42315) (xy 123.354084 -388.450074) (xy 123.35925 -388.457855)
			(xy 123.373978 -388.469317) (xy 123.382786 -388.472426) (xy 123.407743 -388.480436) (xy 123.454727 -388.503663)
			(xy 123.497222 -388.534344) (xy 123.534056 -388.571632) (xy 123.564213 -388.614499) (xy 123.586863 -388.661765)
			(xy 123.594622 -388.686802) (xy 123.596146 -388.692644) (xy 123.915932 -389.245602) (xy 123.919996 -389.24992)
			(xy 123.936187 -389.267639) (xy 123.963613 -389.307027) (xy 123.984759 -389.350114) (xy 123.999135 -389.395905)
			(xy 124.006412 -389.443346) (xy 124.006864 -389.467344) (xy 124.0064 -389.492808) (xy 123.9982 -389.543071)
			(xy 123.982035 -389.591365) (xy 123.958326 -389.636437) (xy 123.927687 -389.677117) (xy 123.890913 -389.71235)
			(xy 123.870212 -389.727186) (xy 123.862391 -389.733159) (xy 123.851519 -389.749531) (xy 123.8476 -389.76879)
			(xy 123.851211 -389.78811) (xy 123.86182 -389.804653) (xy 123.877872 -389.815994) (xy 123.89701 -389.820467)
			(xy 123.906788 -389.819388) (xy 123.915365 -389.818088) (xy 123.932658 -389.816686) (xy 123.941332 -389.816594)
			(xy 123.941586 -389.816848) (xy 124.240798 -389.816848) (xy 124.241052 -389.816594) (xy 124.262114 -389.817006)
			(xy 124.303472 -389.824959) (xy 124.34247 -389.840862) (xy 124.377596 -389.864099) (xy 124.407488 -389.893768)
			(xy 124.430987 -389.92872) (xy 124.447181 -389.967598) (xy 124.455442 -390.008896) (xy 124.455936 -390.029954)
			(xy 124.455936 -390.284716) (xy 124.446792 -390.284716) (xy 124.436768 -390.285113) (xy 124.418248 -390.292789)
			(xy 124.404076 -390.306968) (xy 124.396409 -390.325492) (xy 124.395992 -390.335516) (xy 124.395992 -390.499092)
			(xy 124.395574 -390.509114) (xy 124.387905 -390.527632) (xy 124.373732 -390.541805) (xy 124.355214 -390.549474)
			(xy 124.345192 -390.549892) (xy 123.837192 -390.549892) (xy 123.827157 -390.549518) (xy 123.808605 -390.541873)
			(xy 123.794418 -390.527682) (xy 123.786778 -390.509127) (xy 123.786392 -390.499092) (xy 123.786392 -390.284716)
			(xy 123.777248 -390.284716) (xy 123.767232 -390.284242) (xy 123.748719 -390.27659) (xy 123.734546 -390.262435)
			(xy 123.726871 -390.243932) (xy 123.726448 -390.233916) (xy 123.726448 -390.029954) (xy 123.726789 -390.012721)
			(xy 123.732361 -389.978708) (xy 123.743335 -389.946035) (xy 123.751086 -389.93064) (xy 123.757182 -389.91921)
			(xy 123.756928 -389.89381) (xy 123.702826 -389.796782) (xy 123.68149 -389.783066) (xy 123.668536 -389.78205)
			(xy 123.64464 -389.779922) (xy 123.597854 -389.769323) (xy 123.553213 -389.751758) (xy 123.511748 -389.727632)
			(xy 123.474418 -389.697502) (xy 123.442084 -389.662064) (xy 123.415492 -389.622136) (xy 123.395257 -389.57864)
			(xy 123.38812 -389.555736) (xy 123.386596 -389.549894) (xy 123.066048 -388.995412) (xy 123.061984 -388.991094)
			(xy 123.045886 -388.973419) (xy 123.018636 -388.934142) (xy 122.997624 -388.891203) (xy 122.98333 -388.845586)
			(xy 122.976083 -388.798334) (xy 122.975624 -388.774432) (xy 122.975788 -388.76032) (xy 122.978336 -388.732211)
			(xy 122.980704 -388.718298) (xy 122.98193 -388.709101) (xy 122.978561 -388.690872) (xy 122.9741 -388.682738)
			(xy 122.957336 -388.655814) (xy 122.952151 -388.648094) (xy 122.937421 -388.636765) (xy 122.928634 -388.633716)
			(xy 122.907024 -388.626923) (xy 122.865813 -388.60812) (xy 122.827689 -388.583657) (xy 122.793424 -388.554029)
			(xy 122.778266 -388.537196) (xy 122.775796 -388.534376) (xy 122.770189 -388.5294) (xy 122.76709 -388.52729)
			(xy 122.755065 -388.519206) (xy 122.735173 -388.498148) (xy 122.721164 -388.472793) (xy 122.713923 -388.444745)
			(xy 122.713496 -388.430262) (xy 122.713496 -388.418324) (xy 122.711718 -388.41172) (xy 122.706511 -388.391351)
			(xy 122.700911 -388.349683) (xy 122.700542 -388.328662) (xy 122.136408 -388.328662) (xy 122.136245 -388.342387)
			(xy 122.133831 -388.369732) (xy 122.131582 -388.383272) (xy 122.131328 -388.385304) (xy 122.13082 -388.39013)
			(xy 122.130391 -388.398311) (xy 122.134146 -388.414246) (xy 122.138186 -388.421372) (xy 122.149616 -388.439914)
			(xy 122.152121 -388.443735) (xy 122.158254 -388.450506) (xy 122.161808 -388.453376) (xy 122.18289 -388.469632)
			(xy 122.191018 -388.472426) (xy 122.215853 -388.481194) (xy 122.262436 -388.50576) (xy 122.304338 -388.537662)
			(xy 122.340413 -388.576029) (xy 122.369677 -388.619814) (xy 122.391331 -388.66782) (xy 122.398536 -388.693152)
			(xy 122.400314 -388.699756) (xy 122.71121 -389.237728) (xy 122.716036 -389.2423) (xy 122.733377 -389.26033)
			(xy 122.762785 -389.300793) (xy 122.785501 -389.345359) (xy 122.800966 -389.392929) (xy 122.808799 -389.442333)
			(xy 122.809254 -389.467344) (xy 122.808723 -389.494482) (xy 122.799541 -389.547975) (xy 122.7814 -389.599129)
			(xy 122.754829 -389.646456) (xy 122.7206 -389.688577) (xy 122.700542 -389.706866) (xy 122.691906 -389.713978)
			(xy 122.683016 -389.73379) (xy 122.683016 -389.757412) (xy 122.683016 -389.759952) (xy 122.683897 -389.769535)
			(xy 122.691854 -389.787039) (xy 122.69851 -389.793988) (xy 122.707146 -389.80237) (xy 122.714474 -389.808916)
			(xy 122.732638 -389.816365) (xy 122.742452 -389.816848) (xy 123.040902 -389.816848) (xy 123.041156 -389.816594)
			(xy 123.062221 -389.816931) (xy 123.103586 -389.824889) (xy 123.142589 -389.840799) (xy 123.177717 -389.864047)
			(xy 123.207606 -389.893728) (xy 123.231098 -389.928693) (xy 123.247281 -389.967584) (xy 123.255527 -390.008892)
			(xy 123.25604 -390.029954) (xy 123.25604 -390.233916) (xy 123.25555 -390.243924) (xy 123.247889 -390.262418)
			(xy 123.233738 -390.276575) (xy 123.215248 -390.284245) (xy 123.20524 -390.284716) (xy 123.196096 -390.284716)
			(xy 123.196096 -390.499092) (xy 123.195678 -390.509114) (xy 123.188009 -390.527633) (xy 123.173836 -390.541807)
			(xy 123.155318 -390.549477) (xy 123.145296 -390.549892) (xy 122.700288 -390.549892) (xy 122.692452 -390.557404)
			(xy 122.683488 -390.577149) (xy 122.683016 -390.587992) (xy 122.683016 -391.174732) (xy 122.683479 -391.184608)
			(xy 122.690927 -391.202901) (xy 122.697494 -391.210292) (xy 122.697748 -391.210546) (xy 122.752866 -391.265664)
			(xy 122.753374 -391.266172) (xy 122.760757 -391.272749) (xy 122.779056 -391.280189) (xy 122.788934 -391.28065)
		)
		(stroke
			(width 0)
			(type solid)
		)
		(fill yes)
		(layer "B.Cu")
		(net "P1V8_CPU1_RT3_1A")
	)
	(gr_poly
		(pts
			(xy 157.214824 -391.28065) (xy 157.224702 -391.28019) (xy 157.243003 -391.272751) (xy 157.250384 -391.266172)
			(xy 157.250638 -391.265918) (xy 157.322774 -391.193782) (xy 157.326076 -391.190226) (xy 157.331477 -391.183213)
			(xy 157.337451 -391.166561) (xy 157.33776 -391.157714) (xy 157.33776 -389.795766) (xy 157.31998 -389.769858)
			(xy 157.304994 -389.76427) (xy 157.281768 -389.754823) (xy 157.238384 -389.729691) (xy 157.19948 -389.698065)
			(xy 157.166018 -389.660727) (xy 157.138828 -389.618603) (xy 157.118581 -389.572735) (xy 157.1117 -389.548624)
			(xy 157.109922 -389.542274) (xy 156.7942 -388.996174) (xy 156.790136 -388.991856) (xy 156.773919 -388.974158)
			(xy 156.746486 -388.934769) (xy 156.72534 -388.891678) (xy 156.710968 -388.84588) (xy 156.703704 -388.798432)
			(xy 156.703268 -388.774432) (xy 156.703437 -388.76032) (xy 156.705984 -388.732211) (xy 156.708348 -388.718298)
			(xy 156.70961 -388.709103) (xy 156.706212 -388.690874) (xy 156.701744 -388.682738) (xy 156.68498 -388.655814)
			(xy 156.67978 -388.648104) (xy 156.665063 -388.636763) (xy 156.656278 -388.633716) (xy 156.634662 -388.626942)
			(xy 156.593457 -388.608126) (xy 156.555339 -388.583654) (xy 156.521078 -388.554021) (xy 156.50591 -388.537196)
			(xy 156.503454 -388.534362) (xy 156.497841 -388.52939) (xy 156.494734 -388.52729) (xy 156.482693 -388.519226)
			(xy 156.462795 -388.49817) (xy 156.448795 -388.472807) (xy 156.441584 -388.444748) (xy 156.44114 -388.430262)
			(xy 156.44114 -388.418324) (xy 156.439362 -388.41172) (xy 156.434168 -388.391348) (xy 156.428568 -388.349682)
			(xy 156.428186 -388.328662) (xy 156.42856 -388.307642) (xy 156.43417 -388.265976) (xy 156.439362 -388.245604)
			(xy 156.44114 -388.239) (xy 156.44114 -388.125462) (xy 156.441634 -388.110448) (xy 156.449414 -388.081445)
			(xy 156.464433 -388.055444) (xy 156.485669 -388.034214) (xy 156.511675 -388.019202) (xy 156.54068 -388.01143)
			(xy 156.555694 -388.010908) (xy 156.737304 -388.010908) (xy 156.737812 -388.010654) (xy 156.746194 -388.010654)
			(xy 156.754576 -388.010654) (xy 156.755084 -388.010908) (xy 156.936694 -388.010908) (xy 156.951713 -388.011397)
			(xy 156.980729 -388.019169) (xy 157.006745 -388.034184) (xy 157.027989 -388.05542) (xy 157.043015 -388.08143)
			(xy 157.050797 -388.110443) (xy 157.051248 -388.125462) (xy 157.051248 -388.239) (xy 157.053026 -388.245604)
			(xy 157.058225 -388.265975) (xy 157.063835 -388.307641) (xy 157.064202 -388.328662) (xy 157.064071 -388.343416)
			(xy 157.061399 -388.372801) (xy 157.058868 -388.387336) (xy 157.057501 -388.396574) (xy 157.060754 -388.414947)
			(xy 157.065218 -388.42315) (xy 157.081728 -388.450074) (xy 157.086907 -388.457842) (xy 157.101635 -388.469289)
			(xy 157.11043 -388.472426) (xy 157.135279 -388.480519) (xy 157.182114 -388.503696) (xy 157.224496 -388.534264)
			(xy 157.261272 -388.571389) (xy 157.291437 -388.614059) (xy 157.31417 -388.661111) (xy 157.322012 -388.68604)
			(xy 157.323536 -388.691882) (xy 157.567376 -389.113522) (xy 157.573737 -389.12335) (xy 157.593197 -389.136313)
			(xy 157.604714 -389.138414) (xy 157.616398 -389.140192) (xy 157.638496 -389.132572) (xy 157.892496 -388.878572)
			(xy 157.900667 -388.869272) (xy 157.907949 -388.845652) (xy 157.906466 -388.83336) (xy 157.903863 -388.818767)
			(xy 157.901067 -388.789254) (xy 157.900878 -388.774432) (xy 157.901042 -388.760707) (xy 157.903456 -388.733363)
			(xy 157.905704 -388.719822) (xy 157.905958 -388.71779) (xy 157.906466 -388.712964) (xy 157.906894 -388.704784)
			(xy 157.903137 -388.68885) (xy 157.8991 -388.681722) (xy 157.88767 -388.66318) (xy 157.885164 -388.65936)
			(xy 157.87903 -388.652591) (xy 157.875478 -388.649718) (xy 157.854396 -388.633462) (xy 157.846268 -388.630668)
			(xy 157.819431 -388.621122) (xy 157.769399 -388.59391) (xy 157.724986 -388.558255) (xy 157.705806 -388.537196)
			(xy 157.703285 -388.534356) (xy 157.697546 -388.529381) (xy 157.694376 -388.52729) (xy 157.682332 -388.519229)
			(xy 157.662426 -388.498175) (xy 157.648421 -388.472811) (xy 157.641207 -388.444749) (xy 157.640782 -388.430262)
			(xy 157.640782 -388.418578) (xy 157.639004 -388.411974) (xy 157.633837 -388.391726) (xy 157.628233 -388.350316)
			(xy 157.627828 -388.329424) (xy 157.628082 -388.320788) (xy 157.628845 -388.30182) (xy 157.634324 -388.264255)
			(xy 157.639004 -388.245858) (xy 157.640782 -388.239254) (xy 157.640782 -387.78307) (xy 157.639004 -387.776466)
			(xy 157.633968 -387.756457) (xy 157.628494 -387.715561) (xy 157.628082 -387.694932) (xy 157.628082 -387.689344)
			(xy 157.628656 -387.669481) (xy 157.634129 -387.630122) (xy 157.639004 -387.610858) (xy 157.640782 -387.604508)
			(xy 157.640782 -387.592062) (xy 157.641192 -387.577621) (xy 157.648378 -387.549647) (xy 157.662314 -387.524348)
			(xy 157.682117 -387.503324) (xy 157.694122 -387.495288) (xy 157.694884 -387.490462) (xy 157.695796 -387.485287)
			(xy 157.695676 -387.474783) (xy 157.69463 -387.469634) (xy 157.675072 -387.384798) (xy 157.662372 -387.36778)
			(xy 157.652466 -387.362446) (xy 157.62823 -387.348448) (xy 157.584675 -387.313309) (xy 157.565852 -387.292596)
			(xy 157.563394 -387.289764) (xy 157.557777 -387.284798) (xy 157.554676 -387.28269) (xy 157.542616 -387.274631)
			(xy 157.52267 -387.253582) (xy 157.508605 -387.228224) (xy 157.501308 -387.20016) (xy 157.500828 -387.185662)
			(xy 157.500828 -387.173724) (xy 157.499304 -387.16712) (xy 157.494109 -387.146749) (xy 157.488508 -387.105082)
			(xy 157.488128 -387.084062) (xy 157.488502 -387.063042) (xy 157.494113 -387.021377) (xy 157.499304 -387.001004)
			(xy 157.500828 -386.9944) (xy 157.500828 -386.904484) (xy 157.493312 -386.896662) (xy 157.473566 -386.88773)
			(xy 157.462728 -386.887212) (xy 154.0383 -386.887212) (xy 154.02823 -386.887635) (xy 154.009627 -386.895351)
			(xy 154.002232 -386.902198) (xy 153.975816 -386.928614) (xy 153.96845 -386.935726) (xy 153.96083 -386.954522)
			(xy 153.96083 -387.0198) (xy 153.961233 -387.029081) (xy 153.967877 -387.046412) (xy 153.973784 -387.053582)
			(xy 153.978102 -387.058408) (xy 153.97861 -387.058916) (xy 153.985167 -387.06624) (xy 153.992636 -387.084404)
			(xy 153.993088 -387.094222) (xy 153.993088 -387.931406) (xy 153.993753 -387.943434) (xy 154.004612 -387.964904)
			(xy 154.013916 -387.972554) (xy 154.077924 -388.01929) (xy 154.10307 -388.022846) (xy 154.115262 -388.01802)
			(xy 154.12501 -388.014636) (xy 154.14533 -388.011066) (xy 154.155648 -388.010908) (xy 154.337258 -388.010908)
			(xy 154.337766 -388.010654) (xy 154.346148 -388.010654) (xy 154.35453 -388.010654) (xy 154.355038 -388.010908)
			(xy 154.536648 -388.010908) (xy 154.551672 -388.011402) (xy 154.580697 -388.019179) (xy 154.606726 -388.034193)
			(xy 154.627991 -388.055423) (xy 154.643048 -388.081427) (xy 154.650873 -388.110439) (xy 154.651456 -388.125462)
			(xy 154.651456 -388.239) (xy 154.65298 -388.245604) (xy 154.658178 -388.265975) (xy 154.663788 -388.307641)
			(xy 154.664156 -388.328662) (xy 155.22829 -388.328662) (xy 155.228657 -388.307641) (xy 155.234267 -388.265975)
			(xy 155.239466 -388.245604) (xy 155.241244 -388.239) (xy 155.241244 -388.125462) (xy 155.241703 -388.110444)
			(xy 155.249485 -388.081432) (xy 155.264509 -388.055423) (xy 155.285751 -388.034187) (xy 155.311766 -388.019171)
			(xy 155.34078 -388.011398) (xy 155.355798 -388.010908) (xy 155.537408 -388.010908) (xy 155.537916 -388.010654)
			(xy 155.546298 -388.010654) (xy 155.55468 -388.010654) (xy 155.555188 -388.010908) (xy 155.736798 -388.010908)
			(xy 155.751812 -388.011438) (xy 155.780816 -388.019207) (xy 155.806822 -388.034217) (xy 155.828058 -388.055446)
			(xy 155.843078 -388.081447) (xy 155.850857 -388.110449) (xy 155.851352 -388.125462) (xy 155.851352 -388.239)
			(xy 155.85313 -388.245604) (xy 155.858322 -388.265976) (xy 155.863932 -388.307642) (xy 155.864306 -388.328662)
			(xy 155.864166 -388.343415) (xy 155.86149 -388.372799) (xy 155.858972 -388.387336) (xy 155.857626 -388.396575)
			(xy 155.860873 -388.414943) (xy 155.865322 -388.42315) (xy 155.881832 -388.450074) (xy 155.887017 -388.457841)
			(xy 155.901731 -388.46931) (xy 155.910534 -388.472426) (xy 155.935481 -388.480465) (xy 155.982467 -388.503685)
			(xy 156.024963 -388.534359) (xy 156.061799 -388.571641) (xy 156.091958 -388.614504) (xy 156.11461 -388.661767)
			(xy 156.12237 -388.686802) (xy 156.123894 -388.692644) (xy 156.44368 -389.245602) (xy 156.447744 -389.24992)
			(xy 156.463943 -389.267632) (xy 156.491366 -389.307023) (xy 156.512509 -389.350111) (xy 156.526884 -389.395904)
			(xy 156.53416 -389.443346) (xy 156.534612 -389.467344) (xy 156.534128 -389.492807) (xy 156.525929 -389.543068)
			(xy 156.509767 -389.591361) (xy 156.486061 -389.636432) (xy 156.455427 -389.677113) (xy 156.418659 -389.712348)
			(xy 156.39796 -389.727186) (xy 156.39011 -389.73313) (xy 156.37922 -389.749509) (xy 156.375293 -389.768782)
			(xy 156.378905 -389.788116) (xy 156.389526 -389.804671) (xy 156.405596 -389.816013) (xy 156.424751 -389.820476)
			(xy 156.434536 -389.819388) (xy 156.443112 -389.818082) (xy 156.460405 -389.816685) (xy 156.46908 -389.816594)
			(xy 156.469334 -389.816848) (xy 156.768546 -389.816848) (xy 156.7688 -389.816594) (xy 156.789863 -389.816962)
			(xy 156.831223 -389.824924) (xy 156.870222 -389.840835) (xy 156.905348 -389.864079) (xy 156.935239 -389.893754)
			(xy 156.958736 -389.92871) (xy 156.974929 -389.967593) (xy 156.98319 -390.008894) (xy 156.983684 -390.029954)
			(xy 156.983684 -390.284716) (xy 156.97454 -390.284716) (xy 156.964519 -390.285153) (xy 156.946 -390.292812)
			(xy 156.931826 -390.30698) (xy 156.924157 -390.325496) (xy 156.92374 -390.335516) (xy 156.92374 -390.499092)
			(xy 156.923206 -390.509094) (xy 156.915557 -390.527578) (xy 156.901418 -390.54173) (xy 156.882942 -390.549397)
			(xy 156.87294 -390.549892) (xy 156.36494 -390.549892) (xy 156.354902 -390.549561) (xy 156.336348 -390.541899)
			(xy 156.322163 -390.527695) (xy 156.314526 -390.509131) (xy 156.31414 -390.499092) (xy 156.31414 -390.284716)
			(xy 156.304996 -390.284716) (xy 156.29499 -390.284215) (xy 156.276501 -390.276558) (xy 156.262349 -390.262409)
			(xy 156.254687 -390.243922) (xy 156.254196 -390.233916) (xy 156.254196 -390.029954) (xy 156.254543 -390.012721)
			(xy 156.260113 -389.978709) (xy 156.271084 -389.946036) (xy 156.278834 -389.93064) (xy 156.28493 -389.91921)
			(xy 156.284676 -389.89381) (xy 156.230574 -389.796782) (xy 156.209238 -389.783066) (xy 156.196284 -389.78205)
			(xy 156.172384 -389.779964) (xy 156.125596 -389.769358) (xy 156.080955 -389.751785) (xy 156.039491 -389.727653)
			(xy 156.002161 -389.697517) (xy 155.969828 -389.662074) (xy 155.943238 -389.622142) (xy 155.923004 -389.578642)
			(xy 155.915868 -389.555736) (xy 155.914344 -389.549894) (xy 155.593796 -388.995412) (xy 155.589732 -388.991094)
			(xy 155.573625 -388.973427) (xy 155.546378 -388.934147) (xy 155.525368 -388.891206) (xy 155.511077 -388.845587)
			(xy 155.50383 -388.798334) (xy 155.503372 -388.774432) (xy 155.503535 -388.76032) (xy 155.506083 -388.732211)
			(xy 155.508452 -388.718298) (xy 155.509685 -388.709101) (xy 155.506312 -388.690872) (xy 155.501848 -388.682738)
			(xy 155.485084 -388.655814) (xy 155.479882 -388.648107) (xy 155.465164 -388.636771) (xy 155.456382 -388.633716)
			(xy 155.434765 -388.626943) (xy 155.393556 -388.608133) (xy 155.355434 -388.583664) (xy 155.321171 -388.554031)
			(xy 155.306014 -388.537196) (xy 155.303553 -388.534367) (xy 155.297941 -388.529395) (xy 155.294838 -388.52729)
			(xy 155.282823 -388.519191) (xy 155.262928 -388.49814) (xy 155.248915 -388.472789) (xy 155.241672 -388.444744)
			(xy 155.241244 -388.430262) (xy 155.241244 -388.418324) (xy 155.239466 -388.41172) (xy 155.23426 -388.391351)
			(xy 155.228659 -388.349683) (xy 155.22829 -388.328662) (xy 154.664156 -388.328662) (xy 154.663993 -388.342387)
			(xy 154.661579 -388.369731) (xy 154.65933 -388.383272) (xy 154.659076 -388.385304) (xy 154.658568 -388.39013)
			(xy 154.658138 -388.39831) (xy 154.661897 -388.414244) (xy 154.665934 -388.421372) (xy 154.677364 -388.439914)
			(xy 154.679871 -388.443733) (xy 154.686007 -388.450499) (xy 154.689556 -388.453376) (xy 154.710638 -388.469632)
			(xy 154.718766 -388.472426) (xy 154.743598 -388.481197) (xy 154.790176 -388.505767) (xy 154.832071 -388.537672)
			(xy 154.868141 -388.57604) (xy 154.897401 -388.619824) (xy 154.91905 -388.667829) (xy 154.926284 -388.693152)
			(xy 154.928062 -388.699756) (xy 155.238958 -389.237728) (xy 155.243784 -389.2423) (xy 155.261122 -389.260331)
			(xy 155.290526 -389.300796) (xy 155.313239 -389.345362) (xy 155.328701 -389.392931) (xy 155.336533 -389.442334)
			(xy 155.337002 -389.467344) (xy 155.336471 -389.494483) (xy 155.32729 -389.547977) (xy 155.309151 -389.599133)
			(xy 155.282583 -389.646462) (xy 155.248357 -389.688587) (xy 155.22829 -389.706866) (xy 155.219654 -389.713978)
			(xy 155.210764 -389.73379) (xy 155.210764 -389.757412) (xy 155.210764 -389.759952) (xy 155.211643 -389.769536)
			(xy 155.219595 -389.787045) (xy 155.226258 -389.793988) (xy 155.234894 -389.80237) (xy 155.242224 -389.808909)
			(xy 155.260388 -389.81634) (xy 155.2702 -389.816848) (xy 155.56865 -389.816848) (xy 155.568904 -389.816594)
			(xy 155.589966 -389.816936) (xy 155.631323 -389.8249) (xy 155.670318 -389.840815) (xy 155.705437 -389.864064)
			(xy 155.735319 -389.893745) (xy 155.758805 -389.928706) (xy 155.774983 -389.967592) (xy 155.783227 -390.008895)
			(xy 155.783788 -390.029954) (xy 155.783788 -390.233916) (xy 155.783297 -390.243921) (xy 155.775634 -390.262405)
			(xy 155.761481 -390.27655) (xy 155.742993 -390.284203) (xy 155.732988 -390.284716) (xy 155.723844 -390.284716)
			(xy 155.723844 -390.499092) (xy 155.723358 -390.509104) (xy 155.715701 -390.527606) (xy 155.70155 -390.541772)
			(xy 155.683055 -390.549448) (xy 155.673044 -390.549892) (xy 155.228036 -390.549892) (xy 155.220194 -390.5574)
			(xy 155.211221 -390.577147) (xy 155.210764 -390.587992) (xy 155.210764 -391.174732) (xy 155.211226 -391.184609)
			(xy 155.218668 -391.202907) (xy 155.225242 -391.210292) (xy 155.225496 -391.210546) (xy 155.280614 -391.265664)
			(xy 155.281122 -391.266172) (xy 155.288502 -391.272757) (xy 155.306801 -391.280216) (xy 155.316682 -391.28065)
		)
		(stroke
			(width 0)
			(type solid)
		)
		(fill yes)
		(layer "B.Cu")
		(net "P1V8_CPU1_RT2_1A")
	)
	(gr_poly
		(pts
			(xy 313.586876 -399.66265) (xy 313.59675 -399.662181) (xy 313.615038 -399.654728) (xy 313.622436 -399.648172)
			(xy 313.62269 -399.647918) (xy 313.694826 -399.575782) (xy 313.701505 -399.56837) (xy 313.709076 -399.549934)
			(xy 313.709558 -399.539968) (xy 313.709558 -398.177766) (xy 313.691778 -398.151858) (xy 313.677046 -398.14627)
			(xy 313.653818 -398.136826) (xy 313.610428 -398.111699) (xy 313.571517 -398.080075) (xy 313.53805 -398.042738)
			(xy 313.510854 -398.000614) (xy 313.490604 -397.954744) (xy 313.483752 -397.930624) (xy 313.481974 -397.924274)
			(xy 313.166252 -397.378174) (xy 313.162188 -397.373856) (xy 313.145973 -397.356157) (xy 313.118544 -397.316767)
			(xy 313.097401 -397.273676) (xy 313.083032 -397.227878) (xy 313.075769 -397.180432) (xy 313.07532 -397.156432)
			(xy 313.075489 -397.14232) (xy 313.078036 -397.114211) (xy 313.0804 -397.100298) (xy 313.081663 -397.091104)
			(xy 313.078261 -397.072875) (xy 313.073796 -397.064738) (xy 313.057032 -397.037814) (xy 313.051829 -397.030109)
			(xy 313.037108 -397.018781) (xy 313.02833 -397.015716) (xy 313.006712 -397.008945) (xy 312.965503 -396.990134)
			(xy 312.92738 -396.965666) (xy 312.893114 -396.936036) (xy 312.877962 -396.919196) (xy 312.875505 -396.916364)
			(xy 312.869888 -396.911397) (xy 312.866786 -396.90929) (xy 312.854741 -396.90123) (xy 312.834834 -396.880176)
			(xy 312.820827 -396.854812) (xy 312.813612 -396.82675) (xy 312.813192 -396.812262) (xy 312.813192 -396.800324)
			(xy 312.811414 -396.79372) (xy 312.806221 -396.773348) (xy 312.800621 -396.731682) (xy 312.800238 -396.710662)
			(xy 312.800612 -396.689642) (xy 312.806221 -396.647976) (xy 312.811414 -396.627604) (xy 312.813192 -396.621)
			(xy 312.813192 -396.507462) (xy 312.813643 -396.492445) (xy 312.821426 -396.463436) (xy 312.836453 -396.437431)
			(xy 312.857698 -396.416201) (xy 312.883714 -396.401194) (xy 312.912729 -396.393432) (xy 312.927746 -396.392908)
			(xy 313.109356 -396.392908) (xy 313.109864 -396.392654) (xy 313.118246 -396.392654) (xy 313.126628 -396.392654)
			(xy 313.127136 -396.392908) (xy 313.308746 -396.392908) (xy 313.323761 -396.393403) (xy 313.352765 -396.401184)
			(xy 313.378769 -396.416202) (xy 313.400002 -396.437437) (xy 313.41502 -396.463443) (xy 313.422798 -396.492447)
			(xy 313.4233 -396.507462) (xy 313.4233 -396.621) (xy 313.425078 -396.627604) (xy 313.430276 -396.647975)
			(xy 313.435886 -396.689641) (xy 313.436254 -396.710662) (xy 313.436123 -396.725416) (xy 313.433451 -396.754801)
			(xy 313.43092 -396.769336) (xy 313.429553 -396.778575) (xy 313.432804 -396.796949) (xy 313.43727 -396.80515)
			(xy 313.45378 -396.832074) (xy 313.458955 -396.839847) (xy 313.473679 -396.851308) (xy 313.482482 -396.854426)
			(xy 313.507328 -396.862522) (xy 313.554157 -396.885705) (xy 313.596533 -396.916275) (xy 313.633302 -396.953402)
			(xy 313.663462 -396.996072) (xy 313.68619 -397.043122) (xy 313.694064 -397.06804) (xy 313.695588 -397.073882)
			(xy 313.939428 -397.495522) (xy 313.945785 -397.505356) (xy 313.965242 -397.518338) (xy 313.976766 -397.520414)
			(xy 313.98845 -397.522192) (xy 314.010548 -397.514572) (xy 314.264548 -397.260572) (xy 314.272725 -397.251274)
			(xy 314.280014 -397.227652) (xy 314.278518 -397.21536) (xy 314.275915 -397.200767) (xy 314.273118 -397.171254)
			(xy 314.27293 -397.156432) (xy 314.273094 -397.142707) (xy 314.275508 -397.115363) (xy 314.277756 -397.101822)
			(xy 314.27801 -397.09979) (xy 314.278518 -397.094964) (xy 314.278946 -397.086784) (xy 314.275185 -397.070852)
			(xy 314.271152 -397.063722) (xy 314.259722 -397.04518) (xy 314.257214 -397.041362) (xy 314.251077 -397.034597)
			(xy 314.24753 -397.031718) (xy 314.226448 -397.015462) (xy 314.21832 -397.012668) (xy 314.191481 -397.003126)
			(xy 314.141442 -396.97592) (xy 314.097024 -396.940269) (xy 314.077858 -396.919196) (xy 314.075338 -396.916354)
			(xy 314.069603 -396.911374) (xy 314.066428 -396.90929) (xy 314.054388 -396.901226) (xy 314.034491 -396.880169)
			(xy 314.020492 -396.854806) (xy 314.013281 -396.826748) (xy 314.012834 -396.812262) (xy 314.012834 -396.800578)
			(xy 314.011056 -396.793974) (xy 314.005851 -396.77354) (xy 314.000244 -396.731746) (xy 313.99988 -396.710662)
			(xy 314.000134 -396.702788) (xy 314.000896 -396.68382) (xy 314.006375 -396.646255) (xy 314.011056 -396.627858)
			(xy 314.012834 -396.621254) (xy 314.012834 -396.16507) (xy 314.011056 -396.158466) (xy 314.006021 -396.138457)
			(xy 314.000547 -396.097561) (xy 314.000134 -396.076932) (xy 314.000134 -396.071344) (xy 314.000708 -396.051481)
			(xy 314.00618 -396.012122) (xy 314.011056 -395.992858) (xy 314.012834 -395.986508) (xy 314.012834 -395.974062)
			(xy 314.013244 -395.959622) (xy 314.020433 -395.93165) (xy 314.034372 -395.906356) (xy 314.05418 -395.885339)
			(xy 314.066174 -395.877288) (xy 314.066936 -395.872462) (xy 314.067848 -395.867287) (xy 314.067729 -395.856783)
			(xy 314.066682 -395.851634) (xy 314.047124 -395.766798) (xy 314.034424 -395.74978) (xy 314.024518 -395.744446)
			(xy 314.00028 -395.730451) (xy 313.956719 -395.695317) (xy 313.937904 -395.674596) (xy 313.935448 -395.671762)
			(xy 313.929834 -395.666791) (xy 313.926728 -395.66469) (xy 313.914664 -395.656634) (xy 313.894709 -395.635588)
			(xy 313.880637 -395.61023) (xy 313.873336 -395.582162) (xy 313.87288 -395.567662) (xy 313.87288 -395.555724)
			(xy 313.871356 -395.54912) (xy 313.866162 -395.528748) (xy 313.860562 -395.487082) (xy 313.86018 -395.466062)
			(xy 313.860554 -395.445042) (xy 313.866164 -395.403376) (xy 313.871356 -395.383004) (xy 313.87288 -395.3764)
			(xy 313.87288 -395.28623) (xy 313.865385 -395.278514) (xy 313.845781 -395.269706) (xy 313.835034 -395.269212)
			(xy 310.410352 -395.269212) (xy 310.400286 -395.269644) (xy 310.381695 -395.277372) (xy 310.374284 -395.284198)
			(xy 310.347868 -395.310614) (xy 310.340502 -395.317726) (xy 310.332882 -395.336522) (xy 310.332882 -395.4018)
			(xy 310.333283 -395.411082) (xy 310.339923 -395.428416) (xy 310.345836 -395.435582) (xy 310.350154 -395.440408)
			(xy 310.350662 -395.440916) (xy 310.357111 -395.448213) (xy 310.364433 -395.46624) (xy 310.364886 -395.475968)
			(xy 310.364886 -396.313152) (xy 310.364886 -396.315692) (xy 310.366075 -396.327034) (xy 310.376887 -396.34708)
			(xy 310.385714 -396.3543) (xy 310.449976 -396.40129) (xy 310.475122 -396.404846) (xy 310.487314 -396.40002)
			(xy 310.497061 -396.396632) (xy 310.517382 -396.393053) (xy 310.5277 -396.392908) (xy 310.70931 -396.392908)
			(xy 310.709818 -396.392654) (xy 310.7182 -396.392654) (xy 310.726582 -396.392654) (xy 310.72709 -396.392908)
			(xy 310.9087 -396.392908) (xy 310.923728 -396.393396) (xy 310.952763 -396.401165) (xy 310.978804 -396.416176)
			(xy 311.000079 -396.437407) (xy 311.015143 -396.463416) (xy 311.022972 -396.492435) (xy 311.023508 -396.507462)
			(xy 311.023508 -396.621) (xy 311.025032 -396.627604) (xy 311.030231 -396.647975) (xy 311.035841 -396.689641)
			(xy 311.036208 -396.710662) (xy 311.600342 -396.710662) (xy 311.60071 -396.689641) (xy 311.60632 -396.647975)
			(xy 311.611518 -396.627604) (xy 311.613296 -396.621) (xy 311.613296 -396.507462) (xy 311.61366 -396.492434)
			(xy 311.621449 -396.463403) (xy 311.636487 -396.437379) (xy 311.657749 -396.416133) (xy 311.683785 -396.401115)
			(xy 311.712821 -396.393348) (xy 311.72785 -396.392908) (xy 311.90946 -396.392908) (xy 311.909968 -396.392654)
			(xy 311.91835 -396.392654) (xy 311.926732 -396.392654) (xy 311.92724 -396.392908) (xy 312.10885 -396.392908)
			(xy 312.123867 -396.393435) (xy 312.152881 -396.401197) (xy 312.178898 -396.416203) (xy 312.200143 -396.437432)
			(xy 312.21517 -396.463437) (xy 312.222953 -396.492445) (xy 312.223404 -396.507462) (xy 312.223404 -396.621)
			(xy 312.225182 -396.627604) (xy 312.230375 -396.647976) (xy 312.235984 -396.689642) (xy 312.236358 -396.710662)
			(xy 312.236217 -396.725415) (xy 312.233542 -396.754799) (xy 312.231024 -396.769336) (xy 312.229684 -396.778575)
			(xy 312.232928 -396.796942) (xy 312.237374 -396.80515) (xy 312.253884 -396.832074) (xy 312.25905 -396.839855)
			(xy 312.273778 -396.851317) (xy 312.282586 -396.854426) (xy 312.307543 -396.862436) (xy 312.354527 -396.885663)
			(xy 312.397022 -396.916344) (xy 312.433856 -396.953632) (xy 312.464013 -396.996499) (xy 312.486663 -397.043765)
			(xy 312.494422 -397.068802) (xy 312.495946 -397.074644) (xy 312.815732 -397.627602) (xy 312.819796 -397.63192)
			(xy 312.835987 -397.649639) (xy 312.863413 -397.689027) (xy 312.884559 -397.732114) (xy 312.898935 -397.777905)
			(xy 312.906212 -397.825346) (xy 312.906664 -397.849344) (xy 312.9062 -397.874808) (xy 312.898 -397.925071)
			(xy 312.881835 -397.973365) (xy 312.858126 -398.018437) (xy 312.827487 -398.059117) (xy 312.790713 -398.09435)
			(xy 312.770012 -398.109186) (xy 312.762191 -398.115159) (xy 312.751319 -398.131531) (xy 312.7474 -398.15079)
			(xy 312.751011 -398.17011) (xy 312.76162 -398.186653) (xy 312.777672 -398.197994) (xy 312.79681 -398.202467)
			(xy 312.806588 -398.201388) (xy 312.815165 -398.200088) (xy 312.832458 -398.198686) (xy 312.841132 -398.198594)
			(xy 312.841386 -398.198848) (xy 313.140598 -398.198848) (xy 313.140852 -398.198594) (xy 313.161914 -398.199006)
			(xy 313.203272 -398.206959) (xy 313.24227 -398.222862) (xy 313.277396 -398.246099) (xy 313.307288 -398.275768)
			(xy 313.330787 -398.31072) (xy 313.346981 -398.349598) (xy 313.355242 -398.390896) (xy 313.355736 -398.411954)
			(xy 313.355736 -398.666716) (xy 313.346592 -398.666716) (xy 313.336568 -398.667113) (xy 313.318048 -398.674789)
			(xy 313.303876 -398.688968) (xy 313.296209 -398.707492) (xy 313.295792 -398.717516) (xy 313.295792 -398.881092)
			(xy 313.295374 -398.891114) (xy 313.287705 -398.909632) (xy 313.273532 -398.923805) (xy 313.255014 -398.931474)
			(xy 313.244992 -398.931892) (xy 312.736992 -398.931892) (xy 312.726957 -398.931518) (xy 312.708405 -398.923873)
			(xy 312.694218 -398.909682) (xy 312.686578 -398.891127) (xy 312.686192 -398.881092) (xy 312.686192 -398.666716)
			(xy 312.677048 -398.666716) (xy 312.667032 -398.666242) (xy 312.648519 -398.65859) (xy 312.634346 -398.644435)
			(xy 312.626671 -398.625932) (xy 312.626248 -398.615916) (xy 312.626248 -398.411954) (xy 312.626589 -398.394721)
			(xy 312.632161 -398.360708) (xy 312.643135 -398.328035) (xy 312.650886 -398.31264) (xy 312.656982 -398.30121)
			(xy 312.656728 -398.27581) (xy 312.602626 -398.178782) (xy 312.58129 -398.165066) (xy 312.568336 -398.16405)
			(xy 312.54444 -398.161922) (xy 312.497654 -398.151323) (xy 312.453013 -398.133758) (xy 312.411548 -398.109632)
			(xy 312.374218 -398.079502) (xy 312.341884 -398.044064) (xy 312.315292 -398.004136) (xy 312.295057 -397.96064)
			(xy 312.28792 -397.937736) (xy 312.286396 -397.931894) (xy 311.965848 -397.377412) (xy 311.961784 -397.373094)
			(xy 311.945686 -397.355419) (xy 311.918436 -397.316142) (xy 311.897424 -397.273203) (xy 311.88313 -397.227586)
			(xy 311.875883 -397.180334) (xy 311.875424 -397.156432) (xy 311.875588 -397.14232) (xy 311.878136 -397.114211)
			(xy 311.880504 -397.100298) (xy 311.88173 -397.091101) (xy 311.878361 -397.072872) (xy 311.8739 -397.064738)
			(xy 311.857136 -397.037814) (xy 311.851951 -397.030094) (xy 311.837221 -397.018765) (xy 311.828434 -397.015716)
			(xy 311.806824 -397.008923) (xy 311.765613 -396.99012) (xy 311.727489 -396.965657) (xy 311.693224 -396.936029)
			(xy 311.678066 -396.919196) (xy 311.675596 -396.916376) (xy 311.669989 -396.9114) (xy 311.66689 -396.90929)
			(xy 311.654865 -396.901206) (xy 311.634973 -396.880148) (xy 311.620964 -396.854793) (xy 311.613723 -396.826745)
			(xy 311.613296 -396.812262) (xy 311.613296 -396.800324) (xy 311.611518 -396.79372) (xy 311.606311 -396.773351)
			(xy 311.600711 -396.731683) (xy 311.600342 -396.710662) (xy 311.036208 -396.710662) (xy 311.036045 -396.724387)
			(xy 311.033631 -396.751732) (xy 311.031382 -396.765272) (xy 311.031128 -396.767304) (xy 311.03062 -396.77213)
			(xy 311.030191 -396.780311) (xy 311.033946 -396.796246) (xy 311.037986 -396.803372) (xy 311.049416 -396.821914)
			(xy 311.051921 -396.825735) (xy 311.058054 -396.832506) (xy 311.061608 -396.835376) (xy 311.08269 -396.851632)
			(xy 311.090818 -396.854426) (xy 311.115653 -396.863194) (xy 311.162236 -396.88776) (xy 311.204138 -396.919662)
			(xy 311.240213 -396.958029) (xy 311.269477 -397.001814) (xy 311.291131 -397.04982) (xy 311.298336 -397.075152)
			(xy 311.300114 -397.081756) (xy 311.61101 -397.619728) (xy 311.615836 -397.6243) (xy 311.633177 -397.64233)
			(xy 311.662585 -397.682793) (xy 311.685301 -397.727359) (xy 311.700766 -397.774929) (xy 311.708599 -397.824333)
			(xy 311.709054 -397.849344) (xy 311.708523 -397.876482) (xy 311.699341 -397.929975) (xy 311.6812 -397.981129)
			(xy 311.654629 -398.028456) (xy 311.6204 -398.070577) (xy 311.600342 -398.088866) (xy 311.591706 -398.095978)
			(xy 311.582816 -398.11579) (xy 311.582816 -398.139412) (xy 311.582816 -398.141952) (xy 311.583697 -398.151535)
			(xy 311.591654 -398.169039) (xy 311.59831 -398.175988) (xy 311.606946 -398.18437) (xy 311.614274 -398.190916)
			(xy 311.632438 -398.198365) (xy 311.642252 -398.198848) (xy 311.940702 -398.198848) (xy 311.940956 -398.198594)
			(xy 311.962021 -398.198931) (xy 312.003386 -398.206889) (xy 312.042389 -398.222799) (xy 312.077517 -398.246047)
			(xy 312.107406 -398.275728) (xy 312.130898 -398.310693) (xy 312.147081 -398.349584) (xy 312.155327 -398.390892)
			(xy 312.15584 -398.411954) (xy 312.15584 -398.615916) (xy 312.15535 -398.625924) (xy 312.147689 -398.644418)
			(xy 312.133538 -398.658575) (xy 312.115048 -398.666245) (xy 312.10504 -398.666716) (xy 312.095896 -398.666716)
			(xy 312.095896 -398.881092) (xy 312.095478 -398.891114) (xy 312.087809 -398.909633) (xy 312.073636 -398.923807)
			(xy 312.055118 -398.931477) (xy 312.045096 -398.931892) (xy 311.600088 -398.931892) (xy 311.592252 -398.939404)
			(xy 311.583288 -398.959149) (xy 311.582816 -398.969992) (xy 311.582816 -399.556732) (xy 311.583279 -399.566608)
			(xy 311.590727 -399.584901) (xy 311.597294 -399.592292) (xy 311.597548 -399.592546) (xy 311.652666 -399.647664)
			(xy 311.653174 -399.648172) (xy 311.660557 -399.654749) (xy 311.678856 -399.662189) (xy 311.688734 -399.66265)
		)
		(stroke
			(width 0)
			(type solid)
		)
		(fill yes)
		(layer "B.Cu")
		(net "P1V8_CPU0_RT0_1A")
	)
	(gr_poly
		(pts
			(xy 346.114624 -399.66265) (xy 346.124502 -399.66219) (xy 346.142803 -399.654751) (xy 346.150184 -399.648172)
			(xy 346.150438 -399.647918) (xy 346.222574 -399.575782) (xy 346.229258 -399.568373) (xy 346.236838 -399.549936)
			(xy 346.237306 -399.539968) (xy 346.237306 -398.177766) (xy 346.219526 -398.151858) (xy 346.204794 -398.14627)
			(xy 346.181568 -398.136823) (xy 346.138184 -398.111691) (xy 346.09928 -398.080065) (xy 346.065818 -398.042727)
			(xy 346.038628 -398.000603) (xy 346.018381 -397.954735) (xy 346.0115 -397.930624) (xy 346.009722 -397.924274)
			(xy 345.694 -397.378174) (xy 345.689936 -397.373856) (xy 345.673719 -397.356158) (xy 345.646286 -397.316769)
			(xy 345.62514 -397.273678) (xy 345.610768 -397.22788) (xy 345.603504 -397.180432) (xy 345.603068 -397.156432)
			(xy 345.603237 -397.14232) (xy 345.605784 -397.114211) (xy 345.608148 -397.100298) (xy 345.60941 -397.091103)
			(xy 345.606012 -397.072874) (xy 345.601544 -397.064738) (xy 345.58478 -397.037814) (xy 345.57958 -397.030104)
			(xy 345.564863 -397.018763) (xy 345.556078 -397.015716) (xy 345.534462 -397.008942) (xy 345.493257 -396.990126)
			(xy 345.455139 -396.965654) (xy 345.420878 -396.936021) (xy 345.40571 -396.919196) (xy 345.403254 -396.916362)
			(xy 345.397641 -396.91139) (xy 345.394534 -396.90929) (xy 345.382493 -396.901226) (xy 345.362595 -396.88017)
			(xy 345.348595 -396.854807) (xy 345.341384 -396.826748) (xy 345.34094 -396.812262) (xy 345.34094 -396.800324)
			(xy 345.339162 -396.79372) (xy 345.333968 -396.773348) (xy 345.328368 -396.731682) (xy 345.327986 -396.710662)
			(xy 345.32836 -396.689642) (xy 345.33397 -396.647976) (xy 345.339162 -396.627604) (xy 345.34094 -396.621)
			(xy 345.34094 -396.507462) (xy 345.341434 -396.492448) (xy 345.349214 -396.463445) (xy 345.364233 -396.437444)
			(xy 345.385469 -396.416214) (xy 345.411475 -396.401202) (xy 345.44048 -396.39343) (xy 345.455494 -396.392908)
			(xy 345.637104 -396.392908) (xy 345.637612 -396.392654) (xy 345.645994 -396.392654) (xy 345.654376 -396.392654)
			(xy 345.654884 -396.392908) (xy 345.836494 -396.392908) (xy 345.851513 -396.393397) (xy 345.880529 -396.401169)
			(xy 345.906545 -396.416184) (xy 345.927789 -396.43742) (xy 345.942815 -396.46343) (xy 345.950597 -396.492443)
			(xy 345.951048 -396.507462) (xy 345.951048 -396.621) (xy 345.952826 -396.627604) (xy 345.958025 -396.647975)
			(xy 345.963635 -396.689641) (xy 345.964002 -396.710662) (xy 345.963871 -396.725416) (xy 345.961199 -396.754801)
			(xy 345.958668 -396.769336) (xy 345.957301 -396.778574) (xy 345.960554 -396.796947) (xy 345.965018 -396.80515)
			(xy 345.981528 -396.832074) (xy 345.986707 -396.839842) (xy 346.001435 -396.851289) (xy 346.01023 -396.854426)
			(xy 346.035079 -396.862519) (xy 346.081914 -396.885696) (xy 346.124296 -396.916264) (xy 346.161072 -396.953389)
			(xy 346.191237 -396.996059) (xy 346.21397 -397.043111) (xy 346.221812 -397.06804) (xy 346.223336 -397.073882)
			(xy 346.467176 -397.495522) (xy 346.473537 -397.50535) (xy 346.492997 -397.518313) (xy 346.504514 -397.520414)
			(xy 346.516198 -397.522192) (xy 346.538296 -397.514572) (xy 346.792296 -397.260572) (xy 346.800467 -397.251272)
			(xy 346.807749 -397.227652) (xy 346.806266 -397.21536) (xy 346.803663 -397.200767) (xy 346.800867 -397.171254)
			(xy 346.800678 -397.156432) (xy 346.800842 -397.142707) (xy 346.803256 -397.115363) (xy 346.805504 -397.101822)
			(xy 346.805758 -397.09979) (xy 346.806266 -397.094964) (xy 346.806694 -397.086784) (xy 346.802937 -397.07085)
			(xy 346.7989 -397.063722) (xy 346.78747 -397.04518) (xy 346.784964 -397.04136) (xy 346.77883 -397.034591)
			(xy 346.775278 -397.031718) (xy 346.754196 -397.015462) (xy 346.746068 -397.012668) (xy 346.719231 -397.003122)
			(xy 346.669199 -396.97591) (xy 346.624786 -396.940255) (xy 346.605606 -396.919196) (xy 346.603085 -396.916356)
			(xy 346.597346 -396.911381) (xy 346.594176 -396.90929) (xy 346.582132 -396.901229) (xy 346.562226 -396.880175)
			(xy 346.548221 -396.854811) (xy 346.541007 -396.826749) (xy 346.540582 -396.812262) (xy 346.540582 -396.800578)
			(xy 346.538804 -396.793974) (xy 346.533598 -396.77354) (xy 346.527991 -396.731746) (xy 346.527628 -396.710662)
			(xy 346.527882 -396.702788) (xy 346.528645 -396.68382) (xy 346.534124 -396.646255) (xy 346.538804 -396.627858)
			(xy 346.540582 -396.621254) (xy 346.540582 -396.16507) (xy 346.538804 -396.158466) (xy 346.533768 -396.138457)
			(xy 346.528294 -396.097561) (xy 346.527882 -396.076932) (xy 346.527882 -396.071344) (xy 346.528456 -396.051481)
			(xy 346.533929 -396.012122) (xy 346.538804 -395.992858) (xy 346.540582 -395.986508) (xy 346.540582 -395.974062)
			(xy 346.540992 -395.959621) (xy 346.548178 -395.931647) (xy 346.562114 -395.906348) (xy 346.581917 -395.885324)
			(xy 346.593922 -395.877288) (xy 346.594684 -395.872462) (xy 346.595596 -395.867287) (xy 346.595476 -395.856783)
			(xy 346.59443 -395.851634) (xy 346.574872 -395.766798) (xy 346.562172 -395.74978) (xy 346.552266 -395.744446)
			(xy 346.52803 -395.730448) (xy 346.484475 -395.695309) (xy 346.465652 -395.674596) (xy 346.463194 -395.671764)
			(xy 346.457577 -395.666798) (xy 346.454476 -395.66469) (xy 346.442416 -395.656631) (xy 346.42247 -395.635582)
			(xy 346.408405 -395.610224) (xy 346.401108 -395.58216) (xy 346.400628 -395.567662) (xy 346.400628 -395.555724)
			(xy 346.399104 -395.54912) (xy 346.393909 -395.528749) (xy 346.388308 -395.487082) (xy 346.387928 -395.466062)
			(xy 346.388302 -395.445042) (xy 346.393913 -395.403377) (xy 346.399104 -395.383004) (xy 346.400628 -395.3764)
			(xy 346.400628 -395.28623) (xy 346.393136 -395.278506) (xy 346.373532 -395.269679) (xy 346.362782 -395.269212)
			(xy 342.9381 -395.269212) (xy 342.92803 -395.269635) (xy 342.909427 -395.277351) (xy 342.902032 -395.284198)
			(xy 342.875616 -395.310614) (xy 342.86825 -395.317726) (xy 342.86063 -395.336522) (xy 342.86063 -395.4018)
			(xy 342.861033 -395.411081) (xy 342.867677 -395.428412) (xy 342.873584 -395.435582) (xy 342.877902 -395.440408)
			(xy 342.87841 -395.440916) (xy 342.884854 -395.448215) (xy 342.892169 -395.466242) (xy 342.892634 -395.475968)
			(xy 342.892634 -396.313152) (xy 342.892634 -396.315692) (xy 342.893821 -396.327036) (xy 342.904626 -396.34709)
			(xy 342.913462 -396.3543) (xy 342.977724 -396.40129) (xy 343.00287 -396.404846) (xy 343.015062 -396.40002)
			(xy 343.02481 -396.396636) (xy 343.04513 -396.393066) (xy 343.055448 -396.392908) (xy 343.237058 -396.392908)
			(xy 343.237566 -396.392654) (xy 343.245948 -396.392654) (xy 343.25433 -396.392654) (xy 343.254838 -396.392908)
			(xy 343.436448 -396.392908) (xy 343.451472 -396.393402) (xy 343.480497 -396.401179) (xy 343.506526 -396.416193)
			(xy 343.527791 -396.437423) (xy 343.542848 -396.463427) (xy 343.550673 -396.492439) (xy 343.551256 -396.507462)
			(xy 343.551256 -396.621) (xy 343.55278 -396.627604) (xy 343.557978 -396.647975) (xy 343.563588 -396.689641)
			(xy 343.563956 -396.710662) (xy 344.12809 -396.710662) (xy 344.128457 -396.689641) (xy 344.134067 -396.647975)
			(xy 344.139266 -396.627604) (xy 344.141044 -396.621) (xy 344.141044 -396.507462) (xy 344.141503 -396.492444)
			(xy 344.149285 -396.463432) (xy 344.164309 -396.437423) (xy 344.185551 -396.416187) (xy 344.211566 -396.401171)
			(xy 344.24058 -396.393398) (xy 344.255598 -396.392908) (xy 344.437208 -396.392908) (xy 344.437716 -396.392654)
			(xy 344.446098 -396.392654) (xy 344.45448 -396.392654) (xy 344.454988 -396.392908) (xy 344.636598 -396.392908)
			(xy 344.651612 -396.393438) (xy 344.680616 -396.401207) (xy 344.706622 -396.416217) (xy 344.727858 -396.437446)
			(xy 344.742878 -396.463447) (xy 344.750657 -396.492449) (xy 344.751152 -396.507462) (xy 344.751152 -396.621)
			(xy 344.75293 -396.627604) (xy 344.758122 -396.647976) (xy 344.763732 -396.689642) (xy 344.764106 -396.710662)
			(xy 344.763966 -396.725415) (xy 344.76129 -396.754799) (xy 344.758772 -396.769336) (xy 344.757426 -396.778575)
			(xy 344.760673 -396.796943) (xy 344.765122 -396.80515) (xy 344.781632 -396.832074) (xy 344.786817 -396.839841)
			(xy 344.801531 -396.85131) (xy 344.810334 -396.854426) (xy 344.835281 -396.862465) (xy 344.882267 -396.885685)
			(xy 344.924763 -396.916359) (xy 344.961599 -396.953641) (xy 344.991758 -396.996504) (xy 345.01441 -397.043767)
			(xy 345.02217 -397.068802) (xy 345.023694 -397.074644) (xy 345.34348 -397.627602) (xy 345.347544 -397.63192)
			(xy 345.363743 -397.649632) (xy 345.391166 -397.689023) (xy 345.412309 -397.732111) (xy 345.426684 -397.777904)
			(xy 345.43396 -397.825346) (xy 345.434412 -397.849344) (xy 345.433928 -397.874807) (xy 345.425729 -397.925068)
			(xy 345.409567 -397.973361) (xy 345.385861 -398.018432) (xy 345.355227 -398.059113) (xy 345.318459 -398.094348)
			(xy 345.29776 -398.109186) (xy 345.28991 -398.11513) (xy 345.27902 -398.131509) (xy 345.275093 -398.150782)
			(xy 345.278705 -398.170116) (xy 345.289326 -398.186671) (xy 345.305396 -398.198013) (xy 345.324551 -398.202476)
			(xy 345.334336 -398.201388) (xy 345.342912 -398.200082) (xy 345.360205 -398.198685) (xy 345.36888 -398.198594)
			(xy 345.369134 -398.198848) (xy 345.668346 -398.198848) (xy 345.6686 -398.198594) (xy 345.689663 -398.198962)
			(xy 345.731023 -398.206924) (xy 345.770022 -398.222835) (xy 345.805148 -398.246079) (xy 345.835039 -398.275754)
			(xy 345.858536 -398.31071) (xy 345.874729 -398.349593) (xy 345.88299 -398.390894) (xy 345.883484 -398.411954)
			(xy 345.883484 -398.666716) (xy 345.87434 -398.666716) (xy 345.864319 -398.667153) (xy 345.8458 -398.674812)
			(xy 345.831626 -398.68898) (xy 345.823957 -398.707496) (xy 345.82354 -398.717516) (xy 345.82354 -398.881092)
			(xy 345.823006 -398.891094) (xy 345.815357 -398.909578) (xy 345.801218 -398.92373) (xy 345.782742 -398.931397)
			(xy 345.77274 -398.931892) (xy 345.26474 -398.931892) (xy 345.254702 -398.931561) (xy 345.236148 -398.923899)
			(xy 345.221963 -398.909695) (xy 345.214326 -398.891131) (xy 345.21394 -398.881092) (xy 345.21394 -398.666716)
			(xy 345.204796 -398.666716) (xy 345.19479 -398.666215) (xy 345.176301 -398.658558) (xy 345.162149 -398.644409)
			(xy 345.154487 -398.625922) (xy 345.153996 -398.615916) (xy 345.153996 -398.411954) (xy 345.154343 -398.394721)
			(xy 345.159913 -398.360709) (xy 345.170884 -398.328036) (xy 345.178634 -398.31264) (xy 345.18473 -398.30121)
			(xy 345.184476 -398.27581) (xy 345.130374 -398.178782) (xy 345.109038 -398.165066) (xy 345.096084 -398.16405)
			(xy 345.072184 -398.161964) (xy 345.025396 -398.151358) (xy 344.980755 -398.133785) (xy 344.939291 -398.109653)
			(xy 344.901961 -398.079517) (xy 344.869628 -398.044074) (xy 344.843038 -398.004142) (xy 344.822804 -397.960642)
			(xy 344.815668 -397.937736) (xy 344.814144 -397.931894) (xy 344.493596 -397.377412) (xy 344.489532 -397.373094)
			(xy 344.473425 -397.355427) (xy 344.446178 -397.316147) (xy 344.425168 -397.273206) (xy 344.410877 -397.227587)
			(xy 344.40363 -397.180334) (xy 344.403172 -397.156432) (xy 344.403335 -397.14232) (xy 344.405883 -397.114211)
			(xy 344.408252 -397.100298) (xy 344.409485 -397.091101) (xy 344.406112 -397.072872) (xy 344.401648 -397.064738)
			(xy 344.384884 -397.037814) (xy 344.379682 -397.030107) (xy 344.364964 -397.018771) (xy 344.356182 -397.015716)
			(xy 344.334565 -397.008943) (xy 344.293356 -396.990133) (xy 344.255234 -396.965664) (xy 344.220971 -396.936031)
			(xy 344.205814 -396.919196) (xy 344.203353 -396.916367) (xy 344.197741 -396.911395) (xy 344.194638 -396.90929)
			(xy 344.182623 -396.901191) (xy 344.162728 -396.88014) (xy 344.148715 -396.854789) (xy 344.141472 -396.826744)
			(xy 344.141044 -396.812262) (xy 344.141044 -396.800324) (xy 344.139266 -396.79372) (xy 344.13406 -396.773351)
			(xy 344.128459 -396.731683) (xy 344.12809 -396.710662) (xy 343.563956 -396.710662) (xy 343.563793 -396.724387)
			(xy 343.561379 -396.751731) (xy 343.55913 -396.765272) (xy 343.558876 -396.767304) (xy 343.558368 -396.77213)
			(xy 343.557938 -396.78031) (xy 343.561697 -396.796244) (xy 343.565734 -396.803372) (xy 343.577164 -396.821914)
			(xy 343.579671 -396.825733) (xy 343.585807 -396.832499) (xy 343.589356 -396.835376) (xy 343.610438 -396.851632)
			(xy 343.618566 -396.854426) (xy 343.643398 -396.863197) (xy 343.689976 -396.887767) (xy 343.731871 -396.919672)
			(xy 343.767941 -396.95804) (xy 343.797201 -397.001824) (xy 343.81885 -397.049829) (xy 343.826084 -397.075152)
			(xy 343.827862 -397.081756) (xy 344.138758 -397.619728) (xy 344.143584 -397.6243) (xy 344.160922 -397.642331)
			(xy 344.190326 -397.682796) (xy 344.213039 -397.727362) (xy 344.228501 -397.774931) (xy 344.236333 -397.824334)
			(xy 344.236802 -397.849344) (xy 344.236271 -397.876483) (xy 344.22709 -397.929977) (xy 344.208951 -397.981133)
			(xy 344.182383 -398.028462) (xy 344.148157 -398.070587) (xy 344.12809 -398.088866) (xy 344.119454 -398.095978)
			(xy 344.110564 -398.11579) (xy 344.110564 -398.139412) (xy 344.110564 -398.141952) (xy 344.111443 -398.151536)
			(xy 344.119395 -398.169045) (xy 344.126058 -398.175988) (xy 344.134694 -398.18437) (xy 344.142024 -398.190909)
			(xy 344.160188 -398.19834) (xy 344.17 -398.198848) (xy 344.46845 -398.198848) (xy 344.468704 -398.198594)
			(xy 344.489766 -398.198936) (xy 344.531123 -398.2069) (xy 344.570118 -398.222815) (xy 344.605237 -398.246064)
			(xy 344.635119 -398.275745) (xy 344.658605 -398.310706) (xy 344.674783 -398.349592) (xy 344.683027 -398.390895)
			(xy 344.683588 -398.411954) (xy 344.683588 -398.615916) (xy 344.683097 -398.625921) (xy 344.675434 -398.644405)
			(xy 344.661281 -398.65855) (xy 344.642793 -398.666203) (xy 344.632788 -398.666716) (xy 344.623644 -398.666716)
			(xy 344.623644 -398.881092) (xy 344.623158 -398.891104) (xy 344.615501 -398.909606) (xy 344.60135 -398.923772)
			(xy 344.582855 -398.931448) (xy 344.572844 -398.931892) (xy 344.127836 -398.931892) (xy 344.119994 -398.9394)
			(xy 344.111021 -398.959147) (xy 344.110564 -398.969992) (xy 344.110564 -399.556732) (xy 344.111026 -399.566609)
			(xy 344.118468 -399.584907) (xy 344.125042 -399.592292) (xy 344.125296 -399.592546) (xy 344.180414 -399.647664)
			(xy 344.180922 -399.648172) (xy 344.188302 -399.654757) (xy 344.206601 -399.662216) (xy 344.216482 -399.66265)
		)
		(stroke
			(width 0)
			(type solid)
		)
		(fill yes)
		(layer "B.Cu")
		(net "P1V8_CPU0_RT1_1A")
	)
	(gr_poly
		(pts
			(xy 151.765762 -83.382612) (xy 151.775725 -83.382127) (xy 151.794151 -83.374541) (xy 151.801576 -83.36788)
			(xy 152.084024 -83.085432) (xy 152.084532 -83.084924) (xy 152.091113 -83.077543) (xy 152.098558 -83.059243)
			(xy 152.09901 -83.049364) (xy 152.09901 -73.389998) (xy 152.098587 -73.379928) (xy 152.090873 -73.361323)
			(xy 152.084024 -73.35393) (xy 152.057862 -73.327768) (xy 152.05075 -73.320402) (xy 152.031954 -73.312782)
			(xy 146.106642 -73.312782) (xy 146.096651 -73.313311) (xy 146.078206 -73.321012) (xy 146.070828 -73.327768)
			(xy 146.006312 -73.39203) (xy 145.999538 -73.399456) (xy 145.991953 -73.418053) (xy 145.99158 -73.428098)
			(xy 145.99158 -75.783186) (xy 145.991131 -75.807379) (xy 145.983562 -75.855168) (xy 145.968609 -75.901185)
			(xy 145.946641 -75.944295) (xy 145.918197 -75.983437) (xy 145.90141 -76.000864) (xy 145.78457 -76.11745)
			(xy 145.777458 -76.130912) (xy 145.775934 -76.138278) (xy 145.770471 -76.16401) (xy 145.753414 -76.213772)
			(xy 145.729682 -76.260718) (xy 145.699727 -76.30396) (xy 145.664116 -76.342677) (xy 145.623524 -76.376135)
			(xy 145.578721 -76.4037) (xy 145.530556 -76.42485) (xy 145.479942 -76.439183) (xy 145.42784 -76.446428)
			(xy 145.401538 -76.446888) (xy 145.371547 -76.446336) (xy 145.312305 -76.436949) (xy 145.255268 -76.418386)
			(xy 145.22831 -76.405232) (xy 145.219166 -76.40066) (xy 145.199608 -76.399136) (xy 145.111724 -76.42733)
			(xy 145.096738 -76.44003) (xy 145.091912 -76.449174) (xy 145.079564 -76.472192) (xy 145.049521 -76.514922)
			(xy 145.01393 -76.553155) (xy 144.973458 -76.586177) (xy 144.92886 -76.613371) (xy 144.88097 -76.634228)
			(xy 144.830684 -76.648359) (xy 144.778939 -76.6555) (xy 144.752822 -76.65593) (xy 144.725567 -76.655469)
			(xy 144.67161 -76.647714) (xy 144.619306 -76.632359) (xy 144.569721 -76.609716) (xy 144.523862 -76.580247)
			(xy 144.482664 -76.544551) (xy 144.446966 -76.503356) (xy 144.417494 -76.457499) (xy 144.394849 -76.407914)
			(xy 144.379491 -76.355611) (xy 144.371733 -76.301655) (xy 144.371733 -76.247145) (xy 144.379491 -76.193189)
			(xy 144.394849 -76.140886) (xy 144.417494 -76.091301) (xy 144.446966 -76.045444) (xy 144.482664 -76.004249)
			(xy 144.523862 -75.968553) (xy 144.569721 -75.939084) (xy 144.619306 -75.916441) (xy 144.67161 -75.901086)
			(xy 144.725567 -75.893331) (xy 144.752822 -75.892914) (xy 144.782812 -75.89347) (xy 144.842051 -75.902866)
			(xy 144.899082 -75.921438) (xy 144.92605 -75.93457) (xy 144.935194 -75.939142) (xy 144.954752 -75.940666)
			(xy 145.042636 -75.912472) (xy 145.057622 -75.899772) (xy 145.062448 -75.890628) (xy 145.076056 -75.865342)
			(xy 145.109705 -75.818814) (xy 145.149951 -75.777858) (xy 145.195884 -75.7434) (xy 145.246464 -75.71622)
			(xy 145.300549 -75.696933) (xy 145.32864 -75.690984) (xy 145.336006 -75.68946) (xy 145.349468 -75.682348)
			(xy 145.361152 -75.670664) (xy 145.367918 -75.663235) (xy 145.375491 -75.644639) (xy 145.375884 -75.634596)
			(xy 145.375884 -75.383898) (xy 145.375539 -75.374941) (xy 145.369394 -75.358115) (xy 145.357851 -75.344418)
			(xy 145.35023 -75.339702) (xy 145.261584 -75.289156) (xy 145.234406 -75.28941) (xy 145.222468 -75.296522)
			(xy 145.195869 -75.311722) (xy 145.139473 -75.335656) (xy 145.08039 -75.351856) (xy 145.019674 -75.360032)
			(xy 144.989042 -75.36053) (xy 144.95907 -75.360064) (xy 144.899638 -75.352244) (xy 144.841734 -75.336734)
			(xy 144.786351 -75.313798) (xy 144.734436 -75.283829) (xy 144.686877 -75.24734) (xy 144.644488 -75.204954)
			(xy 144.607994 -75.157399) (xy 144.578021 -75.105486) (xy 144.55508 -75.050105) (xy 144.539564 -74.992204)
			(xy 144.531739 -74.932772) (xy 144.531739 -74.872828) (xy 144.539564 -74.813396) (xy 144.55508 -74.755495)
			(xy 144.578021 -74.700114) (xy 144.607994 -74.648201) (xy 144.644488 -74.600646) (xy 144.686877 -74.55826)
			(xy 144.734436 -74.521771) (xy 144.786351 -74.491802) (xy 144.841734 -74.468866) (xy 144.899638 -74.453356)
			(xy 144.95907 -74.445536) (xy 144.989042 -74.445114) (xy 145.019675 -74.445601) (xy 145.080395 -74.453768)
			(xy 145.139482 -74.469965) (xy 145.19588 -74.493901) (xy 145.222468 -74.509122) (xy 145.234406 -74.516234)
			(xy 145.261584 -74.516488) (xy 145.35023 -74.465942) (xy 145.357842 -74.461211) (xy 145.369402 -74.447531)
			(xy 145.375532 -74.430702) (xy 145.375884 -74.421746) (xy 145.375884 -73.363582) (xy 145.375393 -73.353578)
			(xy 145.367729 -73.335095) (xy 145.353576 -73.320952) (xy 145.335088 -73.313301) (xy 145.325084 -73.312782)
			(xy 143.535146 -73.312782) (xy 143.525154 -73.31331) (xy 143.506708 -73.32101) (xy 143.499332 -73.327768)
			(xy 142.430754 -74.396346) (xy 141.928088 -74.898758) (xy 141.925558 -74.901456) (xy 141.921221 -74.907448)
			(xy 141.919452 -74.910696) (xy 141.915642 -74.917554) (xy 141.914118 -74.925174) (xy 141.908643 -74.950893)
			(xy 141.891565 -75.000626) (xy 141.867819 -75.047542) (xy 141.837855 -75.090753) (xy 141.802239 -75.129438)
			(xy 141.761649 -75.162866) (xy 141.716852 -75.190403) (xy 141.668697 -75.211526) (xy 141.618098 -75.225835)
			(xy 141.566014 -75.23306) (xy 141.539722 -75.23353) (xy 141.512469 -75.233046) (xy 141.458518 -75.225292)
			(xy 141.406219 -75.209939) (xy 141.356638 -75.187299) (xy 141.310783 -75.157834) (xy 141.269588 -75.122143)
			(xy 141.233892 -75.080952) (xy 141.204422 -75.035101) (xy 141.181777 -74.985522) (xy 141.166417 -74.933225)
			(xy 141.158657 -74.879275) (xy 141.158214 -74.852022) (xy 141.158654 -74.825719) (xy 141.165883 -74.773612)
			(xy 141.180207 -74.722993) (xy 141.201353 -74.674825) (xy 141.228921 -74.63002) (xy 141.262387 -74.589431)
			(xy 141.301114 -74.553828) (xy 141.344368 -74.523887) (xy 141.391328 -74.500177) (xy 141.441102 -74.483148)
			(xy 141.466824 -74.477626) (xy 141.470529 -74.476819) (xy 141.477668 -74.474265) (xy 141.481048 -74.472546)
			(xy 141.487652 -74.468736) (xy 141.80566 -74.150982) (xy 142.470124 -73.486264) (xy 142.480346 -73.475298)
			(xy 142.494484 -73.448879) (xy 142.50035 -73.419495) (xy 142.497439 -73.389672) (xy 142.486003 -73.361976)
			(xy 142.467025 -73.338789) (xy 142.442136 -73.322104) (xy 142.413477 -73.313357) (xy 142.398496 -73.312782)
			(xy 138.952224 -73.312782) (xy 138.942198 -73.313197) (xy 138.92367 -73.320862) (xy 138.909486 -73.335035)
			(xy 138.901806 -73.353557) (xy 138.901424 -73.363582) (xy 138.901424 -75.75804) (xy 138.900994 -75.768108)
			(xy 138.893272 -75.786704) (xy 138.886438 -75.794108) (xy 138.555476 -76.12507) (xy 138.548078 -76.131916)
			(xy 138.529479 -76.139646) (xy 138.519408 -76.140056) (xy 137.459974 -76.140056) (xy 137.449907 -76.139627)
			(xy 137.431314 -76.131901) (xy 137.423906 -76.12507) (xy 137.129774 -75.830938) (xy 137.122929 -75.82354)
			(xy 137.115206 -75.804941) (xy 137.114788 -75.79487) (xy 137.114788 -73.354692) (xy 137.112851 -73.346017)
			(xy 137.103947 -73.330652) (xy 137.090326 -73.319255) (xy 137.07363 -73.313201) (xy 137.06475 -73.312782)
			(xy 136.15416 -73.312782) (xy 136.135364 -73.320402) (xy 136.128252 -73.327768) (xy 135.935466 -73.520554)
			(xy 135.928621 -73.527952) (xy 135.920896 -73.546551) (xy 135.92048 -73.556622) (xy 135.92048 -76.324968)
			(xy 142.317214 -76.324968) (xy 142.321285 -76.269346) (xy 142.333411 -76.214909) (xy 142.353334 -76.162818)
			(xy 142.38063 -76.114183) (xy 142.414716 -76.07004) (xy 142.454865 -76.031331) (xy 142.500223 -75.99888)
			(xy 142.549823 -75.973379) (xy 142.602607 -75.955372) (xy 142.65745 -75.945242) (xy 142.713184 -75.943205)
			(xy 142.768621 -75.949305) (xy 142.822578 -75.963411) (xy 142.873907 -75.985223) (xy 142.921513 -76.014277)
			(xy 142.964381 -76.049952) (xy 143.001598 -76.091489) (xy 143.032371 -76.138002) (xy 143.056043 -76.188499)
			(xy 143.072111 -76.241906) (xy 143.080231 -76.297082) (xy 143.08074 -76.324968) (xy 143.080231 -76.352854)
			(xy 143.072111 -76.40803) (xy 143.056043 -76.461437) (xy 143.032371 -76.511934) (xy 143.001598 -76.558447)
			(xy 142.964381 -76.599984) (xy 142.921513 -76.635659) (xy 142.873907 -76.664713) (xy 142.822578 -76.686525)
			(xy 142.768621 -76.700631) (xy 142.713184 -76.706731) (xy 142.65745 -76.704694) (xy 142.602607 -76.694564)
			(xy 142.549823 -76.676557) (xy 142.500223 -76.651056) (xy 142.454865 -76.618605) (xy 142.414716 -76.579896)
			(xy 142.38063 -76.535753) (xy 142.353334 -76.487118) (xy 142.333411 -76.435027) (xy 142.321285 -76.38059)
			(xy 142.317214 -76.324968) (xy 135.92048 -76.324968) (xy 135.92048 -81.935828) (xy 142.645384 -81.935828)
			(xy 142.645384 -81.636616) (xy 142.645855 -81.613709) (xy 142.654784 -81.56878) (xy 142.672545 -81.526555)
			(xy 142.685008 -81.50733) (xy 142.689326 -81.50098) (xy 142.693644 -81.486502) (xy 142.693644 -80.940148)
			(xy 142.694093 -80.915956) (xy 142.701669 -80.86817) (xy 142.716627 -80.822157) (xy 142.738598 -80.77905)
			(xy 142.767042 -80.73991) (xy 142.783814 -80.72247) (xy 142.892272 -80.614266) (xy 142.899892 -80.59547)
			(xy 142.899892 -80.58404) (xy 142.900398 -80.554072) (xy 142.908217 -80.494648) (xy 142.923725 -80.436753)
			(xy 142.946658 -80.381378) (xy 142.976623 -80.32947) (xy 143.013108 -80.281917) (xy 143.055487 -80.239534)
			(xy 143.103036 -80.203046) (xy 143.154942 -80.173076) (xy 143.210315 -80.150138) (xy 143.268209 -80.134625)
			(xy 143.327632 -80.126801) (xy 143.3576 -80.126332) (xy 143.35887 -80.126332) (xy 143.36903 -80.126332)
			(xy 143.387826 -80.118712) (xy 143.4211 -80.085184) (xy 143.438552 -80.068442) (xy 143.477711 -80.040066)
			(xy 143.520823 -80.018158) (xy 143.566829 -80.003256) (xy 143.614598 -79.995727) (xy 143.638778 -79.995268)
			(xy 143.972788 -79.995268) (xy 143.980363 -79.994951) (xy 143.994827 -79.99043) (xy 144.001236 -79.986378)
			(xy 144.024976 -79.971008) (xy 144.07604 -79.946705) (xy 144.130131 -79.930203) (xy 144.186066 -79.921863)
			(xy 144.214342 -79.921354) (xy 144.241589 -79.921919) (xy 144.269437 -79.925926) (xy 144.667984 -79.925926)
			(xy 144.672055 -79.870304) (xy 144.684181 -79.815867) (xy 144.704104 -79.763776) (xy 144.7314 -79.715141)
			(xy 144.765486 -79.670998) (xy 144.805635 -79.632289) (xy 144.850993 -79.599838) (xy 144.900593 -79.574337)
			(xy 144.953377 -79.55633) (xy 145.00822 -79.5462) (xy 145.063954 -79.544163) (xy 145.119391 -79.550263)
			(xy 145.173348 -79.564369) (xy 145.224677 -79.586181) (xy 145.272283 -79.615235) (xy 145.315151 -79.65091)
			(xy 145.352368 -79.692447) (xy 145.383141 -79.73896) (xy 145.406813 -79.789457) (xy 145.422881 -79.842864)
			(xy 145.431001 -79.89804) (xy 145.43151 -79.925926) (xy 145.431001 -79.953812) (xy 145.422881 -80.008988)
			(xy 145.406813 -80.062395) (xy 145.383141 -80.112892) (xy 145.352368 -80.159405) (xy 145.315151 -80.200942)
			(xy 145.272283 -80.236617) (xy 145.224677 -80.265671) (xy 145.173348 -80.287483) (xy 145.119391 -80.301589)
			(xy 145.063954 -80.307689) (xy 145.00822 -80.305652) (xy 144.953377 -80.295522) (xy 144.900593 -80.277515)
			(xy 144.850993 -80.252014) (xy 144.805635 -80.219563) (xy 144.765486 -80.180854) (xy 144.7314 -80.136711)
			(xy 144.704104 -80.088076) (xy 144.684181 -80.035985) (xy 144.672055 -79.981548) (xy 144.667984 -79.925926)
			(xy 144.269437 -79.925926) (xy 144.295526 -79.92968) (xy 144.347811 -79.945037) (xy 144.397378 -79.967678)
			(xy 144.443218 -79.997143) (xy 144.484399 -80.03283) (xy 144.520083 -80.074015) (xy 144.549542 -80.119859)
			(xy 144.572178 -80.169429) (xy 144.587529 -80.221715) (xy 144.595284 -80.275653) (xy 144.595284 -80.330147)
			(xy 144.587529 -80.384085) (xy 144.572178 -80.436371) (xy 144.549542 -80.485941) (xy 144.520083 -80.531785)
			(xy 144.484399 -80.57297) (xy 144.443218 -80.608657) (xy 144.397378 -80.638122) (xy 144.347811 -80.660763)
			(xy 144.295526 -80.67612) (xy 144.241589 -80.683881) (xy 144.214342 -80.68437) (xy 144.186066 -80.683862)
			(xy 144.130134 -80.675513) (xy 144.076045 -80.659007) (xy 144.024982 -80.634705) (xy 144.001236 -80.619346)
			(xy 143.994886 -80.615028) (xy 143.980408 -80.610456) (xy 143.841216 -80.610456) (xy 143.812768 -80.63484)
			(xy 143.809974 -80.653636) (xy 143.804719 -80.684598) (xy 143.786768 -80.744781) (xy 143.760757 -80.801945)
			(xy 143.727176 -80.855015) (xy 143.686654 -80.902997) (xy 143.639953 -80.944988) (xy 143.58795 -80.9802)
			(xy 143.531621 -81.007972) (xy 143.472025 -81.027782) (xy 143.410279 -81.039259) (xy 143.378936 -81.04124)
			(xy 143.369556 -81.042185) (xy 143.352357 -81.049857) (xy 143.345408 -81.056226) (xy 143.324072 -81.077562)
			(xy 143.317365 -81.085033) (xy 143.309782 -81.1036) (xy 143.30934 -81.11363) (xy 143.30934 -81.418176)
			(xy 143.30974 -81.428201) (xy 143.31741 -81.446725) (xy 143.331589 -81.460899) (xy 143.350115 -81.468563)
			(xy 143.36014 -81.468976) (xy 143.628618 -81.468976) (xy 143.634198 -81.468812) (xy 143.645093 -81.466385)
			(xy 143.650208 -81.46415) (xy 143.663924 -81.4578) (xy 143.663924 -81.438496) (xy 143.693896 -81.409032)
			(xy 143.93164 -81.409032) (xy 143.953951 -81.409517) (xy 143.997708 -81.418265) (xy 144.038903 -81.435416)
			(xy 144.07594 -81.460305) (xy 144.107384 -81.491966) (xy 144.132017 -81.529174) (xy 144.148884 -81.570486)
			(xy 144.157332 -81.614302) (xy 144.1577 -81.636616) (xy 144.1577 -81.935828) (xy 144.1577 -81.938876)
			(xy 144.1577 -82.286094) (xy 144.160494 -82.294476) (xy 144.171013 -82.325693) (xy 144.182385 -82.390574)
			(xy 144.1831 -82.423508) (xy 144.182614 -82.450759) (xy 144.174858 -82.504707) (xy 144.159503 -82.557002)
			(xy 144.136861 -82.606579) (xy 144.107395 -82.652429) (xy 144.071704 -82.69362) (xy 144.030513 -82.729311)
			(xy 143.984663 -82.758777) (xy 143.935086 -82.781419) (xy 143.882791 -82.796774) (xy 143.828843 -82.80453)
			(xy 143.774341 -82.80453) (xy 143.720393 -82.796774) (xy 143.668098 -82.781419) (xy 143.618521 -82.758777)
			(xy 143.572671 -82.729311) (xy 143.53148 -82.69362) (xy 143.495789 -82.652429) (xy 143.466323 -82.606579)
			(xy 143.443681 -82.557002) (xy 143.428326 -82.504707) (xy 143.42057 -82.450759) (xy 143.420084 -82.423508)
			(xy 143.420823 -82.390576) (xy 143.432185 -82.325696) (xy 143.44269 -82.294476) (xy 143.445484 -82.286094)
			(xy 143.445484 -82.154268) (xy 143.445038 -82.144256) (xy 143.437365 -82.125761) (xy 143.423199 -82.111608)
			(xy 143.404696 -82.103953) (xy 143.394684 -82.103468) (xy 143.13916 -82.103468) (xy 143.13916 -82.112612)
			(xy 143.138789 -82.122639) (xy 143.131108 -82.141164) (xy 143.11692 -82.155337) (xy 143.098387 -82.162999)
			(xy 143.08836 -82.163412) (xy 142.871444 -82.163412) (xy 142.849132 -82.162908) (xy 142.805372 -82.154171)
			(xy 142.764172 -82.137029) (xy 142.72713 -82.112145) (xy 142.695683 -82.080485) (xy 142.671051 -82.043276)
			(xy 142.654187 -82.001961) (xy 142.645747 -81.958143) (xy 142.645384 -81.935828) (xy 135.92048 -81.935828)
			(xy 135.92048 -82.394552) (xy 135.920912 -82.404618) (xy 135.928637 -82.423211) (xy 135.935466 -82.43062)
			(xy 136.872472 -83.367626) (xy 136.879871 -83.374469) (xy 136.89847 -83.382189) (xy 136.90854 -83.382612)
		)
		(stroke
			(width 0)
			(type solid)
		)
		(fill yes)
		(layer "B.Cu")
		(net "GND")
	)
	(gr_poly
		(pts
			(xy 463.790538 -65.619122) (xy 463.800414 -65.618659) (xy 463.818709 -65.611213) (xy 463.826098 -65.604644)
			(xy 463.826352 -65.60439) (xy 464.08721 -65.343532) (xy 464.087718 -65.343024) (xy 464.0943 -65.335643)
			(xy 464.101748 -65.317344) (xy 464.102196 -65.307464) (xy 464.102196 -52.934108) (xy 464.100418 -52.9209)
			(xy 464.095338 -52.902358) (xy 464.092036 -52.89677) (xy 464.050645 -52.823575) (xy 463.974633 -52.673562)
			(xy 463.906539 -52.519792) (xy 463.846548 -52.362684) (xy 463.794824 -52.202664) (xy 463.751507 -52.040167)
			(xy 463.716714 -51.875633) (xy 463.69054 -51.709511) (xy 463.673056 -51.54225) (xy 463.664309 -51.374306)
			(xy 463.663792 -51.29022) (xy 463.663792 -51.289966) (xy 463.663792 -51.289712) (xy 463.664347 -51.206)
			(xy 463.673055 -51.038804) (xy 463.690424 -50.872284) (xy 463.716406 -50.706889) (xy 463.750931 -50.543064)
			(xy 463.793907 -50.38125) (xy 463.845217 -50.221883) (xy 463.904724 -50.065392) (xy 463.972268 -49.912198)
			(xy 464.047665 -49.762713) (xy 464.088734 -49.689766) (xy 464.095338 -49.678082) (xy 464.095338 -49.677828)
			(xy 464.095592 -49.67732) (xy 464.098643 -49.671554) (xy 464.101977 -49.658948) (xy 464.102196 -49.652428)
			(xy 464.102196 -48.550068) (xy 464.094576 -48.531272) (xy 464.08721 -48.52416) (xy 463.786982 -48.223932)
			(xy 463.779584 -48.217085) (xy 463.760986 -48.209352) (xy 463.750914 -48.208946) (xy 461.976978 -48.208946)
			(xy 461.97243 -48.209066) (xy 461.963483 -48.21072) (xy 461.959198 -48.212248) (xy 461.93583 -48.220884)
			(xy 461.929226 -48.226218) (xy 461.908753 -48.242192) (xy 461.864306 -48.269044) (xy 461.816632 -48.289629)
			(xy 461.76661 -48.303567) (xy 461.71516 -48.3106) (xy 461.689196 -48.311054) (xy 461.662428 -48.310582)
			(xy 461.609421 -48.303061) (xy 461.557984 -48.288211) (xy 461.509126 -48.266321) (xy 461.463805 -48.237821)
			(xy 461.44307 -48.220884) (xy 461.435958 -48.215042) (xy 461.419448 -48.208946) (xy 461.374236 -48.208946)
			(xy 461.35544 -48.216566) (xy 461.348328 -48.223932) (xy 461.336644 -48.235616) (xy 461.329246 -48.242463)
			(xy 461.310647 -48.25019) (xy 461.300576 -48.250602) (xy 454.58888 -48.250602) (xy 454.570084 -48.258222)
			(xy 454.562972 -48.265588) (xy 454.184766 -48.643794) (xy 454.177911 -48.651189) (xy 454.170164 -48.669788)
			(xy 454.16978 -48.679862) (xy 454.16978 -49.318418) (xy 454.169353 -49.328486) (xy 454.161632 -49.347084)
			(xy 454.154794 -49.354486) (xy 454.055734 -49.453546) (xy 460.176878 -49.453546) (xy 460.180949 -49.397924)
			(xy 460.193075 -49.343487) (xy 460.212998 -49.291396) (xy 460.240294 -49.242761) (xy 460.27438 -49.198618)
			(xy 460.314529 -49.159909) (xy 460.359887 -49.127458) (xy 460.409487 -49.101957) (xy 460.462271 -49.08395)
			(xy 460.517114 -49.07382) (xy 460.572848 -49.071783) (xy 460.628285 -49.077883) (xy 460.682242 -49.091989)
			(xy 460.733571 -49.113801) (xy 460.781177 -49.142855) (xy 460.824045 -49.17853) (xy 460.861262 -49.220067)
			(xy 460.892035 -49.26658) (xy 460.915707 -49.317077) (xy 460.931775 -49.370484) (xy 460.939895 -49.42566)
			(xy 460.940404 -49.453546) (xy 460.939895 -49.481432) (xy 460.931775 -49.536608) (xy 460.915707 -49.590015)
			(xy 460.892035 -49.640512) (xy 460.861262 -49.687025) (xy 460.824045 -49.728562) (xy 460.781177 -49.764237)
			(xy 460.733571 -49.793291) (xy 460.682242 -49.815103) (xy 460.628285 -49.829209) (xy 460.572848 -49.835309)
			(xy 460.517114 -49.833272) (xy 460.462271 -49.823142) (xy 460.409487 -49.805135) (xy 460.359887 -49.779634)
			(xy 460.314529 -49.747183) (xy 460.27438 -49.708474) (xy 460.240294 -49.664331) (xy 460.212998 -49.615696)
			(xy 460.193075 -49.563605) (xy 460.180949 -49.509168) (xy 460.176878 -49.453546) (xy 454.055734 -49.453546)
			(xy 453.864726 -49.644554) (xy 453.857326 -49.651394) (xy 453.838727 -49.659109) (xy 453.828658 -49.65954)
			(xy 453.426068 -49.65954) (xy 453.416002 -49.659109) (xy 453.397411 -49.65138) (xy 453.39 -49.644554)
			(xy 452.691246 -48.945546) (xy 452.684403 -48.938147) (xy 452.676681 -48.919548) (xy 452.67626 -48.909478)
			(xy 452.67626 -46.00067) (xy 452.675747 -45.985833) (xy 452.667216 -45.95741) (xy 452.650882 -45.932635)
			(xy 452.62812 -45.913595) (xy 452.600849 -45.901893) (xy 452.571367 -45.898517) (xy 452.542157 -45.90375)
			(xy 452.528686 -45.909992) (xy 452.501777 -45.923022) (xy 452.444909 -45.941469) (xy 452.385858 -45.950813)
			(xy 452.355966 -45.951394) (xy 452.328697 -45.950905) (xy 452.274716 -45.94314) (xy 452.222388 -45.927772)
			(xy 452.172781 -45.905114) (xy 452.126902 -45.875628) (xy 452.085685 -45.839913) (xy 452.049971 -45.798697)
			(xy 452.020485 -45.752818) (xy 451.997827 -45.70321) (xy 451.98246 -45.650882) (xy 451.974695 -45.596901)
			(xy 451.974204 -45.569632) (xy 451.974688 -45.54236) (xy 451.982446 -45.488371) (xy 451.997808 -45.436036)
			(xy 452.020462 -45.38642) (xy 452.049947 -45.340532) (xy 452.085661 -45.299308) (xy 452.126879 -45.263586)
			(xy 452.172762 -45.234094) (xy 452.222374 -45.211431) (xy 452.274707 -45.19606) (xy 452.328694 -45.188293)
			(xy 452.355966 -45.18787) (xy 452.385855 -45.188476) (xy 452.444898 -45.197837) (xy 452.501764 -45.216273)
			(xy 452.528686 -45.229272) (xy 452.542155 -45.235541) (xy 452.571379 -45.24081) (xy 452.600885 -45.237451)
			(xy 452.628177 -45.225749) (xy 452.650952 -45.206693) (xy 452.667284 -45.181892) (xy 452.675794 -45.153442)
			(xy 452.67626 -45.138594) (xy 452.67626 -44.854622) (xy 452.66864 -44.835826) (xy 452.661274 -44.828714)
			(xy 452.515986 -44.683426) (xy 452.508588 -44.676579) (xy 452.48999 -44.668846) (xy 452.479918 -44.66844)
			(xy 450.558662 -44.66844) (xy 450.539866 -44.67606) (xy 450.532754 -44.683426) (xy 450.527166 -44.689014)
			(xy 450.51977 -44.695865) (xy 450.501171 -44.7036) (xy 450.491098 -44.704) (xy 430.032922 -44.704)
			(xy 430.014126 -44.71162) (xy 430.007014 -44.718986) (xy 429.217062 -45.508938) (xy 450.882748 -45.508938)
			(xy 450.882748 -45.44897) (xy 450.890576 -45.389514) (xy 450.906097 -45.331589) (xy 450.929046 -45.276185)
			(xy 450.95903 -45.224251) (xy 450.995536 -45.176675) (xy 451.037941 -45.13427) (xy 451.085517 -45.097764)
			(xy 451.137451 -45.06778) (xy 451.192855 -45.044831) (xy 451.25078 -45.02931) (xy 451.310236 -45.021482)
			(xy 451.370204 -45.021482) (xy 451.42966 -45.02931) (xy 451.487585 -45.044831) (xy 451.542989 -45.06778)
			(xy 451.594923 -45.097764) (xy 451.642499 -45.13427) (xy 451.684904 -45.176675) (xy 451.72141 -45.224251)
			(xy 451.751394 -45.276185) (xy 451.774343 -45.331589) (xy 451.789864 -45.389514) (xy 451.797692 -45.44897)
			(xy 451.798182 -45.478954) (xy 451.797692 -45.508938) (xy 451.789864 -45.568394) (xy 451.774343 -45.626319)
			(xy 451.751394 -45.681723) (xy 451.72141 -45.733657) (xy 451.684904 -45.781233) (xy 451.642499 -45.823638)
			(xy 451.594923 -45.860144) (xy 451.542989 -45.890128) (xy 451.487585 -45.913077) (xy 451.42966 -45.928598)
			(xy 451.370204 -45.936426) (xy 451.310236 -45.936426) (xy 451.25078 -45.928598) (xy 451.192855 -45.913077)
			(xy 451.137451 -45.890128) (xy 451.085517 -45.860144) (xy 451.037941 -45.823638) (xy 450.995536 -45.781233)
			(xy 450.95903 -45.733657) (xy 450.929046 -45.681723) (xy 450.906097 -45.626319) (xy 450.890576 -45.568394)
			(xy 450.882748 -45.508938) (xy 429.217062 -45.508938) (xy 427.547786 -47.178214) (xy 427.540932 -47.185609)
			(xy 427.53319 -47.204208) (xy 427.5328 -47.214282) (xy 427.5328 -51.134518) (xy 430.1744 -51.134518)
			(xy 430.1744 -47.493682) (xy 430.17479 -47.483608) (xy 430.182532 -47.465009) (xy 430.189386 -47.457614)
			(xy 430.448974 -47.198026) (xy 430.456392 -47.191209) (xy 430.474977 -47.183475) (xy 430.485042 -47.18304)
			(xy 450.653658 -47.18304) (xy 450.663726 -47.183477) (xy 450.682325 -47.191188) (xy 450.689726 -47.198026)
			(xy 450.88556 -47.39386) (xy 450.88937 -47.39005) (xy 451.330314 -47.830994) (xy 451.337146 -47.838401)
			(xy 451.34487 -47.856995) (xy 451.3453 -47.867062) (xy 451.3453 -48.950118) (xy 451.34569 -48.960192)
			(xy 451.353432 -48.978791) (xy 451.360286 -48.986186) (xy 451.5231 -49.149) (xy 451.523862 -49.154588)
			(xy 452.701914 -50.33264) (xy 452.708766 -50.340031) (xy 452.711597 -50.34686) (xy 459.606378 -50.34686)
			(xy 459.606378 -50.286924) (xy 459.614201 -50.227502) (xy 459.629714 -50.169609) (xy 459.65265 -50.114236)
			(xy 459.682617 -50.06233) (xy 459.719104 -50.01478) (xy 459.761484 -49.9724) (xy 459.809034 -49.935913)
			(xy 459.86094 -49.905946) (xy 459.916313 -49.88301) (xy 459.974206 -49.867497) (xy 460.033628 -49.859674)
			(xy 460.093564 -49.859674) (xy 460.152986 -49.867497) (xy 460.210879 -49.88301) (xy 460.266252 -49.905946)
			(xy 460.318158 -49.935913) (xy 460.365708 -49.9724) (xy 460.408088 -50.01478) (xy 460.444575 -50.06233)
			(xy 460.474542 -50.114236) (xy 460.497478 -50.169609) (xy 460.512991 -50.227502) (xy 460.520814 -50.286924)
			(xy 460.521304 -50.316892) (xy 460.520814 -50.34686) (xy 460.512991 -50.406282) (xy 460.497478 -50.464175)
			(xy 460.474542 -50.519548) (xy 460.444575 -50.571454) (xy 460.408088 -50.619004) (xy 460.365708 -50.661384)
			(xy 460.318158 -50.697871) (xy 460.266252 -50.727838) (xy 460.210879 -50.750774) (xy 460.152986 -50.766287)
			(xy 460.093564 -50.77411) (xy 460.033628 -50.77411) (xy 459.974206 -50.766287) (xy 459.916313 -50.750774)
			(xy 459.86094 -50.727838) (xy 459.809034 -50.697871) (xy 459.761484 -50.661384) (xy 459.719104 -50.619004)
			(xy 459.682617 -50.571454) (xy 459.65265 -50.519548) (xy 459.629714 -50.464175) (xy 459.614201 -50.406282)
			(xy 459.606378 -50.34686) (xy 452.711597 -50.34686) (xy 452.716478 -50.358637) (xy 452.7169 -50.368708)
			(xy 452.7169 -52.635658) (xy 452.716479 -52.645728) (xy 452.708758 -52.664328) (xy 452.701914 -52.671726)
			(xy 452.598028 -52.775612) (xy 452.598028 -52.78501) (xy 452.297428 -53.085234) (xy 460.855042 -53.085234)
			(xy 460.855042 -53.025298) (xy 460.862865 -52.965876) (xy 460.878378 -52.907983) (xy 460.901314 -52.85261)
			(xy 460.931281 -52.800704) (xy 460.967768 -52.753154) (xy 461.010148 -52.710774) (xy 461.057698 -52.674287)
			(xy 461.109604 -52.64432) (xy 461.164977 -52.621384) (xy 461.22287 -52.605871) (xy 461.282292 -52.598048)
			(xy 461.342228 -52.598048) (xy 461.40165 -52.605871) (xy 461.459543 -52.621384) (xy 461.514916 -52.64432)
			(xy 461.566822 -52.674287) (xy 461.614372 -52.710774) (xy 461.656752 -52.753154) (xy 461.693239 -52.800704)
			(xy 461.723206 -52.85261) (xy 461.746142 -52.907983) (xy 461.761655 -52.965876) (xy 461.769478 -53.025298)
			(xy 461.769968 -53.055266) (xy 461.769478 -53.085234) (xy 461.761655 -53.144656) (xy 461.746142 -53.202549)
			(xy 461.723206 -53.257922) (xy 461.693239 -53.309828) (xy 461.656752 -53.357378) (xy 461.614372 -53.399758)
			(xy 461.566822 -53.436245) (xy 461.514916 -53.466212) (xy 461.459543 -53.489148) (xy 461.40165 -53.504661)
			(xy 461.342228 -53.512484) (xy 461.282292 -53.512484) (xy 461.22287 -53.504661) (xy 461.164977 -53.489148)
			(xy 461.109604 -53.466212) (xy 461.057698 -53.436245) (xy 461.010148 -53.399758) (xy 460.967768 -53.357378)
			(xy 460.931281 -53.309828) (xy 460.901314 -53.257922) (xy 460.878378 -53.202549) (xy 460.862865 -53.144656)
			(xy 460.855042 -53.085234) (xy 452.297428 -53.085234) (xy 452.19239 -53.19014) (xy 452.1835 -53.19014)
			(xy 452.145146 -53.228494) (xy 452.137723 -53.235306) (xy 452.119141 -53.243042) (xy 452.109078 -53.24348)
			(xy 441.821062 -53.24348) (xy 441.81099 -53.24308) (xy 441.792392 -53.235342) (xy 441.784994 -53.228494)
			(xy 440.646566 -52.090066) (xy 440.639454 -52.0827) (xy 440.620658 -52.07508) (xy 440.464448 -52.07508)
			(xy 440.450536 -52.075609) (xy 440.42375 -52.083138) (xy 440.399993 -52.097623) (xy 440.381032 -52.117985)
			(xy 440.368275 -52.142713) (xy 440.362672 -52.169967) (xy 440.364638 -52.197722) (xy 440.374028 -52.223914)
			(xy 440.390143 -52.246596) (xy 440.400694 -52.255674) (xy 440.434622 -52.283774) (xy 440.497333 -52.345652)
			(xy 440.553621 -52.413425) (xy 440.602934 -52.486431) (xy 440.644789 -52.563953) (xy 440.678777 -52.645233)
			(xy 440.704564 -52.729474) (xy 440.721898 -52.815852) (xy 440.730609 -52.90352) (xy 440.731148 -52.94757)
			(xy 440.730644 -52.989918) (xy 440.722593 -53.074232) (xy 440.706564 -53.157398) (xy 440.682703 -53.238665)
			(xy 440.651224 -53.317295) (xy 440.612413 -53.392576) (xy 440.566623 -53.463828) (xy 440.514267 -53.530404)
			(xy 440.455819 -53.591702) (xy 440.391809 -53.647167) (xy 440.322817 -53.696296) (xy 440.249467 -53.738645)
			(xy 440.172424 -53.773829) (xy 440.092385 -53.801531) (xy 440.010076 -53.821499) (xy 439.926241 -53.833552)
			(xy 439.84164 -53.837583) (xy 439.757039 -53.833552) (xy 439.673204 -53.821499) (xy 439.590895 -53.801531)
			(xy 439.510856 -53.773829) (xy 439.433813 -53.738645) (xy 439.360463 -53.696296) (xy 439.291471 -53.647167)
			(xy 439.227461 -53.591702) (xy 439.169013 -53.530404) (xy 439.116657 -53.463828) (xy 439.070867 -53.392576)
			(xy 439.032056 -53.317295) (xy 439.000577 -53.238665) (xy 438.976716 -53.157398) (xy 438.960687 -53.074232)
			(xy 438.952636 -52.989918) (xy 438.952132 -52.94757) (xy 438.952685 -52.90352) (xy 438.961388 -52.815851)
			(xy 438.978716 -52.729472) (xy 439.004499 -52.64523) (xy 439.038485 -52.563949) (xy 439.08034 -52.486427)
			(xy 439.129655 -52.413422) (xy 439.185946 -52.345651) (xy 439.248661 -52.283777) (xy 439.282586 -52.255674)
			(xy 439.293153 -52.246593) (xy 439.309313 -52.223908) (xy 439.318737 -52.197698) (xy 439.320723 -52.169917)
			(xy 439.315123 -52.142633) (xy 439.302354 -52.11788) (xy 439.283368 -52.097502) (xy 439.259578 -52.083017)
			(xy 439.232758 -52.075503) (xy 439.218832 -52.07508) (xy 432.749198 -52.07508) (xy 432.735287 -52.075584)
			(xy 432.708505 -52.083124) (xy 432.684754 -52.097614) (xy 432.665797 -52.11798) (xy 432.653043 -52.142708)
			(xy 432.64744 -52.169961) (xy 432.649404 -52.197714) (xy 432.658789 -52.223907) (xy 432.674897 -52.246593)
			(xy 432.685444 -52.255674) (xy 432.719361 -52.283786) (xy 432.782074 -52.345662) (xy 432.838364 -52.413433)
			(xy 432.887679 -52.486436) (xy 432.929536 -52.563957) (xy 432.963525 -52.645236) (xy 432.989313 -52.729476)
			(xy 433.006648 -52.815853) (xy 433.015359 -52.90352) (xy 433.015898 -52.94757) (xy 433.015394 -52.989918)
			(xy 433.007343 -53.074232) (xy 432.991314 -53.157398) (xy 432.967453 -53.238665) (xy 432.935974 -53.317295)
			(xy 432.897163 -53.392576) (xy 432.851373 -53.463828) (xy 432.799017 -53.530404) (xy 432.740569 -53.591702)
			(xy 432.676559 -53.647167) (xy 432.607567 -53.696296) (xy 432.534217 -53.738645) (xy 432.457174 -53.773829)
			(xy 432.377135 -53.801531) (xy 432.294826 -53.821499) (xy 432.210991 -53.833552) (xy 432.12639 -53.837583)
			(xy 432.041789 -53.833552) (xy 431.957954 -53.821499) (xy 431.875645 -53.801531) (xy 431.795606 -53.773829)
			(xy 431.718563 -53.738645) (xy 431.645213 -53.696296) (xy 431.576221 -53.647167) (xy 431.512211 -53.591702)
			(xy 431.453763 -53.530404) (xy 431.401407 -53.463828) (xy 431.355617 -53.392576) (xy 431.316806 -53.317295)
			(xy 431.285327 -53.238665) (xy 431.261466 -53.157398) (xy 431.245437 -53.074232) (xy 431.237386 -52.989918)
			(xy 431.236882 -52.94757) (xy 431.237416 -52.903519) (xy 431.24612 -52.815849) (xy 431.263449 -52.729469)
			(xy 431.289234 -52.645226) (xy 431.323222 -52.563945) (xy 431.36508 -52.486423) (xy 431.414397 -52.413419)
			(xy 431.470691 -52.345648) (xy 431.533409 -52.283776) (xy 431.567336 -52.255674) (xy 431.577877 -52.246568)
			(xy 431.594024 -52.223886) (xy 431.60344 -52.197684) (xy 431.605423 -52.169912) (xy 431.599825 -52.142638)
			(xy 431.587063 -52.117893) (xy 431.568087 -52.097518) (xy 431.544311 -52.083031) (xy 431.517503 -52.07551)
			(xy 431.503582 -52.07508) (xy 431.114962 -52.07508) (xy 431.10489 -52.07468) (xy 431.086292 -52.066942)
			(xy 431.078894 -52.060094) (xy 430.189386 -51.170586) (xy 430.182546 -51.163186) (xy 430.174827 -51.144587)
			(xy 430.1744 -51.134518) (xy 427.5328 -51.134518) (xy 427.5328 -53.471318) (xy 427.533227 -53.481387)
			(xy 427.540946 -53.499986) (xy 427.547786 -53.507386) (xy 430.862994 -56.822594) (xy 430.870392 -56.829442)
			(xy 430.88899 -56.83718) (xy 430.899062 -56.83758) (xy 437.175148 -56.83758) (xy 437.185215 -56.838011)
			(xy 437.203809 -56.845736) (xy 437.211216 -56.852566) (xy 437.906922 -57.548526) (xy 437.913773 -57.555922)
			(xy 437.92151 -57.574521) (xy 437.921908 -57.584594) (xy 437.921908 -64.558926) (xy 437.922336 -64.568994)
			(xy 437.930058 -64.587591) (xy 437.936894 -64.594994) (xy 438.946036 -65.604136) (xy 438.953433 -65.610984)
			(xy 438.972032 -65.618715) (xy 438.982104 -65.619122)
		)
		(stroke
			(width 0)
			(type solid)
		)
		(fill yes)
		(layer "B.Cu")
		(net "GND")
	)
	(gr_poly
		(pts
			(xy 336.655918 -165.227) (xy 336.665987 -165.226573) (xy 336.684586 -165.218854) (xy 336.691986 -165.212014)
			(xy 336.814414 -165.089586) (xy 336.821268 -165.082191) (xy 336.82901 -165.063592) (xy 336.8294 -165.053518)
			(xy 336.8294 -161.666682) (xy 336.829827 -161.656613) (xy 336.837546 -161.638014) (xy 336.844386 -161.630614)
			(xy 337.627214 -160.847786) (xy 337.634609 -160.840932) (xy 337.653208 -160.83319) (xy 337.663282 -160.8328)
			(xy 339.881718 -160.8328) (xy 339.891787 -160.832373) (xy 339.910386 -160.824654) (xy 339.917786 -160.817814)
			(xy 340.114128 -160.621472) (xy 340.120978 -160.614075) (xy 340.128713 -160.595477) (xy 340.129114 -160.585404)
			(xy 340.129114 -152.550622) (xy 340.129552 -152.540558) (xy 340.137288 -152.521976) (xy 340.1441 -152.514554)
			(xy 341.185246 -151.473662) (xy 341.192644 -151.466816) (xy 341.211243 -151.459089) (xy 341.221314 -151.458676)
			(xy 349.383096 -151.458676) (xy 349.393166 -151.458253) (xy 349.411769 -151.450537) (xy 349.419164 -151.44369)
			(xy 352.51517 -148.347684) (xy 352.522568 -148.34084) (xy 352.541168 -148.333117) (xy 352.551238 -148.332698)
			(xy 356.757478 -148.332698) (xy 356.767542 -148.33226) (xy 356.786125 -148.324526) (xy 356.793546 -148.317712)
			(xy 357.281988 -147.82927) (xy 357.288831 -147.82187) (xy 357.296556 -147.803272) (xy 357.296974 -147.793202)
			(xy 357.296974 -131.8514) (xy 357.29655 -131.84133) (xy 357.288833 -131.822728) (xy 357.281988 -131.815332)
			(xy 356.741984 -131.275328) (xy 356.734586 -131.268481) (xy 356.715988 -131.260748) (xy 356.705916 -131.260342)
			(xy 334.157574 -131.260342) (xy 334.147507 -131.260771) (xy 334.128913 -131.268497) (xy 334.121506 -131.275328)
			(xy 333.646272 -131.750562) (xy 333.639427 -131.75796) (xy 333.631704 -131.776559) (xy 333.631286 -131.78663)
			(xy 333.631286 -134.283196) (xy 333.630863 -134.293266) (xy 333.623148 -134.31187) (xy 333.6163 -134.319264)
			(xy 333.45247 -134.483094) (xy 333.44507 -134.489936) (xy 333.426472 -134.497661) (xy 333.416402 -134.49808)
			(xy 329.981306 -134.49808) (xy 329.971235 -134.498501) (xy 329.952627 -134.506212) (xy 329.945238 -134.513066)
			(xy 329.196954 -135.26135) (xy 329.196954 -135.264906) (xy 327.987914 -136.473946) (xy 330.23556 -136.473946)
			(xy 330.236051 -136.446712) (xy 330.243797 -136.392797) (xy 330.259138 -136.340534) (xy 330.281761 -136.290986)
			(xy 330.311206 -136.245162) (xy 330.346873 -136.203996) (xy 330.388036 -136.168325) (xy 330.433858 -136.138877)
			(xy 330.483404 -136.116249) (xy 330.535666 -136.100904) (xy 330.58958 -136.093154) (xy 330.616814 -136.092692)
			(xy 330.617322 -136.092692) (xy 330.64323 -136.093454) (xy 330.645008 -136.093708) (xy 331.239368 -136.093708)
			(xy 331.252364 -136.09382) (xy 331.278295 -136.095597) (xy 331.291184 -136.097264) (xy 331.29474 -136.097772)
			(xy 331.376528 -136.097772) (xy 331.376528 -136.10082) (xy 331.391768 -136.125204) (xy 331.40523 -136.131808)
			(xy 331.439012 -136.150096) (xy 331.445048 -136.153601) (xy 331.458453 -136.157466) (xy 331.465428 -136.157716)
			(xy 331.9018 -136.157716) (xy 331.9018 -136.148572) (xy 331.902265 -136.138563) (xy 331.909934 -136.12007)
			(xy 331.924094 -136.105918) (xy 331.94259 -136.09826) (xy 331.9526 -136.097772) (xy 332.169262 -136.097772)
			(xy 332.191573 -136.098287) (xy 332.235332 -136.107023) (xy 332.27653 -136.124165) (xy 332.31357 -136.149048)
			(xy 332.345017 -136.180706) (xy 332.36965 -136.217913) (xy 332.386515 -136.259226) (xy 332.394958 -136.303042)
			(xy 332.395322 -136.325356) (xy 332.395068 -136.325356) (xy 332.395068 -136.360408) (xy 332.395471 -136.37048)
			(xy 332.403206 -136.389079) (xy 332.410054 -136.396476) (xy 333.967328 -137.953496) (xy 333.984628 -137.971484)
			(xy 334.013958 -138.011859) (xy 334.036611 -138.056326) (xy 334.052028 -138.103789) (xy 334.059831 -138.15308)
			(xy 334.060292 -138.178032) (xy 334.060292 -139.774422) (xy 334.060682 -139.784496) (xy 334.068425 -139.803095)
			(xy 334.075278 -139.81049) (xy 336.68335 -142.418562) (xy 336.690778 -142.425367) (xy 336.709356 -142.433108)
			(xy 336.719418 -142.433548) (xy 337.316318 -142.433548) (xy 337.327851 -142.432989) (xy 337.348616 -142.422952)
			(xy 337.356196 -142.414244) (xy 337.374826 -142.391462) (xy 337.417026 -142.350442) (xy 337.464132 -142.315164)
			(xy 337.515368 -142.286209) (xy 337.569891 -142.264055) (xy 337.626802 -142.249066) (xy 337.685164 -142.241489)
			(xy 337.71459 -142.241016) (xy 337.744561 -142.241437) (xy 337.80399 -142.249259) (xy 337.86189 -142.264772)
			(xy 337.91727 -142.28771) (xy 337.969182 -142.317681) (xy 338.016737 -142.35417) (xy 338.059123 -142.396555)
			(xy 338.095614 -142.44411) (xy 338.125585 -142.496021) (xy 338.148524 -142.5514) (xy 338.164039 -142.6093)
			(xy 338.171863 -142.668729) (xy 338.171863 -142.728671) (xy 338.164039 -142.7881) (xy 338.148524 -142.846)
			(xy 338.125585 -142.901379) (xy 338.095614 -142.95329) (xy 338.059123 -143.000845) (xy 338.016737 -143.04323)
			(xy 337.969182 -143.079719) (xy 337.91727 -143.10969) (xy 337.86189 -143.132628) (xy 337.80399 -143.148141)
			(xy 337.744561 -143.155963) (xy 337.71459 -143.156432) (xy 337.680564 -143.155768) (xy 337.613271 -143.145618)
			(xy 337.548218 -143.125631) (xy 337.486834 -143.096246) (xy 337.458304 -143.077692) (xy 337.45186 -143.073741)
			(xy 337.437408 -143.069341) (xy 337.429856 -143.069056) (xy 336.56651 -143.069056) (xy 336.541562 -143.068534)
			(xy 336.492281 -143.060725) (xy 336.444824 -143.045314) (xy 336.400358 -143.022678) (xy 336.359974 -142.993374)
			(xy 336.341974 -142.976092) (xy 333.517748 -140.151866) (xy 333.500426 -140.133899) (xy 333.471099 -140.093517)
			(xy 333.448451 -140.049045) (xy 333.433039 -140.001578) (xy 333.425242 -139.952284) (xy 333.424784 -139.92733)
			(xy 333.424784 -138.33094) (xy 333.424342 -138.320873) (xy 333.416633 -138.302274) (xy 333.409798 -138.294872)
			(xy 331.982064 -136.867138) (xy 331.974666 -136.860295) (xy 331.956065 -136.852576) (xy 331.945996 -136.852152)
			(xy 331.9018 -136.852152) (xy 331.9018 -136.843008) (xy 331.901374 -136.832987) (xy 331.893707 -136.81447)
			(xy 331.879536 -136.800298) (xy 331.861021 -136.792628) (xy 331.851 -136.792208) (xy 331.465428 -136.792208)
			(xy 331.458463 -136.792526) (xy 331.44507 -136.796378) (xy 331.439012 -136.799828) (xy 331.40523 -136.818116)
			(xy 331.391768 -136.82472) (xy 331.376528 -136.849104) (xy 331.376528 -136.852152) (xy 331.29474 -136.852152)
			(xy 331.291184 -136.85266) (xy 331.278294 -136.854316) (xy 331.252364 -136.856094) (xy 331.239368 -136.856216)
			(xy 330.617576 -136.856216) (xy 330.587656 -136.855646) (xy 330.528556 -136.846273) (xy 330.471647 -136.827777)
			(xy 330.418329 -136.800612) (xy 330.369912 -136.765446) (xy 330.348336 -136.74471) (xy 330.34732 -136.743694)
			(xy 330.326499 -136.722115) (xy 330.291246 -136.673608) (xy 330.26402 -136.620182) (xy 330.24549 -136.563154)
			(xy 330.236114 -136.503928) (xy 330.23556 -136.473946) (xy 327.987914 -136.473946) (xy 327.324212 -137.137648)
			(xy 327.321509 -137.140501) (xy 327.316924 -137.146883) (xy 327.315068 -137.150348) (xy 327.312487 -137.155775)
			(xy 327.309666 -137.167455) (xy 327.30948 -137.173462) (xy 327.30948 -137.849864) (xy 328.187556 -137.849864)
			(xy 328.191627 -137.794242) (xy 328.203753 -137.739805) (xy 328.223676 -137.687714) (xy 328.250972 -137.639079)
			(xy 328.285058 -137.594936) (xy 328.325207 -137.556227) (xy 328.370565 -137.523776) (xy 328.420165 -137.498275)
			(xy 328.472949 -137.480268) (xy 328.527792 -137.470138) (xy 328.583526 -137.468101) (xy 328.638963 -137.474201)
			(xy 328.69292 -137.488307) (xy 328.744249 -137.510119) (xy 328.791855 -137.539173) (xy 328.834723 -137.574848)
			(xy 328.87194 -137.616385) (xy 328.902713 -137.662898) (xy 328.926385 -137.713395) (xy 328.942453 -137.766802)
			(xy 328.950573 -137.821978) (xy 328.951082 -137.849864) (xy 328.950573 -137.87775) (xy 328.942453 -137.932926)
			(xy 328.926385 -137.986333) (xy 328.902713 -138.03683) (xy 328.87194 -138.083343) (xy 328.834723 -138.12488)
			(xy 328.791855 -138.160555) (xy 328.744249 -138.189609) (xy 328.69292 -138.211421) (xy 328.638963 -138.225527)
			(xy 328.583526 -138.231627) (xy 328.527792 -138.22959) (xy 328.472949 -138.21946) (xy 328.420165 -138.201453)
			(xy 328.370565 -138.175952) (xy 328.325207 -138.143501) (xy 328.285058 -138.104792) (xy 328.250972 -138.060649)
			(xy 328.223676 -138.012014) (xy 328.203753 -137.959923) (xy 328.191627 -137.905486) (xy 328.187556 -137.849864)
			(xy 327.30948 -137.849864) (xy 327.30948 -140.408152) (xy 332.324962 -140.408152) (xy 332.329033 -140.35253)
			(xy 332.341159 -140.298093) (xy 332.361082 -140.246002) (xy 332.388378 -140.197367) (xy 332.422464 -140.153224)
			(xy 332.462613 -140.114515) (xy 332.507971 -140.082064) (xy 332.557571 -140.056563) (xy 332.610355 -140.038556)
			(xy 332.665198 -140.028426) (xy 332.720932 -140.026389) (xy 332.776369 -140.032489) (xy 332.830326 -140.046595)
			(xy 332.881655 -140.068407) (xy 332.929261 -140.097461) (xy 332.972129 -140.133136) (xy 333.009346 -140.174673)
			(xy 333.040119 -140.221186) (xy 333.063791 -140.271683) (xy 333.079859 -140.32509) (xy 333.087979 -140.380266)
			(xy 333.088488 -140.408152) (xy 333.087979 -140.436038) (xy 333.079859 -140.491214) (xy 333.063791 -140.544621)
			(xy 333.040119 -140.595118) (xy 333.009346 -140.641631) (xy 332.972129 -140.683168) (xy 332.929261 -140.718843)
			(xy 332.881655 -140.747897) (xy 332.830326 -140.769709) (xy 332.776369 -140.783815) (xy 332.720932 -140.789915)
			(xy 332.665198 -140.787878) (xy 332.610355 -140.777748) (xy 332.557571 -140.759741) (xy 332.507971 -140.73424)
			(xy 332.462613 -140.701789) (xy 332.422464 -140.66308) (xy 332.388378 -140.618937) (xy 332.361082 -140.570302)
			(xy 332.341159 -140.518211) (xy 332.329033 -140.463774) (xy 332.324962 -140.408152) (xy 327.30948 -140.408152)
			(xy 327.30948 -142.578074) (xy 328.532234 -142.578074) (xy 328.536305 -142.522452) (xy 328.548431 -142.468015)
			(xy 328.568354 -142.415924) (xy 328.59565 -142.367289) (xy 328.629736 -142.323146) (xy 328.669885 -142.284437)
			(xy 328.715243 -142.251986) (xy 328.764843 -142.226485) (xy 328.817627 -142.208478) (xy 328.87247 -142.198348)
			(xy 328.928204 -142.196311) (xy 328.935138 -142.197074) (xy 332.301086 -142.197074) (xy 332.305157 -142.141452)
			(xy 332.317283 -142.087015) (xy 332.337206 -142.034924) (xy 332.364502 -141.986289) (xy 332.398588 -141.942146)
			(xy 332.438737 -141.903437) (xy 332.484095 -141.870986) (xy 332.533695 -141.845485) (xy 332.586479 -141.827478)
			(xy 332.641322 -141.817348) (xy 332.697056 -141.815311) (xy 332.752493 -141.821411) (xy 332.80645 -141.835517)
			(xy 332.857779 -141.857329) (xy 332.905385 -141.886383) (xy 332.948253 -141.922058) (xy 332.98547 -141.963595)
			(xy 333.016243 -142.010108) (xy 333.039915 -142.060605) (xy 333.055983 -142.114012) (xy 333.064103 -142.169188)
			(xy 333.064612 -142.197074) (xy 333.064103 -142.22496) (xy 333.055983 -142.280136) (xy 333.039915 -142.333543)
			(xy 333.016243 -142.38404) (xy 332.98547 -142.430553) (xy 332.948253 -142.47209) (xy 332.905385 -142.507765)
			(xy 332.857779 -142.536819) (xy 332.80645 -142.558631) (xy 332.752493 -142.572737) (xy 332.697056 -142.578837)
			(xy 332.641322 -142.5768) (xy 332.586479 -142.56667) (xy 332.533695 -142.548663) (xy 332.484095 -142.523162)
			(xy 332.438737 -142.490711) (xy 332.398588 -142.452002) (xy 332.364502 -142.407859) (xy 332.337206 -142.359224)
			(xy 332.317283 -142.307133) (xy 332.305157 -142.252696) (xy 332.301086 -142.197074) (xy 328.935138 -142.197074)
			(xy 328.983641 -142.202411) (xy 329.037598 -142.216517) (xy 329.088927 -142.238329) (xy 329.136533 -142.267383)
			(xy 329.179401 -142.303058) (xy 329.216618 -142.344595) (xy 329.247391 -142.391108) (xy 329.271063 -142.441605)
			(xy 329.287131 -142.495012) (xy 329.295251 -142.550188) (xy 329.29576 -142.578074) (xy 329.295251 -142.60596)
			(xy 329.287131 -142.661136) (xy 329.271063 -142.714543) (xy 329.247391 -142.76504) (xy 329.216618 -142.811553)
			(xy 329.179401 -142.85309) (xy 329.136533 -142.888765) (xy 329.088927 -142.917819) (xy 329.037598 -142.939631)
			(xy 328.983641 -142.953737) (xy 328.928204 -142.959837) (xy 328.87247 -142.9578) (xy 328.817627 -142.94767)
			(xy 328.764843 -142.929663) (xy 328.715243 -142.904162) (xy 328.669885 -142.871711) (xy 328.629736 -142.833002)
			(xy 328.59565 -142.788859) (xy 328.568354 -142.740224) (xy 328.548431 -142.688133) (xy 328.536305 -142.633696)
			(xy 328.532234 -142.578074) (xy 327.30948 -142.578074) (xy 327.30948 -147.985409) (xy 344.826329 -147.985409)
			(xy 344.826329 -147.824515) (xy 344.834349 -147.663822) (xy 344.850369 -147.503729) (xy 344.874349 -147.344632)
			(xy 344.906229 -147.186929) (xy 344.945931 -147.031011) (xy 344.993355 -146.877266) (xy 345.048384 -146.726076)
			(xy 345.11088 -146.577817) (xy 345.180689 -146.432857) (xy 345.257637 -146.291557) (xy 345.341532 -146.154269)
			(xy 345.432167 -146.021332) (xy 345.529315 -145.893079) (xy 345.632735 -145.769828) (xy 345.74217 -145.651885)
			(xy 345.857348 -145.539543) (xy 345.977983 -145.433083) (xy 346.103774 -145.332767) (xy 346.234409 -145.238847)
			(xy 346.369564 -145.151555) (xy 346.508902 -145.071108) (xy 346.652076 -144.997707) (xy 346.798731 -144.931534)
			(xy 346.948502 -144.872753) (xy 347.101017 -144.821511) (xy 347.255897 -144.777934) (xy 347.412756 -144.742132)
			(xy 347.571205 -144.714193) (xy 347.73085 -144.694187) (xy 347.891293 -144.682164) (xy 348.052136 -144.678153)
			(xy 348.212979 -144.682164) (xy 348.373422 -144.694187) (xy 348.533067 -144.714193) (xy 348.691516 -144.742132)
			(xy 348.848375 -144.777934) (xy 349.003255 -144.821511) (xy 349.15577 -144.872753) (xy 349.305541 -144.931534)
			(xy 349.452196 -144.997707) (xy 349.59537 -145.071108) (xy 349.734708 -145.151555) (xy 349.869863 -145.238847)
			(xy 350.000498 -145.332767) (xy 350.126289 -145.433083) (xy 350.246924 -145.539543) (xy 350.362102 -145.651885)
			(xy 350.471537 -145.769828) (xy 350.574957 -145.893079) (xy 350.672105 -146.021332) (xy 350.76274 -146.154269)
			(xy 350.846635 -146.291557) (xy 350.923583 -146.432857) (xy 350.993392 -146.577817) (xy 351.055888 -146.726076)
			(xy 351.110917 -146.877266) (xy 351.158341 -147.031011) (xy 351.198043 -147.186929) (xy 351.229923 -147.344632)
			(xy 351.253903 -147.503729) (xy 351.269923 -147.663822) (xy 351.277943 -147.824515) (xy 351.278444 -147.904962)
			(xy 351.277943 -147.985409) (xy 351.269923 -148.146102) (xy 351.253903 -148.306195) (xy 351.229923 -148.465292)
			(xy 351.198043 -148.622995) (xy 351.158341 -148.778913) (xy 351.110917 -148.932658) (xy 351.055888 -149.083848)
			(xy 350.993392 -149.232107) (xy 350.923583 -149.377067) (xy 350.846635 -149.518367) (xy 350.76274 -149.655655)
			(xy 350.672105 -149.788592) (xy 350.574957 -149.916845) (xy 350.471537 -150.040096) (xy 350.362102 -150.158039)
			(xy 350.246924 -150.270381) (xy 350.126289 -150.376841) (xy 350.000498 -150.477157) (xy 349.869863 -150.571077)
			(xy 349.734708 -150.658369) (xy 349.59537 -150.738816) (xy 349.452196 -150.812217) (xy 349.305541 -150.87839)
			(xy 349.15577 -150.937171) (xy 349.003255 -150.988413) (xy 348.848375 -151.03199) (xy 348.691516 -151.067792)
			(xy 348.533067 -151.095731) (xy 348.373422 -151.115737) (xy 348.212979 -151.12776) (xy 348.052136 -151.131772)
			(xy 347.891293 -151.12776) (xy 347.73085 -151.115737) (xy 347.571205 -151.095731) (xy 347.412756 -151.067792)
			(xy 347.255897 -151.03199) (xy 347.101017 -150.988413) (xy 346.948502 -150.937171) (xy 346.798731 -150.87839)
			(xy 346.652076 -150.812217) (xy 346.508902 -150.738816) (xy 346.369564 -150.658369) (xy 346.234409 -150.571077)
			(xy 346.103774 -150.477157) (xy 345.977983 -150.376841) (xy 345.857348 -150.270381) (xy 345.74217 -150.158039)
			(xy 345.632735 -150.040096) (xy 345.529315 -149.916845) (xy 345.432167 -149.788592) (xy 345.341532 -149.655655)
			(xy 345.257637 -149.518367) (xy 345.180689 -149.377067) (xy 345.11088 -149.232107) (xy 345.048384 -149.083848)
			(xy 344.993355 -148.932658) (xy 344.945931 -148.778913) (xy 344.906229 -148.622995) (xy 344.874349 -148.465292)
			(xy 344.850369 -148.306195) (xy 344.834349 -148.146102) (xy 344.826329 -147.985409) (xy 327.30948 -147.985409)
			(xy 327.30948 -150.222458) (xy 327.309648 -150.228467) (xy 327.312473 -150.240149) (xy 327.315068 -150.245572)
			(xy 327.316904 -150.249049) (xy 327.321491 -150.255434) (xy 327.324212 -150.258272) (xy 328.053954 -150.988014)
			(xy 328.061351 -150.994861) (xy 328.079951 -151.002589) (xy 328.090022 -151.003) (xy 338.49437 -151.003)
			(xy 338.504435 -151.003436) (xy 338.52302 -151.011168) (xy 338.530438 -151.017986) (xy 338.719414 -151.206962)
			(xy 338.72626 -151.21436) (xy 338.733985 -151.232959) (xy 338.7344 -151.24303) (xy 338.7344 -153.399998)
			(xy 338.733977 -153.410068) (xy 338.726263 -153.428673) (xy 338.719414 -153.436066) (xy 338.507832 -153.647648)
			(xy 338.500432 -153.654489) (xy 338.481834 -153.662207) (xy 338.471764 -153.662634) (xy 336.560922 -153.662634)
			(xy 336.550859 -153.663072) (xy 336.532278 -153.67081) (xy 336.524854 -153.67762) (xy 336.234786 -153.967688)
			(xy 336.227928 -153.975082) (xy 336.220176 -153.993681) (xy 336.2198 -154.003756) (xy 336.2198 -160.202118)
			(xy 336.219373 -160.212187) (xy 336.211654 -160.230786) (xy 336.204814 -160.238186) (xy 335.498186 -160.944814)
			(xy 335.490791 -160.951668) (xy 335.472192 -160.95941) (xy 335.462118 -160.9598) (xy 332.456282 -160.9598)
			(xy 332.446213 -160.960227) (xy 332.427614 -160.967946) (xy 332.420214 -160.974786) (xy 332.348586 -161.046414)
			(xy 332.341732 -161.053809) (xy 332.33399 -161.072408) (xy 332.3336 -161.082482) (xy 332.3336 -165.028118)
			(xy 332.334027 -165.038187) (xy 332.341746 -165.056786) (xy 332.348586 -165.064186) (xy 332.496414 -165.212014)
			(xy 332.503809 -165.218868) (xy 332.522408 -165.22661) (xy 332.532482 -165.227)
		)
		(stroke
			(width 0)
			(type solid)
		)
		(fill yes)
		(layer "B.Cu")
		(net "GND")
	)
	(gr_poly
		(pts
			(xy 129.651252 -81.113122) (xy 129.661319 -81.11269) (xy 129.679911 -81.104965) (xy 129.68732 -81.098136)
			(xy 129.986024 -80.799432) (xy 129.992868 -80.792033) (xy 130.000589 -80.773434) (xy 130.00101 -80.763364)
			(xy 130.00101 -71.103998) (xy 130.000587 -71.093928) (xy 129.992873 -71.075323) (xy 129.986024 -71.06793)
			(xy 129.959862 -71.041768) (xy 129.952465 -71.03492) (xy 129.933866 -71.027189) (xy 129.923794 -71.026782)
			(xy 125.382782 -71.026782) (xy 125.372796 -71.027322) (xy 125.354366 -71.035038) (xy 125.346968 -71.041768)
			(xy 125.234954 -71.153782) (xy 125.19914 -71.189596) (xy 125.198886 -71.189596) (xy 125.182122 -71.20636)
			(xy 125.175283 -71.213761) (xy 125.167567 -71.232359) (xy 125.167136 -71.242428) (xy 125.167136 -72.317102)
			(xy 125.171708 -72.33158) (xy 125.176026 -72.33793) (xy 125.188837 -72.357646) (xy 125.206871 -72.401058)
			(xy 125.215548 -72.447259) (xy 125.21565 -72.470772) (xy 125.215396 -72.47128) (xy 125.215396 -72.766428)
			(xy 125.21565 -72.766428) (xy 125.215287 -72.788744) (xy 125.206847 -72.832565) (xy 125.189984 -72.873883)
			(xy 125.165352 -72.911095) (xy 125.133906 -72.942759) (xy 125.096865 -72.967648) (xy 125.055665 -72.984796)
			(xy 125.011903 -72.993538) (xy 124.98959 -72.994012) (xy 124.772928 -72.994012) (xy 124.762928 -72.993497)
			(xy 124.744458 -72.985815) (xy 124.730308 -72.971676) (xy 124.722611 -72.953212) (xy 124.722128 -72.943212)
			(xy 124.722128 -72.934068) (xy 124.62002 -72.934068) (xy 124.610491 -72.935134) (xy 124.593201 -72.943392)
			(xy 124.580164 -72.957433) (xy 124.573208 -72.975286) (xy 124.572776 -72.984868) (xy 124.572776 -73.395586)
			(xy 124.572893 -73.400541) (xy 124.574809 -73.410264) (xy 124.576586 -73.41489) (xy 124.587254 -73.441052)
			(xy 124.594112 -73.448164) (xy 124.614139 -73.469567) (xy 124.64915 -73.516579) (xy 124.677874 -73.567676)
			(xy 124.699839 -73.622022) (xy 124.714686 -73.678727) (xy 124.722173 -73.736864) (xy 124.722636 -73.766172)
			(xy 124.722148 -73.796142) (xy 124.714328 -73.855568) (xy 124.698818 -73.913466) (xy 124.675884 -73.968843)
			(xy 124.645917 -74.020754) (xy 124.609432 -74.068309) (xy 124.567051 -74.110695) (xy 124.519501 -74.147186)
			(xy 124.467594 -74.177159) (xy 124.412219 -74.2001) (xy 124.354323 -74.215617) (xy 124.294897 -74.223444)
			(xy 124.264928 -74.22388) (xy 124.264166 -74.22388) (xy 124.232562 -74.223307) (xy 124.169962 -74.214539)
			(xy 124.109161 -74.197256) (xy 124.080016 -74.185018) (xy 124.07011 -74.1807) (xy 123.792742 -74.1807)
			(xy 123.785122 -74.181208) (xy 123.773946 -74.182986) (xy 123.753372 -74.189336) (xy 123.74753 -74.193146)
			(xy 123.724262 -74.207626) (xy 123.674461 -74.2305) (xy 123.621903 -74.246028) (xy 123.567667 -74.253892)
			(xy 123.540266 -74.25436) (xy 123.540012 -74.25436) (xy 123.508448 -74.25371) (xy 123.446182 -74.243324)
			(xy 123.386473 -74.222833) (xy 123.358402 -74.208386) (xy 123.345956 -74.20356) (xy 123.321248 -74.197229)
			(xy 123.273652 -74.178898) (xy 123.228916 -74.154401) (xy 123.187834 -74.124172) (xy 123.169172 -74.106786)
			(xy 123.160028 -74.097896) (xy 123.136152 -74.090784) (xy 123.029472 -74.112374) (xy 123.010168 -74.127868)
			(xy 123.005088 -74.139552) (xy 122.993634 -74.164835) (xy 122.964491 -74.212073) (xy 122.92881 -74.254589)
			(xy 122.887344 -74.291486) (xy 122.84097 -74.321985) (xy 122.790665 -74.345442) (xy 122.737493 -74.361361)
			(xy 122.682574 -74.369407) (xy 122.654822 -74.36993) (xy 122.627567 -74.369469) (xy 122.57361 -74.361714)
			(xy 122.521306 -74.346359) (xy 122.471721 -74.323716) (xy 122.425862 -74.294247) (xy 122.384664 -74.258551)
			(xy 122.348966 -74.217356) (xy 122.319494 -74.171499) (xy 122.296849 -74.121914) (xy 122.281491 -74.069611)
			(xy 122.273733 -74.015655) (xy 122.273733 -73.961145) (xy 122.281491 -73.907189) (xy 122.296849 -73.854886)
			(xy 122.319494 -73.805301) (xy 122.348966 -73.759444) (xy 122.384664 -73.718249) (xy 122.425862 -73.682553)
			(xy 122.471721 -73.653084) (xy 122.521306 -73.630441) (xy 122.57361 -73.615086) (xy 122.627567 -73.607331)
			(xy 122.654822 -73.606914) (xy 122.684156 -73.607453) (xy 122.742133 -73.616434) (xy 122.798053 -73.63418)
			(xy 122.850599 -73.660274) (xy 122.898533 -73.694102) (xy 122.919998 -73.714102) (xy 122.929142 -73.722992)
			(xy 122.953018 -73.730104) (xy 123.059698 -73.708514) (xy 123.079002 -73.69302) (xy 123.084082 -73.681336)
			(xy 123.095536 -73.656052) (xy 123.124679 -73.608813) (xy 123.16036 -73.566295) (xy 123.201825 -73.529396)
			(xy 123.248199 -73.498895) (xy 123.298504 -73.475435) (xy 123.351676 -73.459512) (xy 123.406595 -73.451462)
			(xy 123.434348 -73.450958) (xy 123.465912 -73.451605) (xy 123.528182 -73.461985) (xy 123.587894 -73.482472)
			(xy 123.615958 -73.496932) (xy 123.628404 -73.501758) (xy 123.643392 -73.505475) (xy 123.672764 -73.515014)
			(xy 123.687078 -73.520808) (xy 123.696476 -73.524872) (xy 123.848876 -73.524872) (xy 123.861104 -73.524103)
			(xy 123.882737 -73.512685) (xy 123.890278 -73.503028) (xy 123.90069 -73.488548) (xy 123.923448 -73.461083)
			(xy 123.935744 -73.448164) (xy 123.942602 -73.441052) (xy 123.95327 -73.41489) (xy 123.955042 -73.410262)
			(xy 123.956959 -73.40054) (xy 123.95708 -73.395586) (xy 123.95708 -73.063608) (xy 123.956682 -73.054087)
			(xy 123.949767 -73.036344) (xy 123.943618 -73.029064) (xy 123.919996 -73.00341) (xy 123.904756 -72.995282)
			(xy 123.89612 -72.994012) (xy 123.875994 -72.99057) (xy 123.837314 -72.977504) (xy 123.801567 -72.957782)
			(xy 123.769887 -72.932028) (xy 123.743281 -72.901062) (xy 123.722591 -72.865866) (xy 123.708476 -72.827557)
			(xy 123.701383 -72.787351) (xy 123.701048 -72.766936) (xy 123.701048 -72.466962) (xy 123.701444 -72.444433)
			(xy 123.710015 -72.400204) (xy 123.727073 -72.358507) (xy 123.751961 -72.320953) (xy 123.783715 -72.288994)
			(xy 123.821108 -72.263866) (xy 123.862695 -72.24654) (xy 123.906869 -72.237685) (xy 123.929394 -72.237092)
			(xy 124.148596 -72.237092) (xy 124.159518 -72.238362) (xy 124.165106 -72.239632) (xy 124.167392 -72.239632)
			(xy 124.224796 -72.297036) (xy 124.501148 -72.297036) (xy 124.511152 -72.29654) (xy 124.529634 -72.288873)
			(xy 124.54378 -72.274723) (xy 124.551443 -72.25624) (xy 124.551948 -72.246236) (xy 124.551948 -71.093838)
			(xy 124.552202 -71.079868) (xy 124.552202 -71.077582) (xy 124.551711 -71.067577) (xy 124.544048 -71.049091)
			(xy 124.529896 -71.034943) (xy 124.511408 -71.027286) (xy 124.501402 -71.026782) (xy 121.863612 -71.026782)
			(xy 121.853601 -71.027268) (xy 121.835102 -71.034924) (xy 121.820941 -71.049077) (xy 121.813273 -71.067572)
			(xy 121.812812 -71.077582) (xy 121.812812 -71.664068) (xy 121.812812 -71.685404) (xy 121.78284 -71.714868)
			(xy 121.768616 -71.714868) (xy 121.758629 -71.715401) (xy 121.740194 -71.723103) (xy 121.726074 -71.737238)
			(xy 121.718391 -71.755681) (xy 121.717816 -71.765668) (xy 121.717816 -72.266302) (xy 121.722388 -72.28078)
			(xy 121.726706 -72.28713) (xy 121.739518 -72.306845) (xy 121.757554 -72.350257) (xy 121.766231 -72.396459)
			(xy 121.76633 -72.419972) (xy 121.766076 -72.42048) (xy 121.766076 -72.64679) (xy 122.433824 -72.64679)
			(xy 122.433824 -72.586854) (xy 122.441647 -72.527432) (xy 122.45716 -72.469539) (xy 122.480096 -72.414166)
			(xy 122.510063 -72.36226) (xy 122.54655 -72.31471) (xy 122.58893 -72.27233) (xy 122.63648 -72.235843)
			(xy 122.688386 -72.205876) (xy 122.743759 -72.18294) (xy 122.801652 -72.167427) (xy 122.861074 -72.159604)
			(xy 122.92101 -72.159604) (xy 122.980432 -72.167427) (xy 123.038325 -72.18294) (xy 123.093698 -72.205876)
			(xy 123.145604 -72.235843) (xy 123.193154 -72.27233) (xy 123.235534 -72.31471) (xy 123.272021 -72.36226)
			(xy 123.301988 -72.414166) (xy 123.324924 -72.469539) (xy 123.340437 -72.527432) (xy 123.34826 -72.586854)
			(xy 123.34875 -72.616822) (xy 123.34826 -72.64679) (xy 123.340437 -72.706212) (xy 123.324924 -72.764105)
			(xy 123.301988 -72.819478) (xy 123.272021 -72.871384) (xy 123.235534 -72.918934) (xy 123.193154 -72.961314)
			(xy 123.145604 -72.997801) (xy 123.093698 -73.027768) (xy 123.038325 -73.050704) (xy 122.980432 -73.066217)
			(xy 122.92101 -73.07404) (xy 122.861074 -73.07404) (xy 122.801652 -73.066217) (xy 122.743759 -73.050704)
			(xy 122.688386 -73.027768) (xy 122.63648 -72.997801) (xy 122.58893 -72.961314) (xy 122.54655 -72.918934)
			(xy 122.510063 -72.871384) (xy 122.480096 -72.819478) (xy 122.45716 -72.764105) (xy 122.441647 -72.706212)
			(xy 122.433824 -72.64679) (xy 121.766076 -72.64679) (xy 121.766076 -72.715628) (xy 121.76633 -72.715628)
			(xy 121.765967 -72.737943) (xy 121.757527 -72.781763) (xy 121.740664 -72.823079) (xy 121.716031 -72.860289)
			(xy 121.684585 -72.891951) (xy 121.647543 -72.916837) (xy 121.606343 -72.933982) (xy 121.562582 -72.94272)
			(xy 121.54027 -72.943212) (xy 121.323608 -72.943212) (xy 121.31361 -72.942694) (xy 121.295148 -72.935008)
			(xy 121.281003 -72.920869) (xy 121.27331 -72.902409) (xy 121.272808 -72.892412) (xy 121.272808 -72.883268)
			(xy 120.794018 -72.883268) (xy 120.785026 -72.884392) (xy 120.768631 -72.892084) (xy 120.755926 -72.904989)
			(xy 120.748491 -72.921502) (xy 120.747536 -72.930512) (xy 120.747536 -72.943212) (xy 120.480074 -72.943212)
			(xy 120.462444 -72.942875) (xy 120.427612 -72.937389) (xy 120.410732 -72.93229) (xy 120.389904 -72.92467)
			(xy 120.386094 -72.922892) (xy 120.359678 -72.908668) (xy 120.359678 -72.908414) (xy 120.351864 -72.903425)
			(xy 120.336987 -72.892363) (xy 120.32996 -72.886316) (xy 120.322806 -72.880534) (xy 120.305621 -72.874007)
			(xy 120.296432 -72.873616) (xy 119.802402 -72.873616) (xy 119.792332 -72.874039) (xy 119.773729 -72.881755)
			(xy 119.766334 -72.888602) (xy 119.744797 -72.909618) (xy 119.697166 -72.946394) (xy 119.645125 -72.976608)
			(xy 119.589572 -72.999738) (xy 119.531466 -73.015384) (xy 119.47181 -73.023277) (xy 119.441722 -73.02373)
			(xy 119.411751 -73.023262) (xy 119.35232 -73.015441) (xy 119.294419 -72.999929) (xy 119.239039 -72.976992)
			(xy 119.187126 -72.947022) (xy 119.139569 -72.910532) (xy 119.097182 -72.868148) (xy 119.06069 -72.820592)
			(xy 119.030718 -72.768681) (xy 119.007778 -72.713301) (xy 118.992264 -72.655401) (xy 118.984439 -72.595971)
			(xy 118.984439 -72.536029) (xy 118.992264 -72.476599) (xy 119.007778 -72.418699) (xy 119.030718 -72.363319)
			(xy 119.06069 -72.311408) (xy 119.097182 -72.263852) (xy 119.139569 -72.221468) (xy 119.187126 -72.184978)
			(xy 119.239039 -72.155008) (xy 119.294419 -72.132071) (xy 119.35232 -72.116559) (xy 119.411751 -72.108738)
			(xy 119.441722 -72.108314) (xy 119.471809 -72.108793) (xy 119.531462 -72.116684) (xy 119.589566 -72.132328)
			(xy 119.645118 -72.155455) (xy 119.697158 -72.185664) (xy 119.744789 -72.222436) (xy 119.766334 -72.243442)
			(xy 119.773732 -72.250289) (xy 119.79233 -72.258021) (xy 119.802402 -72.258428) (xy 120.296432 -72.258428)
			(xy 120.305625 -72.25804) (xy 120.322817 -72.251528) (xy 120.32996 -72.245728) (xy 120.336584 -72.239995)
			(xy 120.350568 -72.229441) (xy 120.3579 -72.224646) (xy 120.367298 -72.218804) (xy 120.372378 -72.215756)
			(xy 120.381522 -72.211438) (xy 120.386094 -72.209152) (xy 120.389904 -72.207374) (xy 120.410732 -72.199754)
			(xy 120.427615 -72.194668) (xy 120.462445 -72.189181) (xy 120.480074 -72.188832) (xy 120.696736 -72.188832)
			(xy 120.706787 -72.189178) (xy 120.725389 -72.196779) (xy 120.739603 -72.210984) (xy 120.747216 -72.229581)
			(xy 120.747536 -72.239632) (xy 120.747536 -72.248776) (xy 121.056146 -72.248776) (xy 121.065041 -72.247669)
			(xy 121.081281 -72.240109) (xy 121.093941 -72.227435) (xy 121.101483 -72.211186) (xy 121.102628 -72.202294)
			(xy 121.102628 -71.697342) (xy 121.098056 -71.682864) (xy 121.093738 -71.676514) (xy 121.08092 -71.6568)
			(xy 121.062872 -71.61339) (xy 121.054184 -71.567186) (xy 121.054114 -71.543672) (xy 121.054368 -71.543164)
			(xy 121.054368 -71.25208) (xy 121.054114 -71.251572) (xy 121.054214 -71.228061) (xy 121.062918 -71.181868)
			(xy 121.080943 -71.138454) (xy 121.093738 -71.11873) (xy 121.098056 -71.11238) (xy 121.102628 -71.097902)
			(xy 121.102628 -71.074026) (xy 121.101512 -71.06451) (xy 121.093211 -71.047258) (xy 121.079199 -71.034211)
			(xy 121.061399 -71.027161) (xy 121.051828 -71.026782) (xy 116.703856 -71.026782) (xy 116.693853 -71.027277)
			(xy 116.675373 -71.034944) (xy 116.661229 -71.049095) (xy 116.653572 -71.067579) (xy 116.653056 -71.077582)
			(xy 116.653056 -73.496678) (xy 116.652566 -73.506638) (xy 116.644971 -73.525055) (xy 116.638324 -73.532492)
			(xy 116.527326 -73.64349) (xy 116.307616 -73.863454) (xy 116.305838 -73.865232) (xy 116.304822 -73.865994)
			(xy 116.30025 -73.870566) (xy 116.281708 -73.87844) (xy 116.274088 -73.87844) (xy 115.288314 -73.87844)
			(xy 115.278154 -73.87844) (xy 115.259612 -73.870566) (xy 115.25504 -73.865994) (xy 115.254024 -73.865232)
			(xy 115.252246 -73.863454) (xy 115.05692 -73.667874) (xy 114.958368 -73.569322) (xy 114.951684 -73.561912)
			(xy 114.944099 -73.543476) (xy 114.943636 -73.533508) (xy 114.943636 -71.074026) (xy 114.94252 -71.06451)
			(xy 114.93422 -71.047256) (xy 114.920208 -71.034207) (xy 114.902408 -71.027155) (xy 114.892836 -71.026782)
			(xy 114.62766 -71.026782) (xy 114.617593 -71.027212) (xy 114.598997 -71.034934) (xy 114.591592 -71.041768)
			(xy 113.865406 -71.767954) (xy 113.85804 -71.775066) (xy 113.85042 -71.793862) (xy 113.85042 -74.038968)
			(xy 120.219214 -74.038968) (xy 120.223285 -73.983346) (xy 120.235411 -73.928909) (xy 120.255334 -73.876818)
			(xy 120.28263 -73.828183) (xy 120.316716 -73.78404) (xy 120.356865 -73.745331) (xy 120.402223 -73.71288)
			(xy 120.451823 -73.687379) (xy 120.504607 -73.669372) (xy 120.55945 -73.659242) (xy 120.615184 -73.657205)
			(xy 120.670621 -73.663305) (xy 120.724578 -73.677411) (xy 120.775907 -73.699223) (xy 120.823513 -73.728277)
			(xy 120.866381 -73.763952) (xy 120.903598 -73.805489) (xy 120.934371 -73.852002) (xy 120.958043 -73.902499)
			(xy 120.974111 -73.955906) (xy 120.982231 -74.011082) (xy 120.98274 -74.038968) (xy 120.982231 -74.066854)
			(xy 120.974111 -74.12203) (xy 120.958043 -74.175437) (xy 120.934371 -74.225934) (xy 120.903598 -74.272447)
			(xy 120.866381 -74.313984) (xy 120.823513 -74.349659) (xy 120.775907 -74.378713) (xy 120.724578 -74.400525)
			(xy 120.670621 -74.414631) (xy 120.615184 -74.420731) (xy 120.55945 -74.418694) (xy 120.504607 -74.408564)
			(xy 120.451823 -74.390557) (xy 120.402223 -74.365056) (xy 120.356865 -74.332605) (xy 120.316716 -74.293896)
			(xy 120.28263 -74.249753) (xy 120.255334 -74.201118) (xy 120.235411 -74.149027) (xy 120.223285 -74.09459)
			(xy 120.219214 -74.038968) (xy 113.85042 -74.038968) (xy 113.85042 -80.136492) (xy 113.850894 -80.146363)
			(xy 113.858358 -80.164641) (xy 113.864898 -80.172052) (xy 113.865152 -80.172306) (xy 113.960402 -80.267556)
			(xy 120.689116 -80.267556) (xy 120.689116 -80.029812) (xy 120.71858 -79.99984) (xy 120.737884 -79.99984)
			(xy 120.744234 -79.986124) (xy 120.746496 -79.981018) (xy 120.74892 -79.970118) (xy 120.74906 -79.964534)
			(xy 120.74906 -79.475076) (xy 120.739916 -79.475076) (xy 120.729893 -79.474667) (xy 120.711371 -79.466998)
			(xy 120.697198 -79.452822) (xy 120.689531 -79.434299) (xy 120.689116 -79.424276) (xy 120.689116 -79.20736)
			(xy 120.689617 -79.18505) (xy 120.698365 -79.141295) (xy 120.715514 -79.100101) (xy 120.7404 -79.063065)
			(xy 120.772059 -79.031621) (xy 120.809264 -79.006988) (xy 120.850573 -78.990119) (xy 120.894387 -78.98167)
			(xy 120.9167 -78.9813) (xy 121.215912 -78.9813) (xy 121.23882 -78.981756) (xy 121.28375 -78.990691)
			(xy 121.325974 -79.008458) (xy 121.345198 -79.020924) (xy 121.351548 -79.025242) (xy 121.366026 -79.02956)
			(xy 121.874026 -79.02956) (xy 121.884071 -79.029189) (xy 121.902668 -79.021602) (xy 121.910094 -79.014828)
			(xy 121.912126 -79.012796) (xy 121.918964 -79.005395) (xy 121.926684 -78.986796) (xy 121.927112 -78.976728)
			(xy 121.927112 -78.376272) (xy 121.926435 -78.36373) (xy 121.914572 -78.341621) (xy 121.904506 -78.334108)
			(xy 121.882484 -78.318875) (xy 121.842541 -78.283212) (xy 121.807979 -78.242314) (xy 121.779477 -78.196982)
			(xy 121.757597 -78.148109) (xy 121.742769 -78.096657) (xy 121.735284 -78.043635) (xy 121.734834 -78.016862)
			(xy 121.73522 -77.989606) (xy 121.742983 -77.93565) (xy 121.758346 -77.883348) (xy 121.780996 -77.833765)
			(xy 121.810472 -77.78791) (xy 121.846174 -77.746717) (xy 121.887374 -77.711024) (xy 121.933236 -77.681557)
			(xy 121.982823 -77.658918) (xy 122.035129 -77.643566) (xy 122.089086 -77.635814) (xy 122.116342 -77.635354)
			(xy 122.145434 -77.63592) (xy 122.202943 -77.64476) (xy 122.258438 -77.662242) (xy 122.31063 -77.687961)
			(xy 122.334782 -77.704188) (xy 122.346466 -77.712316) (xy 122.373898 -77.714348) (xy 122.479308 -77.66177)
			(xy 122.49404 -77.638402) (xy 122.494548 -77.624432) (xy 122.496038 -77.595145) (xy 122.50549 -77.53727)
			(xy 122.522257 -77.481076) (xy 122.546064 -77.427485) (xy 122.576522 -77.377373) (xy 122.613131 -77.331562)
			(xy 122.655292 -77.290803) (xy 122.702314 -77.255763) (xy 122.753426 -77.227017) (xy 122.807792 -77.205034)
			(xy 122.86452 -77.190176) (xy 122.922681 -77.182686) (xy 122.952002 -77.182218) (xy 122.981971 -77.182656)
			(xy 123.041397 -77.19048) (xy 123.099293 -77.205993) (xy 123.154669 -77.228931) (xy 123.206577 -77.258901)
			(xy 123.25413 -77.295389) (xy 123.296512 -77.337772) (xy 123.333001 -77.385324) (xy 123.36297 -77.437233)
			(xy 123.385907 -77.492609) (xy 123.40142 -77.550505) (xy 123.409244 -77.609931) (xy 123.409244 -77.669869)
			(xy 123.40142 -77.729295) (xy 123.385907 -77.787191) (xy 123.36297 -77.842567) (xy 123.333001 -77.894476)
			(xy 123.296512 -77.942028) (xy 123.25413 -77.984411) (xy 123.206577 -78.020899) (xy 123.154669 -78.050869)
			(xy 123.099293 -78.073807) (xy 123.041397 -78.08932) (xy 122.981971 -78.097144) (xy 122.952002 -78.097634)
			(xy 122.921316 -78.097158) (xy 122.860497 -78.088942) (xy 122.801322 -78.072669) (xy 122.744853 -78.048633)
			(xy 122.692104 -78.017263) (xy 122.644022 -77.979125) (xy 122.601469 -77.934901) (xy 122.58294 -77.910436)
			(xy 122.576779 -77.902773) (xy 122.560101 -77.892396) (xy 122.540748 -77.889036) (xy 122.521549 -77.893185)
			(xy 122.50531 -77.904236) (xy 122.494405 -77.920574) (xy 122.490429 -77.93981) (xy 122.491754 -77.949552)
			(xy 122.493786 -77.96149) (xy 122.494602 -77.966295) (xy 122.497802 -77.9755) (xy 122.500136 -77.979778)
			(xy 122.513387 -78.003517) (xy 122.532181 -78.054527) (xy 122.541724 -78.108045) (xy 122.5423 -78.135226)
			(xy 122.5423 -78.976728) (xy 122.542684 -78.986802) (xy 122.550431 -79.005401) (xy 122.557286 -79.012796)
			(xy 122.578312 -79.034322) (xy 122.61508 -79.081958) (xy 122.645287 -79.134002) (xy 122.668409 -79.189557)
			(xy 122.68405 -79.247664) (xy 122.691937 -79.30732) (xy 122.692414 -79.337408) (xy 122.691925 -79.367376)
			(xy 122.684101 -79.426798) (xy 122.668588 -79.484691) (xy 122.645652 -79.540063) (xy 122.615684 -79.591968)
			(xy 122.579197 -79.639518) (xy 122.536817 -79.681899) (xy 122.489267 -79.718385) (xy 122.437361 -79.748353)
			(xy 122.381989 -79.771289) (xy 122.324096 -79.786802) (xy 122.264674 -79.794626) (xy 122.234706 -79.795116)
			(xy 122.204618 -79.794649) (xy 122.144963 -79.78676) (xy 122.086857 -79.771116) (xy 122.031303 -79.747989)
			(xy 121.979262 -79.717777) (xy 121.931632 -79.681003) (xy 121.910094 -79.659988) (xy 121.902602 -79.653308)
			(xy 121.884051 -79.645709) (xy 121.874026 -79.645256) (xy 121.434352 -79.645256) (xy 121.424347 -79.645748)
			(xy 121.405862 -79.653415) (xy 121.391713 -79.667566) (xy 121.384047 -79.686051) (xy 121.383552 -79.696056)
			(xy 121.383552 -79.7306) (xy 121.384087 -79.740602) (xy 121.391738 -79.759084) (xy 121.405875 -79.773235)
			(xy 121.424351 -79.780904) (xy 121.434352 -79.7814) (xy 121.566178 -79.7814) (xy 121.57456 -79.778606)
			(xy 121.605779 -79.768091) (xy 121.670658 -79.756717) (xy 121.703592 -79.756) (xy 121.730846 -79.756447)
			(xy 121.784799 -79.764203) (xy 121.837099 -79.779559) (xy 121.886681 -79.802201) (xy 121.932536 -79.83167)
			(xy 121.97373 -79.867364) (xy 122.009426 -79.908558) (xy 122.038895 -79.954412) (xy 122.061539 -80.003994)
			(xy 122.076895 -80.056293) (xy 122.084653 -80.110246) (xy 122.084653 -80.164754) (xy 122.076895 -80.218707)
			(xy 122.061539 -80.271006) (xy 122.038895 -80.320588) (xy 122.009426 -80.366442) (xy 121.97373 -80.407636)
			(xy 121.932536 -80.44333) (xy 121.886681 -80.472799) (xy 121.837099 -80.495441) (xy 121.784799 -80.510797)
			(xy 121.730846 -80.518553) (xy 121.703592 -80.519016) (xy 121.670659 -80.518281) (xy 121.60578 -80.506917)
			(xy 121.57456 -80.49641) (xy 121.566178 -80.493616) (xy 121.219214 -80.493616) (xy 121.21896 -80.493616)
			(xy 121.215912 -80.493616) (xy 120.9167 -80.493616) (xy 120.894384 -80.493309) (xy 120.850565 -80.484856)
			(xy 120.809251 -80.467981) (xy 120.772044 -80.443339) (xy 120.740386 -80.411885) (xy 120.715505 -80.374838)
			(xy 120.698365 -80.333634) (xy 120.68963 -80.28987) (xy 120.689116 -80.267556) (xy 113.960402 -80.267556)
			(xy 114.790982 -81.098136) (xy 114.798382 -81.104976) (xy 114.816981 -81.112691) (xy 114.82705 -81.113122)
		)
		(stroke
			(width 0)
			(type solid)
		)
		(fill yes)
		(layer "B.Cu")
		(net "GND")
	)
	(gr_poly
		(pts
			(xy 445.16548 -26.579322) (xy 445.16989 -26.579231) (xy 445.178575 -26.577692) (xy 445.182752 -26.576274)
			(xy 445.20612 -26.567892) (xy 445.212216 -26.563066) (xy 445.249793 -26.533348) (xy 445.328702 -26.479004)
			(xy 445.41148 -26.430759) (xy 445.497657 -26.388885) (xy 445.586743 -26.353622) (xy 445.678232 -26.325169)
			(xy 445.771605 -26.303688) (xy 445.86633 -26.289301) (xy 445.96187 -26.282089) (xy 446.009776 -26.281634)
			(xy 446.010792 -26.281634) (xy 446.051432 -26.282396) (xy 446.055496 -26.282396) (xy 446.086738 -26.265632)
			(xy 446.091978 -26.262612) (xy 446.10097 -26.254528) (xy 446.104518 -26.24963) (xy 446.134016 -26.2075)
			(xy 446.198838 -26.127642) (xy 446.269905 -26.053287) (xy 446.346752 -25.984923) (xy 446.428875 -25.922996)
			(xy 446.515737 -25.867912) (xy 446.606769 -25.820033) (xy 446.701374 -25.779671) (xy 446.798933 -25.747091)
			(xy 446.848738 -25.734264) (xy 446.855596 -25.73274) (xy 446.861692 -25.729184) (xy 446.87236 -25.721056)
			(xy 447.740786 -24.85263) (xy 447.747623 -24.845228) (xy 447.755334 -24.82663) (xy 447.755772 -24.816562)
			(xy 447.755772 -24.247348) (xy 447.755339 -24.237283) (xy 447.747608 -24.218694) (xy 447.740786 -24.21128)
			(xy 447.651378 -24.121872) (xy 447.627756 -24.114506) (xy 447.615564 -24.116538) (xy 447.562069 -24.125142)
			(xy 447.454098 -24.134295) (xy 447.399918 -24.134826) (xy 447.396108 -24.134826) (xy 447.346305 -24.134191)
			(xy 447.247025 -24.126094) (xy 447.148684 -24.110248) (xy 447.051885 -24.086749) (xy 446.957224 -24.055742)
			(xy 446.865283 -24.017418) (xy 446.776624 -23.972011) (xy 446.691794 -23.919801) (xy 446.611312 -23.861108)
			(xy 446.535674 -23.796293) (xy 446.465344 -23.725753) (xy 446.400754 -23.649923) (xy 446.342301 -23.569268)
			(xy 446.290343 -23.484283) (xy 446.245199 -23.39549) (xy 446.207148 -23.303434) (xy 446.176423 -23.208682)
			(xy 446.153211 -23.111814) (xy 446.137657 -23.013427) (xy 446.129855 -22.914123) (xy 446.12941 -22.864318)
			(xy 446.12941 -22.864064) (xy 446.129997 -22.810102) (xy 446.139178 -22.70257) (xy 446.157445 -22.596203)
			(xy 446.184667 -22.491769) (xy 446.220647 -22.390019) (xy 446.265127 -22.291687) (xy 446.290954 -22.244304)
			(xy 446.294038 -22.237171) (xy 446.29622 -22.221792) (xy 446.295272 -22.214078) (xy 446.291585 -22.195052)
			(xy 446.287644 -22.156495) (xy 446.287398 -22.137116) (xy 446.287398 -22.136862) (xy 446.287886 -22.109613)
			(xy 446.295647 -22.055669) (xy 446.311006 -22.00338) (xy 446.333649 -21.953807) (xy 446.363117 -21.907962)
			(xy 446.398808 -21.866777) (xy 446.439998 -21.83109) (xy 446.485846 -21.801628) (xy 446.535421 -21.77899)
			(xy 446.587712 -21.763638) (xy 446.641657 -21.755883) (xy 446.668906 -21.755354) (xy 446.66916 -21.755354)
			(xy 446.687503 -21.755596) (xy 446.724015 -21.759156) (xy 446.742058 -21.762466) (xy 446.742312 -21.762466)
			(xy 446.752218 -21.763482) (xy 446.771014 -21.758402) (xy 446.782698 -21.75383) (xy 446.829906 -21.728237)
			(xy 446.927844 -21.684178) (xy 447.029151 -21.648541) (xy 447.133104 -21.621582) (xy 447.238961 -21.603491)
			(xy 447.345968 -21.5944) (xy 447.399664 -21.59381) (xy 447.403728 -21.59381) (xy 447.42354 -21.594064)
			(xy 447.429095 -21.594018) (xy 447.439984 -21.591838) (xy 447.44513 -21.589746) (xy 447.45529 -21.585174)
			(xy 447.51371 -21.516848) (xy 447.519334 -21.509708) (xy 447.525591 -21.492657) (xy 447.525902 -21.483574)
			(xy 447.52514 -21.475192) (xy 447.51644 -21.42112) (xy 447.506773 -21.312019) (xy 447.505836 -21.25726)
			(xy 447.505836 -21.24583) (xy 447.506451 -21.192441) (xy 447.515086 -21.086012) (xy 447.532121 -20.980601)
			(xy 447.55745 -20.876869) (xy 447.590914 -20.775469) (xy 447.632302 -20.677037) (xy 447.681354 -20.582192)
			(xy 447.737763 -20.491529) (xy 447.801174 -20.405617) (xy 447.871189 -20.324996) (xy 447.908934 -20.287234)
			(xy 447.916155 -20.278742) (xy 447.923125 -20.257596) (xy 447.920475 -20.23549) (xy 447.91503 -20.225766)
			(xy 447.887503 -20.180207) (xy 447.838892 -20.0855) (xy 447.79791 -19.98725) (xy 447.764813 -19.886072)
			(xy 447.739807 -19.782597) (xy 447.723049 -19.67747) (xy 447.714642 -19.571349) (xy 447.714116 -19.518122)
			(xy 447.714647 -19.464235) (xy 447.72326 -19.356806) (xy 447.740432 -19.250409) (xy 447.766054 -19.145725)
			(xy 447.799962 -19.043424) (xy 447.841938 -18.944161) (xy 447.891715 -18.84857) (xy 447.948973 -18.757265)
			(xy 448.013346 -18.670828) (xy 448.084422 -18.589813) (xy 448.161747 -18.514739) (xy 448.244825 -18.446086)
			(xy 448.333124 -18.384293) (xy 448.379342 -18.35658) (xy 448.379596 -18.35658) (xy 448.401186 -18.344134)
			(xy 448.407056 -18.292672) (xy 448.426104 -18.190852) (xy 448.453378 -18.090921) (xy 448.488699 -17.993542)
			(xy 448.531831 -17.899363) (xy 448.582489 -17.809009) (xy 448.640335 -17.723079) (xy 448.704986 -17.642144)
			(xy 448.776012 -17.566743) (xy 448.852942 -17.497375) (xy 448.935265 -17.434501) (xy 449.022434 -17.37854)
			(xy 449.11387 -17.329861) (xy 449.208966 -17.288789) (xy 449.30709 -17.255597) (xy 449.407591 -17.230505)
			(xy 449.509802 -17.213679) (xy 449.613043 -17.205231) (xy 449.664836 -17.20469) (xy 449.691346 -17.204801)
			(xy 449.744323 -17.206962) (xy 449.770754 -17.209008) (xy 449.781907 -17.209382) (xy 449.80285 -17.201746)
			(xy 449.81114 -17.194276) (xy 449.815204 -17.190212) (xy 450.792342 -17.190212) (xy 450.802409 -17.190643)
			(xy 450.821001 -17.19837) (xy 450.82841 -17.205198) (xy 450.900292 -17.27708) (xy 450.907881 -17.283956)
			(xy 450.926883 -17.29154) (xy 450.937122 -17.291812) (xy 450.988684 -17.290796) (xy 451.04099 -17.291295)
			(xy 451.145286 -17.299416) (xy 451.248638 -17.315603) (xy 451.350424 -17.339758) (xy 451.450028 -17.371735)
			(xy 451.546853 -17.411343) (xy 451.640313 -17.458341) (xy 451.729846 -17.512447) (xy 451.814912 -17.573336)
			(xy 451.894999 -17.640639) (xy 451.969624 -17.713952) (xy 452.038338 -17.792832) (xy 452.100726 -17.876805)
			(xy 452.156412 -17.965364) (xy 452.205061 -18.057976) (xy 452.24638 -18.154082) (xy 452.263764 -18.203418)
			(xy 452.263764 -18.203672) (xy 452.265244 -18.207848) (xy 452.269463 -18.215639) (xy 452.272146 -18.219166)
			(xy 452.281798 -18.228564) (xy 452.303838 -18.245481) (xy 452.343246 -18.284642) (xy 452.376553 -18.329109)
			(xy 452.390256 -18.353278) (xy 452.39305 -18.358104) (xy 452.424292 -18.382996) (xy 452.431658 -18.385282)
			(xy 452.458074 -18.378424) (xy 452.460614 -18.375884) (xy 452.472552 -18.3642) (xy 452.508318 -18.32965)
			(xy 452.584158 -18.265312) (xy 452.664533 -18.206739) (xy 452.749007 -18.15425) (xy 452.792846 -18.130774)
			(xy 452.7931 -18.130774) (xy 452.80109 -18.12609) (xy 452.813287 -18.112173) (xy 452.819711 -18.094819)
			(xy 452.820024 -18.085562) (xy 452.820024 -17.945354) (xy 452.820456 -17.935288) (xy 452.828185 -17.916698)
			(xy 452.83501 -17.909286) (xy 454.454006 -16.29029) (xy 454.458995 -16.284791) (xy 454.465842 -16.271626)
			(xy 454.467468 -16.264382) (xy 454.468484 -16.25473) (xy 454.468484 -14.295374) (xy 454.468319 -14.289364)
			(xy 454.4655 -14.277679) (xy 454.462896 -14.27226) (xy 454.461055 -14.268787) (xy 454.456459 -14.26241)
			(xy 454.453752 -14.25956) (xy 454.213976 -14.019784) (xy 454.211123 -14.017081) (xy 454.204741 -14.012495)
			(xy 454.201276 -14.01064) (xy 454.19585 -14.008053) (xy 454.18417 -14.005223) (xy 454.178162 -14.005052)
			(xy 453.86625 -14.005052) (xy 453.857236 -14.005419) (xy 453.840328 -14.011674) (xy 453.83323 -14.017244)
			(xy 453.826372 -14.023086) (xy 453.817736 -14.03858) (xy 453.816212 -14.047724) (xy 453.807788 -14.096796)
			(xy 453.784253 -14.193551) (xy 453.753216 -14.288165) (xy 453.714866 -14.38006) (xy 453.669441 -14.46867)
			(xy 453.617218 -14.553453) (xy 453.558518 -14.633887) (xy 453.493701 -14.709478) (xy 453.423166 -14.779764)
			(xy 453.347345 -14.844312) (xy 453.266703 -14.902726) (xy 453.181736 -14.954647) (xy 453.092965 -14.999758)
			(xy 453.000935 -15.037781) (xy 452.906211 -15.068482) (xy 452.809373 -15.091674) (xy 452.711018 -15.107214)
			(xy 452.611748 -15.115006) (xy 452.56196 -15.11554) (xy 452.561452 -15.11554) (xy 452.516187 -15.11513)
			(xy 452.425887 -15.108671) (xy 452.336276 -15.095802) (xy 452.291958 -15.086584) (xy 452.277988 -15.085568)
			(xy 452.257563 -15.086778) (xy 452.216661 -15.088047) (xy 452.1962 -15.088108) (xy 452.151043 -15.087701)
			(xy 452.060959 -15.081271) (xy 451.971558 -15.068465) (xy 451.883291 -15.049347) (xy 451.839838 -15.037054)
			(xy 451.833787 -15.035564) (xy 451.821334 -15.035186) (xy 451.8152 -15.036292) (xy 451.77153 -15.045207)
			(xy 451.683262 -15.057639) (xy 451.59434 -15.063859) (xy 451.54977 -15.064232) (xy 451.549262 -15.064232)
			(xy 451.499008 -15.063731) (xy 451.398816 -15.055767) (xy 451.299566 -15.039909) (xy 451.201881 -15.016255)
			(xy 451.106371 -14.984954) (xy 451.013635 -14.946201) (xy 450.924251 -14.900239) (xy 450.881242 -14.87424)
			(xy 450.87389 -14.870005) (xy 450.857362 -14.86621) (xy 450.840506 -14.868058) (xy 450.832728 -14.871446)
			(xy 450.807155 -14.882991) (xy 450.753466 -14.899285) (xy 450.697968 -14.907529) (xy 450.669914 -14.908022)
			(xy 450.643477 -14.907665) (xy 450.591088 -14.900531) (xy 450.56552 -14.893798) (xy 450.562472 -14.892782)
			(xy 450.556376 -14.89202) (xy 450.552259 -14.891506) (xy 450.543964 -14.891631) (xy 450.539866 -14.892274)
			(xy 450.529198 -14.894306) (xy 450.480828 -14.913443) (xy 450.381728 -14.945091) (xy 450.280482 -14.969002)
			(xy 450.177694 -14.985034) (xy 450.073975 -14.993092) (xy 450.02196 -14.99362) (xy 449.976607 -14.99324)
			(xy 449.886106 -14.987137) (xy 449.841112 -14.981428) (xy 449.834949 -14.980733) (xy 449.822616 -14.982017)
			(xy 449.816728 -14.983968) (xy 449.763831 -15.002862) (xy 449.655436 -15.032352) (xy 449.54486 -15.052147)
			(xy 449.432967 -15.062093) (xy 449.3768 -15.062708) (xy 449.329962 -15.062271) (xy 449.23654 -15.055352)
			(xy 449.143883 -15.041566) (xy 449.052494 -15.020989) (xy 448.96287 -14.993732) (xy 448.875499 -14.959944)
			(xy 448.832986 -14.94028) (xy 448.824677 -14.936776) (xy 448.806723 -14.935215) (xy 448.797934 -14.937232)
			(xy 448.740257 -14.952244) (xy 448.622935 -14.973253) (xy 448.504214 -14.983813) (xy 448.44462 -14.984476)
			(xy 448.443858 -14.984476) (xy 448.399851 -14.984141) (xy 448.312023 -14.978419) (xy 448.268344 -14.973046)
			(xy 448.264643 -14.972838) (xy 448.257248 -14.973343) (xy 448.253612 -14.974062) (xy 448.227987 -14.98086)
			(xy 448.175472 -14.988123) (xy 448.148964 -14.98854) (xy 448.122835 -14.988106) (xy 448.071068 -14.980958)
			(xy 448.020764 -14.966801) (xy 447.972867 -14.9459) (xy 447.950336 -14.93266) (xy 447.944282 -14.929222)
			(xy 447.930879 -14.925477) (xy 447.92392 -14.925294) (xy 447.247772 -14.925294) (xy 447.238264 -14.925754)
			(xy 447.220547 -14.932669) (xy 447.213228 -14.938756) (xy 447.191994 -14.957558) (xy 447.145008 -14.989318)
			(xy 447.093837 -15.013773) (xy 447.03961 -15.030381) (xy 446.983521 -15.038778) (xy 446.926807 -15.038778)
			(xy 446.870718 -15.030381) (xy 446.816491 -15.013773) (xy 446.76532 -14.989318) (xy 446.718334 -14.957558)
			(xy 446.6971 -14.938756) (xy 446.689841 -14.93257) (xy 446.672086 -14.925648) (xy 446.662556 -14.925294)
			(xy 442.765942 -14.925294) (xy 442.755876 -14.925727) (xy 442.737286 -14.933456) (xy 442.729874 -14.94028)
			(xy 442.129164 -15.54099) (xy 442.122309 -15.548385) (xy 442.114561 -15.566984) (xy 442.114178 -15.577058)
			(xy 442.114178 -18.449798) (xy 445.241934 -18.449798) (xy 445.242434 -18.399848) (xy 445.250267 -18.300255)
			(xy 445.265899 -18.201586) (xy 445.289235 -18.104449) (xy 445.32013 -18.009447) (xy 445.358393 -17.917165)
			(xy 445.403787 -17.828174) (xy 445.456033 -17.743024) (xy 445.514806 -17.662242) (xy 445.579744 -17.586327)
			(xy 445.650445 -17.515748) (xy 445.726473 -17.450942) (xy 445.807357 -17.392309) (xy 445.892597 -17.340211)
			(xy 445.981666 -17.294971) (xy 446.074015 -17.256868) (xy 446.169071 -17.226138) (xy 446.217548 -17.214088)
			(xy 446.225697 -17.211798) (xy 446.239975 -17.202729) (xy 446.245488 -17.196308) (xy 446.263662 -17.17424)
			(xy 446.305517 -17.135301) (xy 446.352718 -17.103048) (xy 446.404206 -17.078205) (xy 446.458826 -17.061329)
			(xy 446.515354 -17.052798) (xy 446.543938 -17.05229) (xy 446.570135 -17.052732) (xy 446.622037 -17.059899)
			(xy 446.672468 -17.074107) (xy 446.720478 -17.095088) (xy 446.765163 -17.122446) (xy 446.805679 -17.155667)
			(xy 446.841264 -17.194123) (xy 446.856612 -17.215358) (xy 446.861742 -17.222099) (xy 446.875507 -17.231959)
			(xy 446.883536 -17.234662) (xy 446.93179 -17.249917) (xy 447.025928 -17.287089) (xy 447.116809 -17.331633)
			(xy 447.203859 -17.383267) (xy 447.286524 -17.441663) (xy 447.364281 -17.506451) (xy 447.436637 -17.577221)
			(xy 447.503132 -17.653523) (xy 447.563346 -17.734874) (xy 447.616897 -17.820757) (xy 447.663444 -17.910629)
			(xy 447.702693 -18.00392) (xy 447.734396 -18.100038) (xy 447.75835 -18.198373) (xy 447.774405 -18.298302)
			(xy 447.782458 -18.399193) (xy 447.78295 -18.449798) (xy 447.78246 -18.499697) (xy 447.77463 -18.599188)
			(xy 447.759018 -18.697757) (xy 447.735721 -18.794798) (xy 447.704881 -18.889712) (xy 447.66669 -18.981914)
			(xy 447.621383 -19.070835) (xy 447.569238 -19.155927) (xy 447.510578 -19.236665) (xy 447.445764 -19.312552)
			(xy 447.375196 -19.38312) (xy 447.299309 -19.447934) (xy 447.218571 -19.506594) (xy 447.133479 -19.558739)
			(xy 447.044558 -19.604046) (xy 446.952356 -19.642237) (xy 446.857442 -19.673077) (xy 446.760401 -19.696374)
			(xy 446.661832 -19.711986) (xy 446.562341 -19.719816) (xy 446.462543 -19.719816) (xy 446.363052 -19.711986)
			(xy 446.264483 -19.696374) (xy 446.167442 -19.673077) (xy 446.072528 -19.642237) (xy 445.980326 -19.604046)
			(xy 445.891405 -19.558739) (xy 445.806313 -19.506594) (xy 445.725575 -19.447934) (xy 445.649688 -19.38312)
			(xy 445.57912 -19.312552) (xy 445.514306 -19.236665) (xy 445.455646 -19.155927) (xy 445.403501 -19.070835)
			(xy 445.358194 -18.981914) (xy 445.320003 -18.889712) (xy 445.289163 -18.794798) (xy 445.265866 -18.697757)
			(xy 445.250254 -18.599188) (xy 445.242424 -18.499697) (xy 445.241934 -18.449798) (xy 442.114178 -18.449798)
			(xy 442.114178 -20.254722) (xy 446.285618 -20.254722) (xy 446.289689 -20.1991) (xy 446.301815 -20.144663)
			(xy 446.321738 -20.092572) (xy 446.349034 -20.043937) (xy 446.38312 -19.999794) (xy 446.423269 -19.961085)
			(xy 446.468627 -19.928634) (xy 446.518227 -19.903133) (xy 446.571011 -19.885126) (xy 446.625854 -19.874996)
			(xy 446.681588 -19.872959) (xy 446.737025 -19.879059) (xy 446.790982 -19.893165) (xy 446.842311 -19.914977)
			(xy 446.889917 -19.944031) (xy 446.932785 -19.979706) (xy 446.970002 -20.021243) (xy 447.000775 -20.067756)
			(xy 447.024447 -20.118253) (xy 447.040515 -20.17166) (xy 447.048635 -20.226836) (xy 447.049144 -20.254722)
			(xy 447.048635 -20.282608) (xy 447.040515 -20.337784) (xy 447.024447 -20.391191) (xy 447.000775 -20.441688)
			(xy 446.970002 -20.488201) (xy 446.932785 -20.529738) (xy 446.889917 -20.565413) (xy 446.842311 -20.594467)
			(xy 446.790982 -20.616279) (xy 446.737025 -20.630385) (xy 446.681588 -20.636485) (xy 446.625854 -20.634448)
			(xy 446.571011 -20.624318) (xy 446.518227 -20.606311) (xy 446.468627 -20.58081) (xy 446.423269 -20.548359)
			(xy 446.38312 -20.50965) (xy 446.349034 -20.465507) (xy 446.321738 -20.416872) (xy 446.301815 -20.364781)
			(xy 446.289689 -20.310344) (xy 446.285618 -20.254722) (xy 442.114178 -20.254722) (xy 442.114178 -21.166836)
			(xy 442.113748 -21.176903) (xy 442.106022 -21.195496) (xy 442.099192 -21.202904) (xy 442.054234 -21.247862)
			(xy 446.286888 -21.247862) (xy 446.290959 -21.19224) (xy 446.303085 -21.137803) (xy 446.323008 -21.085712)
			(xy 446.350304 -21.037077) (xy 446.38439 -20.992934) (xy 446.424539 -20.954225) (xy 446.469897 -20.921774)
			(xy 446.519497 -20.896273) (xy 446.572281 -20.878266) (xy 446.627124 -20.868136) (xy 446.682858 -20.866099)
			(xy 446.738295 -20.872199) (xy 446.792252 -20.886305) (xy 446.843581 -20.908117) (xy 446.891187 -20.937171)
			(xy 446.934055 -20.972846) (xy 446.971272 -21.014383) (xy 447.002045 -21.060896) (xy 447.025717 -21.111393)
			(xy 447.041785 -21.1648) (xy 447.049905 -21.219976) (xy 447.050414 -21.247862) (xy 447.049905 -21.275748)
			(xy 447.041785 -21.330924) (xy 447.025717 -21.384331) (xy 447.002045 -21.434828) (xy 446.971272 -21.481341)
			(xy 446.934055 -21.522878) (xy 446.891187 -21.558553) (xy 446.843581 -21.587607) (xy 446.792252 -21.609419)
			(xy 446.738295 -21.623525) (xy 446.682858 -21.629625) (xy 446.627124 -21.627588) (xy 446.572281 -21.617458)
			(xy 446.519497 -21.599451) (xy 446.469897 -21.57395) (xy 446.424539 -21.541499) (xy 446.38439 -21.50279)
			(xy 446.350304 -21.458647) (xy 446.323008 -21.410012) (xy 446.303085 -21.357921) (xy 446.290959 -21.303484)
			(xy 446.286888 -21.247862) (xy 442.054234 -21.247862) (xy 442.031374 -21.270722) (xy 442.023978 -21.277573)
			(xy 442.005379 -21.28531) (xy 441.995306 -21.285708) (xy 440.536584 -21.285708) (xy 440.526515 -21.286134)
			(xy 440.507916 -21.293854) (xy 440.500516 -21.300694) (xy 440.349132 -21.452078) (xy 440.342294 -21.459479)
			(xy 440.334583 -21.478078) (xy 440.334146 -21.488146) (xy 440.334146 -23.189692) (xy 440.334565 -23.199711)
			(xy 440.342235 -23.218223) (xy 440.356409 -23.232386) (xy 440.374927 -23.240043) (xy 440.384946 -23.240492)
			(xy 440.85383 -23.240492) (xy 440.86437 -23.239977) (xy 440.883677 -23.231522) (xy 440.89795 -23.216011)
			(xy 440.901836 -23.206202) (xy 440.917671 -23.161685) (xy 440.955689 -23.075175) (xy 441.000718 -22.992099)
			(xy 441.052449 -22.913022) (xy 441.110529 -22.838484) (xy 441.174564 -22.768994) (xy 441.244115 -22.705026)
			(xy 441.318708 -22.647016) (xy 441.397834 -22.59536) (xy 441.480953 -22.550411) (xy 441.567498 -22.512475)
			(xy 441.65688 -22.481811) (xy 441.748486 -22.458629) (xy 441.841694 -22.443086) (xy 441.935867 -22.435288)
			(xy 441.983114 -22.434804) (xy 441.983622 -22.434804) (xy 442.036452 -22.435397) (xy 442.141661 -22.445151)
			(xy 442.245521 -22.464573) (xy 442.347146 -22.493497) (xy 442.396626 -22.51202) (xy 442.405531 -22.515006)
			(xy 442.424297 -22.515006) (xy 442.433202 -22.51202) (xy 442.482684 -22.493504) (xy 442.584309 -22.464585)
			(xy 442.688168 -22.445165) (xy 442.793376 -22.43541) (xy 442.846206 -22.434804) (xy 442.846714 -22.434804)
			(xy 442.893979 -22.435293) (xy 442.988187 -22.4431) (xy 443.081429 -22.45866) (xy 443.173067 -22.481867)
			(xy 443.262475 -22.512561) (xy 443.349044 -22.550533) (xy 443.432182 -22.595525) (xy 443.51132 -22.647228)
			(xy 443.585919 -22.705289) (xy 443.655468 -22.769312) (xy 443.719493 -22.83886) (xy 443.777556 -22.913457)
			(xy 443.829261 -22.992594) (xy 443.874254 -23.075731) (xy 443.912229 -23.162298) (xy 443.942925 -23.251706)
			(xy 443.966134 -23.343344) (xy 443.981696 -23.436585) (xy 443.989506 -23.530793) (xy 443.989968 -23.578058)
			(xy 443.989496 -23.623975) (xy 443.982103 -23.71551) (xy 443.967393 -23.806158) (xy 443.945461 -23.895335)
			(xy 443.916449 -23.982465) (xy 443.880542 -24.066988) (xy 443.837973 -24.14836) (xy 443.789016 -24.226056)
			(xy 443.761876 -24.263096) (xy 443.75733 -24.269684) (xy 443.75216 -24.284822) (xy 443.751716 -24.292814)
			(xy 443.750431 -24.341675) (xy 443.74055 -24.438925) (xy 443.722401 -24.534976) (xy 443.696116 -24.629126)
			(xy 443.661888 -24.720688) (xy 443.619966 -24.808992) (xy 443.570657 -24.893395) (xy 443.514321 -24.973278)
			(xy 443.451369 -25.048059) (xy 443.417198 -25.083008) (xy 443.010544 -25.489662) (xy 445.226438 -25.489662)
			(xy 445.230509 -25.43404) (xy 445.242635 -25.379603) (xy 445.262558 -25.327512) (xy 445.289854 -25.278877)
			(xy 445.32394 -25.234734) (xy 445.364089 -25.196025) (xy 445.409447 -25.163574) (xy 445.459047 -25.138073)
			(xy 445.511831 -25.120066) (xy 445.566674 -25.109936) (xy 445.622408 -25.107899) (xy 445.677845 -25.113999)
			(xy 445.731802 -25.128105) (xy 445.783131 -25.149917) (xy 445.830737 -25.178971) (xy 445.873605 -25.214646)
			(xy 445.910822 -25.256183) (xy 445.941595 -25.302696) (xy 445.965267 -25.353193) (xy 445.981335 -25.4066)
			(xy 445.989455 -25.461776) (xy 445.989964 -25.489662) (xy 445.989455 -25.517548) (xy 445.981335 -25.572724)
			(xy 445.965267 -25.626131) (xy 445.941595 -25.676628) (xy 445.910822 -25.723141) (xy 445.873605 -25.764678)
			(xy 445.830737 -25.800353) (xy 445.783131 -25.829407) (xy 445.731802 -25.851219) (xy 445.677845 -25.865325)
			(xy 445.622408 -25.871425) (xy 445.566674 -25.869388) (xy 445.511831 -25.859258) (xy 445.459047 -25.841251)
			(xy 445.409447 -25.81575) (xy 445.364089 -25.783299) (xy 445.32394 -25.74459) (xy 445.289854 -25.700447)
			(xy 445.262558 -25.651812) (xy 445.242635 -25.599721) (xy 445.230509 -25.545284) (xy 445.226438 -25.489662)
			(xy 443.010544 -25.489662) (xy 442.926978 -25.573228) (xy 442.894388 -25.605225) (xy 442.82489 -25.664495)
			(xy 442.750883 -25.718027) (xy 442.712094 -25.742138) (xy 442.704728 -25.747472) (xy 442.684403 -25.764841)
			(xy 442.639802 -25.79432) (xy 442.591528 -25.817297) (xy 442.540524 -25.833321) (xy 442.514228 -25.83815)
			(xy 442.505592 -25.840436) (xy 442.45899 -25.85665) (xy 442.363605 -25.881935) (xy 442.266398 -25.898912)
			(xy 442.168089 -25.907456) (xy 442.11875 -25.908) (xy 440.360054 -25.908) (xy 440.351219 -25.908373)
			(xy 440.334586 -25.914339) (xy 440.327542 -25.919684) (xy 440.310173 -25.933885) (xy 440.274476 -25.961071)
			(xy 440.256168 -25.97404) (xy 440.24677 -25.980644) (xy 440.235848 -25.999694) (xy 440.22772 -26.088594)
			(xy 440.227355 -26.099743) (xy 440.235005 -26.120672) (xy 440.242452 -26.12898) (xy 440.3471 -26.233628)
			(xy 440.678062 -26.564336) (xy 440.685461 -26.57118) (xy 440.70406 -26.578902) (xy 440.71413 -26.579322)
		)
		(stroke
			(width 0)
			(type solid)
		)
		(fill yes)
		(layer "B.Cu")
		(net "P12V_OCP_SFF")
	)
	(gr_poly
		(pts
			(xy 102.728268 -191.078612) (xy 102.738333 -191.078177) (xy 102.756921 -191.070447) (xy 102.764336 -191.063626)
			(xy 103.021892 -190.80607) (xy 103.028735 -190.79867) (xy 103.036459 -190.780072) (xy 103.036878 -190.770002)
			(xy 103.036878 -186.748166) (xy 103.037307 -186.738098) (xy 103.045027 -186.7195) (xy 103.051864 -186.712098)
			(xy 103.242364 -186.521598) (xy 103.249766 -186.514762) (xy 103.268364 -186.507051) (xy 103.278432 -186.506612)
			(xy 109.722412 -186.506612) (xy 109.732481 -186.507038) (xy 109.751081 -186.514756) (xy 109.75848 -186.521598)
			(xy 110.523528 -187.286646) (xy 110.530375 -187.294043) (xy 110.538104 -187.312643) (xy 110.538514 -187.322714)
			(xy 110.538514 -190.46571) (xy 110.538939 -190.475779) (xy 110.546658 -190.49438) (xy 110.5535 -190.501778)
			(xy 110.604808 -190.553086) (xy 110.612206 -190.559933) (xy 110.630804 -190.567666) (xy 110.640876 -190.568072)
			(xy 111.914432 -190.568072) (xy 111.924499 -190.567642) (xy 111.943092 -190.559917) (xy 111.9505 -190.553086)
			(xy 111.973106 -190.53048) (xy 111.979948 -190.52308) (xy 111.987675 -190.504482) (xy 111.988092 -190.494412)
			(xy 111.988092 -186.371484) (xy 111.987666 -186.361415) (xy 111.979946 -186.342816) (xy 111.973106 -186.335416)
			(xy 111.709454 -186.072018) (xy 111.702566 -186.064957) (xy 111.689601 -186.050087) (xy 111.683546 -186.0423)
			(xy 111.678974 -186.03722) (xy 111.635032 -185.993278) (xy 111.628185 -185.98588) (xy 111.620454 -185.967281)
			(xy 111.620046 -185.95721) (xy 111.620046 -185.868056) (xy 111.620046 -185.86704) (xy 111.619792 -185.855864)
			(xy 111.619792 -180.30825) (xy 111.620046 -180.297074) (xy 111.620046 -180.296058) (xy 111.620046 -180.182012)
			(xy 111.620554 -180.181758) (xy 111.620554 -180.06949) (xy 111.62098 -180.059422) (xy 111.628703 -180.040825)
			(xy 111.63554 -180.033422) (xy 111.827564 -179.841398) (xy 111.834966 -179.834562) (xy 111.853564 -179.826851)
			(xy 111.863632 -179.826412) (xy 113.402872 -179.826412) (xy 113.412937 -179.825976) (xy 113.431523 -179.818245)
			(xy 113.43894 -179.811426) (xy 116.406168 -176.844198) (xy 116.41357 -176.837362) (xy 116.432168 -176.829653)
			(xy 116.442236 -176.829212) (xy 120.279668 -176.829212) (xy 120.289733 -176.828777) (xy 120.308321 -176.821047)
			(xy 120.315736 -176.814226) (xy 120.774968 -176.354994) (xy 120.781817 -176.347597) (xy 120.789554 -176.328998)
			(xy 120.789954 -176.318926) (xy 120.789954 -173.573694) (xy 120.79038 -173.563625) (xy 120.798102 -173.545028)
			(xy 120.80494 -173.537626) (xy 124.356368 -169.986198) (xy 124.36377 -169.979362) (xy 124.382368 -169.971653)
			(xy 124.392436 -169.971212) (xy 124.39269 -169.971212) (xy 124.403358 -169.96029) (xy 124.410755 -169.953443)
			(xy 124.429355 -169.945716) (xy 124.439426 -169.945304) (xy 124.53239 -169.945304) (xy 124.533406 -169.945304)
			(xy 124.544582 -169.94505) (xy 129.423414 -169.94505) (xy 129.433482 -169.944623) (xy 129.452078 -169.936899)
			(xy 129.459482 -169.930064) (xy 129.658364 -169.731182) (xy 129.665212 -169.723784) (xy 129.672945 -169.705186)
			(xy 129.67335 -169.695114) (xy 129.67335 -165.18763) (xy 129.673787 -165.177567) (xy 129.681525 -165.158985)
			(xy 129.688336 -165.151562) (xy 130.022854 -164.817298) (xy 130.030256 -164.81046) (xy 130.048854 -164.802746)
			(xy 130.058922 -164.802312) (xy 143.120872 -164.802312) (xy 152.616154 -164.802312) (xy 153.98242 -163.436046)
			(xy 153.98242 -139.187682) (xy 152.997916 -138.203178) (xy 146.05508 -138.203178) (xy 130.562858 -138.203178)
			(xy 123.98248 -138.203178) (xy 123.360688 -138.82497) (xy 123.360688 -147.633182) (xy 123.775216 -148.04771)
			(xy 129.687574 -148.04771) (xy 129.923794 -148.28393) (xy 129.924222 -148.293998) (xy 129.931944 -148.312595)
			(xy 129.93878 -148.319998) (xy 131.427728 -149.808946) (xy 131.435126 -149.815794) (xy 131.453724 -149.823526)
			(xy 131.463796 -149.823932) (xy 138.193272 -149.823932) (xy 138.203336 -149.824369) (xy 138.221918 -149.832105)
			(xy 138.22934 -149.838918) (xy 138.587988 -150.197566) (xy 138.594825 -150.204968) (xy 138.602537 -150.223566)
			(xy 138.602974 -150.233634) (xy 138.602974 -151.56307) (xy 138.602538 -151.573134) (xy 138.594802 -151.591718)
			(xy 138.587988 -151.599138) (xy 137.96518 -152.221946) (xy 137.958332 -152.229343) (xy 137.950602 -152.247942)
			(xy 137.950194 -152.258014) (xy 137.950194 -155.41625) (xy 137.949761 -155.426316) (xy 137.942034 -155.444907)
			(xy 137.935208 -155.452318) (xy 136.974326 -156.4132) (xy 136.966923 -156.420035) (xy 136.948325 -156.427742)
			(xy 136.938258 -156.428186) (xy 134.62 -156.428186) (xy 134.60993 -156.427763) (xy 134.591327 -156.420047)
			(xy 134.583932 -156.4132) (xy 134.291324 -156.120592) (xy 134.284476 -156.113194) (xy 134.276741 -156.094596)
			(xy 134.276338 -156.084524) (xy 134.276338 -154.480768) (xy 134.275907 -154.470702) (xy 134.268178 -154.452112)
			(xy 134.261352 -154.4447) (xy 133.966204 -154.149552) (xy 133.958808 -154.142699) (xy 133.94021 -154.134955)
			(xy 133.930136 -154.134566) (xy 132.597652 -154.134566) (xy 132.587587 -154.135) (xy 132.569002 -154.142734)
			(xy 132.561584 -154.149552) (xy 132.389118 -154.322018) (xy 132.382341 -154.329442) (xy 132.374751 -154.34804)
			(xy 132.374386 -154.358086) (xy 132.374386 -156.106622) (xy 132.373878 -156.106876) (xy 132.373878 -156.120084)
			(xy 131.865878 -156.628084) (xy 131.85267 -156.628084) (xy 131.852416 -156.628592) (xy 127.03937 -156.628592)
			(xy 124.730256 -156.628592) (xy 122.317256 -159.041592) (xy 122.308335 -159.041984) (xy 122.291568 -159.048087)
			(xy 122.28449 -159.05353) (xy 122.26798 -159.07004) (xy 122.02414 -159.313626) (xy 122.017293 -159.321024)
			(xy 122.009562 -159.339622) (xy 122.009154 -159.349694) (xy 122.009154 -160.95853) (xy 122.009584 -160.968597)
			(xy 122.017312 -160.987188) (xy 122.02414 -160.994598) (xy 122.070368 -161.040826) (xy 122.077767 -161.04767)
			(xy 122.096366 -161.055391) (xy 122.106436 -161.055812) (xy 123.226068 -161.055812) (xy 123.236133 -161.055377)
			(xy 123.254721 -161.047647) (xy 123.262136 -161.040826) (xy 124.019564 -160.283398) (xy 124.026966 -160.276562)
			(xy 124.045564 -160.268851) (xy 124.055632 -160.268412) (xy 127.611124 -160.268412) (xy 127.621192 -160.26884)
			(xy 127.639789 -160.276562) (xy 127.647192 -160.283398) (xy 128.267968 -160.904174) (xy 128.274806 -160.911575)
			(xy 128.282519 -160.930174) (xy 128.282954 -160.940242) (xy 128.282954 -164.66693) (xy 128.282524 -164.676997)
			(xy 128.274797 -164.695589) (xy 128.267968 -164.702998) (xy 127.896366 -165.0746) (xy 127.888966 -165.081441)
			(xy 127.870368 -165.089163) (xy 127.860298 -165.089586) (xy 126.1618 -165.089586) (xy 126.15173 -165.089163)
			(xy 126.133127 -165.081447) (xy 126.125732 -165.0746) (xy 125.833124 -164.781992) (xy 125.826276 -164.774594)
			(xy 125.818541 -164.755996) (xy 125.818138 -164.745924) (xy 125.818138 -162.992308) (xy 125.817715 -162.982238)
			(xy 125.809995 -162.963638) (xy 125.803152 -162.95624) (xy 125.657864 -162.810952) (xy 125.650466 -162.804106)
			(xy 125.631867 -162.796376) (xy 125.621796 -162.795966) (xy 124.139452 -162.795966) (xy 124.129387 -162.7964)
			(xy 124.110802 -162.804134) (xy 124.103384 -162.810952) (xy 123.895104 -163.019232) (xy 123.888262 -163.026632)
			(xy 123.880539 -163.04523) (xy 123.880118 -163.0553) (xy 123.880118 -165.007798) (xy 123.8796 -165.017697)
			(xy 123.872022 -165.035994) (xy 123.865386 -165.043358) (xy 123.851162 -165.057836) (xy 123.851162 -165.06571)
			(xy 123.664726 -165.251892) (xy 123.656598 -165.251892) (xy 123.524518 -165.384226) (xy 123.517119 -165.391068)
			(xy 123.498519 -165.398784) (xy 123.48845 -165.399212) (xy 118.598696 -165.399212) (xy 113.838482 -165.399212)
			(xy 113.449354 -165.78834) (xy 113.449354 -167.400478) (xy 113.449793 -167.410541) (xy 113.457533 -167.429119)
			(xy 113.46434 -167.436546) (xy 113.79962 -167.771826) (xy 113.807016 -167.778677) (xy 113.825615 -167.786416)
			(xy 113.835688 -167.786812) (xy 114.971068 -167.786812) (xy 114.981133 -167.786377) (xy 114.999721 -167.778647)
			(xy 115.007136 -167.771826) (xy 115.713764 -167.065198) (xy 115.721166 -167.058362) (xy 115.739764 -167.050651)
			(xy 115.749832 -167.050212) (xy 118.630954 -167.050212) (xy 118.632224 -167.051482) (xy 118.84406 -167.051482)
			(xy 118.854126 -167.051915) (xy 118.872716 -167.059643) (xy 118.880128 -167.066468) (xy 119.936768 -168.123108)
			(xy 119.943617 -168.130505) (xy 119.951353 -168.149104) (xy 119.951754 -168.159176) (xy 119.951754 -171.42333)
			(xy 119.951324 -171.433397) (xy 119.943597 -171.451989) (xy 119.936768 -171.459398) (xy 119.590566 -171.8056)
			(xy 119.583166 -171.812441) (xy 119.564568 -171.820163) (xy 119.554498 -171.820586) (xy 117.8814 -171.820586)
			(xy 117.87133 -171.820163) (xy 117.852727 -171.812447) (xy 117.845332 -171.8056) (xy 117.552724 -171.512992)
			(xy 117.545876 -171.505594) (xy 117.538141 -171.486996) (xy 117.537738 -171.476924) (xy 117.537738 -169.723308)
			(xy 117.537315 -169.713238) (xy 117.529595 -169.694638) (xy 117.522752 -169.68724) (xy 117.377464 -169.541952)
			(xy 117.370066 -169.535106) (xy 117.351467 -169.527376) (xy 117.341396 -169.526966) (xy 115.859052 -169.526966)
			(xy 115.848987 -169.5274) (xy 115.830402 -169.535134) (xy 115.822984 -169.541952) (xy 115.614704 -169.750232)
			(xy 115.607862 -169.757632) (xy 115.600139 -169.77623) (xy 115.599718 -169.7863) (xy 115.599718 -171.738544)
			(xy 115.599287 -171.748611) (xy 115.591564 -171.767206) (xy 115.584732 -171.774612) (xy 115.365784 -171.99356)
			(xy 115.358387 -172.000408) (xy 115.339788 -172.008143) (xy 115.329716 -172.008546) (xy 110.277656 -172.008546)
			(xy 110.267591 -172.008113) (xy 110.249003 -172.000382) (xy 110.241588 -171.99356) (xy 109.77372 -171.525692)
			(xy 109.766873 -171.518294) (xy 109.759138 -171.499696) (xy 109.758734 -171.489624) (xy 109.758734 -165.491414)
			(xy 109.758293 -165.481352) (xy 109.75055 -165.462777) (xy 109.743748 -165.455346) (xy 107.76966 -163.481258)
			(xy 107.762262 -163.474412) (xy 107.743663 -163.466683) (xy 107.733592 -163.466272) (xy 104.527096 -163.466272)
			(xy 104.517025 -163.466695) (xy 104.498419 -163.474407) (xy 104.491028 -163.481258) (xy 103.7336 -164.238686)
			(xy 103.726767 -164.246089) (xy 103.719064 -164.264687) (xy 103.718614 -164.274754) (xy 103.718614 -167.77081)
			(xy 103.719039 -167.780879) (xy 103.726758 -167.79948) (xy 103.7336 -167.806878) (xy 105.458768 -169.532046)
			(xy 105.46561 -169.539446) (xy 105.473333 -169.558044) (xy 105.473754 -169.568114) (xy 105.473754 -173.88713)
			(xy 105.474184 -173.897197) (xy 105.481912 -173.915788) (xy 105.48874 -173.923198) (xy 105.534968 -173.969426)
			(xy 105.542367 -173.97627) (xy 105.560966 -173.983991) (xy 105.571036 -173.984412) (xy 106.614468 -173.984412)
			(xy 106.624533 -173.983977) (xy 106.643121 -173.976247) (xy 106.650536 -173.969426) (xy 107.280964 -173.338998)
			(xy 107.288366 -173.332162) (xy 107.306964 -173.324451) (xy 107.317032 -173.324012) (xy 107.81792 -173.324012)
			(xy 107.967272 -173.17466) (xy 107.972352 -173.16958) (xy 111.4425 -173.16958) (xy 111.44758 -173.17466)
			(xy 111.672624 -173.399704) (xy 111.672624 -174.17542) (xy 111.672878 -174.180246) (xy 111.672878 -177.689002)
			(xy 111.672454 -177.699072) (xy 111.664737 -177.717673) (xy 111.657892 -177.72507) (xy 111.328962 -178.054)
			(xy 111.321561 -178.06084) (xy 111.302963 -178.068561) (xy 111.292894 -178.068986) (xy 109.6518 -178.068986)
			(xy 109.64173 -178.068563) (xy 109.623127 -178.060847) (xy 109.615732 -178.054) (xy 109.323124 -177.761392)
			(xy 109.316276 -177.753994) (xy 109.308541 -177.735396) (xy 109.308138 -177.725324) (xy 109.308138 -175.971708)
			(xy 109.307715 -175.961638) (xy 109.299995 -175.943038) (xy 109.293152 -175.93564) (xy 109.147864 -175.790352)
			(xy 109.140466 -175.783506) (xy 109.121867 -175.775776) (xy 109.111796 -175.775366) (xy 107.629452 -175.775366)
			(xy 107.619387 -175.7758) (xy 107.600802 -175.783534) (xy 107.593384 -175.790352) (xy 107.385104 -175.998632)
			(xy 107.378262 -176.006032) (xy 107.370539 -176.02463) (xy 107.370118 -176.0347) (xy 107.370118 -178.086766)
			(xy 107.369683 -178.096831) (xy 107.361954 -178.11542) (xy 107.355132 -178.122834) (xy 107.21594 -178.262026)
			(xy 107.208542 -178.268871) (xy 107.189943 -178.276596) (xy 107.179872 -178.277012) (xy 103.722678 -178.277012)
			(xy 103.712674 -178.277504) (xy 103.694192 -178.285168) (xy 103.680049 -178.299321) (xy 103.672397 -178.317808)
			(xy 103.671878 -178.327812) (xy 103.671878 -182.007002) (xy 103.671454 -182.017072) (xy 103.663737 -182.035673)
			(xy 103.656892 -182.04307) (xy 102.865936 -182.834026) (xy 102.858537 -182.84087) (xy 102.839938 -182.848593)
			(xy 102.829868 -182.849012) (xy 101.456236 -182.849012) (xy 101.446171 -182.848578) (xy 101.427582 -182.840848)
			(xy 101.420168 -182.834026) (xy 100.941124 -182.354982) (xy 100.934278 -182.347584) (xy 100.926546 -182.328985)
			(xy 100.926138 -182.318914) (xy 100.926138 -180.492908) (xy 100.925715 -180.482838) (xy 100.917995 -180.464238)
			(xy 100.911152 -180.45684) (xy 100.765864 -180.311552) (xy 100.758466 -180.304706) (xy 100.739867 -180.296976)
			(xy 100.729796 -180.296566) (xy 99.247452 -180.296566) (xy 99.237387 -180.297) (xy 99.218802 -180.304734)
			(xy 99.211384 -180.311552) (xy 99.003104 -180.519832) (xy 98.996262 -180.527232) (xy 98.988539 -180.54583)
			(xy 98.988118 -180.5559) (xy 98.988118 -182.508144) (xy 98.987687 -182.518211) (xy 98.979964 -182.536806)
			(xy 98.973132 -182.544212) (xy 98.749866 -182.767478) (xy 98.742467 -182.774322) (xy 98.723868 -182.782047)
			(xy 98.713798 -182.782464) (xy 92.9005 -182.782464) (xy 92.890431 -182.78204) (xy 92.871829 -182.774322)
			(xy 92.864432 -182.767478) (xy 92.479622 -182.382668) (xy 92.472778 -182.375269) (xy 92.465052 -182.356671)
			(xy 92.464636 -182.3466) (xy 92.464636 -180.603144) (xy 92.464201 -180.59308) (xy 92.456465 -180.574496)
			(xy 92.44965 -180.567076) (xy 92.203778 -180.321204) (xy 92.196378 -180.314361) (xy 92.17778 -180.306634)
			(xy 92.16771 -180.306218) (xy 90.717878 -180.306218) (xy 90.712858 -180.306308) (xy 90.703005 -180.308223)
			(xy 90.69832 -180.310028) (xy 90.681048 -180.317394) (xy 90.676486 -180.319403) (xy 90.668175 -180.324906)
			(xy 90.664538 -180.328316) (xy 90.62974 -180.363114) (xy 90.622891 -180.370511) (xy 90.615156 -180.38911)
			(xy 90.614754 -180.399182) (xy 90.614754 -182.521606) (xy 90.614328 -182.531675) (xy 90.606607 -182.550273)
			(xy 90.599768 -182.557674) (xy 90.374216 -182.783226) (xy 90.366817 -182.790067) (xy 90.348217 -182.797783)
			(xy 90.338148 -182.798212) (xy 84.637372 -182.798212) (xy 84.627304 -182.797784) (xy 84.608705 -182.790064)
			(xy 84.601304 -182.783226) (xy 84.453222 -182.635144) (xy 84.151724 -182.333392) (xy 84.144876 -182.325994)
			(xy 84.137141 -182.307396) (xy 84.136738 -182.297324) (xy 84.136738 -180.543708) (xy 84.136315 -180.533638)
			(xy 84.128595 -180.515038) (xy 84.121752 -180.50764) (xy 83.976464 -180.362352) (xy 83.969066 -180.355506)
			(xy 83.950467 -180.347776) (xy 83.940396 -180.347366) (xy 82.458052 -180.347366) (xy 82.448019 -180.347802)
			(xy 82.429439 -180.355371) (xy 82.421984 -180.362098) (xy 82.260948 -180.523134) (xy 82.254102 -180.530532)
			(xy 82.246372 -180.549131) (xy 82.245962 -180.559202) (xy 82.245962 -182.619142) (xy 82.24553 -182.629208)
			(xy 82.237801 -182.647798) (xy 82.230976 -182.65521) (xy 82.072226 -182.81396) (xy 82.064825 -182.820799)
			(xy 82.046227 -182.828513) (xy 82.036158 -182.828946) (xy 78.331822 -182.828946) (xy 78.321759 -182.828507)
			(xy 78.303181 -182.820767) (xy 78.295754 -182.81396) (xy 77.905864 -182.42407) (xy 77.899015 -182.416673)
			(xy 77.891282 -182.398074) (xy 77.890878 -182.388002) (xy 77.890878 -177.799746) (xy 77.890466 -177.78972)
			(xy 77.882803 -177.771191) (xy 77.868629 -177.75701) (xy 77.850104 -177.749339) (xy 77.840078 -177.748946)
			(xy 76.248514 -177.748946) (xy 76.238452 -177.748506) (xy 76.219875 -177.740763) (xy 76.212446 -177.73396)
			(xy 75.843384 -177.364898) (xy 75.836529 -177.357503) (xy 75.828782 -177.338904) (xy 75.828398 -177.32883)
			(xy 75.828398 -175.541686) (xy 75.827972 -175.531617) (xy 75.820254 -175.513016) (xy 75.813412 -175.505618)
			(xy 75.619864 -175.31207) (xy 75.612467 -175.305222) (xy 75.593868 -175.297489) (xy 75.583796 -175.297084)
			(xy 74.10196 -175.297084) (xy 74.091893 -175.297514) (xy 74.073297 -175.305237) (xy 74.065892 -175.31207)
			(xy 73.905364 -175.472598) (xy 73.89851 -175.479993) (xy 73.890765 -175.498592) (xy 73.890378 -175.508666)
			(xy 73.890378 -177.59045) (xy 73.889945 -177.600516) (xy 73.882216 -177.619105) (xy 73.875392 -177.626518)
			(xy 73.704196 -177.797714) (xy 73.696801 -177.804569) (xy 73.678202 -177.812316) (xy 73.668128 -177.8127)
			(xy 70.140576 -177.8127) (xy 70.130508 -177.812272) (xy 70.11191 -177.804552) (xy 70.104508 -177.797714)
			(xy 69.941186 -177.634392) (xy 69.936868 -177.634392) (xy 69.650356 -177.34788) (xy 69.643507 -177.340483)
			(xy 69.635771 -177.321884) (xy 69.63537 -177.311812) (xy 69.63537 -168.967658) (xy 69.634939 -168.957592)
			(xy 69.62721 -168.939001) (xy 69.620384 -168.93159) (xy 69.526912 -168.838118) (xy 69.519515 -168.831268)
			(xy 69.500917 -168.823526) (xy 69.490844 -168.823132) (xy 67.8434 -168.823132) (xy 67.833329 -168.82271)
			(xy 67.814722 -168.814999) (xy 67.807332 -168.808146) (xy 67.514724 -168.515538) (xy 67.507885 -168.508137)
			(xy 67.500169 -168.489539) (xy 67.499738 -168.47947) (xy 67.499738 -166.725854) (xy 67.499305 -166.715789)
			(xy 67.491572 -166.697202) (xy 67.484752 -166.689786) (xy 67.339464 -166.544498) (xy 67.332063 -166.537658)
			(xy 67.313465 -166.529937) (xy 67.303396 -166.529512) (xy 65.821052 -166.529512) (xy 65.810986 -166.529944)
			(xy 65.792395 -166.537672) (xy 65.784984 -166.544498) (xy 65.639188 -166.690294) (xy 65.632331 -166.697688)
			(xy 65.624581 -166.716287) (xy 65.624202 -166.726362) (xy 65.624202 -168.788842) (xy 65.623771 -168.798909)
			(xy 65.616046 -168.817502) (xy 65.609216 -168.82491) (xy 65.43802 -168.996106) (xy 65.430617 -169.002939)
			(xy 65.412019 -169.010643) (xy 65.401952 -169.011092) (xy 59.543696 -169.011092) (xy 59.533626 -169.010668)
			(xy 59.515024 -169.002952) (xy 59.507628 -168.996106) (xy 59.18962 -168.678098) (xy 59.182772 -168.6707)
			(xy 59.175035 -168.652102) (xy 59.174634 -168.64203) (xy 59.174634 -164.551614) (xy 59.174193 -164.541552)
			(xy 59.16645 -164.522977) (xy 59.159648 -164.515546) (xy 58.70702 -164.062918) (xy 58.699618 -164.056082)
			(xy 58.68102 -164.048374) (xy 58.670952 -164.047932) (xy 51.110896 -164.047932) (xy 51.104292 -164.054536)
			(xy 49.43983 -164.054536) (xy 49.112678 -164.381688) (xy 49.112678 -174.162974) (xy 51.900328 -176.950624)
			(xy 51.900756 -176.960692) (xy 51.90848 -176.979287) (xy 51.915314 -176.986692) (xy 53.799994 -178.871372)
			(xy 53.80683 -178.878774) (xy 53.814539 -178.897372) (xy 53.81498 -178.90744) (xy 53.81498 -181.08041)
			(xy 56.477916 -181.08041) (xy 56.478406 -181.050426) (xy 56.486234 -180.99097) (xy 56.501755 -180.933045)
			(xy 56.524704 -180.877641) (xy 56.554688 -180.825707) (xy 56.591194 -180.778131) (xy 56.633599 -180.735726)
			(xy 56.681175 -180.69922) (xy 56.733109 -180.669236) (xy 56.788513 -180.646287) (xy 56.846438 -180.630766)
			(xy 56.905894 -180.622938) (xy 56.965862 -180.622938) (xy 57.025318 -180.630766) (xy 57.083243 -180.646287)
			(xy 57.138647 -180.669236) (xy 57.190581 -180.69922) (xy 57.238157 -180.735726) (xy 57.280562 -180.778131)
			(xy 57.317068 -180.825707) (xy 57.347052 -180.877641) (xy 57.370001 -180.933045) (xy 57.385522 -180.99097)
			(xy 57.39335 -181.050426) (xy 57.39384 -181.08041) (xy 57.393365 -181.109388) (xy 57.386053 -181.166879)
			(xy 57.371546 -181.22299) (xy 57.350077 -181.276821) (xy 57.321988 -181.327515) (xy 57.287728 -181.374259)
			(xy 57.247845 -181.416308) (xy 57.225692 -181.434994) (xy 57.215266 -181.44409) (xy 57.199421 -181.466763)
			(xy 57.19024 -181.492856) (xy 57.188397 -181.520456) (xy 57.194027 -181.547538) (xy 57.206716 -181.572117)
			(xy 57.215786 -181.582568) (xy 57.234866 -181.603862) (xy 57.267061 -181.651112) (xy 57.291848 -181.702635)
			(xy 57.308671 -181.757279) (xy 57.317154 -181.813822) (xy 57.31764 -181.84241) (xy 57.317154 -181.869679)
			(xy 57.309392 -181.923663) (xy 57.294027 -181.975993) (xy 57.27137 -182.025603) (xy 57.241884 -182.071484)
			(xy 57.206169 -182.112701) (xy 57.164952 -182.148416) (xy 57.119071 -182.177902) (xy 57.069461 -182.200559)
			(xy 57.017131 -182.215924) (xy 56.963147 -182.223686) (xy 56.908609 -182.223686) (xy 56.854625 -182.215924)
			(xy 56.802295 -182.200559) (xy 56.752685 -182.177902) (xy 56.706804 -182.148416) (xy 56.665587 -182.112701)
			(xy 56.629872 -182.071484) (xy 56.600386 -182.025603) (xy 56.577729 -181.975993) (xy 56.562364 -181.923663)
			(xy 56.554602 -181.869679) (xy 56.554116 -181.84241) (xy 56.554595 -181.813823) (xy 56.563089 -181.757283)
			(xy 56.579919 -181.702642) (xy 56.604708 -181.651122) (xy 56.636903 -181.603873) (xy 56.65597 -181.582568)
			(xy 56.665002 -181.572088) (xy 56.677702 -181.547526) (xy 56.683337 -181.520455) (xy 56.681493 -181.492866)
			(xy 56.672305 -181.466786) (xy 56.656448 -181.444133) (xy 56.646064 -181.434994) (xy 56.623924 -181.416292)
			(xy 56.584031 -181.374251) (xy 56.549762 -181.327511) (xy 56.521664 -181.276821) (xy 56.500188 -181.222991)
			(xy 56.485677 -181.166881) (xy 56.478362 -181.109388) (xy 56.477916 -181.08041) (xy 53.81498 -181.08041)
			(xy 53.81498 -186.615578) (xy 53.815417 -186.625642) (xy 53.823149 -186.644228) (xy 53.829966 -186.651646)
			(xy 55.036974 -187.858654) (xy 55.044374 -187.865494) (xy 55.062973 -187.873209) (xy 55.073042 -187.87364)
			(xy 58.604658 -187.87364) (xy 58.614722 -187.873205) (xy 58.633306 -187.865469) (xy 58.640726 -187.858654)
			(xy 58.867294 -187.632086) (xy 58.874139 -187.624687) (xy 58.881869 -187.606089) (xy 58.88228 -187.596018)
			(xy 58.88228 -177.249074) (xy 58.882707 -177.239005) (xy 58.890426 -177.220406) (xy 58.897266 -177.213006)
			(xy 58.902854 -177.207418) (xy 58.910254 -177.200578) (xy 58.928853 -177.19286) (xy 58.938922 -177.192432)
			(xy 68.670932 -177.192432) (xy 68.680999 -177.192862) (xy 68.699592 -177.200588) (xy 68.707 -177.207418)
			(xy 69.075808 -177.576226) (xy 69.082649 -177.583626) (xy 69.090373 -177.602224) (xy 69.090794 -177.612294)
			(xy 69.090794 -178.720496) (xy 69.088254 -178.723036) (xy 69.088254 -184.97677) (xy 69.088691 -184.986833)
			(xy 69.09643 -185.005414) (xy 69.10324 -185.012838) (xy 69.144388 -185.053986) (xy 69.151785 -185.060836)
			(xy 69.170383 -185.068577) (xy 69.180456 -185.068972) (xy 70.352412 -185.068972) (xy 70.362482 -185.069397)
			(xy 70.381086 -185.077111) (xy 70.38848 -185.083958) (xy 71.25462 -185.950098) (xy 71.26202 -185.956941)
			(xy 71.280618 -185.964669) (xy 71.290688 -185.965084) (xy 77.742796 -185.965084) (xy 77.752867 -185.965506)
			(xy 77.771474 -185.973217) (xy 77.778864 -185.98007) (xy 78.383892 -186.585098) (xy 78.39074 -186.592496)
			(xy 78.398476 -186.611094) (xy 78.398878 -186.621166) (xy 78.398878 -190.770002) (xy 78.399301 -190.780073)
			(xy 78.407013 -190.798679) (xy 78.413864 -190.80607) (xy 78.67142 -191.063626) (xy 78.678816 -191.070477)
			(xy 78.697415 -191.078216) (xy 78.707488 -191.078612)
		)
		(stroke
			(width 0)
			(type solid)
		)
		(fill yes)
		(layer "B.Cu")
		(net "GND")
	)
	(gr_poly
		(pts
			(xy 345.22537 -256.059178) (xy 345.236882 -256.058601) (xy 345.257521 -256.048398) (xy 345.264994 -256.03962)
			(xy 345.294458 -255.998726) (xy 345.313508 -255.972056) (xy 345.316857 -255.967053) (xy 345.321345 -255.955886)
			(xy 345.322398 -255.949958) (xy 345.324176 -255.938528) (xy 345.324176 -255.938274) (xy 345.320112 -255.926844)
			(xy 345.312181 -255.901934) (xy 345.303632 -255.850365) (xy 345.303094 -255.824228) (xy 345.303584 -255.799239)
			(xy 345.311403 -255.749876) (xy 345.326847 -255.702344) (xy 345.349537 -255.657812) (xy 345.378913 -255.617379)
			(xy 345.414253 -255.582039) (xy 345.454686 -255.552663) (xy 345.499218 -255.529973) (xy 345.54675 -255.514529)
			(xy 345.596113 -255.50671) (xy 345.646091 -255.50671) (xy 345.695454 -255.514529) (xy 345.742986 -255.529973)
			(xy 345.787518 -255.552663) (xy 345.827951 -255.582039) (xy 345.863291 -255.617379) (xy 345.892667 -255.657812)
			(xy 345.915357 -255.702344) (xy 345.930801 -255.749876) (xy 345.93862 -255.799239) (xy 345.93911 -255.824228)
			(xy 345.938577 -255.850365) (xy 345.930019 -255.901932) (xy 345.922092 -255.926844) (xy 345.918028 -255.938274)
			(xy 345.918028 -255.938528) (xy 345.919806 -255.949958) (xy 345.92085 -255.955887) (xy 345.925351 -255.96705)
			(xy 345.928696 -255.972056) (xy 345.947746 -255.998726) (xy 345.97721 -256.03962) (xy 345.98468 -256.048399)
			(xy 346.005322 -256.058603) (xy 346.016834 -256.059178) (xy 347.00083 -256.059178) (xy 347.00966 -256.058803)
			(xy 347.026214 -256.052643) (xy 347.039611 -256.041132) (xy 347.048192 -256.025694) (xy 347.049852 -256.017014)
			(xy 347.049852 -255.590548) (xy 347.050331 -255.58053) (xy 347.05798 -255.562014) (xy 347.072133 -255.547834)
			(xy 347.090635 -255.54015) (xy 347.100652 -255.539748) (xy 347.275658 -255.539748) (xy 347.288866 -255.534922)
			(xy 347.2988 -255.529106) (xy 347.312413 -255.510574) (xy 347.315028 -255.499362) (xy 347.334586 -255.479804)
			(xy 347.570552 -255.479804) (xy 347.592727 -255.480388) (xy 347.636122 -255.489548) (xy 347.67671 -255.507426)
			(xy 347.712761 -255.533259) (xy 347.742738 -255.565945) (xy 347.765363 -255.604092) (xy 347.77967 -255.646072)
			(xy 347.782896 -255.668018) (xy 347.784674 -255.675892) (xy 347.78696 -255.684274) (xy 347.788738 -255.688084)
			(xy 347.798384 -255.709468) (xy 347.811983 -255.754364) (xy 347.818833 -255.800772) (xy 347.819218 -255.824228)
			(xy 347.81879 -255.847449) (xy 347.812035 -255.893398) (xy 347.798687 -255.937882) (xy 347.789246 -255.959102)
			(xy 347.787001 -255.964215) (xy 347.784556 -255.97511) (xy 347.78442 -255.980692) (xy 347.78442 -255.994916)
			(xy 347.783658 -256.014982) (xy 347.785114 -256.024009) (xy 347.793556 -256.04021) (xy 347.807218 -256.052339)
			(xy 347.824306 -256.058802) (xy 347.833442 -256.059178) (xy 348.045278 -256.059178) (xy 348.056789 -256.058599)
			(xy 348.077425 -256.048394) (xy 348.084902 -256.03962) (xy 348.114366 -255.998726) (xy 348.133416 -255.972056)
			(xy 348.136764 -255.967053) (xy 348.141252 -255.955885) (xy 348.142306 -255.949958) (xy 348.144084 -255.938528)
			(xy 348.144084 -255.938274) (xy 348.14002 -255.926844) (xy 348.132088 -255.901934) (xy 348.12354 -255.850365)
			(xy 348.123002 -255.824228) (xy 348.123464 -255.799236) (xy 348.13128 -255.749866) (xy 348.146723 -255.702327)
			(xy 348.169413 -255.657789) (xy 348.198792 -255.617349) (xy 348.234135 -255.582004) (xy 348.274573 -255.552623)
			(xy 348.31911 -255.52993) (xy 348.366648 -255.514484) (xy 348.416018 -255.506666) (xy 348.44101 -255.50622)
			(xy 348.459806 -255.506728) (xy 348.470474 -255.507236) (xy 348.479618 -255.503934) (xy 348.484447 -255.502082)
			(xy 348.493281 -255.496706) (xy 348.497144 -255.493266) (xy 348.55023 -255.443228) (xy 348.55676 -255.436496)
			(xy 348.564731 -255.419533) (xy 348.565724 -255.410208) (xy 348.565724 -254.439166) (xy 348.565978 -254.433832)
			(xy 348.565978 -253.718314) (xy 348.565724 -253.713234) (xy 348.565724 -253.325884) (xy 348.565978 -253.320296)
			(xy 348.565978 -253.278894) (xy 348.565978 -253.27864) (xy 348.566421 -253.26876) (xy 348.573877 -253.250464)
			(xy 348.580456 -253.24308) (xy 348.62389 -253.199646) (xy 348.630599 -253.192407) (xy 348.638181 -253.174201)
			(xy 348.638622 -253.16434) (xy 348.638622 -253.090172) (xy 348.639151 -253.080332) (xy 348.64673 -253.062162)
			(xy 348.653354 -253.054866) (xy 348.78264 -252.92558) (xy 348.789203 -252.918335) (xy 348.796674 -252.900292)
			(xy 348.797118 -252.890528) (xy 348.797118 -252.285754) (xy 348.797372 -252.283722) (xy 348.797372 -252.268482)
			(xy 348.82709 -252.238764) (xy 349.012256 -252.238764) (xy 349.022639 -252.238176) (xy 349.041639 -252.22977)
			(xy 349.049086 -252.222508) (xy 349.054513 -252.216085) (xy 349.06114 -252.200642) (xy 349.06204 -252.192282)
			(xy 349.06204 -252.17882) (xy 349.149924 -252.17882) (xy 349.159822 -252.178396) (xy 349.178098 -252.170789)
			(xy 349.192055 -252.156749) (xy 349.199554 -252.138428) (xy 349.199962 -252.128528) (xy 349.199962 -251.2568)
			(xy 349.18904 -251.2568) (xy 349.18904 -251.252228) (xy 349.188879 -251.246852) (xy 349.186576 -251.236348)
			(xy 349.184468 -251.2314) (xy 349.179642 -251.220478) (xy 349.177368 -251.21583) (xy 349.171228 -251.207503)
			(xy 349.16745 -251.203968) (xy 349.15983 -251.196856) (xy 348.95409 -251.196856) (xy 348.924372 -251.167138)
			(xy 348.924372 -251.151898) (xy 348.924118 -251.149866) (xy 348.924118 -250.800108) (xy 348.923597 -250.790361)
			(xy 348.916139 -250.772341) (xy 348.90964 -250.765056) (xy 348.643702 -250.498864) (xy 348.633034 -250.498864)
			(xy 348.412054 -250.277884) (xy 348.403253 -250.270034) (xy 348.380861 -250.262736) (xy 348.369128 -250.263914)
			(xy 348.350078 -250.266708) (xy 348.289372 -250.275852) (xy 348.283442 -250.276894) (xy 348.272278 -250.281393)
			(xy 348.267274 -250.284742) (xy 348.258384 -250.291092) (xy 348.252542 -250.302268) (xy 348.240632 -250.323903)
			(xy 348.211158 -250.363529) (xy 348.175914 -250.398122) (xy 348.135745 -250.426851) (xy 348.091618 -250.449025)
			(xy 348.044594 -250.464112) (xy 347.995802 -250.471747) (xy 347.97111 -250.472194) (xy 347.946119 -250.47173)
			(xy 347.896751 -250.463912) (xy 347.849215 -250.448468) (xy 347.80468 -250.425777) (xy 347.764243 -250.396398)
			(xy 347.7289 -250.361054) (xy 347.699521 -250.320617) (xy 347.676831 -250.276082) (xy 347.661387 -250.228545)
			(xy 347.653569 -250.179177) (xy 347.653102 -250.154186) (xy 347.653575 -250.129074) (xy 347.661462 -250.079473)
			(xy 347.677039 -250.031725) (xy 347.699918 -249.987015) (xy 347.729533 -249.946451) (xy 347.765149 -249.91104)
			(xy 347.805883 -249.881659) (xy 347.828108 -249.86996) (xy 347.82887 -249.869706) (xy 347.834047 -249.866841)
			(xy 347.843031 -249.859146) (xy 347.84665 -249.854466) (xy 347.849952 -249.849894) (xy 347.854524 -249.838972)
			(xy 347.86824 -249.75312) (xy 347.869514 -249.741259) (xy 347.862218 -249.718583) (xy 347.85427 -249.709686)
			(xy 347.822774 -249.67819) (xy 347.815685 -249.671742) (xy 347.798049 -249.664293) (xy 347.788484 -249.663712)
			(xy 347.718888 -249.662696) (xy 347.714083 -249.662733) (xy 347.70462 -249.664391) (xy 347.700092 -249.665998)
			(xy 347.691202 -249.6693) (xy 347.688916 -249.671586) (xy 347.683836 -249.676158) (xy 347.668913 -249.689343)
			(xy 347.635167 -249.710476) (xy 347.598089 -249.724988) (xy 347.558964 -249.732378) (xy 347.539056 -249.7328)
			(xy 347.33484 -249.7328) (xy 347.324813 -249.732387) (xy 347.306283 -249.724725) (xy 347.292098 -249.710551)
			(xy 347.28442 -249.692026) (xy 347.28404 -249.682) (xy 347.28404 -249.672856) (xy 347.04909 -249.672856)
			(xy 347.019372 -249.643138) (xy 347.019372 -249.627898) (xy 347.019118 -249.625866) (xy 347.019118 -249.088656)
			(xy 347.018636 -249.078837) (xy 347.01113 -249.06069) (xy 346.997269 -249.046777) (xy 346.979151 -249.039202)
			(xy 346.969334 -249.038618) (xy 345.985084 -249.038618) (xy 345.976351 -249.038937) (xy 345.959933 -249.044891)
			(xy 345.946548 -249.056108) (xy 345.941904 -249.06351) (xy 345.927934 -249.086878) (xy 345.927934 -249.087386)
			(xy 345.898216 -249.138186) (xy 345.895093 -249.144003) (xy 345.891609 -249.156735) (xy 345.891358 -249.163332)
			(xy 345.891358 -249.176032) (xy 345.898216 -249.188224) (xy 345.911074 -249.212185) (xy 345.929305 -249.263411)
			(xy 345.938549 -249.316993) (xy 345.93911 -249.34418) (xy 345.93862 -249.369169) (xy 345.930801 -249.418532)
			(xy 345.915357 -249.466064) (xy 345.892667 -249.510596) (xy 345.863291 -249.551029) (xy 345.827951 -249.586369)
			(xy 345.787518 -249.615745) (xy 345.742986 -249.638435) (xy 345.695454 -249.653879) (xy 345.646091 -249.661698)
			(xy 345.596113 -249.661698) (xy 345.54675 -249.653879) (xy 345.499218 -249.638435) (xy 345.454686 -249.615745)
			(xy 345.414253 -249.586369) (xy 345.378913 -249.551029) (xy 345.349537 -249.510596) (xy 345.326847 -249.466064)
			(xy 345.311403 -249.418532) (xy 345.303584 -249.369169) (xy 345.303094 -249.34418) (xy 345.303651 -249.316993)
			(xy 345.312903 -249.263412) (xy 345.331133 -249.212186) (xy 345.343988 -249.188224) (xy 345.344242 -249.18797)
			(xy 345.347273 -249.182068) (xy 345.350493 -249.169203) (xy 345.350592 -249.16257) (xy 345.350592 -249.14987)
			(xy 345.31427 -249.087386) (xy 345.31427 -249.086878) (xy 345.3003 -249.06351) (xy 345.295591 -249.056162)
			(xy 345.282217 -249.044968) (xy 345.265838 -249.038977) (xy 345.25712 -249.038618) (xy 344.442796 -249.038618)
			(xy 344.432954 -249.039143) (xy 344.414777 -249.046715) (xy 344.40749 -249.05335) (xy 344.322654 -249.138186)
			(xy 344.315941 -249.145424) (xy 344.308342 -249.163629) (xy 344.307922 -249.173492) (xy 344.307922 -249.816366)
			(xy 344.308173 -249.823779) (xy 344.312431 -249.837981) (xy 344.316304 -249.844306) (xy 344.320114 -249.850148)
			(xy 344.331036 -249.859546) (xy 344.337894 -249.862594) (xy 344.36029 -249.87282) (xy 344.401887 -249.899152)
			(xy 344.438927 -249.931582) (xy 344.470525 -249.969334) (xy 344.495925 -250.011506) (xy 344.51452 -250.05709)
			(xy 344.525866 -250.104996) (xy 344.529691 -250.154078) (xy 344.527755 -250.179175) (xy 345.773484 -250.179175)
			(xy 345.773484 -250.129197) (xy 345.781303 -250.079834) (xy 345.796747 -250.032302) (xy 345.819437 -249.98777)
			(xy 345.848813 -249.947337) (xy 345.884153 -249.911997) (xy 345.924586 -249.882621) (xy 345.969118 -249.859931)
			(xy 346.01665 -249.844487) (xy 346.066013 -249.836668) (xy 346.115991 -249.836668) (xy 346.165354 -249.844487)
			(xy 346.212886 -249.859931) (xy 346.257418 -249.882621) (xy 346.297851 -249.911997) (xy 346.333191 -249.947337)
			(xy 346.362567 -249.98777) (xy 346.385257 -250.032302) (xy 346.400701 -250.079834) (xy 346.40852 -250.129197)
			(xy 346.40901 -250.154186) (xy 346.40852 -250.179175) (xy 346.400701 -250.228538) (xy 346.385257 -250.27607)
			(xy 346.362567 -250.320602) (xy 346.333191 -250.361035) (xy 346.297851 -250.396375) (xy 346.257418 -250.425751)
			(xy 346.212886 -250.448441) (xy 346.165354 -250.463885) (xy 346.115991 -250.471704) (xy 346.066013 -250.471704)
			(xy 346.01665 -250.463885) (xy 345.969118 -250.448441) (xy 345.924586 -250.425751) (xy 345.884153 -250.396375)
			(xy 345.848813 -250.361035) (xy 345.819437 -250.320602) (xy 345.796747 -250.27607) (xy 345.781303 -250.228538)
			(xy 345.773484 -250.179175) (xy 344.527755 -250.179175) (xy 344.525904 -250.203163) (xy 344.514595 -250.251077)
			(xy 344.496034 -250.296675) (xy 344.470667 -250.338867) (xy 344.439098 -250.376644) (xy 344.402082 -250.409102)
			(xy 344.360506 -250.435466) (xy 344.338148 -250.445778) (xy 344.33764 -250.445778) (xy 344.331036 -250.448826)
			(xy 344.320114 -250.458224) (xy 344.316304 -250.464066) (xy 344.312445 -250.470397) (xy 344.308197 -250.484596)
			(xy 344.307922 -250.492006) (xy 344.307922 -250.989181) (xy 345.303584 -250.989181) (xy 345.303584 -250.939203)
			(xy 345.311403 -250.88984) (xy 345.326847 -250.842308) (xy 345.349537 -250.797776) (xy 345.378913 -250.757343)
			(xy 345.414253 -250.722003) (xy 345.454686 -250.692627) (xy 345.499218 -250.669937) (xy 345.54675 -250.654493)
			(xy 345.596113 -250.646674) (xy 345.646091 -250.646674) (xy 345.695454 -250.654493) (xy 345.742986 -250.669937)
			(xy 345.787518 -250.692627) (xy 345.827951 -250.722003) (xy 345.863291 -250.757343) (xy 345.892667 -250.797776)
			(xy 345.915357 -250.842308) (xy 345.930801 -250.88984) (xy 345.93862 -250.939203) (xy 345.93911 -250.964192)
			(xy 345.93862 -250.989181) (xy 345.930801 -251.038544) (xy 345.915357 -251.086076) (xy 345.892667 -251.130608)
			(xy 345.881443 -251.146056) (xy 347.019372 -251.146056) (xy 347.019372 -250.638564) (xy 347.019858 -250.628557)
			(xy 347.027524 -250.61007) (xy 347.041677 -250.59592) (xy 347.060165 -250.588256) (xy 347.070172 -250.587764)
			(xy 347.28404 -250.587764) (xy 347.28404 -250.57862) (xy 347.284437 -250.568595) (xy 347.292108 -250.550071)
			(xy 347.306288 -250.535897) (xy 347.324815 -250.528233) (xy 347.33484 -250.52782) (xy 347.539056 -250.52782)
			(xy 347.5601 -250.528364) (xy 347.601374 -250.536597) (xy 347.640236 -250.552754) (xy 347.675182 -250.576209)
			(xy 347.704858 -250.606053) (xy 347.728114 -250.641131) (xy 347.744051 -250.680084) (xy 347.752052 -250.721404)
			(xy 347.752416 -250.74245) (xy 347.752416 -250.75261) (xy 347.752776 -250.760265) (xy 347.75743 -250.774857)
			(xy 347.76156 -250.781312) (xy 347.76156 -250.781566) (xy 347.775155 -250.801747) (xy 347.796697 -250.845375)
			(xy 347.811344 -250.891775) (xy 347.818755 -250.939864) (xy 347.819218 -250.964192) (xy 347.81871 -250.98918)
			(xy 347.810893 -251.038542) (xy 347.795451 -251.086074) (xy 347.772763 -251.130604) (xy 347.743389 -251.171037)
			(xy 347.708051 -251.206377) (xy 347.667619 -251.235754) (xy 347.62309 -251.258444) (xy 347.57556 -251.273889)
			(xy 347.526198 -251.281709) (xy 347.50121 -251.2822) (xy 347.471611 -251.281531) (xy 347.413443 -251.270531)
			(xy 347.38564 -251.260356) (xy 347.376496 -251.2568) (xy 347.28404 -251.2568) (xy 347.28404 -251.247656)
			(xy 347.283549 -251.23765) (xy 347.275882 -251.219165) (xy 347.261731 -251.205015) (xy 347.243246 -251.19735)
			(xy 347.23324 -251.196856) (xy 347.070172 -251.196856) (xy 347.060143 -251.196503) (xy 347.041617 -251.188815)
			(xy 347.027444 -251.174622) (xy 347.019783 -251.156085) (xy 347.019372 -251.146056) (xy 345.881443 -251.146056)
			(xy 345.863291 -251.171041) (xy 345.827951 -251.206381) (xy 345.787518 -251.235757) (xy 345.742986 -251.258447)
			(xy 345.695454 -251.273891) (xy 345.646091 -251.28171) (xy 345.596113 -251.28171) (xy 345.54675 -251.273891)
			(xy 345.499218 -251.258447) (xy 345.454686 -251.235757) (xy 345.414253 -251.206381) (xy 345.378913 -251.171041)
			(xy 345.349537 -251.130608) (xy 345.326847 -251.086076) (xy 345.311403 -251.038544) (xy 345.303584 -250.989181)
			(xy 344.307922 -250.989181) (xy 344.307922 -251.436378) (xy 344.308175 -251.443791) (xy 344.312435 -251.45799)
			(xy 344.316304 -251.464318) (xy 344.320114 -251.47016) (xy 344.331036 -251.479558) (xy 344.337894 -251.482606)
			(xy 344.360296 -251.492832) (xy 344.401907 -251.519166) (xy 344.43896 -251.5516) (xy 344.47057 -251.589359)
			(xy 344.495981 -251.631539) (xy 344.514586 -251.677132) (xy 344.52594 -251.725049) (xy 344.529772 -251.774143)
			(xy 344.527842 -251.799187) (xy 345.773484 -251.799187) (xy 345.773484 -251.749209) (xy 345.781303 -251.699846)
			(xy 345.796747 -251.652314) (xy 345.819437 -251.607782) (xy 345.848813 -251.567349) (xy 345.884153 -251.532009)
			(xy 345.924586 -251.502633) (xy 345.969118 -251.479943) (xy 346.01665 -251.464499) (xy 346.066013 -251.45668)
			(xy 346.115991 -251.45668) (xy 346.165354 -251.464499) (xy 346.212886 -251.479943) (xy 346.257418 -251.502633)
			(xy 346.297851 -251.532009) (xy 346.333191 -251.567349) (xy 346.362567 -251.607782) (xy 346.385257 -251.652314)
			(xy 346.400701 -251.699846) (xy 346.40852 -251.749209) (xy 346.40901 -251.774198) (xy 346.40852 -251.799187)
			(xy 347.653592 -251.799187) (xy 347.653592 -251.749209) (xy 347.661411 -251.699846) (xy 347.676855 -251.652314)
			(xy 347.699545 -251.607782) (xy 347.728921 -251.567349) (xy 347.764261 -251.532009) (xy 347.804694 -251.502633)
			(xy 347.849226 -251.479943) (xy 347.896758 -251.464499) (xy 347.946121 -251.45668) (xy 347.996099 -251.45668)
			(xy 348.045462 -251.464499) (xy 348.092994 -251.479943) (xy 348.137526 -251.502633) (xy 348.177959 -251.532009)
			(xy 348.213299 -251.567349) (xy 348.242675 -251.607782) (xy 348.265365 -251.652314) (xy 348.280809 -251.699846)
			(xy 348.288628 -251.749209) (xy 348.289118 -251.774198) (xy 348.288628 -251.799187) (xy 348.280809 -251.84855)
			(xy 348.265365 -251.896082) (xy 348.242675 -251.940614) (xy 348.213299 -251.981047) (xy 348.177959 -252.016387)
			(xy 348.137526 -252.045763) (xy 348.092994 -252.068453) (xy 348.045462 -252.083897) (xy 347.996099 -252.091716)
			(xy 347.946121 -252.091716) (xy 347.896758 -252.083897) (xy 347.849226 -252.068453) (xy 347.804694 -252.045763)
			(xy 347.764261 -252.016387) (xy 347.728921 -251.981047) (xy 347.699545 -251.940614) (xy 347.676855 -251.896082)
			(xy 347.661411 -251.84855) (xy 347.653592 -251.799187) (xy 346.40852 -251.799187) (xy 346.400701 -251.84855)
			(xy 346.385257 -251.896082) (xy 346.362567 -251.940614) (xy 346.333191 -251.981047) (xy 346.297851 -252.016387)
			(xy 346.257418 -252.045763) (xy 346.212886 -252.068453) (xy 346.165354 -252.083897) (xy 346.115991 -252.091716)
			(xy 346.066013 -252.091716) (xy 346.01665 -252.083897) (xy 345.969118 -252.068453) (xy 345.924586 -252.045763)
			(xy 345.884153 -252.016387) (xy 345.848813 -251.981047) (xy 345.819437 -251.940614) (xy 345.796747 -251.896082)
			(xy 345.781303 -251.84855) (xy 345.773484 -251.799187) (xy 344.527842 -251.799187) (xy 344.525989 -251.82324)
			(xy 344.514682 -251.871168) (xy 344.496122 -251.91678) (xy 344.470753 -251.958985) (xy 344.43918 -251.996775)
			(xy 344.402159 -252.029245) (xy 344.360575 -252.055621) (xy 344.338148 -252.06579) (xy 344.33764 -252.06579)
			(xy 344.331036 -252.068838) (xy 344.320114 -252.078236) (xy 344.316304 -252.084078) (xy 344.312433 -252.090406)
			(xy 344.308161 -252.104605) (xy 344.307922 -252.112018) (xy 344.307922 -252.609193) (xy 345.303584 -252.609193)
			(xy 345.303584 -252.559215) (xy 345.311403 -252.509852) (xy 345.326847 -252.46232) (xy 345.349537 -252.417788)
			(xy 345.378913 -252.377355) (xy 345.414253 -252.342015) (xy 345.454686 -252.312639) (xy 345.499218 -252.289949)
			(xy 345.54675 -252.274505) (xy 345.596113 -252.266686) (xy 345.646091 -252.266686) (xy 345.695454 -252.274505)
			(xy 345.742986 -252.289949) (xy 345.787518 -252.312639) (xy 345.827951 -252.342015) (xy 345.863291 -252.377355)
			(xy 345.892667 -252.417788) (xy 345.915357 -252.46232) (xy 345.930801 -252.509852) (xy 345.93862 -252.559215)
			(xy 345.93911 -252.584204) (xy 345.93862 -252.609193) (xy 345.930801 -252.658556) (xy 345.915357 -252.706088)
			(xy 345.892667 -252.75062) (xy 345.863291 -252.791053) (xy 345.857288 -252.797056) (xy 347.019372 -252.797056)
			(xy 347.019372 -252.289564) (xy 347.019858 -252.279557) (xy 347.027524 -252.26107) (xy 347.041677 -252.24692)
			(xy 347.060165 -252.239256) (xy 347.070172 -252.238764) (xy 347.28404 -252.238764) (xy 347.28404 -252.22962)
			(xy 347.284437 -252.219595) (xy 347.292108 -252.201071) (xy 347.306288 -252.186897) (xy 347.324815 -252.179233)
			(xy 347.33484 -252.17882) (xy 347.539056 -252.17882) (xy 347.558926 -252.179384) (xy 347.597971 -252.186802)
			(xy 347.634969 -252.201316) (xy 347.668642 -252.222425) (xy 347.697829 -252.2494) (xy 347.721521 -252.281309)
			(xy 347.7389 -252.31705) (xy 347.749366 -252.35539) (xy 347.7514 -252.375162) (xy 347.752184 -252.381987)
			(xy 347.756956 -252.394866) (xy 347.760798 -252.400562) (xy 347.774563 -252.420819) (xy 347.7964 -252.464655)
			(xy 347.811251 -252.511323) (xy 347.818766 -252.559717) (xy 347.819218 -252.584204) (xy 347.818637 -252.611571)
			(xy 347.809263 -252.665498) (xy 347.790809 -252.717028) (xy 347.763817 -252.764646) (xy 347.729084 -252.806948)
			(xy 347.708728 -252.82525) (xy 347.702886 -252.831346) (xy 347.690626 -252.845452) (xy 347.662027 -252.869509)
			(xy 347.629672 -252.888211) (xy 347.594552 -252.900985) (xy 347.557742 -252.907442) (xy 347.539056 -252.9078)
			(xy 347.28404 -252.9078) (xy 347.28404 -252.898656) (xy 347.283549 -252.88865) (xy 347.275882 -252.870165)
			(xy 347.261731 -252.856015) (xy 347.243246 -252.84835) (xy 347.23324 -252.847856) (xy 347.070172 -252.847856)
			(xy 347.060143 -252.847503) (xy 347.041617 -252.839815) (xy 347.027444 -252.825622) (xy 347.019783 -252.807085)
			(xy 347.019372 -252.797056) (xy 345.857288 -252.797056) (xy 345.827951 -252.826393) (xy 345.787518 -252.855769)
			(xy 345.742986 -252.878459) (xy 345.695454 -252.893903) (xy 345.646091 -252.901722) (xy 345.596113 -252.901722)
			(xy 345.54675 -252.893903) (xy 345.499218 -252.878459) (xy 345.454686 -252.855769) (xy 345.414253 -252.826393)
			(xy 345.378913 -252.791053) (xy 345.349537 -252.75062) (xy 345.326847 -252.706088) (xy 345.311403 -252.658556)
			(xy 345.303584 -252.609193) (xy 344.307922 -252.609193) (xy 344.307922 -253.05639) (xy 344.308176 -253.063802)
			(xy 344.31244 -253.078) (xy 344.316304 -253.08433) (xy 344.320114 -253.090172) (xy 344.331036 -253.09957)
			(xy 344.337894 -253.102618) (xy 344.360296 -253.112844) (xy 344.401904 -253.139178) (xy 344.438955 -253.171611)
			(xy 344.470564 -253.209369) (xy 344.495974 -253.251548) (xy 344.514577 -253.29714) (xy 344.52593 -253.345055)
			(xy 344.529761 -253.394147) (xy 344.52783 -253.419199) (xy 345.773484 -253.419199) (xy 345.773484 -253.369221)
			(xy 345.781303 -253.319858) (xy 345.796747 -253.272326) (xy 345.819437 -253.227794) (xy 345.848813 -253.187361)
			(xy 345.884153 -253.152021) (xy 345.924586 -253.122645) (xy 345.969118 -253.099955) (xy 346.01665 -253.084511)
			(xy 346.066013 -253.076692) (xy 346.115991 -253.076692) (xy 346.165354 -253.084511) (xy 346.212886 -253.099955)
			(xy 346.257418 -253.122645) (xy 346.297851 -253.152021) (xy 346.333191 -253.187361) (xy 346.362567 -253.227794)
			(xy 346.385257 -253.272326) (xy 346.400701 -253.319858) (xy 346.40852 -253.369221) (xy 346.40901 -253.39421)
			(xy 346.40852 -253.419199) (xy 347.653592 -253.419199) (xy 347.653592 -253.369221) (xy 347.661411 -253.319858)
			(xy 347.676855 -253.272326) (xy 347.699545 -253.227794) (xy 347.728921 -253.187361) (xy 347.764261 -253.152021)
			(xy 347.804694 -253.122645) (xy 347.849226 -253.099955) (xy 347.896758 -253.084511) (xy 347.946121 -253.076692)
			(xy 347.996099 -253.076692) (xy 348.045462 -253.084511) (xy 348.092994 -253.099955) (xy 348.137526 -253.122645)
			(xy 348.177959 -253.152021) (xy 348.213299 -253.187361) (xy 348.242675 -253.227794) (xy 348.265365 -253.272326)
			(xy 348.280809 -253.319858) (xy 348.288628 -253.369221) (xy 348.289118 -253.39421) (xy 348.288628 -253.419199)
			(xy 348.280809 -253.468562) (xy 348.265365 -253.516094) (xy 348.242675 -253.560626) (xy 348.213299 -253.601059)
			(xy 348.177959 -253.636399) (xy 348.137526 -253.665775) (xy 348.092994 -253.688465) (xy 348.045462 -253.703909)
			(xy 347.996099 -253.711728) (xy 347.946121 -253.711728) (xy 347.896758 -253.703909) (xy 347.849226 -253.688465)
			(xy 347.804694 -253.665775) (xy 347.764261 -253.636399) (xy 347.728921 -253.601059) (xy 347.699545 -253.560626)
			(xy 347.676855 -253.516094) (xy 347.661411 -253.468562) (xy 347.653592 -253.419199) (xy 346.40852 -253.419199)
			(xy 346.400701 -253.468562) (xy 346.385257 -253.516094) (xy 346.362567 -253.560626) (xy 346.333191 -253.601059)
			(xy 346.297851 -253.636399) (xy 346.257418 -253.665775) (xy 346.212886 -253.688465) (xy 346.165354 -253.703909)
			(xy 346.115991 -253.711728) (xy 346.066013 -253.711728) (xy 346.01665 -253.703909) (xy 345.969118 -253.688465)
			(xy 345.924586 -253.665775) (xy 345.884153 -253.636399) (xy 345.848813 -253.601059) (xy 345.819437 -253.560626)
			(xy 345.796747 -253.516094) (xy 345.781303 -253.468562) (xy 345.773484 -253.419199) (xy 344.52783 -253.419199)
			(xy 344.525977 -253.443243) (xy 344.51467 -253.491169) (xy 344.49611 -253.536779) (xy 344.470741 -253.578983)
			(xy 344.439169 -253.61677) (xy 344.402148 -253.649239) (xy 344.360565 -253.675613) (xy 344.338148 -253.685802)
			(xy 344.33764 -253.685802) (xy 344.331036 -253.68885) (xy 344.320114 -253.698248) (xy 344.316304 -253.70409)
			(xy 344.312435 -253.710418) (xy 344.308166 -253.724617) (xy 344.307922 -253.73203) (xy 344.307922 -254.229205)
			(xy 345.303584 -254.229205) (xy 345.303584 -254.179227) (xy 345.311403 -254.129864) (xy 345.326847 -254.082332)
			(xy 345.349537 -254.0378) (xy 345.378913 -253.997367) (xy 345.414253 -253.962027) (xy 345.454686 -253.932651)
			(xy 345.499218 -253.909961) (xy 345.54675 -253.894517) (xy 345.596113 -253.886698) (xy 345.646091 -253.886698)
			(xy 345.695454 -253.894517) (xy 345.742986 -253.909961) (xy 345.787518 -253.932651) (xy 345.827951 -253.962027)
			(xy 345.863291 -253.997367) (xy 345.892667 -254.0378) (xy 345.915357 -254.082332) (xy 345.930801 -254.129864)
			(xy 345.93862 -254.179227) (xy 345.93911 -254.204216) (xy 345.93862 -254.229205) (xy 345.930801 -254.278568)
			(xy 345.916996 -254.321056) (xy 347.019372 -254.321056) (xy 347.019372 -253.813564) (xy 347.019858 -253.803557)
			(xy 347.027524 -253.78507) (xy 347.041677 -253.77092) (xy 347.060165 -253.763256) (xy 347.070172 -253.762764)
			(xy 347.28404 -253.762764) (xy 347.28404 -253.75362) (xy 347.284437 -253.743595) (xy 347.292108 -253.725071)
			(xy 347.306288 -253.710897) (xy 347.324815 -253.703233) (xy 347.33484 -253.70282) (xy 347.539056 -253.70282)
			(xy 347.5601 -253.703364) (xy 347.601374 -253.711597) (xy 347.640236 -253.727754) (xy 347.675182 -253.751209)
			(xy 347.704858 -253.781053) (xy 347.728114 -253.816131) (xy 347.744051 -253.855084) (xy 347.752052 -253.896404)
			(xy 347.752416 -253.91745) (xy 347.752416 -253.917704) (xy 347.752416 -253.992634) (xy 347.752767 -254.000289)
			(xy 347.757427 -254.014882) (xy 347.76156 -254.021336) (xy 347.76156 -254.02159) (xy 347.775165 -254.041764)
			(xy 347.796705 -254.085395) (xy 347.811349 -254.131796) (xy 347.818757 -254.179887) (xy 347.819218 -254.204216)
			(xy 347.818732 -254.229205) (xy 347.810912 -254.278568) (xy 347.795466 -254.326099) (xy 347.772775 -254.37063)
			(xy 347.743398 -254.411063) (xy 347.708058 -254.446402) (xy 347.667625 -254.475779) (xy 347.623094 -254.498469)
			(xy 347.575562 -254.513913) (xy 347.526199 -254.521733) (xy 347.50121 -254.522224) (xy 347.476369 -254.521767)
			(xy 347.42729 -254.514048) (xy 347.380007 -254.498796) (xy 347.335669 -254.476382) (xy 347.295352 -254.44735)
			(xy 347.260037 -254.412405) (xy 347.244924 -254.392684) (xy 347.237339 -254.383391) (xy 347.216005 -254.372509)
			(xy 347.20403 -254.371856) (xy 347.070172 -254.371856) (xy 347.060143 -254.371503) (xy 347.041617 -254.363815)
			(xy 347.027444 -254.349622) (xy 347.019783 -254.331085) (xy 347.019372 -254.321056) (xy 345.916996 -254.321056)
			(xy 345.915357 -254.3261) (xy 345.892667 -254.370632) (xy 345.863291 -254.411065) (xy 345.827951 -254.446405)
			(xy 345.787518 -254.475781) (xy 345.742986 -254.498471) (xy 345.695454 -254.513915) (xy 345.646091 -254.521734)
			(xy 345.596113 -254.521734) (xy 345.54675 -254.513915) (xy 345.499218 -254.498471) (xy 345.454686 -254.475781)
			(xy 345.414253 -254.446405) (xy 345.378913 -254.411065) (xy 345.349537 -254.370632) (xy 345.326847 -254.3261)
			(xy 345.311403 -254.278568) (xy 345.303584 -254.229205) (xy 344.307922 -254.229205) (xy 344.307922 -254.676402)
			(xy 344.308178 -254.683813) (xy 344.312444 -254.698009) (xy 344.316304 -254.704342) (xy 344.320114 -254.710184)
			(xy 344.331036 -254.719582) (xy 344.337894 -254.72263) (xy 344.360295 -254.732856) (xy 344.401901 -254.759189)
			(xy 344.438951 -254.791622) (xy 344.470558 -254.829379) (xy 344.495966 -254.871557) (xy 344.514568 -254.917148)
			(xy 344.52592 -254.965061) (xy 344.52975 -255.014152) (xy 344.529725 -255.014476) (xy 345.772994 -255.014476)
			(xy 345.772994 -255.014222) (xy 345.773373 -254.993036) (xy 345.779026 -254.951042) (xy 345.790207 -254.910172)
			(xy 345.79814 -254.890524) (xy 345.802204 -254.880872) (xy 345.802204 -254.806704) (xy 345.80195 -254.80645)
			(xy 345.802288 -254.7854) (xy 345.810289 -254.744073) (xy 345.826227 -254.705112) (xy 345.849486 -254.670027)
			(xy 345.879165 -254.640175) (xy 345.914115 -254.616712) (xy 345.952982 -254.600548) (xy 345.994263 -254.592307)
			(xy 346.01531 -254.59182) (xy 346.270072 -254.59182) (xy 346.270072 -254.600964) (xy 346.270548 -254.61098)
			(xy 346.278201 -254.62949) (xy 346.292356 -254.643663) (xy 346.310857 -254.651339) (xy 346.320872 -254.651764)
			(xy 346.484448 -254.651764) (xy 346.494454 -254.652248) (xy 346.51294 -254.659917) (xy 346.52709 -254.67407)
			(xy 346.534754 -254.692558) (xy 346.535248 -254.702564) (xy 346.535248 -255.039211) (xy 347.653592 -255.039211)
			(xy 347.653592 -254.989233) (xy 347.661411 -254.93987) (xy 347.676855 -254.892338) (xy 347.699545 -254.847806)
			(xy 347.728921 -254.807373) (xy 347.764261 -254.772033) (xy 347.804694 -254.742657) (xy 347.849226 -254.719967)
			(xy 347.896758 -254.704523) (xy 347.946121 -254.696704) (xy 347.996099 -254.696704) (xy 348.045462 -254.704523)
			(xy 348.092994 -254.719967) (xy 348.137526 -254.742657) (xy 348.177959 -254.772033) (xy 348.213299 -254.807373)
			(xy 348.242675 -254.847806) (xy 348.265365 -254.892338) (xy 348.280809 -254.93987) (xy 348.288628 -254.989233)
			(xy 348.289118 -255.014222) (xy 348.288628 -255.039211) (xy 348.280809 -255.088574) (xy 348.265365 -255.136106)
			(xy 348.242675 -255.180638) (xy 348.213299 -255.221071) (xy 348.177959 -255.256411) (xy 348.137526 -255.285787)
			(xy 348.092994 -255.308477) (xy 348.045462 -255.323921) (xy 347.996099 -255.33174) (xy 347.946121 -255.33174)
			(xy 347.896758 -255.323921) (xy 347.849226 -255.308477) (xy 347.804694 -255.285787) (xy 347.764261 -255.256411)
			(xy 347.728921 -255.221071) (xy 347.699545 -255.180638) (xy 347.676855 -255.136106) (xy 347.661411 -255.088574)
			(xy 347.653592 -255.039211) (xy 346.535248 -255.039211) (xy 346.535248 -255.210056) (xy 346.534677 -255.220055)
			(xy 346.527041 -255.238536) (xy 346.512914 -255.252689) (xy 346.494446 -255.260359) (xy 346.484448 -255.260856)
			(xy 346.308934 -255.260856) (xy 346.300915 -255.261156) (xy 346.28565 -255.266073) (xy 346.278962 -255.270508)
			(xy 346.270072 -255.276858) (xy 346.270072 -255.291082) (xy 346.240354 -255.3208) (xy 346.17533 -255.3208)
			(xy 346.169234 -255.322578) (xy 346.149996 -255.327115) (xy 346.110766 -255.33196) (xy 346.091002 -255.33223)
			(xy 346.070777 -255.331933) (xy 346.03065 -255.326837) (xy 346.010992 -255.32207) (xy 346.00134 -255.320546)
			(xy 345.979524 -255.318645) (xy 345.937328 -255.306947) (xy 345.898403 -255.286892) (xy 345.864384 -255.259322)
			(xy 345.836701 -255.225396) (xy 345.816515 -255.186539) (xy 345.810078 -255.165606) (xy 345.806522 -255.156716)
			(xy 345.795946 -255.134513) (xy 345.781016 -255.087657) (xy 345.773455 -255.039065) (xy 345.772994 -255.014476)
			(xy 344.529725 -255.014476) (xy 344.525966 -255.063246) (xy 344.514658 -255.111171) (xy 344.496098 -255.156779)
			(xy 344.470729 -255.19898) (xy 344.439157 -255.236766) (xy 344.402138 -255.269234) (xy 344.360556 -255.295606)
			(xy 344.338148 -255.305814) (xy 344.33764 -255.305814) (xy 344.331036 -255.308862) (xy 344.320114 -255.31826)
			(xy 344.316304 -255.324102) (xy 344.312436 -255.330431) (xy 344.308171 -255.344629) (xy 344.307922 -255.352042)
			(xy 344.307922 -255.911604) (xy 344.308444 -255.921352) (xy 344.315898 -255.939374) (xy 344.3224 -255.946656)
			(xy 344.420444 -256.0447) (xy 344.427693 -256.051253) (xy 344.445736 -256.058706) (xy 344.455496 -256.059178)
		)
		(stroke
			(width 0)
			(type solid)
		)
		(fill yes)
		(layer "B.Cu")
		(net "PVDD18_S5_P0")
	)
	(gr_poly
		(pts
			(xy 403.836632 -318.512444) (xy 403.846509 -318.511983) (xy 403.864808 -318.504541) (xy 403.872192 -318.497966)
			(xy 403.872446 -318.497712) (xy 404.125938 -318.24422) (xy 404.126446 -318.243712) (xy 404.133023 -318.236329)
			(xy 404.140462 -318.21803) (xy 404.140924 -318.208152) (xy 404.140924 -314.697364) (xy 404.133304 -314.678568)
			(xy 404.125938 -314.671456) (xy 398.431512 -308.97703) (xy 398.4244 -308.969664) (xy 398.405604 -308.962044)
			(xy 395.28369 -308.962044) (xy 395.273622 -308.961618) (xy 395.255025 -308.953894) (xy 395.247622 -308.947058)
			(xy 394.897102 -308.596538) (xy 394.88999 -308.589172) (xy 394.871194 -308.581552) (xy 389.164068 -308.581552)
			(xy 389.154001 -308.581122) (xy 389.13541 -308.573394) (xy 389.128 -308.566566) (xy 388.604252 -308.042818)
			(xy 388.599934 -308.039008) (xy 388.591298 -308.031896) (xy 388.587996 -308.030118) (xy 388.514126 -307.98682)
			(xy 388.369965 -307.89439) (xy 388.230169 -307.795484) (xy 388.095027 -307.690307) (xy 387.964821 -307.579078)
			(xy 387.839822 -307.462029) (xy 387.720289 -307.339402) (xy 387.606471 -307.211452) (xy 387.498605 -307.078447)
			(xy 387.396916 -306.940662) (xy 387.301614 -306.798384) (xy 387.212898 -306.651909) (xy 387.130952 -306.501542)
			(xy 387.055947 -306.347595) (xy 386.988039 -306.190388) (xy 386.927369 -306.030249) (xy 386.874063 -305.86751)
			(xy 386.828232 -305.70251) (xy 386.789972 -305.535592) (xy 386.759361 -305.367103) (xy 386.736464 -305.197394)
			(xy 386.721329 -305.026818) (xy 386.713986 -304.855729) (xy 386.714451 -304.684482) (xy 386.722723 -304.513436)
			(xy 386.738785 -304.342944) (xy 386.762603 -304.173361) (xy 386.794128 -304.005041) (xy 386.833294 -303.838334)
			(xy 386.880021 -303.673585) (xy 386.93421 -303.511138) (xy 386.995749 -303.351331) (xy 387.06451 -303.194495)
			(xy 387.140349 -303.040958) (xy 387.223111 -302.891038) (xy 387.312621 -302.745047) (xy 387.408694 -302.603289)
			(xy 387.511131 -302.466058) (xy 387.619717 -302.33364) (xy 387.734228 -302.206311) (xy 387.854425 -302.084335)
			(xy 387.916928 -302.025812) (xy 387.91769 -302.02505) (xy 387.920484 -302.022256) (xy 387.920738 -302.022002)
			(xy 387.927315 -302.014619) (xy 387.934751 -301.99632) (xy 387.935216 -301.986442) (xy 387.935216 -301.027338)
			(xy 387.927596 -301.008542) (xy 387.92023 -301.00143) (xy 384.013456 -297.094656) (xy 384.00661 -297.087258)
			(xy 383.998883 -297.068659) (xy 383.99847 -297.058588) (xy 383.99847 -295.970452) (xy 383.998037 -295.960386)
			(xy 383.990307 -295.941797) (xy 383.983484 -295.934384) (xy 383.786126 -295.737026) (xy 383.778725 -295.730188)
			(xy 383.760126 -295.722477) (xy 383.750058 -295.72204) (xy 381.801878 -295.72204) (xy 381.79181 -295.722468)
			(xy 381.773216 -295.730193) (xy 381.76581 -295.737026) (xy 381.758698 -295.744138) (xy 381.752856 -295.749726)
			(xy 381.708152 -295.79443) (xy 381.707898 -295.79443) (xy 381.68326 -295.819068) (xy 381.675914 -295.825876)
			(xy 381.657451 -295.833599) (xy 381.647446 -295.834054) (xy 381.550672 -295.834054) (xy 381.549656 -295.834054)
			(xy 381.54102 -295.834308) (xy 380.80188 -295.834308) (xy 380.793244 -295.834054) (xy 380.792228 -295.834054)
			(xy 380.695454 -295.834054) (xy 380.685463 -295.833525) (xy 380.667021 -295.82582) (xy 380.65964 -295.819068)
			(xy 380.635002 -295.79443) (xy 380.634748 -295.79443) (xy 380.593854 -295.753536) (xy 380.592838 -295.752266)
			(xy 380.590044 -295.749726) (xy 380.584202 -295.744138) (xy 380.57709 -295.737026) (xy 380.569692 -295.730178)
			(xy 380.551094 -295.722443) (xy 380.541022 -295.72204) (xy 377.901454 -295.72204) (xy 377.891463 -295.722569)
			(xy 377.873021 -295.730273) (xy 377.86564 -295.737026) (xy 377.668028 -295.934384) (xy 377.661245 -295.941806)
			(xy 377.653641 -295.960404) (xy 377.653296 -295.970452) (xy 377.653296 -296.51706) (xy 378.919232 -296.51706)
			(xy 378.919748 -296.48946) (xy 378.927975 -296.434877) (xy 378.944245 -296.38213) (xy 378.968195 -296.332398)
			(xy 378.99929 -296.28679) (xy 379.036835 -296.246326) (xy 379.079992 -296.211909) (xy 379.127796 -296.18431)
			(xy 379.17918 -296.164143) (xy 379.232995 -296.15186) (xy 379.28804 -296.147735) (xy 379.343085 -296.15186)
			(xy 379.3969 -296.164143) (xy 379.448284 -296.18431) (xy 379.496088 -296.211909) (xy 379.539245 -296.246326)
			(xy 379.57679 -296.28679) (xy 379.607885 -296.332398) (xy 379.631835 -296.38213) (xy 379.648105 -296.434877)
			(xy 379.656332 -296.48946) (xy 379.656848 -296.51706) (xy 379.656424 -296.54224) (xy 379.64957 -296.592132)
			(xy 379.635996 -296.640629) (xy 379.615956 -296.68683) (xy 379.603254 -296.708576) (xy 379.599874 -296.714654)
			(xy 379.596132 -296.728042) (xy 379.595888 -296.734992) (xy 379.595888 -297.34256) (xy 379.59632 -297.352351)
			(xy 379.603633 -297.370513) (xy 379.610112 -297.377866) (xy 379.610874 -297.378628) (xy 379.79858 -297.56608)
			(xy 379.80874 -297.5757) (xy 379.833161 -297.589345) (xy 379.860368 -297.595852) (xy 379.88832 -297.594734)
			(xy 379.91492 -297.586074) (xy 379.938173 -297.570522) (xy 379.956334 -297.549245) (xy 379.968041 -297.523838)
			(xy 379.972417 -297.496209) (xy 379.969131 -297.468428) (xy 379.964188 -297.455336) (xy 379.943614 -297.405806)
			(xy 379.932616 -297.377591) (xy 379.920707 -297.318224) (xy 379.919992 -297.28795) (xy 379.919992 -296.734992)
			(xy 379.919793 -296.728034) (xy 379.916058 -296.714631) (xy 379.912626 -296.708576) (xy 379.899918 -296.686833)
			(xy 379.879875 -296.640632) (xy 379.866304 -296.592134) (xy 379.859458 -296.542241) (xy 379.859032 -296.51706)
			(xy 379.859548 -296.48946) (xy 379.867775 -296.434877) (xy 379.884045 -296.38213) (xy 379.907995 -296.332398)
			(xy 379.93909 -296.28679) (xy 379.976635 -296.246326) (xy 380.019792 -296.211909) (xy 380.067596 -296.18431)
			(xy 380.11898 -296.164143) (xy 380.172795 -296.15186) (xy 380.22784 -296.147735) (xy 380.282885 -296.15186)
			(xy 380.3367 -296.164143) (xy 380.388084 -296.18431) (xy 380.435888 -296.211909) (xy 380.479045 -296.246326)
			(xy 380.51659 -296.28679) (xy 380.547685 -296.332398) (xy 380.571635 -296.38213) (xy 380.587905 -296.434877)
			(xy 380.596132 -296.48946) (xy 380.596648 -296.51706) (xy 380.596224 -296.54224) (xy 380.58937 -296.592132)
			(xy 380.575796 -296.640629) (xy 380.555756 -296.68683) (xy 380.543054 -296.708576) (xy 380.539674 -296.714654)
			(xy 380.535932 -296.728042) (xy 380.535688 -296.734992) (xy 380.535688 -297.21683) (xy 380.535688 -297.22699)
			(xy 382.358646 -301.627286) (xy 382.364469 -301.640009) (xy 382.381767 -301.661981) (xy 382.404382 -301.67843)
			(xy 382.430615 -301.688118) (xy 382.458493 -301.690317) (xy 382.485921 -301.684863) (xy 382.510836 -301.672164)
			(xy 382.531365 -301.653176) (xy 382.545966 -301.629326) (xy 382.553541 -301.602407) (xy 382.553972 -301.588424)
			(xy 382.553972 -299.772578) (xy 382.553972 -299.762418) (xy 381.823722 -297.998896) (xy 381.812721 -297.970681)
			(xy 381.800814 -297.911315) (xy 381.8001 -297.88104) (xy 381.8001 -296.734992) (xy 381.799913 -296.728033)
			(xy 381.796171 -296.71463) (xy 381.792734 -296.708576) (xy 381.780027 -296.686833) (xy 381.759983 -296.640632)
			(xy 381.746412 -296.592134) (xy 381.739566 -296.542241) (xy 381.73914 -296.51706) (xy 381.739656 -296.48946)
			(xy 381.747883 -296.434877) (xy 381.764153 -296.38213) (xy 381.788103 -296.332398) (xy 381.819198 -296.28679)
			(xy 381.856743 -296.246326) (xy 381.8999 -296.211909) (xy 381.947704 -296.18431) (xy 381.999088 -296.164143)
			(xy 382.052903 -296.15186) (xy 382.107948 -296.147735) (xy 382.162993 -296.15186) (xy 382.216808 -296.164143)
			(xy 382.268192 -296.18431) (xy 382.315996 -296.211909) (xy 382.359153 -296.246326) (xy 382.396698 -296.28679)
			(xy 382.427793 -296.332398) (xy 382.451743 -296.38213) (xy 382.468013 -296.434877) (xy 382.47624 -296.48946)
			(xy 382.476756 -296.51706) (xy 382.476331 -296.54224) (xy 382.469477 -296.592132) (xy 382.455904 -296.640629)
			(xy 382.435864 -296.68683) (xy 382.423162 -296.708576) (xy 382.419783 -296.714655) (xy 382.41604 -296.728042)
			(xy 382.415796 -296.734992) (xy 382.415796 -297.80992) (xy 382.415796 -297.82008) (xy 383.146046 -299.583602)
			(xy 383.153843 -299.603327) (xy 383.164545 -299.64437) (xy 383.167382 -299.66539) (xy 383.168652 -299.676058)
			(xy 383.178812 -299.693838) (xy 383.187448 -299.700188) (xy 383.195226 -299.705481) (xy 383.213322 -299.710563)
			(xy 383.232035 -299.708781) (xy 383.248847 -299.700374) (xy 383.261499 -299.686473) (xy 383.26829 -299.668946)
			(xy 383.268728 -299.659548) (xy 383.268728 -299.451776) (xy 383.268728 -299.441616) (xy 382.763776 -298.22267)
			(xy 382.752925 -298.194552) (xy 382.741161 -298.135452) (xy 382.740408 -298.105322) (xy 382.740408 -296.742358)
			(xy 382.736344 -296.728388) (xy 382.732788 -296.723054) (xy 382.732788 -296.70883) (xy 382.726184 -296.697146)
			(xy 382.711389 -296.669463) (xy 382.690435 -296.610301) (xy 382.679817 -296.548442) (xy 382.679194 -296.51706)
			(xy 382.679625 -296.490715) (xy 382.687129 -296.438562) (xy 382.701978 -296.388007) (xy 382.72387 -296.34008)
			(xy 382.75236 -296.295756) (xy 382.786867 -296.255937) (xy 382.826689 -296.221434) (xy 382.871017 -296.19295)
			(xy 382.918946 -296.171063) (xy 382.969503 -296.15622) (xy 383.021657 -296.148722) (xy 383.048002 -296.148252)
			(xy 383.074344 -296.14876) (xy 383.126493 -296.156257) (xy 383.177043 -296.1711) (xy 383.224968 -296.192984)
			(xy 383.26929 -296.221466) (xy 383.309108 -296.255965) (xy 383.343611 -296.29578) (xy 383.372097 -296.340099)
			(xy 383.393987 -296.388021) (xy 383.408834 -296.43857) (xy 383.416337 -296.490718) (xy 383.41681 -296.51706)
			(xy 383.416124 -296.548435) (xy 383.405476 -296.610276) (xy 383.384547 -296.669434) (xy 383.36982 -296.697146)
			(xy 383.362454 -296.709846) (xy 383.359285 -296.715714) (xy 383.355798 -296.728581) (xy 383.355596 -296.735246)
			(xy 383.355596 -298.033186) (xy 383.355596 -298.043346) (xy 383.860802 -299.2628) (xy 383.871803 -299.291015)
			(xy 383.88371 -299.350381) (xy 383.884424 -299.380656) (xy 383.884424 -301.051214) (xy 386.821932 -301.051214)
			(xy 386.826003 -300.995592) (xy 386.838129 -300.941155) (xy 386.858052 -300.889064) (xy 386.885348 -300.840429)
			(xy 386.919434 -300.796286) (xy 386.959583 -300.757577) (xy 387.004941 -300.725126) (xy 387.054541 -300.699625)
			(xy 387.107325 -300.681618) (xy 387.162168 -300.671488) (xy 387.217902 -300.669451) (xy 387.273339 -300.675551)
			(xy 387.327296 -300.689657) (xy 387.378625 -300.711469) (xy 387.426231 -300.740523) (xy 387.469099 -300.776198)
			(xy 387.506316 -300.817735) (xy 387.537089 -300.864248) (xy 387.560761 -300.914745) (xy 387.576829 -300.968152)
			(xy 387.584949 -301.023328) (xy 387.585458 -301.051214) (xy 387.584949 -301.0791) (xy 387.576829 -301.134276)
			(xy 387.560761 -301.187683) (xy 387.537089 -301.23818) (xy 387.506316 -301.284693) (xy 387.469099 -301.32623)
			(xy 387.426231 -301.361905) (xy 387.378625 -301.390959) (xy 387.327296 -301.412771) (xy 387.273339 -301.426877)
			(xy 387.217902 -301.432977) (xy 387.162168 -301.43094) (xy 387.107325 -301.42081) (xy 387.054541 -301.402803)
			(xy 387.004941 -301.377302) (xy 386.959583 -301.344851) (xy 386.919434 -301.306142) (xy 386.885348 -301.261999)
			(xy 386.858052 -301.213364) (xy 386.838129 -301.161273) (xy 386.826003 -301.106836) (xy 386.821932 -301.051214)
			(xy 383.884424 -301.051214) (xy 383.884424 -302.190912) (xy 383.884424 -302.201072) (xy 383.918094 -302.282352)
			(xy 386.0071 -302.282352) (xy 386.011171 -302.22673) (xy 386.023297 -302.172293) (xy 386.04322 -302.120202)
			(xy 386.070516 -302.071567) (xy 386.104602 -302.027424) (xy 386.144751 -301.988715) (xy 386.190109 -301.956264)
			(xy 386.239709 -301.930763) (xy 386.292493 -301.912756) (xy 386.347336 -301.902626) (xy 386.40307 -301.900589)
			(xy 386.458507 -301.906689) (xy 386.512464 -301.920795) (xy 386.563793 -301.942607) (xy 386.611399 -301.971661)
			(xy 386.654267 -302.007336) (xy 386.691484 -302.048873) (xy 386.722257 -302.095386) (xy 386.745929 -302.145883)
			(xy 386.761997 -302.19929) (xy 386.770117 -302.254466) (xy 386.770626 -302.282352) (xy 386.770117 -302.310238)
			(xy 386.761997 -302.365414) (xy 386.745929 -302.418821) (xy 386.722257 -302.469318) (xy 386.691484 -302.515831)
			(xy 386.654267 -302.557368) (xy 386.611399 -302.593043) (xy 386.563793 -302.622097) (xy 386.512464 -302.643909)
			(xy 386.458507 -302.658015) (xy 386.40307 -302.664115) (xy 386.347336 -302.662078) (xy 386.292493 -302.651948)
			(xy 386.239709 -302.633941) (xy 386.190109 -302.60844) (xy 386.144751 -302.575989) (xy 386.104602 -302.53728)
			(xy 386.070516 -302.493137) (xy 386.04322 -302.444502) (xy 386.023297 -302.392411) (xy 386.011171 -302.337974)
			(xy 386.0071 -302.282352) (xy 383.918094 -302.282352) (xy 386.082032 -307.506116) (xy 386.084084 -307.510701)
			(xy 386.089713 -307.519018) (xy 386.093208 -307.522626) (xy 388.396226 -309.825644) (xy 388.39648 -309.825898)
			(xy 388.403881 -309.832451) (xy 388.422167 -309.839908) (xy 388.43204 -309.840376) (xy 392.301222 -309.840376)
			(xy 392.311106 -309.839963) (xy 392.329405 -309.832492) (xy 392.336782 -309.825898) (xy 392.33729 -309.82539)
			(xy 392.680952 -309.481474) (xy 392.698369 -309.464677) (xy 392.737514 -309.436235) (xy 392.780627 -309.414268)
			(xy 392.826646 -309.399318) (xy 392.874437 -309.391752) (xy 392.89863 -309.391304) (xy 397.8656 -309.391304)
			(xy 397.88979 -309.391797) (xy 397.937574 -309.399364) (xy 397.983586 -309.414312) (xy 398.026694 -309.436273)
			(xy 398.065836 -309.464707) (xy 398.083278 -309.481474) (xy 401.356576 -312.754772) (xy 401.373282 -312.772188)
			(xy 401.40161 -312.811256) (xy 401.4235 -312.854262) (xy 401.438416 -312.900156) (xy 401.445996 -312.947814)
			(xy 401.446492 -312.971942) (xy 401.446492 -313.445906) (xy 401.446817 -313.45535) (xy 401.45361 -313.47297)
			(xy 401.4597 -313.480196) (xy 401.473425 -313.496037) (xy 401.495341 -313.53176) (xy 401.510298 -313.570911)
			(xy 401.517783 -313.612147) (xy 401.51812 -313.633104) (xy 401.51812 -313.682888) (xy 401.518552 -313.69277)
			(xy 401.52601 -313.711069) (xy 401.532598 -313.718448) (xy 401.533106 -313.718956) (xy 402.35759 -314.543186)
			(xy 402.367251 -314.553204) (xy 402.384932 -314.574699) (xy 402.392896 -314.586112) (xy 402.396452 -314.591446)
			(xy 402.406104 -314.599828) (xy 402.411946 -314.602876) (xy 402.417368 -314.605474) (xy 402.42905 -314.608298)
			(xy 402.43506 -314.608464) (xy 402.491448 -314.608464) (xy 402.501454 -314.608948) (xy 402.51994 -314.616617)
			(xy 402.53409 -314.63077) (xy 402.541754 -314.649258) (xy 402.542248 -314.659264) (xy 402.542248 -315.192664)
			(xy 402.541787 -315.202542) (xy 402.534347 -315.220841) (xy 402.52777 -315.228224) (xy 402.512784 -315.243464)
			(xy 402.498306 -315.243464) (xy 402.488365 -315.243992) (xy 402.470015 -315.251655) (xy 402.455953 -315.265718)
			(xy 402.448291 -315.284069) (xy 402.44776 -315.29401) (xy 402.44776 -315.462158) (xy 402.448222 -315.472036)
			(xy 402.455661 -315.490335) (xy 402.462238 -315.497718) (xy 402.462746 -315.498226) (xy 402.84146 -315.87694)
			(xy 402.845524 -315.879734) (xy 402.851974 -315.883847) (xy 402.866581 -315.888368) (xy 402.874226 -315.888624)
			(xy 403.408896 -315.888624) (xy 403.425592 -315.889138) (xy 403.45785 -315.897771) (xy 403.486779 -315.91445)
			(xy 403.510412 -315.938041) (xy 403.527142 -315.96694) (xy 403.535832 -315.999183) (xy 403.536404 -316.015878)
			(xy 403.536404 -317.819278) (xy 403.535794 -317.835934) (xy 403.52719 -317.868114) (xy 403.510561 -317.896977)
			(xy 403.487037 -317.920562) (xy 403.458216 -317.937265) (xy 403.426058 -317.945951) (xy 403.409404 -317.946532)
			(xy 402.392388 -317.946532) (xy 402.377155 -317.946047) (xy 402.347568 -317.93878) (xy 402.320544 -317.924711)
			(xy 402.297623 -317.904639) (xy 402.288502 -317.89243) (xy 402.280872 -317.882816) (xy 402.259101 -317.871553)
			(xy 402.246846 -317.87084) (xy 401.055078 -317.87084) (xy 401.042819 -317.871552) (xy 401.021049 -317.88281)
			(xy 401.013422 -317.89243) (xy 401.004325 -317.904658) (xy 400.981393 -317.924724) (xy 400.954363 -317.938791)
			(xy 400.924771 -317.94606) (xy 400.909536 -317.946532) (xy 399.893028 -317.946532) (xy 399.876337 -317.945941)
			(xy 399.844089 -317.937319) (xy 399.815165 -317.920654) (xy 399.791533 -317.897078) (xy 399.774798 -317.868195)
			(xy 399.766099 -317.835967) (xy 399.76552 -317.819278) (xy 399.76552 -316.015878) (xy 399.766068 -315.999219)
			(xy 399.774684 -315.967033) (xy 399.791326 -315.938168) (xy 399.814862 -315.914584) (xy 399.843694 -315.897884)
			(xy 399.875862 -315.889202) (xy 399.89252 -315.888624) (xy 400.427698 -315.888624) (xy 400.43777 -315.888218)
			(xy 400.456369 -315.880486) (xy 400.463766 -315.873638) (xy 400.844004 -315.493146) (xy 400.850608 -315.46546)
			(xy 400.846036 -315.451744) (xy 400.8389 -315.428517) (xy 400.831249 -315.380535) (xy 400.830796 -315.35624)
			(xy 400.830796 -315.289692) (xy 400.830357 -315.278929) (xy 400.821633 -315.259255) (xy 400.805599 -315.2449)
			(xy 400.79549 -315.241178) (xy 400.795236 -315.241178) (xy 400.785112 -315.237442) (xy 400.76901 -315.223107)
			(xy 400.760173 -315.203443) (xy 400.759676 -315.192664) (xy 400.759676 -314.636912) (xy 400.759245 -314.62703)
			(xy 400.751786 -314.608731) (xy 400.745198 -314.601352) (xy 400.74469 -314.600844) (xy 400.318986 -314.17514)
			(xy 400.318732 -314.174886) (xy 400.311329 -314.168336) (xy 400.293045 -314.160878) (xy 400.283172 -314.160408)
			(xy 400.231864 -314.160408) (xy 400.209571 -314.15988) (xy 400.16585 -314.151146) (xy 400.124683 -314.134023)
			(xy 400.087665 -314.109174) (xy 400.056226 -314.07756) (xy 400.031583 -314.040404) (xy 400.01469 -313.999143)
			(xy 400.006199 -313.955373) (xy 400.005804 -313.933078) (xy 400.005804 -313.633104) (xy 400.006217 -313.61029)
			(xy 400.015102 -313.565541) (xy 400.032773 -313.52348) (xy 400.045174 -313.504326) (xy 400.049746 -313.497722)
			(xy 400.054064 -313.483498) (xy 400.054064 -313.1439) (xy 400.053617 -313.134021) (xy 400.046167 -313.115722)
			(xy 400.039586 -313.10834) (xy 400.039078 -313.107832) (xy 397.920718 -310.989472) (xy 397.920464 -310.989218)
			(xy 397.913091 -310.982629) (xy 397.894783 -310.975196) (xy 397.884904 -310.97474) (xy 397.301212 -310.97474)
			(xy 397.286237 -310.975391) (xy 397.25759 -310.984132) (xy 397.232709 -311.000807) (xy 397.213735 -311.023982)
			(xy 397.2023 -311.051664) (xy 397.199385 -311.081474) (xy 397.205243 -311.110847) (xy 397.219369 -311.137258)
			(xy 397.229584 -311.148222) (xy 398.553686 -312.47207) (xy 398.570503 -312.489469) (xy 398.59894 -312.52862)
			(xy 398.620902 -312.571737) (xy 398.635848 -312.61776) (xy 398.64341 -312.665554) (xy 398.643856 -312.689748)
			(xy 398.643856 -313.177682) (xy 398.648174 -313.191906) (xy 398.652746 -313.19851) (xy 398.665153 -313.217659)
			(xy 398.682804 -313.259726) (xy 398.691679 -313.304475) (xy 398.692116 -313.327288) (xy 398.692116 -313.627262)
			(xy 398.691794 -313.649562) (xy 398.683303 -313.693342) (xy 398.666404 -313.734612) (xy 398.641752 -313.771776)
			(xy 398.610301 -313.803393) (xy 398.573269 -313.828241) (xy 398.532089 -313.845357) (xy 398.488354 -313.85408)
			(xy 398.466056 -313.854592) (xy 398.19834 -313.854592) (xy 398.19834 -313.845448) (xy 398.198008 -313.835431)
			(xy 398.190448 -313.816884) (xy 398.17632 -313.802688) (xy 398.15781 -313.795039) (xy 398.147794 -313.794648)
			(xy 397.789146 -313.794648) (xy 397.779198 -313.795127) (xy 397.760832 -313.802793) (xy 397.746766 -313.816872)
			(xy 397.739117 -313.835245) (xy 397.7386 -313.845194) (xy 397.7386 -313.998102) (xy 397.739055 -314.007645)
			(xy 397.746095 -314.025389) (xy 397.759127 -314.039339) (xy 397.776352 -314.047567) (xy 397.785844 -314.048648)
			(xy 397.795332 -314.049741) (xy 397.812548 -314.057979) (xy 397.82558 -314.071922) (xy 397.832638 -314.089654)
			(xy 397.833088 -314.099194) (xy 397.833088 -314.518548) (xy 397.833549 -314.528426) (xy 397.840988 -314.546726)
			(xy 397.847566 -314.554108) (xy 397.848074 -314.554616) (xy 398.393666 -315.100208) (xy 398.39392 -315.100462)
			(xy 398.401301 -315.107041) (xy 398.419602 -315.114481) (xy 398.42948 -315.11494) (xy 399.142204 -315.11494)
			(xy 399.15893 -315.115386) (xy 399.19124 -315.124046) (xy 399.220207 -315.140776) (xy 399.243856 -315.164434)
			(xy 399.260574 -315.193408) (xy 399.269221 -315.225722) (xy 399.269712 -315.242448) (xy 399.269712 -316.461648)
			(xy 399.269205 -316.478365) (xy 399.260542 -316.510657) (xy 399.243818 -316.539607) (xy 399.220172 -316.563245)
			(xy 399.191216 -316.579958) (xy 399.158921 -316.588611) (xy 399.142204 -316.589156) (xy 397.627602 -316.589156)
			(xy 397.60017 -316.611254) (xy 397.596106 -316.62878) (xy 397.589132 -316.656893) (xy 397.566104 -316.710035)
			(xy 397.533552 -316.757938) (xy 397.513556 -316.778894) (xy 397.16456 -317.127636) (xy 397.164306 -317.12789)
			(xy 397.157749 -317.135288) (xy 397.150294 -317.153576) (xy 397.149828 -317.16345) (xy 397.149828 -318.061848)
			(xy 397.149305 -318.078563) (xy 397.140643 -318.110853) (xy 397.123922 -318.139802) (xy 397.10028 -318.163439)
			(xy 397.071327 -318.180154) (xy 397.039036 -318.188809) (xy 397.02232 -318.189356) (xy 395.52372 -318.189356)
			(xy 395.50701 -318.188746) (xy 395.474727 -318.180102) (xy 395.445781 -318.163399) (xy 395.422143 -318.139774)
			(xy 395.405424 -318.110836) (xy 395.396763 -318.078558) (xy 395.396212 -318.061848) (xy 395.396212 -316.842648)
			(xy 395.396731 -316.825927) (xy 395.405377 -316.793623) (xy 395.422092 -316.764658) (xy 395.445736 -316.741009)
			(xy 395.474697 -316.724288) (xy 395.506999 -316.715635) (xy 395.52372 -316.71514) (xy 396.68577 -316.71514)
			(xy 396.695649 -316.714684) (xy 396.713948 -316.707241) (xy 396.72133 -316.700662) (xy 396.721838 -316.700154)
			(xy 396.9766 -316.445392) (xy 396.979394 -316.441328) (xy 396.983492 -316.43487) (xy 396.988022 -316.420269)
			(xy 396.988284 -316.412626) (xy 396.988284 -315.357764) (xy 396.987825 -315.347885) (xy 396.980386 -315.329585)
			(xy 396.973806 -315.322204) (xy 396.973298 -315.321696) (xy 396.409926 -314.758324) (xy 396.409672 -314.75807)
			(xy 396.40229 -314.751492) (xy 396.38399 -314.744051) (xy 396.374112 -314.743592) (xy 396.315184 -314.743592)
			(xy 396.315184 -314.734448) (xy 396.314808 -314.724436) (xy 396.307257 -314.705898) (xy 396.293143 -314.691703)
			(xy 396.274648 -314.684047) (xy 396.264638 -314.683648) (xy 396.101316 -314.683648) (xy 396.091315 -314.6831)
			(xy 396.072833 -314.675455) (xy 396.058681 -314.661321) (xy 396.051013 -314.642848) (xy 396.050516 -314.632848)
			(xy 396.050516 -314.22594) (xy 396.050061 -314.216061) (xy 396.042618 -314.197762) (xy 396.036038 -314.19038)
			(xy 396.03553 -314.189872) (xy 395.714982 -313.869324) (xy 395.714728 -313.86907) (xy 395.707328 -313.862516)
			(xy 395.689041 -313.855061) (xy 395.679168 -313.854592) (xy 395.62786 -313.854592) (xy 395.605566 -313.854084)
			(xy 395.561843 -313.845348) (xy 395.520675 -313.828223) (xy 395.483655 -313.803372) (xy 395.452216 -313.771754)
			(xy 395.427574 -313.734595) (xy 395.410682 -313.693331) (xy 395.402194 -313.649558) (xy 395.4018 -313.627262)
			(xy 395.4018 -313.327288) (xy 395.402253 -313.304476) (xy 395.411121 -313.259729) (xy 395.428776 -313.217666)
			(xy 395.44117 -313.19851) (xy 395.445742 -313.191906) (xy 395.45006 -313.177682) (xy 395.45006 -312.838084)
			(xy 395.449622 -312.828204) (xy 395.442166 -312.809905) (xy 395.435582 -312.802524) (xy 395.435074 -312.802016)
			(xy 395.36497 -312.731912) (xy 395.364716 -312.731658) (xy 395.357321 -312.725097) (xy 395.339031 -312.717646)
			(xy 395.329156 -312.71718) (xy 394.175742 -312.71718) (xy 394.160789 -312.717705) (xy 394.132159 -312.726351)
			(xy 394.107259 -312.742915) (xy 394.088221 -312.765979) (xy 394.076675 -312.793567) (xy 394.073611 -312.823316)
			(xy 394.07929 -312.852678) (xy 394.093226 -312.879138) (xy 394.103352 -312.890154) (xy 394.123808 -312.911683)
			(xy 394.158427 -312.959936) (xy 394.185148 -313.012971) (xy 394.203325 -313.069507) (xy 394.212519 -313.128177)
			(xy 394.21308 -313.15787) (xy 394.212571 -313.185139) (xy 394.204813 -313.239124) (xy 394.189452 -313.291454)
			(xy 394.166799 -313.341066) (xy 394.137316 -313.386949) (xy 394.101603 -313.428169) (xy 394.060388 -313.463887)
			(xy 394.014509 -313.493376) (xy 393.9649 -313.516035) (xy 393.912571 -313.531403) (xy 393.858587 -313.539167)
			(xy 393.831318 -313.539632) (xy 393.818517 -313.53955) (xy 393.792969 -313.537899) (xy 393.780264 -313.53633)
			(xy 393.766069 -313.534859) (xy 393.737844 -313.538997) (xy 393.71187 -313.550795) (xy 393.690182 -313.569327)
			(xy 393.674478 -313.593143) (xy 393.665989 -313.620378) (xy 393.665202 -313.634628) (xy 393.664225 -313.661517)
			(xy 393.655514 -313.714614) (xy 393.639437 -313.765964) (xy 393.616312 -313.814549) (xy 393.586598 -313.859407)
			(xy 393.550882 -313.899652) (xy 393.509872 -313.934486) (xy 393.464379 -313.963219) (xy 393.415304 -313.985284)
			(xy 393.363618 -314.000243) (xy 393.310344 -314.0078) (xy 393.28344 -314.008262) (xy 393.256167 -314.007801)
			(xy 393.202176 -314.000044) (xy 393.149838 -313.984681) (xy 393.10022 -313.962026) (xy 393.054332 -313.932539)
			(xy 393.013107 -313.896822) (xy 392.977385 -313.8556) (xy 392.947894 -313.809715) (xy 392.925233 -313.760099)
			(xy 392.909865 -313.707763) (xy 392.902102 -313.653773) (xy 392.902102 -313.599227) (xy 392.909865 -313.545237)
			(xy 392.925233 -313.492901) (xy 392.947894 -313.443285) (xy 392.977385 -313.3974) (xy 393.013107 -313.356178)
			(xy 393.054332 -313.320461) (xy 393.10022 -313.290974) (xy 393.149838 -313.268319) (xy 393.202176 -313.252956)
			(xy 393.256167 -313.245199) (xy 393.28344 -313.244738) (xy 393.296241 -313.244814) (xy 393.321789 -313.246469)
			(xy 393.334494 -313.24804) (xy 393.348691 -313.249498) (xy 393.376918 -313.245369) (xy 393.402895 -313.233577)
			(xy 393.424584 -313.215046) (xy 393.440287 -313.191229) (xy 393.448772 -313.163992) (xy 393.449556 -313.149742)
			(xy 393.450732 -313.120881) (xy 393.460679 -313.063985) (xy 393.479083 -313.009237) (xy 393.505523 -312.957884)
			(xy 393.539395 -312.9111) (xy 393.559284 -312.890154) (xy 393.56939 -312.879124) (xy 393.583319 -312.852666)
			(xy 393.588994 -312.82331) (xy 393.58593 -312.793567) (xy 393.574388 -312.765984) (xy 393.555356 -312.742923)
			(xy 393.530465 -312.726357) (xy 393.501844 -312.717705) (xy 393.486894 -312.71718) (xy 387.660388 -312.71718)
			(xy 387.636198 -312.716699) (xy 387.588413 -312.70913) (xy 387.5424 -312.694179) (xy 387.499293 -312.672215)
			(xy 387.460151 -312.643779) (xy 387.44271 -312.62701) (xy 383.795778 -308.980078) (xy 383.774969 -308.958165)
			(xy 383.741454 -308.907892) (xy 383.72923 -308.880256) (xy 382.710944 -306.422298) (xy 382.700099 -306.394178)
			(xy 382.688332 -306.335079) (xy 382.687576 -306.30495) (xy 382.687576 -305.607212) (xy 382.687576 -305.597052)
			(xy 379.671072 -298.314364) (xy 379.669023 -298.309778) (xy 379.663392 -298.301461) (xy 379.659896 -298.297854)
			(xy 379.070362 -297.708574) (xy 379.053575 -297.691147) (xy 379.025132 -297.652005) (xy 379.003164 -297.608894)
			(xy 378.988211 -297.562878) (xy 378.980642 -297.515089) (xy 378.980192 -297.490896) (xy 378.980192 -296.734992)
			(xy 378.979993 -296.728034) (xy 378.976258 -296.714631) (xy 378.972826 -296.708576) (xy 378.960118 -296.686833)
			(xy 378.940075 -296.640632) (xy 378.926504 -296.592134) (xy 378.919658 -296.542241) (xy 378.919232 -296.51706)
			(xy 377.653296 -296.51706) (xy 377.653296 -296.541698) (xy 377.653393 -296.546716) (xy 377.655321 -296.556564)
			(xy 377.657106 -296.561256) (xy 377.812808 -296.937176) (xy 378.74956 -299.198538) (xy 378.755656 -299.204634)
			(xy 378.758196 -299.21962) (xy 378.760482 -299.224954) (xy 381.09652 -304.865278) (xy 381.096774 -304.865786)
			(xy 381.098044 -304.868834) (xy 381.098298 -304.869596) (xy 381.10287 -304.880518) (xy 381.10287 -304.880772)
			(xy 381.109728 -304.897282) (xy 381.109728 -304.897536) (xy 381.11811 -304.917094) (xy 381.119126 -304.920142)
			(xy 381.119888 -304.92192) (xy 381.119888 -307.6448) (xy 381.120345 -307.654679) (xy 381.127782 -307.672983)
			(xy 381.134366 -307.68036) (xy 381.13462 -307.680614) (xy 386.763514 -313.309254) (xy 386.764022 -313.309762)
			(xy 386.771402 -313.316348) (xy 386.789701 -313.323808) (xy 386.799582 -313.32424) (xy 389.133588 -313.32424)
			(xy 389.147304 -313.322462) (xy 389.16483 -313.317382) (xy 389.170418 -313.314334) (xy 389.170926 -313.31408)
			(xy 389.171688 -313.313572) (xy 389.200008 -313.298769) (xy 389.260368 -313.277802) (xy 389.32338 -313.267205)
			(xy 389.35533 -313.266582) (xy 389.355584 -313.266582) (xy 389.355838 -313.266582) (xy 389.387784 -313.267234)
			(xy 389.450785 -313.277861) (xy 389.511149 -313.298797) (xy 389.53948 -313.313572) (xy 389.540242 -313.31408)
			(xy 389.54075 -313.314334) (xy 389.546338 -313.317382) (xy 389.563864 -313.322462) (xy 389.57758 -313.32424)
			(xy 391.700258 -313.32424) (xy 391.710323 -313.324675) (xy 391.728908 -313.332409) (xy 391.736326 -313.339226)
			(xy 391.821416 -313.424316) (xy 391.826905 -313.429498) (xy 391.840219 -313.436599) (xy 391.847578 -313.438286)
			(xy 391.847832 -313.438286) (xy 391.855212 -313.439457) (xy 391.870068 -313.43792) (xy 391.877042 -313.435238)
			(xy 391.877296 -313.434984) (xy 391.899006 -313.426265) (xy 391.944838 -313.416918) (xy 391.968228 -313.416442)
			(xy 391.968482 -313.416442) (xy 392.267694 -313.416442) (xy 392.267948 -313.416442) (xy 392.290278 -313.416835)
			(xy 392.334116 -313.425328) (xy 392.375446 -313.442234) (xy 392.41267 -313.466899) (xy 392.444349 -313.49837)
			(xy 392.46926 -313.53543) (xy 392.486438 -313.576648) (xy 392.495221 -313.62043) (xy 392.495786 -313.642756)
			(xy 392.495786 -313.859926) (xy 392.495341 -313.869669) (xy 392.488048 -313.88774) (xy 392.474529 -313.901776)
			(xy 392.465814 -313.906154) (xy 392.452098 -313.912504) (xy 392.435842 -313.937396) (xy 392.435842 -314.231528)
			(xy 392.662156 -314.457842) (xy 392.662156 -314.504336) (xy 393.52523 -314.504336) (xy 393.52523 -314.444368)
			(xy 393.533058 -314.384912) (xy 393.548579 -314.326987) (xy 393.571528 -314.271583) (xy 393.601512 -314.219649)
			(xy 393.638018 -314.172073) (xy 393.680423 -314.129668) (xy 393.727999 -314.093162) (xy 393.779933 -314.063178)
			(xy 393.835337 -314.040229) (xy 393.893262 -314.024708) (xy 393.952718 -314.01688) (xy 394.012686 -314.01688)
			(xy 394.072142 -314.024708) (xy 394.130067 -314.040229) (xy 394.185471 -314.063178) (xy 394.237405 -314.093162)
			(xy 394.284981 -314.129668) (xy 394.327386 -314.172073) (xy 394.363892 -314.219649) (xy 394.393876 -314.271583)
			(xy 394.416825 -314.326987) (xy 394.432346 -314.384912) (xy 394.440174 -314.444368) (xy 394.440664 -314.474352)
			(xy 394.440174 -314.504336) (xy 394.432346 -314.563792) (xy 394.416825 -314.621717) (xy 394.393876 -314.677121)
			(xy 394.363892 -314.729055) (xy 394.327386 -314.776631) (xy 394.284981 -314.819036) (xy 394.237405 -314.855542)
			(xy 394.185471 -314.885526) (xy 394.130067 -314.908475) (xy 394.072142 -314.923996) (xy 394.012686 -314.931824)
			(xy 393.952718 -314.931824) (xy 393.893262 -314.923996) (xy 393.835337 -314.908475) (xy 393.779933 -314.885526)
			(xy 393.727999 -314.855542) (xy 393.680423 -314.819036) (xy 393.638018 -314.776631) (xy 393.601512 -314.729055)
			(xy 393.571528 -314.677121) (xy 393.548579 -314.621717) (xy 393.533058 -314.563792) (xy 393.52523 -314.504336)
			(xy 392.662156 -314.504336) (xy 392.662156 -315.37148) (xy 393.056364 -315.765434) (xy 393.056364 -316.077854)
			(xy 395.429232 -318.450468) (xy 395.432847 -318.453905) (xy 395.441163 -318.459413) (xy 395.445742 -318.46139)
			(xy 395.467078 -318.47028) (xy 395.467586 -318.47028) (xy 395.568424 -318.512444) (xy 395.578838 -318.512444)
		)
		(stroke
			(width 0)
			(type solid)
		)
		(fill yes)
		(layer "B.Cu")
		(net "GND")
	)
	(gr_poly
		(pts
			(xy 97.285302 -256.059432) (xy 97.296823 -256.058871) (xy 97.317493 -256.048692) (xy 97.324926 -256.039874)
			(xy 97.35439 -255.99898) (xy 97.37344 -255.97231) (xy 97.376798 -255.967311) (xy 97.381304 -255.956146)
			(xy 97.38233 -255.950212) (xy 97.384108 -255.938782) (xy 97.382076 -255.932686) (xy 97.380044 -255.927098)
			(xy 97.37211 -255.902189) (xy 97.363555 -255.850619) (xy 97.363026 -255.824482) (xy 97.363516 -255.799493)
			(xy 97.371335 -255.75013) (xy 97.386779 -255.702598) (xy 97.409469 -255.658066) (xy 97.438845 -255.617633)
			(xy 97.474185 -255.582293) (xy 97.514618 -255.552917) (xy 97.55915 -255.530227) (xy 97.606682 -255.514783)
			(xy 97.656045 -255.506964) (xy 97.706023 -255.506964) (xy 97.755386 -255.514783) (xy 97.802918 -255.530227)
			(xy 97.84745 -255.552917) (xy 97.887883 -255.582293) (xy 97.923223 -255.617633) (xy 97.952599 -255.658066)
			(xy 97.975289 -255.702598) (xy 97.990733 -255.75013) (xy 97.998552 -255.799493) (xy 97.999042 -255.824482)
			(xy 97.998513 -255.850619) (xy 97.98996 -255.902189) (xy 97.982024 -255.927098) (xy 97.979992 -255.932686)
			(xy 97.97796 -255.938782) (xy 97.979738 -255.950212) (xy 97.980778 -255.956143) (xy 97.985273 -255.96731)
			(xy 97.988628 -255.97231) (xy 98.007678 -255.99898) (xy 98.037142 -256.039874) (xy 98.044618 -256.04864)
			(xy 98.06526 -256.05882) (xy 98.076766 -256.059432) (xy 99.060762 -256.059432) (xy 99.069586 -256.059051)
			(xy 99.086125 -256.052883) (xy 99.099503 -256.041369) (xy 99.108064 -256.025933) (xy 99.109784 -256.017268)
			(xy 99.109784 -255.591056) (xy 99.1108 -255.58115) (xy 99.1108 -255.570482) (xy 99.140518 -255.540764)
			(xy 99.152202 -255.540764) (xy 99.154996 -255.54051) (xy 99.160584 -255.540256) (xy 99.332796 -255.540256)
			(xy 99.33432 -255.540002) (xy 99.367848 -255.50622) (xy 99.375468 -255.487932) (xy 99.375468 -255.48082)
			(xy 99.393248 -255.48082) (xy 99.39401 -255.480312) (xy 99.630484 -255.480312) (xy 99.652657 -255.480899)
			(xy 99.696046 -255.490064) (xy 99.736628 -255.507945) (xy 99.772673 -255.533779) (xy 99.802643 -255.566465)
			(xy 99.825263 -255.60461) (xy 99.839566 -255.646586) (xy 99.842828 -255.668526) (xy 99.844098 -255.67513)
			(xy 99.846892 -255.684528) (xy 99.84867 -255.688338) (xy 99.858312 -255.709723) (xy 99.871902 -255.75462)
			(xy 99.878743 -255.801027) (xy 99.87915 -255.824482) (xy 99.878761 -255.847518) (xy 99.872143 -255.893111)
			(xy 99.859 -255.937267) (xy 99.849686 -255.95834) (xy 99.849178 -255.959356) (xy 99.846938 -255.96447)
			(xy 99.844503 -255.975365) (xy 99.844352 -255.980946) (xy 99.844352 -255.99517) (xy 99.844352 -255.99898)
			(xy 99.844352 -256.00406) (xy 99.853242 -256.023872) (xy 99.878896 -256.046732) (xy 99.88611 -256.052534)
			(xy 99.903428 -256.059037) (xy 99.912678 -256.059432) (xy 100.10521 -256.059432) (xy 100.11673 -256.058869)
			(xy 100.137397 -256.048688) (xy 100.144834 -256.039874) (xy 100.174298 -255.99898) (xy 100.193348 -255.97231)
			(xy 100.196705 -255.96731) (xy 100.20121 -255.956145) (xy 100.202238 -255.950212) (xy 100.204016 -255.938782)
			(xy 100.201984 -255.932686) (xy 100.199952 -255.927098) (xy 100.192018 -255.902189) (xy 100.183462 -255.850619)
			(xy 100.182934 -255.824482) (xy 100.1834 -255.799493) (xy 100.191222 -255.750131) (xy 100.206669 -255.7026)
			(xy 100.229362 -255.658071) (xy 100.258742 -255.61764) (xy 100.294086 -255.582303) (xy 100.334522 -255.552931)
			(xy 100.379055 -255.530246) (xy 100.426589 -255.514808) (xy 100.475953 -255.506996) (xy 100.500942 -255.506474)
			(xy 100.519738 -255.506982) (xy 100.530406 -255.50749) (xy 100.53955 -255.504188) (xy 100.543822 -255.502533)
			(xy 100.551745 -255.497935) (xy 100.555298 -255.495044) (xy 100.610162 -255.443482) (xy 100.616682 -255.436745)
			(xy 100.624632 -255.419782) (xy 100.625656 -255.410462) (xy 100.625656 -254.439928) (xy 100.62591 -254.43434)
			(xy 100.62591 -253.718314) (xy 100.625656 -253.713234) (xy 100.625656 -253.326138) (xy 100.62591 -253.32055)
			(xy 100.62591 -253.279148) (xy 100.62591 -253.278894) (xy 100.626344 -253.269011) (xy 100.633789 -253.250704)
			(xy 100.640388 -253.243334) (xy 100.683822 -253.1999) (xy 100.690536 -253.192662) (xy 100.698133 -253.174457)
			(xy 100.698554 -253.164594) (xy 100.698554 -253.090426) (xy 100.69909 -253.080588) (xy 100.706672 -253.062424)
			(xy 100.713286 -253.05512) (xy 100.877116 -252.89129) (xy 100.883668 -252.884042) (xy 100.89111 -252.865998)
			(xy 100.891594 -252.856238) (xy 100.891594 -252.342396) (xy 100.891848 -252.340364) (xy 100.891848 -252.32487)
			(xy 100.921566 -252.295152) (xy 101.106986 -252.295152) (xy 101.116166 -252.294691) (xy 101.133278 -252.288024)
			(xy 101.146873 -252.275678) (xy 101.155153 -252.259285) (xy 101.156516 -252.250194) (xy 101.156516 -252.235208)
			(xy 101.209856 -252.235208) (xy 101.219686 -252.234741) (xy 101.237861 -252.22725) (xy 101.2518 -252.213386)
			(xy 101.259388 -252.195251) (xy 101.259894 -252.185424) (xy 101.259894 -251.262134) (xy 101.259894 -251.261372)
			(xy 101.259688 -251.256124) (xy 101.257393 -251.245878) (xy 101.255322 -251.241052) (xy 101.24186 -251.213112)
			(xy 101.236018 -251.208286) (xy 101.214174 -251.200412) (xy 101.209996 -251.198999) (xy 101.201311 -251.197462)
			(xy 101.196902 -251.197364) (xy 101.073966 -251.197364) (xy 101.044248 -251.167646) (xy 101.044248 -251.152152)
			(xy 101.043994 -251.15012) (xy 101.043994 -250.860306) (xy 101.043472 -250.850559) (xy 101.036011 -250.832543)
			(xy 101.029516 -250.825254) (xy 100.703634 -250.499372) (xy 100.692966 -250.499372) (xy 100.586286 -250.392692)
			(xy 100.47097 -250.277122) (xy 100.462263 -250.269701) (xy 100.440433 -250.262938) (xy 100.42906 -250.264168)
			(xy 100.410264 -250.266962) (xy 100.409756 -250.266962) (xy 100.347018 -250.276614) (xy 100.341716 -250.277764)
			(xy 100.33173 -250.282001) (xy 100.327206 -250.284996) (xy 100.323396 -250.28779) (xy 100.315522 -250.29668)
			(xy 100.312474 -250.302522) (xy 100.300565 -250.324157) (xy 100.271092 -250.363781) (xy 100.235847 -250.398372)
			(xy 100.195677 -250.427097) (xy 100.15155 -250.449265) (xy 100.104525 -250.464344) (xy 100.055734 -250.471971)
			(xy 100.031042 -250.472448) (xy 100.006047 -250.471987) (xy 99.956673 -250.464173) (xy 99.909129 -250.448732)
			(xy 99.864585 -250.426043) (xy 99.82414 -250.396666) (xy 99.788788 -250.361323) (xy 99.7594 -250.320885)
			(xy 99.736699 -250.276347) (xy 99.721246 -250.228807) (xy 99.71342 -250.179434) (xy 99.713034 -250.15444)
			(xy 99.713511 -250.12933) (xy 99.721405 -250.079735) (xy 99.736987 -250.031994) (xy 99.759871 -249.987291)
			(xy 99.789489 -249.946735) (xy 99.825107 -249.911333) (xy 99.865842 -249.881961) (xy 99.88804 -249.870214)
			(xy 99.888802 -249.86996) (xy 99.889056 -249.86996) (xy 99.89418 -249.867097) (xy 99.903036 -249.859397)
			(xy 99.906582 -249.85472) (xy 99.909884 -249.850148) (xy 99.91217 -249.844814) (xy 99.915472 -249.83313)
			(xy 99.928172 -249.753374) (xy 99.929458 -249.741509) (xy 99.922172 -249.718821) (xy 99.914202 -249.70994)
			(xy 99.812094 -249.607832) (xy 99.805528 -249.601712) (xy 99.789256 -249.594168) (xy 99.780344 -249.5931)
			(xy 99.771962 -249.592338) (xy 99.75469 -249.597164) (xy 99.746816 -249.602752) (xy 99.735386 -249.610626)
			(xy 99.733862 -249.611642) (xy 99.730306 -249.613928) (xy 99.720146 -249.624342) (xy 99.715066 -249.629422)
			(xy 99.712272 -249.633994) (xy 99.70031 -249.651867) (xy 99.670499 -249.682855) (xy 99.635106 -249.707275)
			(xy 99.595554 -249.724145) (xy 99.553431 -249.732787) (xy 99.531932 -249.733308) (xy 99.327716 -249.733308)
			(xy 99.317692 -249.732891) (xy 99.299168 -249.725224) (xy 99.284989 -249.711052) (xy 99.277313 -249.692532)
			(xy 99.276916 -249.682508) (xy 99.276916 -249.673364) (xy 99.041966 -249.673364) (xy 99.012248 -249.643646)
			(xy 99.012248 -249.628152) (xy 99.011994 -249.62612) (xy 99.011994 -249.08891) (xy 99.01152 -249.079086)
			(xy 99.004023 -249.060924) (xy 98.99016 -249.047) (xy 98.972032 -249.039423) (xy 98.96221 -249.038872)
			(xy 98.045016 -249.038872) (xy 98.032616 -249.039524) (xy 98.010766 -249.051256) (xy 98.00336 -249.061224)
			(xy 97.987866 -249.087132) (xy 97.987866 -249.08764) (xy 97.956624 -249.141234) (xy 97.954187 -249.146501)
			(xy 97.951498 -249.157787) (xy 97.95129 -249.163586) (xy 97.95129 -249.176286) (xy 97.958148 -249.188478)
			(xy 97.971008 -249.212438) (xy 97.989245 -249.263664) (xy 97.998495 -249.317246) (xy 97.999042 -249.344434)
			(xy 97.998552 -249.369423) (xy 97.990733 -249.418786) (xy 97.975289 -249.466318) (xy 97.952599 -249.51085)
			(xy 97.923223 -249.551283) (xy 97.887883 -249.586623) (xy 97.84745 -249.615999) (xy 97.802918 -249.638689)
			(xy 97.755386 -249.654133) (xy 97.706023 -249.661952) (xy 97.656045 -249.661952) (xy 97.606682 -249.654133)
			(xy 97.55915 -249.638689) (xy 97.514618 -249.615999) (xy 97.474185 -249.586623) (xy 97.438845 -249.551283)
			(xy 97.409469 -249.51085) (xy 97.386779 -249.466318) (xy 97.371335 -249.418786) (xy 97.363516 -249.369423)
			(xy 97.363026 -249.344434) (xy 97.363587 -249.317248) (xy 97.372847 -249.263671) (xy 97.391085 -249.21245)
			(xy 97.40392 -249.188478) (xy 97.405444 -249.185684) (xy 97.407866 -249.180285) (xy 97.410439 -249.16874)
			(xy 97.410524 -249.162824) (xy 97.410524 -249.150124) (xy 97.374202 -249.08764) (xy 97.374202 -249.087132)
			(xy 97.358708 -249.061224) (xy 97.351299 -249.051264) (xy 97.329448 -249.039548) (xy 97.317052 -249.038872)
			(xy 96.502728 -249.038872) (xy 96.49289 -249.039408) (xy 96.474727 -249.046992) (xy 96.467422 -249.053604)
			(xy 96.382586 -249.13844) (xy 96.375877 -249.145679) (xy 96.368294 -249.163885) (xy 96.367854 -249.173746)
			(xy 96.367854 -249.81662) (xy 96.368111 -249.824031) (xy 96.372377 -249.838227) (xy 96.376236 -249.84456)
			(xy 96.380046 -249.850402) (xy 96.390968 -249.8598) (xy 96.397826 -249.862848) (xy 96.420223 -249.873075)
			(xy 96.461824 -249.899411) (xy 96.498867 -249.931844) (xy 96.530468 -249.9696) (xy 96.555871 -250.011776)
			(xy 96.574469 -250.057363) (xy 96.585818 -250.105273) (xy 96.589646 -250.154359) (xy 96.587713 -250.179429)
			(xy 97.833416 -250.179429) (xy 97.833416 -250.129451) (xy 97.841235 -250.080088) (xy 97.856679 -250.032556)
			(xy 97.879369 -249.988024) (xy 97.908745 -249.947591) (xy 97.944085 -249.912251) (xy 97.984518 -249.882875)
			(xy 98.02905 -249.860185) (xy 98.076582 -249.844741) (xy 98.125945 -249.836922) (xy 98.175923 -249.836922)
			(xy 98.225286 -249.844741) (xy 98.272818 -249.860185) (xy 98.31735 -249.882875) (xy 98.357783 -249.912251)
			(xy 98.393123 -249.947591) (xy 98.422499 -249.988024) (xy 98.445189 -250.032556) (xy 98.460633 -250.080088)
			(xy 98.468452 -250.129451) (xy 98.468942 -250.15444) (xy 98.468452 -250.179429) (xy 98.460633 -250.228792)
			(xy 98.445189 -250.276324) (xy 98.422499 -250.320856) (xy 98.393123 -250.361289) (xy 98.357783 -250.396629)
			(xy 98.31735 -250.426005) (xy 98.272818 -250.448695) (xy 98.225286 -250.464139) (xy 98.175923 -250.471958)
			(xy 98.125945 -250.471958) (xy 98.076582 -250.464139) (xy 98.02905 -250.448695) (xy 97.984518 -250.426005)
			(xy 97.944085 -250.396629) (xy 97.908745 -250.361289) (xy 97.879369 -250.320856) (xy 97.856679 -250.276324)
			(xy 97.841235 -250.228792) (xy 97.833416 -250.179429) (xy 96.587713 -250.179429) (xy 96.585861 -250.203449)
			(xy 96.574555 -250.251369) (xy 96.555997 -250.296973) (xy 96.530631 -250.339171) (xy 96.499063 -250.376955)
			(xy 96.462049 -250.409421) (xy 96.420472 -250.435793) (xy 96.39808 -250.446032) (xy 96.397826 -250.446032)
			(xy 96.393508 -250.448064) (xy 96.390968 -250.44908) (xy 96.380046 -250.458478) (xy 96.376236 -250.46432)
			(xy 96.372369 -250.470649) (xy 96.368105 -250.484848) (xy 96.367854 -250.49226) (xy 96.367854 -250.989435)
			(xy 97.363516 -250.989435) (xy 97.363516 -250.939457) (xy 97.371335 -250.890094) (xy 97.386779 -250.842562)
			(xy 97.409469 -250.79803) (xy 97.438845 -250.757597) (xy 97.474185 -250.722257) (xy 97.514618 -250.692881)
			(xy 97.55915 -250.670191) (xy 97.606682 -250.654747) (xy 97.656045 -250.646928) (xy 97.706023 -250.646928)
			(xy 97.755386 -250.654747) (xy 97.802918 -250.670191) (xy 97.84745 -250.692881) (xy 97.887883 -250.722257)
			(xy 97.923223 -250.757597) (xy 97.952599 -250.79803) (xy 97.975289 -250.842562) (xy 97.990733 -250.890094)
			(xy 97.998552 -250.939457) (xy 97.999042 -250.964446) (xy 97.998552 -250.989435) (xy 97.990733 -251.038798)
			(xy 97.975289 -251.08633) (xy 97.952599 -251.130862) (xy 97.941191 -251.146564) (xy 99.139248 -251.146564)
			(xy 99.139248 -250.638564) (xy 99.139591 -250.628534) (xy 99.147282 -250.610007) (xy 99.161478 -250.595835)
			(xy 99.180018 -250.588175) (xy 99.190048 -250.587764) (xy 99.403916 -250.587764) (xy 99.403916 -250.57862)
			(xy 99.404337 -250.568598) (xy 99.412003 -250.550079) (xy 99.426175 -250.535905) (xy 99.444694 -250.528237)
			(xy 99.454716 -250.52782) (xy 99.658932 -250.52782) (xy 99.679978 -250.528295) (xy 99.721255 -250.536542)
			(xy 99.760118 -250.552712) (xy 99.795063 -250.576177) (xy 99.824738 -250.606031) (xy 99.847993 -250.641116)
			(xy 99.863929 -250.680076) (xy 99.871928 -250.721401) (xy 99.872292 -250.74245) (xy 99.872292 -250.742958)
			(xy 99.872292 -250.897898) (xy 99.873054 -250.902724) (xy 99.875896 -250.917996) (xy 99.87895 -250.948913)
			(xy 99.87915 -250.964446) (xy 99.878953 -250.979979) (xy 99.875898 -251.010896) (xy 99.873054 -251.026168)
			(xy 99.872292 -251.030994) (xy 99.872292 -251.042424) (xy 99.871893 -251.06378) (xy 99.863677 -251.105689)
			(xy 99.847296 -251.145128) (xy 99.823404 -251.180526) (xy 99.792954 -251.21047) (xy 99.757161 -251.233766)
			(xy 99.717453 -251.249484) (xy 99.696524 -251.253752) (xy 99.685602 -251.257054) (xy 99.665848 -251.26509)
			(xy 99.624729 -251.276406) (xy 99.582466 -251.282112) (xy 99.561142 -251.282454) (xy 99.531544 -251.281773)
			(xy 99.473376 -251.270781) (xy 99.445572 -251.26061) (xy 99.436428 -251.257308) (xy 99.403916 -251.257308)
			(xy 99.403916 -251.241052) (xy 99.391823 -251.233948) (xy 99.368802 -251.217923) (xy 99.357942 -251.209048)
			(xy 99.350878 -251.203734) (xy 99.33426 -251.19775) (xy 99.32543 -251.197364) (xy 99.190048 -251.197364)
			(xy 99.180025 -251.19694) (xy 99.161503 -251.189279) (xy 99.147327 -251.175108) (xy 99.139662 -251.156587)
			(xy 99.139248 -251.146564) (xy 97.941191 -251.146564) (xy 97.923223 -251.171295) (xy 97.887883 -251.206635)
			(xy 97.84745 -251.236011) (xy 97.802918 -251.258701) (xy 97.755386 -251.274145) (xy 97.706023 -251.281964)
			(xy 97.656045 -251.281964) (xy 97.606682 -251.274145) (xy 97.55915 -251.258701) (xy 97.514618 -251.236011)
			(xy 97.474185 -251.206635) (xy 97.438845 -251.171295) (xy 97.409469 -251.130862) (xy 97.386779 -251.08633)
			(xy 97.371335 -251.038798) (xy 97.363516 -250.989435) (xy 96.367854 -250.989435) (xy 96.367854 -251.436632)
			(xy 96.368113 -251.444043) (xy 96.372381 -251.458237) (xy 96.376236 -251.464572) (xy 96.380046 -251.470414)
			(xy 96.390968 -251.479812) (xy 96.397826 -251.48286) (xy 96.420223 -251.493087) (xy 96.461821 -251.519423)
			(xy 96.498862 -251.551855) (xy 96.530462 -251.58961) (xy 96.555863 -251.631785) (xy 96.57446 -251.677371)
			(xy 96.585808 -251.725279) (xy 96.589635 -251.774364) (xy 96.587701 -251.799441) (xy 97.833416 -251.799441)
			(xy 97.833416 -251.749463) (xy 97.841235 -251.7001) (xy 97.856679 -251.652568) (xy 97.879369 -251.608036)
			(xy 97.908745 -251.567603) (xy 97.944085 -251.532263) (xy 97.984518 -251.502887) (xy 98.02905 -251.480197)
			(xy 98.076582 -251.464753) (xy 98.125945 -251.456934) (xy 98.175923 -251.456934) (xy 98.225286 -251.464753)
			(xy 98.272818 -251.480197) (xy 98.31735 -251.502887) (xy 98.357783 -251.532263) (xy 98.393123 -251.567603)
			(xy 98.422499 -251.608036) (xy 98.445189 -251.652568) (xy 98.460633 -251.7001) (xy 98.468452 -251.749463)
			(xy 98.468942 -251.774452) (xy 98.468452 -251.799441) (xy 99.713524 -251.799441) (xy 99.713524 -251.749463)
			(xy 99.721343 -251.7001) (xy 99.736787 -251.652568) (xy 99.759477 -251.608036) (xy 99.788853 -251.567603)
			(xy 99.824193 -251.532263) (xy 99.864626 -251.502887) (xy 99.909158 -251.480197) (xy 99.95669 -251.464753)
			(xy 100.006053 -251.456934) (xy 100.056031 -251.456934) (xy 100.105394 -251.464753) (xy 100.152926 -251.480197)
			(xy 100.197458 -251.502887) (xy 100.237891 -251.532263) (xy 100.273231 -251.567603) (xy 100.302607 -251.608036)
			(xy 100.325297 -251.652568) (xy 100.340741 -251.7001) (xy 100.34856 -251.749463) (xy 100.34905 -251.774452)
			(xy 100.34856 -251.799441) (xy 100.340741 -251.848804) (xy 100.325297 -251.896336) (xy 100.302607 -251.940868)
			(xy 100.273231 -251.981301) (xy 100.237891 -252.016641) (xy 100.197458 -252.046017) (xy 100.152926 -252.068707)
			(xy 100.105394 -252.084151) (xy 100.056031 -252.09197) (xy 100.006053 -252.09197) (xy 99.95669 -252.084151)
			(xy 99.909158 -252.068707) (xy 99.864626 -252.046017) (xy 99.824193 -252.016641) (xy 99.788853 -251.981301)
			(xy 99.759477 -251.940868) (xy 99.736787 -251.896336) (xy 99.721343 -251.848804) (xy 99.713524 -251.799441)
			(xy 98.468452 -251.799441) (xy 98.460633 -251.848804) (xy 98.445189 -251.896336) (xy 98.422499 -251.940868)
			(xy 98.393123 -251.981301) (xy 98.357783 -252.016641) (xy 98.31735 -252.046017) (xy 98.272818 -252.068707)
			(xy 98.225286 -252.084151) (xy 98.175923 -252.09197) (xy 98.125945 -252.09197) (xy 98.076582 -252.084151)
			(xy 98.02905 -252.068707) (xy 97.984518 -252.046017) (xy 97.944085 -252.016641) (xy 97.908745 -251.981301)
			(xy 97.879369 -251.940868) (xy 97.856679 -251.896336) (xy 97.841235 -251.848804) (xy 97.833416 -251.799441)
			(xy 96.587701 -251.799441) (xy 96.58585 -251.823452) (xy 96.574543 -251.87137) (xy 96.555985 -251.916972)
			(xy 96.530619 -251.959169) (xy 96.499052 -251.99695) (xy 96.462038 -252.029415) (xy 96.420463 -252.055785)
			(xy 96.39808 -252.066044) (xy 96.397826 -252.066044) (xy 96.393508 -252.068076) (xy 96.390968 -252.069092)
			(xy 96.380046 -252.07849) (xy 96.376236 -252.084332) (xy 96.37237 -252.090661) (xy 96.36811 -252.10486)
			(xy 96.367854 -252.112272) (xy 96.367854 -252.609447) (xy 97.363516 -252.609447) (xy 97.363516 -252.559469)
			(xy 97.371335 -252.510106) (xy 97.386779 -252.462574) (xy 97.409469 -252.418042) (xy 97.438845 -252.377609)
			(xy 97.474185 -252.342269) (xy 97.514618 -252.312893) (xy 97.55915 -252.290203) (xy 97.606682 -252.274759)
			(xy 97.656045 -252.26694) (xy 97.706023 -252.26694) (xy 97.755386 -252.274759) (xy 97.802918 -252.290203)
			(xy 97.84745 -252.312893) (xy 97.887883 -252.342269) (xy 97.923223 -252.377609) (xy 97.952599 -252.418042)
			(xy 97.975289 -252.462574) (xy 97.990733 -252.510106) (xy 97.998552 -252.559469) (xy 97.999042 -252.584458)
			(xy 97.998552 -252.609447) (xy 97.990733 -252.65881) (xy 97.975289 -252.706342) (xy 97.952599 -252.750874)
			(xy 97.923223 -252.791307) (xy 97.887883 -252.826647) (xy 97.850301 -252.853952) (xy 99.113848 -252.853952)
			(xy 99.113848 -252.345952) (xy 99.11425 -252.335935) (xy 99.121934 -252.317433) (xy 99.136114 -252.30328)
			(xy 99.15463 -252.295631) (xy 99.164648 -252.295152) (xy 99.378516 -252.295152) (xy 99.378516 -252.286008)
			(xy 99.378926 -252.275985) (xy 99.386597 -252.257465) (xy 99.400772 -252.243292) (xy 99.419293 -252.235625)
			(xy 99.429316 -252.235208) (xy 99.633532 -252.235208) (xy 99.653666 -252.235676) (xy 99.693221 -252.243219)
			(xy 99.730658 -252.258048) (xy 99.764649 -252.279639) (xy 99.793984 -252.307223) (xy 99.817624 -252.339821)
			(xy 99.834727 -252.376276) (xy 99.844688 -252.415292) (xy 99.846384 -252.43536) (xy 99.846762 -252.439947)
			(xy 99.848937 -252.448889) (xy 99.850702 -252.45314) (xy 99.859669 -252.473859) (xy 99.87232 -252.517197)
			(xy 99.878735 -252.561885) (xy 99.87915 -252.584458) (xy 99.878767 -252.606845) (xy 99.872485 -252.651176)
			(xy 99.860041 -252.694185) (xy 99.85121 -252.71476) (xy 99.846892 -252.724666) (xy 99.846892 -252.749558)
			(xy 99.846892 -252.750066) (xy 99.846527 -252.771114) (xy 99.838525 -252.812437) (xy 99.822588 -252.851394)
			(xy 99.799332 -252.886477) (xy 99.769658 -252.916327) (xy 99.734714 -252.939791) (xy 99.695852 -252.955959)
			(xy 99.654577 -252.964206) (xy 99.633532 -252.964696) (xy 99.378516 -252.964696) (xy 99.378516 -252.955552)
			(xy 99.378052 -252.945543) (xy 99.370379 -252.927054) (xy 99.35622 -252.912903) (xy 99.337725 -252.905242)
			(xy 99.327716 -252.904752) (xy 99.164648 -252.904752) (xy 99.154624 -252.90434) (xy 99.136099 -252.896677)
			(xy 99.121923 -252.882501) (xy 99.11426 -252.863976) (xy 99.113848 -252.853952) (xy 97.850301 -252.853952)
			(xy 97.84745 -252.856023) (xy 97.802918 -252.878713) (xy 97.755386 -252.894157) (xy 97.706023 -252.901976)
			(xy 97.656045 -252.901976) (xy 97.606682 -252.894157) (xy 97.55915 -252.878713) (xy 97.514618 -252.856023)
			(xy 97.474185 -252.826647) (xy 97.438845 -252.791307) (xy 97.409469 -252.750874) (xy 97.386779 -252.706342)
			(xy 97.371335 -252.65881) (xy 97.363516 -252.609447) (xy 96.367854 -252.609447) (xy 96.367854 -253.056644)
			(xy 96.368101 -253.064059) (xy 96.372348 -253.078266) (xy 96.376236 -253.084584) (xy 96.380046 -253.090426)
			(xy 96.390968 -253.099824) (xy 96.397826 -253.102872) (xy 96.420222 -253.113099) (xy 96.461818 -253.139434)
			(xy 96.498858 -253.171866) (xy 96.530455 -253.209621) (xy 96.555856 -253.251794) (xy 96.574451 -253.297379)
			(xy 96.585798 -253.345286) (xy 96.589624 -253.394369) (xy 96.587689 -253.419453) (xy 97.833416 -253.419453)
			(xy 97.833416 -253.369475) (xy 97.841235 -253.320112) (xy 97.856679 -253.27258) (xy 97.879369 -253.228048)
			(xy 97.908745 -253.187615) (xy 97.944085 -253.152275) (xy 97.984518 -253.122899) (xy 98.02905 -253.100209)
			(xy 98.076582 -253.084765) (xy 98.125945 -253.076946) (xy 98.175923 -253.076946) (xy 98.225286 -253.084765)
			(xy 98.272818 -253.100209) (xy 98.31735 -253.122899) (xy 98.357783 -253.152275) (xy 98.393123 -253.187615)
			(xy 98.422499 -253.228048) (xy 98.445189 -253.27258) (xy 98.460633 -253.320112) (xy 98.468452 -253.369475)
			(xy 98.468942 -253.394464) (xy 98.468452 -253.419453) (xy 99.713524 -253.419453) (xy 99.713524 -253.369475)
			(xy 99.721343 -253.320112) (xy 99.736787 -253.27258) (xy 99.759477 -253.228048) (xy 99.788853 -253.187615)
			(xy 99.824193 -253.152275) (xy 99.864626 -253.122899) (xy 99.909158 -253.100209) (xy 99.95669 -253.084765)
			(xy 100.006053 -253.076946) (xy 100.056031 -253.076946) (xy 100.105394 -253.084765) (xy 100.152926 -253.100209)
			(xy 100.197458 -253.122899) (xy 100.237891 -253.152275) (xy 100.273231 -253.187615) (xy 100.302607 -253.228048)
			(xy 100.325297 -253.27258) (xy 100.340741 -253.320112) (xy 100.34856 -253.369475) (xy 100.34905 -253.394464)
			(xy 100.34856 -253.419453) (xy 100.340741 -253.468816) (xy 100.325297 -253.516348) (xy 100.302607 -253.56088)
			(xy 100.273231 -253.601313) (xy 100.237891 -253.636653) (xy 100.197458 -253.666029) (xy 100.152926 -253.688719)
			(xy 100.105394 -253.704163) (xy 100.056031 -253.711982) (xy 100.006053 -253.711982) (xy 99.95669 -253.704163)
			(xy 99.909158 -253.688719) (xy 99.864626 -253.666029) (xy 99.824193 -253.636653) (xy 99.788853 -253.601313)
			(xy 99.759477 -253.56088) (xy 99.736787 -253.516348) (xy 99.721343 -253.468816) (xy 99.713524 -253.419453)
			(xy 98.468452 -253.419453) (xy 98.460633 -253.468816) (xy 98.445189 -253.516348) (xy 98.422499 -253.56088)
			(xy 98.393123 -253.601313) (xy 98.357783 -253.636653) (xy 98.31735 -253.666029) (xy 98.272818 -253.688719)
			(xy 98.225286 -253.704163) (xy 98.175923 -253.711982) (xy 98.125945 -253.711982) (xy 98.076582 -253.704163)
			(xy 98.02905 -253.688719) (xy 97.984518 -253.666029) (xy 97.944085 -253.636653) (xy 97.908745 -253.601313)
			(xy 97.879369 -253.56088) (xy 97.856679 -253.516348) (xy 97.841235 -253.468816) (xy 97.833416 -253.419453)
			(xy 96.587689 -253.419453) (xy 96.585838 -253.443455) (xy 96.574531 -253.491371) (xy 96.555973 -253.536971)
			(xy 96.530608 -253.579166) (xy 96.499041 -253.616946) (xy 96.462028 -253.649409) (xy 96.420453 -253.675778)
			(xy 96.39808 -253.686056) (xy 96.397826 -253.686056) (xy 96.393508 -253.688088) (xy 96.390968 -253.689104)
			(xy 96.380046 -253.698502) (xy 96.376236 -253.704344) (xy 96.372372 -253.710674) (xy 96.368115 -253.724872)
			(xy 96.367854 -253.732284) (xy 96.367854 -254.229459) (xy 97.363516 -254.229459) (xy 97.363516 -254.179481)
			(xy 97.371335 -254.130118) (xy 97.386779 -254.082586) (xy 97.409469 -254.038054) (xy 97.438845 -253.997621)
			(xy 97.474185 -253.962281) (xy 97.514618 -253.932905) (xy 97.55915 -253.910215) (xy 97.606682 -253.894771)
			(xy 97.656045 -253.886952) (xy 97.706023 -253.886952) (xy 97.755386 -253.894771) (xy 97.802918 -253.910215)
			(xy 97.84745 -253.932905) (xy 97.887883 -253.962281) (xy 97.923223 -253.997621) (xy 97.952599 -254.038054)
			(xy 97.975289 -254.082586) (xy 97.990733 -254.130118) (xy 97.998552 -254.179481) (xy 97.999042 -254.20447)
			(xy 97.998552 -254.229459) (xy 97.990733 -254.278822) (xy 97.976845 -254.321564) (xy 99.139248 -254.321564)
			(xy 99.139248 -253.813564) (xy 99.139591 -253.803534) (xy 99.147282 -253.785007) (xy 99.161478 -253.770835)
			(xy 99.180018 -253.763175) (xy 99.190048 -253.762764) (xy 99.403916 -253.762764) (xy 99.403916 -253.75362)
			(xy 99.404337 -253.743598) (xy 99.412003 -253.725079) (xy 99.426175 -253.710905) (xy 99.444694 -253.703237)
			(xy 99.454716 -253.70282) (xy 99.658932 -253.70282) (xy 99.679978 -253.703295) (xy 99.721255 -253.711542)
			(xy 99.760118 -253.727712) (xy 99.795063 -253.751177) (xy 99.824738 -253.781031) (xy 99.847993 -253.816116)
			(xy 99.863929 -253.855076) (xy 99.871928 -253.896401) (xy 99.872292 -253.91745) (xy 99.872292 -253.917958)
			(xy 99.872292 -254.137922) (xy 99.873054 -254.142748) (xy 99.8759 -254.15802) (xy 99.878951 -254.188937)
			(xy 99.87915 -254.20447) (xy 99.87859 -254.229456) (xy 99.870778 -254.278814) (xy 99.85534 -254.326342)
			(xy 99.832658 -254.370871) (xy 99.803289 -254.411302) (xy 99.767957 -254.446642) (xy 99.727532 -254.47602)
			(xy 99.683009 -254.498713) (xy 99.635484 -254.514161) (xy 99.586128 -254.521985) (xy 99.561142 -254.522478)
			(xy 99.536301 -254.522016) (xy 99.487221 -254.514301) (xy 99.439938 -254.499051) (xy 99.395599 -254.476638)
			(xy 99.355282 -254.447605) (xy 99.319968 -254.41266) (xy 99.304856 -254.392938) (xy 99.297222 -254.383741)
			(xy 99.275897 -254.373009) (xy 99.263962 -254.372364) (xy 99.190048 -254.372364) (xy 99.180025 -254.37194)
			(xy 99.161503 -254.364279) (xy 99.147327 -254.350108) (xy 99.139662 -254.331587) (xy 99.139248 -254.321564)
			(xy 97.976845 -254.321564) (xy 97.975289 -254.326354) (xy 97.952599 -254.370886) (xy 97.923223 -254.411319)
			(xy 97.887883 -254.446659) (xy 97.84745 -254.476035) (xy 97.802918 -254.498725) (xy 97.755386 -254.514169)
			(xy 97.706023 -254.521988) (xy 97.656045 -254.521988) (xy 97.606682 -254.514169) (xy 97.55915 -254.498725)
			(xy 97.514618 -254.476035) (xy 97.474185 -254.446659) (xy 97.438845 -254.411319) (xy 97.409469 -254.370886)
			(xy 97.386779 -254.326354) (xy 97.371335 -254.278822) (xy 97.363516 -254.229459) (xy 96.367854 -254.229459)
			(xy 96.367854 -254.676656) (xy 96.368102 -254.68407) (xy 96.372353 -254.698276) (xy 96.376236 -254.704596)
			(xy 96.380046 -254.710438) (xy 96.390968 -254.719836) (xy 96.397826 -254.722884) (xy 96.420221 -254.733111)
			(xy 96.461815 -254.759446) (xy 96.498853 -254.791877) (xy 96.530449 -254.829631) (xy 96.555848 -254.871803)
			(xy 96.574442 -254.917387) (xy 96.585788 -254.965292) (xy 96.589613 -255.014374) (xy 96.589586 -255.01473)
			(xy 97.832926 -255.01473) (xy 97.832926 -255.014476) (xy 97.833288 -254.993289) (xy 97.838947 -254.951295)
			(xy 97.850135 -254.910425) (xy 97.858072 -254.890778) (xy 97.862136 -254.881126) (xy 97.862136 -254.806958)
			(xy 97.861882 -254.806704) (xy 97.862166 -254.785636) (xy 97.870132 -254.744266) (xy 97.88605 -254.705258)
			(xy 97.909305 -254.670127) (xy 97.938993 -254.640234) (xy 97.973964 -254.61674) (xy 98.012862 -254.600554)
			(xy 98.054177 -254.592306) (xy 98.075242 -254.59182) (xy 98.330004 -254.59182) (xy 98.330004 -254.600964)
			(xy 98.330449 -254.610983) (xy 98.338108 -254.6295) (xy 98.352273 -254.643674) (xy 98.370785 -254.651344)
			(xy 98.380804 -254.651764) (xy 98.54438 -254.651764) (xy 98.554382 -254.652303) (xy 98.572866 -254.65995)
			(xy 98.587019 -254.674087) (xy 98.594686 -254.692563) (xy 98.59518 -254.702564) (xy 98.59518 -255.039465)
			(xy 99.713524 -255.039465) (xy 99.713524 -254.989487) (xy 99.721343 -254.940124) (xy 99.736787 -254.892592)
			(xy 99.759477 -254.84806) (xy 99.788853 -254.807627) (xy 99.824193 -254.772287) (xy 99.864626 -254.742911)
			(xy 99.909158 -254.720221) (xy 99.95669 -254.704777) (xy 100.006053 -254.696958) (xy 100.056031 -254.696958)
			(xy 100.105394 -254.704777) (xy 100.152926 -254.720221) (xy 100.197458 -254.742911) (xy 100.237891 -254.772287)
			(xy 100.273231 -254.807627) (xy 100.302607 -254.84806) (xy 100.325297 -254.892592) (xy 100.340741 -254.940124)
			(xy 100.34856 -254.989487) (xy 100.34905 -255.014476) (xy 100.34856 -255.039465) (xy 100.340741 -255.088828)
			(xy 100.325297 -255.13636) (xy 100.302607 -255.180892) (xy 100.273231 -255.221325) (xy 100.237891 -255.256665)
			(xy 100.197458 -255.286041) (xy 100.152926 -255.308731) (xy 100.105394 -255.324175) (xy 100.056031 -255.331994)
			(xy 100.006053 -255.331994) (xy 99.95669 -255.324175) (xy 99.909158 -255.308731) (xy 99.864626 -255.286041)
			(xy 99.824193 -255.256665) (xy 99.788853 -255.221325) (xy 99.759477 -255.180892) (xy 99.736787 -255.13636)
			(xy 99.721343 -255.088828) (xy 99.713524 -255.039465) (xy 98.59518 -255.039465) (xy 98.59518 -255.210564)
			(xy 98.59475 -255.220585) (xy 98.587089 -255.239105) (xy 98.572919 -255.25328) (xy 98.554401 -255.260947)
			(xy 98.54438 -255.261364) (xy 98.368612 -255.261364) (xy 98.360659 -255.261707) (xy 98.345526 -255.266614)
			(xy 98.338894 -255.271016) (xy 98.330004 -255.277112) (xy 98.330004 -255.29159) (xy 98.300286 -255.321308)
			(xy 98.235262 -255.321308) (xy 98.229166 -255.322832) (xy 98.20993 -255.327381) (xy 98.170699 -255.332218)
			(xy 98.150934 -255.332484) (xy 98.130709 -255.332182) (xy 98.090582 -255.32709) (xy 98.070924 -255.322324)
			(xy 98.061272 -255.3208) (xy 98.039464 -255.318834) (xy 97.997273 -255.307147) (xy 97.95835 -255.287103)
			(xy 97.924331 -255.259546) (xy 97.896644 -255.225633) (xy 97.876452 -255.186787) (xy 97.87001 -255.16586)
			(xy 97.866454 -255.15697) (xy 97.855892 -255.134761) (xy 97.840958 -255.087908) (xy 97.833391 -255.039318)
			(xy 97.832926 -255.01473) (xy 96.589586 -255.01473) (xy 96.585827 -255.063458) (xy 96.574519 -255.111372)
			(xy 96.555961 -255.156971) (xy 96.530596 -255.199164) (xy 96.49903 -255.236942) (xy 96.462017 -255.269403)
			(xy 96.420444 -255.295771) (xy 96.39808 -255.306068) (xy 96.397826 -255.306068) (xy 96.393508 -255.3081)
			(xy 96.390968 -255.309116) (xy 96.380046 -255.318514) (xy 96.376236 -255.324356) (xy 96.372373 -255.330686)
			(xy 96.36812 -255.344885) (xy 96.367854 -255.352296) (xy 96.367854 -255.911858) (xy 96.368369 -255.921609)
			(xy 96.375815 -255.939639) (xy 96.382332 -255.94691) (xy 96.480376 -256.044954) (xy 96.487624 -256.051507)
			(xy 96.505668 -256.058955) (xy 96.515428 -256.059432)
		)
		(stroke
			(width 0)
			(type solid)
		)
		(fill yes)
		(layer "B.Cu")
		(net "PVDD18_S5_P1")
	)
	(gr_poly
		(pts
			(xy 182.644034 -118.596156) (xy 182.653876 -118.595628) (xy 182.672051 -118.588056) (xy 182.67934 -118.581424)
			(xy 182.784496 -118.476268) (xy 182.791051 -118.46902) (xy 182.798509 -118.450977) (xy 182.798974 -118.441216)
			(xy 182.793386 -118.418356) (xy 182.790846 -118.413276) (xy 182.786092 -118.403462) (xy 182.777581 -118.383383)
			(xy 182.773828 -118.373144) (xy 182.763156 -118.341631) (xy 182.751652 -118.276106) (xy 182.750968 -118.242842)
			(xy 182.751532 -118.212622) (xy 182.761036 -118.152934) (xy 182.77983 -118.095491) (xy 182.807442 -118.041728)
			(xy 182.843184 -117.992989) (xy 182.864252 -117.971316) (xy 182.924196 -117.911372) (xy 182.927632 -117.907756)
			(xy 182.933137 -117.89944) (xy 182.935118 -117.894862) (xy 182.938928 -117.885972) (xy 182.938928 -117.77091)
			(xy 182.939468 -117.761075) (xy 182.947063 -117.742921) (xy 182.95366 -117.735604) (xy 182.987696 -117.701568)
			(xy 182.994934 -117.694854) (xy 183.013139 -117.687258) (xy 183.023002 -117.686836) (xy 183.127904 -117.686836)
			(xy 183.132924 -117.686748) (xy 183.14278 -117.684838) (xy 183.147462 -117.683026) (xy 183.156352 -117.679216)
			(xy 183.262524 -117.573044) (xy 183.284137 -117.55226) (xy 183.33264 -117.517014) (xy 183.386058 -117.489785)
			(xy 183.443077 -117.471245) (xy 183.502293 -117.461849) (xy 183.532272 -117.461284) (xy 183.532526 -117.461284)
			(xy 183.558297 -117.461711) (xy 183.609368 -117.468659) (xy 183.659038 -117.482425) (xy 183.706399 -117.502758)
			(xy 183.75059 -117.529287) (xy 183.790802 -117.561528) (xy 183.808878 -117.579902) (xy 183.809386 -117.58041)
			(xy 184.110884 -117.882162) (xy 184.20207 -117.973094) (xy 184.20588 -117.977158) (xy 184.265824 -118.037102)
			(xy 184.273019 -118.043623) (xy 184.290926 -118.05108) (xy 184.300622 -118.05158) (xy 184.363614 -118.05158)
			(xy 184.373456 -118.051054) (xy 184.391629 -118.043479) (xy 184.39892 -118.036848) (xy 184.45988 -117.975634)
			(xy 184.46242 -117.973094) (xy 184.483997 -117.952323) (xy 184.532466 -117.917141) (xy 184.585841 -117.889977)
			(xy 184.64281 -117.871499) (xy 184.701968 -117.862161) (xy 184.731914 -117.861588) (xy 184.732676 -117.861588)
			(xy 184.762594 -117.862192) (xy 184.82169 -117.871574) (xy 184.878597 -117.890064) (xy 184.931921 -117.91721)
			(xy 184.980355 -117.952345) (xy 185.001916 -117.973094) (xy 185.06948 -118.040658) (xy 185.076729 -118.04721)
			(xy 185.094772 -118.054656) (xy 185.104532 -118.055136) (xy 185.368438 -118.055136) (xy 185.370724 -118.05158)
			(xy 185.546492 -118.05158) (xy 185.548778 -118.055136) (xy 185.93943 -118.055136) (xy 185.94445 -118.055046)
			(xy 185.954303 -118.053131) (xy 185.958988 -118.051326) (xy 185.967878 -118.047516) (xy 186.442096 -117.573298)
			(xy 186.458207 -117.557671) (xy 186.493475 -117.529908) (xy 186.512454 -117.517926) (xy 186.537346 -117.503956)
			(xy 186.5376 -117.503702) (xy 186.543675 -117.50036) (xy 186.553854 -117.490952) (xy 186.557666 -117.48516)
			(xy 186.561222 -117.479572) (xy 186.565032 -117.466872) (xy 186.565032 -117.342412) (xy 186.568588 -117.33657)
			(xy 186.568842 -117.336316) (xy 186.57189 -117.33149) (xy 186.572652 -117.33022) (xy 186.572906 -117.329966)
			(xy 186.608974 -117.27434) (xy 186.609228 -117.273832) (xy 186.609736 -117.27307) (xy 186.612276 -117.269006)
			(xy 186.612784 -117.268498) (xy 186.612784 -117.268244) (xy 186.623706 -117.25148) (xy 186.706764 -117.25148)
			(xy 186.708288 -117.249956) (xy 186.756548 -117.249956) (xy 186.758072 -117.25148) (xy 186.799982 -117.25148)
			(xy 186.807602 -117.263672) (xy 186.807856 -117.263672) (xy 186.812174 -117.270276) (xy 186.812936 -117.271546)
			(xy 186.813698 -117.272562) (xy 186.813952 -117.272816) (xy 186.815222 -117.274848) (xy 186.815984 -117.276118)
			(xy 186.816492 -117.27688) (xy 186.850782 -117.329966) (xy 186.852306 -117.332506) (xy 186.853322 -117.334284)
			(xy 186.858656 -117.342412) (xy 186.858656 -117.444774) (xy 186.858874 -117.451815) (xy 186.862735 -117.465355)
			(xy 186.866276 -117.471444) (xy 186.882532 -117.49786) (xy 186.891422 -117.506242) (xy 186.89701 -117.509544)
			(xy 186.900566 -117.511322) (xy 186.90209 -117.512338) (xy 186.911234 -117.517926) (xy 186.911742 -117.517926)
			(xy 186.930649 -117.529926) (xy 186.965795 -117.557682) (xy 186.981846 -117.573298) (xy 187.052966 -117.644418)
			(xy 187.060212 -117.650977) (xy 187.078256 -117.658434) (xy 187.088018 -117.658896) (xy 187.135516 -117.658896)
			(xy 187.140536 -117.658807) (xy 187.15039 -117.656893) (xy 187.155074 -117.655086) (xy 187.163964 -117.651276)
			(xy 187.241942 -117.573298) (xy 187.251886 -117.563547) (xy 187.27299 -117.545367) (xy 187.284106 -117.536976)
			(xy 187.287154 -117.53469) (xy 187.3504 -117.471444) (xy 187.356339 -117.465131) (xy 187.363882 -117.44954)
			(xy 187.365132 -117.440964) (xy 187.365132 -117.342412) (xy 187.368688 -117.33657) (xy 187.368942 -117.336316)
			(xy 187.37199 -117.33149) (xy 187.372752 -117.33022) (xy 187.373006 -117.329966) (xy 187.409074 -117.27434)
			(xy 187.409328 -117.273832) (xy 187.409836 -117.27307) (xy 187.412376 -117.269006) (xy 187.412884 -117.268498)
			(xy 187.412884 -117.268244) (xy 187.423806 -117.25148) (xy 187.600082 -117.25148) (xy 187.607702 -117.263672)
			(xy 187.607956 -117.263672) (xy 187.612274 -117.270276) (xy 187.613036 -117.271546) (xy 187.613798 -117.272562)
			(xy 187.614052 -117.272816) (xy 187.615322 -117.274848) (xy 187.616084 -117.276118) (xy 187.616592 -117.27688)
			(xy 187.650882 -117.329966) (xy 187.652406 -117.332506) (xy 187.653422 -117.334284) (xy 187.658756 -117.342412)
			(xy 187.658756 -117.43309) (xy 187.659276 -117.442838) (xy 187.666731 -117.46086) (xy 187.673234 -117.468142)
			(xy 187.676028 -117.470936) (xy 187.676028 -117.498622) (xy 187.705172 -117.513198) (xy 187.758426 -117.550745)
			(xy 187.781946 -117.573298) (xy 188.181742 -117.973094) (xy 188.202535 -117.994688) (xy 188.237748 -118.0432)
			(xy 188.26493 -118.096628) (xy 188.283408 -118.153653) (xy 188.292727 -118.212869) (xy 188.293248 -118.242842)
			(xy 188.292923 -118.266595) (xy 188.287086 -118.313739) (xy 188.27542 -118.359789) (xy 188.267086 -118.382034)
			(xy 188.266832 -118.382542) (xy 188.26439 -118.389579) (xy 188.263226 -118.404422) (xy 188.264546 -118.411752)
			(xy 188.265816 -118.418102) (xy 188.272674 -118.430802) (xy 188.42355 -118.581678) (xy 188.430798 -118.588233)
			(xy 188.448841 -118.595686) (xy 188.458602 -118.596156) (xy 188.859414 -118.596156) (xy 188.869257 -118.595631)
			(xy 188.887438 -118.588065) (xy 188.89472 -118.581424) (xy 189.030356 -118.445788) (xy 189.037064 -118.438548)
			(xy 189.044652 -118.420343) (xy 189.045088 -118.410482) (xy 189.045088 -117.97919) (xy 189.04458 -117.969437)
			(xy 189.03714 -117.951399) (xy 189.03061 -117.944138) (xy 188.952886 -117.866414) (xy 188.945639 -117.859855)
			(xy 188.927597 -117.852389) (xy 188.917834 -117.851936) (xy 188.608462 -117.851936) (xy 188.598621 -117.851407)
			(xy 188.580448 -117.843832) (xy 188.573156 -117.837204) (xy 188.485526 -117.749574) (xy 188.482478 -117.747288)
			(xy 188.461527 -117.730911) (xy 188.42393 -117.693305) (xy 188.407548 -117.672358) (xy 188.405262 -117.66931)
			(xy 188.404246 -117.668294) (xy 188.397896 -117.65915) (xy 188.397896 -117.658642) (xy 188.382086 -117.634716)
			(xy 188.357055 -117.58312) (xy 188.340028 -117.52836) (xy 188.331387 -117.471669) (xy 188.33084 -117.442996)
			(xy 188.33084 -116.642134) (xy 188.331441 -116.611966) (xy 188.340994 -116.55239) (xy 188.359804 -116.495061)
			(xy 188.387403 -116.441406) (xy 188.423102 -116.392763) (xy 188.444124 -116.371116) (xy 188.504576 -116.310664)
			(xy 188.508012 -116.307048) (xy 188.513519 -116.298732) (xy 188.515498 -116.294154) (xy 188.519308 -116.285264)
			(xy 188.519308 -116.21008) (xy 188.518781 -116.200238) (xy 188.511208 -116.182063) (xy 188.504576 -116.174774)
			(xy 188.444124 -116.114322) (xy 188.423028 -116.092673) (xy 188.387271 -116.04394) (xy 188.359657 -115.990172)
			(xy 188.340882 -115.932717) (xy 188.331415 -115.873019) (xy 188.33084 -115.842796) (xy 188.331411 -115.812828)
			(xy 188.340752 -115.753626) (xy 188.359234 -115.696612) (xy 188.386403 -115.64319) (xy 188.42159 -115.594672)
			(xy 188.442346 -115.573048) (xy 188.502036 -115.513358) (xy 188.505469 -115.50974) (xy 188.510968 -115.501421)
			(xy 188.512958 -115.496848) (xy 188.516768 -115.487958) (xy 188.516768 -114.62766) (xy 188.516237 -114.617821)
			(xy 188.508654 -114.599655) (xy 188.502036 -114.592354) (xy 188.442346 -114.532664) (xy 188.421551 -114.51107)
			(xy 188.386331 -114.46256) (xy 188.359142 -114.409133) (xy 188.340656 -114.352107) (xy 188.331328 -114.29289)
			(xy 188.33084 -114.262916) (xy 188.331398 -114.232694) (xy 188.340892 -114.172999) (xy 188.359676 -114.115548)
			(xy 188.38728 -114.061775) (xy 188.423015 -114.013025) (xy 188.444124 -113.99139) (xy 188.504576 -113.930938)
			(xy 188.508011 -113.927321) (xy 188.513513 -113.919004) (xy 188.515498 -113.914428) (xy 188.519308 -113.905538)
			(xy 188.519308 -113.8301) (xy 188.518785 -113.820354) (xy 188.511324 -113.802337) (xy 188.50483 -113.795048)
			(xy 188.449966 -113.740184) (xy 188.44895 -113.739168) (xy 188.43065 -113.721132) (xy 188.39857 -113.680996)
			(xy 188.372169 -113.636917) (xy 188.351924 -113.589692) (xy 188.338203 -113.540177) (xy 188.331255 -113.489268)
			(xy 188.33084 -113.463578) (xy 188.33084 -112.674146) (xy 188.330586 -112.66297) (xy 188.331067 -112.635407)
			(xy 188.338995 -112.580856) (xy 188.354695 -112.528014) (xy 188.377841 -112.477983) (xy 188.40795 -112.431807)
			(xy 188.444394 -112.390448) (xy 188.486414 -112.354768) (xy 188.533133 -112.32551) (xy 188.55817 -112.313974)
			(xy 188.56706 -112.310164) (xy 188.580776 -112.296448) (xy 188.588014 -112.289734) (xy 188.606218 -112.282133)
			(xy 188.616082 -112.281716) (xy 188.925454 -112.281716) (xy 188.935293 -112.281183) (xy 188.95346 -112.273602)
			(xy 188.96076 -112.266984) (xy 189.073536 -112.154208) (xy 189.08025 -112.14697) (xy 189.087847 -112.128765)
			(xy 189.088268 -112.118902) (xy 189.088268 -111.65713) (xy 189.087752 -111.64738) (xy 189.080305 -111.62935)
			(xy 189.07379 -111.622078) (xy 188.952886 -111.501174) (xy 188.945642 -111.494608) (xy 188.927599 -111.487133)
			(xy 188.917834 -111.486696) (xy 188.517022 -111.486696) (xy 188.507185 -111.487234) (xy 188.489026 -111.494822)
			(xy 188.481716 -111.501428) (xy 188.33338 -111.649764) (xy 188.32666 -111.657) (xy 188.31905 -111.675205)
			(xy 188.318648 -111.68507) (xy 188.318648 -111.996982) (xy 188.318111 -112.006819) (xy 188.310526 -112.024982)
			(xy 188.303916 -112.032288) (xy 188.18606 -112.150144) (xy 188.182505 -112.153566) (xy 188.174317 -112.159071)
			(xy 188.169804 -112.161066) (xy 188.16066 -112.164876) (xy 188.153548 -112.164876) (xy 188.13907 -112.169448)
			(xy 188.132212 -112.174274) (xy 188.107922 -112.190767) (xy 188.055339 -112.216884) (xy 187.999374 -112.23463)
			(xy 187.94135 -112.243585) (xy 187.911994 -112.244124) (xy 187.882027 -112.243552) (xy 187.822825 -112.234211)
			(xy 187.765813 -112.215727) (xy 187.712392 -112.188556) (xy 187.663877 -112.153366) (xy 187.642246 -112.132618)
			(xy 187.624466 -112.114584) (xy 187.617436 -112.108845) (xy 187.60051 -112.10234) (xy 187.591446 -112.101884)
			(xy 187.43295 -112.101884) (xy 187.427931 -112.101976) (xy 187.418079 -112.103895) (xy 187.413392 -112.105694)
			(xy 187.404502 -112.109504) (xy 187.381642 -112.132618) (xy 187.376308 -112.137698) (xy 187.317888 -112.196118)
			(xy 187.311948 -112.20243) (xy 187.304411 -112.218022) (xy 187.303156 -112.226598) (xy 187.303156 -112.351312)
			(xy 187.280804 -112.36579) (xy 187.280042 -112.366298) (xy 187.236354 -112.394492) (xy 187.224924 -112.401858)
			(xy 187.22467 -112.401858) (xy 187.212478 -112.409732) (xy 187.120022 -112.409732) (xy 187.111458 -112.411021)
			(xy 187.09588 -112.418561) (xy 187.089542 -112.424464) (xy 186.99226 -112.522) (xy 186.988704 -112.525556)
			(xy 186.966914 -112.547718) (xy 186.917453 -112.585348) (xy 186.86253 -112.61443) (xy 186.833256 -112.62487)
			(xy 186.803826 -112.634129) (xy 186.742944 -112.644092) (xy 186.712098 -112.644682) (xy 186.711844 -112.644682)
			(xy 186.679854 -112.644014) (xy 186.616778 -112.633295) (xy 186.586368 -112.623346) (xy 186.556993 -112.612435)
			(xy 186.501986 -112.582429) (xy 186.452607 -112.543857) (xy 186.43092 -112.521238) (xy 186.429396 -112.519714)
			(xy 186.13247 -112.222788) (xy 186.125231 -112.216078) (xy 186.107026 -112.20849) (xy 186.097164 -112.208056)
			(xy 185.64352 -112.208056) (xy 185.63717 -112.208564) (xy 185.625232 -112.20958) (xy 185.618628 -112.212628)
			(xy 185.593548 -112.223681) (xy 185.541008 -112.23928) (xy 185.486773 -112.24718) (xy 185.45937 -112.24768)
			(xy 184.735216 -112.24768) (xy 184.705299 -112.247075) (xy 184.646204 -112.237692) (xy 184.589298 -112.219199)
			(xy 184.535976 -112.192051) (xy 184.487545 -112.156914) (xy 184.465976 -112.136174) (xy 184.46242 -112.132618)
			(xy 184.453186 -112.123182) (xy 184.435897 -112.103226) (xy 184.427876 -112.09274) (xy 184.42686 -112.091724)
			(xy 184.425082 -112.08893) (xy 184.423558 -112.086898) (xy 184.422542 -112.085628) (xy 184.416446 -112.077246)
			(xy 184.386728 -112.061498) (xy 184.381143 -112.058764) (xy 184.369068 -112.055806) (xy 184.362852 -112.055656)
			(xy 184.29986 -112.055656) (xy 184.294841 -112.055747) (xy 184.284987 -112.057664) (xy 184.280302 -112.059466)
			(xy 184.271412 -112.063276) (xy 184.203848 -112.13084) (xy 184.182239 -112.151906) (xy 184.133599 -112.187623)
			(xy 184.079936 -112.215225) (xy 184.022592 -112.23402) (xy 183.963003 -112.24354) (xy 183.93283 -112.244124)
			(xy 183.932322 -112.244124) (xy 183.905941 -112.243679) (xy 183.853682 -112.236412) (xy 183.802922 -112.222013)
			(xy 183.754631 -112.200757) (xy 183.70973 -112.173049) (xy 183.669074 -112.139419) (xy 183.633441 -112.100507)
			(xy 183.618124 -112.079024) (xy 183.615838 -112.075722) (xy 183.604916 -112.064292) (xy 183.599836 -112.06099)
			(xy 183.599328 -112.060736) (xy 183.593573 -112.057656) (xy 183.580961 -112.054315) (xy 183.574436 -112.054132)
			(xy 183.500776 -112.054132) (xy 183.490935 -112.05466) (xy 183.472765 -112.062239) (xy 183.46547 -112.068864)
			(xy 183.40451 -112.130078) (xy 183.40197 -112.132618) (xy 183.380392 -112.153388) (xy 183.331923 -112.188567)
			(xy 183.278547 -112.215729) (xy 183.221579 -112.234205) (xy 183.162421 -112.243541) (xy 183.132476 -112.244124)
			(xy 183.131968 -112.244124) (xy 183.102026 -112.243537) (xy 183.042877 -112.234175) (xy 182.985917 -112.215688)
			(xy 182.932546 -112.188528) (xy 182.884073 -112.153363) (xy 182.862474 -112.132618) (xy 182.859934 -112.130078)
			(xy 182.798212 -112.068102) (xy 182.79106 -112.061988) (xy 182.773575 -112.055073) (xy 182.764176 -112.05464)
			(xy 182.644034 -112.05464) (xy 182.636414 -112.042448) (xy 182.63616 -112.042448) (xy 182.631842 -112.035844)
			(xy 182.63108 -112.034574) (xy 182.630318 -112.033558) (xy 182.630064 -112.033304) (xy 182.628794 -112.031272)
			(xy 182.628032 -112.030002) (xy 182.627524 -112.02924) (xy 182.593234 -111.976154) (xy 182.59171 -111.973614)
			(xy 182.590694 -111.971836) (xy 182.58536 -111.963708) (xy 182.58536 -111.875824) (xy 182.584899 -111.866339)
			(xy 182.577851 -111.848721) (xy 182.571644 -111.841534) (xy 182.470806 -111.74095) (xy 182.469282 -111.739426)
			(xy 182.44927 -111.71969) (xy 182.414673 -111.675395) (xy 182.386934 -111.626513) (xy 182.376318 -111.600488)
			(xy 182.373524 -111.593122) (xy 182.368444 -111.586772) (xy 182.360989 -111.578268) (xy 182.340626 -111.568478)
			(xy 182.329328 -111.567976) (xy 182.134002 -111.567976) (xy 182.124166 -111.568516) (xy 182.10601 -111.576108)
			(xy 182.098696 -111.582708) (xy 181.95798 -111.723424) (xy 181.95127 -111.730663) (xy 181.943681 -111.748868)
			(xy 181.943248 -111.75873) (xy 181.943248 -112.042702) (xy 181.94377 -112.052449) (xy 181.951227 -112.070469)
			(xy 181.957726 -112.077754) (xy 182.166768 -112.286796) (xy 182.1712 -112.290956) (xy 182.181602 -112.29724)
			(xy 182.187342 -112.299242) (xy 182.217314 -112.299242) (xy 182.224172 -112.29721) (xy 182.250376 -112.289974)
			(xy 182.304179 -112.282203) (xy 182.33136 -112.281716) (xy 182.332122 -112.281716) (xy 182.359355 -112.282203)
			(xy 182.413266 -112.289957) (xy 182.465525 -112.305303) (xy 182.515068 -112.32793) (xy 182.560887 -112.357377)
			(xy 182.60205 -112.393044) (xy 182.637718 -112.434206) (xy 182.667166 -112.480025) (xy 182.689794 -112.529568)
			(xy 182.705141 -112.581826) (xy 182.712896 -112.635737) (xy 182.713376 -112.66297) (xy 182.713376 -112.663224)
			(xy 182.712803 -112.693191) (xy 182.70346 -112.752392) (xy 182.684977 -112.809404) (xy 182.657807 -112.862826)
			(xy 182.622619 -112.911342) (xy 182.60187 -112.932972) (xy 182.1307 -113.404142) (xy 182.12399 -113.411381)
			(xy 182.116405 -113.429586) (xy 182.115968 -113.439448) (xy 182.115968 -113.486692) (xy 182.116489 -113.49644)
			(xy 182.123945 -113.51446) (xy 182.130446 -113.521744) (xy 182.195216 -113.586514) (xy 182.196232 -113.58753)
			(xy 182.209694 -113.600992) (xy 182.210202 -113.6015) (xy 182.310532 -113.702084) (xy 182.317693 -113.708332)
			(xy 182.335327 -113.715374) (xy 182.344822 -113.7158) (xy 182.43296 -113.7158) (xy 182.438802 -113.71961)
			(xy 182.43931 -113.719864) (xy 182.441088 -113.721134) (xy 182.444136 -113.723166) (xy 182.444644 -113.72342)
			(xy 182.445406 -113.723928) (xy 182.501032 -113.759996) (xy 182.50154 -113.76025) (xy 182.502302 -113.760758)
			(xy 182.506366 -113.763298) (xy 182.506874 -113.763806) (xy 182.507128 -113.763806) (xy 182.523892 -113.774728)
			(xy 182.523892 -113.89487) (xy 182.524276 -113.904281) (xy 182.531189 -113.921786) (xy 182.537354 -113.928906)
			(xy 182.59933 -113.990628) (xy 182.60187 -113.993168) (xy 182.622646 -114.014743) (xy 182.657837 -114.063209)
			(xy 182.685011 -114.116584) (xy 182.703499 -114.173554) (xy 182.712846 -114.232715) (xy 182.713376 -114.262662)
			(xy 182.713376 -114.262916) (xy 182.7131 -114.285805) (xy 182.707756 -114.331267) (xy 182.702708 -114.353594)
			(xy 182.694705 -114.383784) (xy 182.670201 -114.441229) (xy 182.65394 -114.467894) (xy 182.650384 -114.473482)
			(xy 182.644034 -114.493294) (xy 182.642957 -114.496946) (xy 182.641807 -114.504473) (xy 182.641748 -114.50828)
			(xy 182.641748 -114.704622) (xy 182.641222 -114.714464) (xy 182.633652 -114.732642) (xy 182.627016 -114.739928)
			(xy 182.5371 -114.829844) (xy 182.530391 -114.837083) (xy 182.522806 -114.855289) (xy 182.522368 -114.86515)
			(xy 182.522368 -114.93373) (xy 182.523384 -114.934492) (xy 182.523384 -115.11026) (xy 182.522368 -115.111022)
			(xy 182.522368 -115.472972) (xy 182.522885 -115.482721) (xy 182.530337 -115.500747) (xy 182.536846 -115.508024)
			(xy 182.60187 -115.573048) (xy 182.610015 -115.581329) (xy 182.625393 -115.59874) (xy 182.632604 -115.607846)
			(xy 182.65267 -115.636294) (xy 182.655718 -115.640866) (xy 182.659528 -115.644676) (xy 182.659528 -115.646708)
			(xy 182.665878 -115.658138) (xy 182.680771 -115.686435) (xy 182.701915 -115.74678) (xy 182.712674 -115.80981)
			(xy 182.713376 -115.84178) (xy 182.713376 -115.842796) (xy 182.713376 -115.843304) (xy 182.712783 -115.873245)
			(xy 182.703413 -115.932388) (xy 182.684919 -115.989342) (xy 182.657756 -116.042708) (xy 182.62259 -116.091176)
			(xy 182.60187 -116.112798) (xy 182.538624 -116.17579) (xy 182.531903 -116.183025) (xy 182.524296 -116.20123)
			(xy 182.523892 -116.211096) (xy 182.523892 -116.330984) (xy 182.507128 -116.341652) (xy 182.503318 -116.344192)
			(xy 182.502556 -116.3447) (xy 182.502048 -116.345208) (xy 182.501286 -116.345716) (xy 182.501032 -116.345716)
			(xy 182.471568 -116.364512) (xy 182.458106 -116.373148) (xy 182.456836 -116.374164) (xy 182.445406 -116.38153)
			(xy 182.445152 -116.38153) (xy 182.43296 -116.389404) (xy 182.340758 -116.389404) (xy 182.332191 -116.390687)
			(xy 182.316602 -116.398216) (xy 182.310278 -116.404136) (xy 182.202074 -116.512594) (xy 182.195724 -116.51869)
			(xy 182.17388 -116.540534) (xy 182.167171 -116.547774) (xy 182.159586 -116.565979) (xy 182.159148 -116.57584)
			(xy 182.159148 -116.642642) (xy 183.551068 -116.642642) (xy 183.551068 -116.523516) (xy 183.551668 -116.493598)
			(xy 183.561034 -116.434499) (xy 183.579524 -116.37759) (xy 183.606682 -116.324271) (xy 183.641841 -116.275853)
			(xy 183.662574 -116.254276) (xy 183.697626 -116.219478) (xy 183.70446 -116.212069) (xy 183.7122 -116.193477)
			(xy 183.712203 -116.173337) (xy 183.704468 -116.154743) (xy 183.697626 -116.147342) (xy 183.662574 -116.112544)
			(xy 183.641852 -116.090958) (xy 183.60671 -116.042532) (xy 183.579558 -115.989215) (xy 183.561062 -115.932312)
			(xy 183.551675 -115.87322) (xy 183.551068 -115.843304) (xy 183.551068 -115.842796) (xy 183.551573 -115.815557)
			(xy 183.559323 -115.761634) (xy 183.574665 -115.709361) (xy 183.597286 -115.659802) (xy 183.626727 -115.613965)
			(xy 183.662389 -115.572783) (xy 183.703546 -115.537091) (xy 183.749362 -115.507617) (xy 183.798904 -115.48496)
			(xy 183.851166 -115.469581) (xy 183.905084 -115.461793) (xy 183.932322 -115.461288) (xy 183.959292 -115.46175)
			(xy 184.012692 -115.469359) (xy 184.064486 -115.48442) (xy 184.11364 -115.506634) (xy 184.15917 -115.535557)
			(xy 184.179972 -115.552728) (xy 184.195212 -115.565682) (xy 184.234582 -115.564158) (xy 184.248806 -115.549934)
			(xy 184.255466 -115.542504) (xy 184.26306 -115.524079) (xy 184.263066 -115.504149) (xy 184.255482 -115.485719)
			(xy 184.248806 -115.478306) (xy 184.062624 -115.292124) (xy 184.042042 -115.270735) (xy 184.007087 -115.222763)
			(xy 183.993028 -115.19662) (xy 183.986678 -115.184174) (xy 183.962294 -115.169188) (xy 183.84647 -115.169188)
			(xy 183.798464 -115.169188) (xy 183.739028 -115.109752) (xy 183.739028 -114.936778) (xy 183.799226 -114.87658)
			(xy 183.839612 -114.87658) (xy 183.846724 -114.876072) (xy 183.947816 -114.876072) (xy 183.957135 -114.875608)
			(xy 183.974539 -114.868939) (xy 183.988408 -114.85649) (xy 183.993028 -114.848386) (xy 184.007065 -114.822171)
			(xy 184.042022 -114.774071) (xy 184.062624 -114.752628) (xy 184.107328 -114.707924) (xy 184.114183 -114.700571)
			(xy 184.121919 -114.682032) (xy 184.121915 -114.661944) (xy 184.114169 -114.643409) (xy 184.107328 -114.636042)
			(xy 184.096914 -114.625628) (xy 184.068974 -114.619278) (xy 184.055004 -114.624104) (xy 184.02522 -114.63357)
			(xy 183.963567 -114.643777) (xy 183.932322 -114.644424) (xy 183.905075 -114.64397) (xy 183.851136 -114.636214)
			(xy 183.79885 -114.620857) (xy 183.749284 -114.598211) (xy 183.703448 -114.568738) (xy 183.662275 -114.53304)
			(xy 183.626604 -114.491842) (xy 183.597163 -114.445985) (xy 183.574552 -114.396404) (xy 183.55923 -114.344108)
			(xy 183.551511 -114.290163) (xy 183.551068 -114.262916) (xy 183.551596 -114.232944) (xy 183.560917 -114.173729)
			(xy 183.579395 -114.116705) (xy 183.606574 -114.063277) (xy 183.641784 -114.014764) (xy 183.662574 -113.993168)
			(xy 183.725312 -113.93043) (xy 183.732163 -113.923073) (xy 183.739903 -113.904536) (xy 183.7399 -113.884448)
			(xy 183.732154 -113.865914) (xy 183.725312 -113.858548) (xy 183.662574 -113.79581) (xy 183.641836 -113.774239)
			(xy 183.606696 -113.725809) (xy 183.579547 -113.672488) (xy 183.561055 -113.615582) (xy 183.551672 -113.556487)
			(xy 183.551068 -113.52657) (xy 183.551068 -113.46307) (xy 183.551504 -113.435835) (xy 183.55926 -113.38192)
			(xy 183.57461 -113.329658) (xy 183.597241 -113.280113) (xy 183.626693 -113.234292) (xy 183.662366 -113.193129)
			(xy 183.703533 -113.157461) (xy 183.749358 -113.128016) (xy 183.798907 -113.105391) (xy 183.851171 -113.090049)
			(xy 183.905087 -113.0823) (xy 183.932322 -113.081816) (xy 183.958927 -113.082241) (xy 184.011621 -113.089626)
			(xy 184.062778 -113.104264) (xy 184.111403 -113.12587) (xy 184.156553 -113.154026) (xy 184.197351 -113.188183)
			(xy 184.233006 -113.22768) (xy 184.248298 -113.249456) (xy 184.254816 -113.25817) (xy 184.273382 -113.269484)
			(xy 184.284112 -113.2713) (xy 184.42051 -113.2713) (xy 184.479184 -113.362232) (xy 184.479184 -113.484406)
			(xy 184.481245 -113.496751) (xy 184.495516 -113.517275) (xy 184.506362 -113.523522) (xy 184.534787 -113.538858)
			(xy 184.586503 -113.577538) (xy 184.609232 -113.600484) (xy 184.610248 -113.6015) (xy 184.890156 -113.881408)
			(xy 184.90057 -113.881408) (xy 185.18886 -113.593118) (xy 185.210251 -113.572538) (xy 185.258221 -113.537581)
			(xy 185.284364 -113.523522) (xy 185.29681 -113.517172) (xy 185.311796 -113.492788) (xy 185.311796 -113.376964)
			(xy 185.311796 -113.330482) (xy 185.37047 -113.271808) (xy 185.398156 -113.271808) (xy 185.51906 -113.271808)
			(xy 185.546492 -113.271808) (xy 185.604912 -113.330228) (xy 185.604912 -113.376964) (xy 185.604912 -113.47831)
			(xy 185.605389 -113.487627) (xy 185.612053 -113.50503) (xy 185.624497 -113.518901) (xy 185.632598 -113.523522)
			(xy 185.658811 -113.537562) (xy 185.706912 -113.572517) (xy 185.728356 -113.593118) (xy 186.00166 -113.866422)
			(xy 186.009077 -113.87324) (xy 186.027663 -113.880972) (xy 186.037728 -113.881408) (xy 186.132978 -113.881408)
			(xy 186.143049 -113.880996) (xy 186.161648 -113.873269) (xy 186.169046 -113.866422) (xy 186.433968 -113.6015)
			(xy 186.434984 -113.600484) (xy 186.457645 -113.577541) (xy 186.509227 -113.538848) (xy 186.5376 -113.523522)
			(xy 186.550046 -113.517172) (xy 186.565032 -113.492788) (xy 186.565032 -113.376964) (xy 186.565032 -113.32972)
			(xy 186.622944 -113.271808) (xy 186.651392 -113.271808) (xy 186.754008 -113.271808) (xy 186.766463 -113.271173)
			(xy 186.78844 -113.259438) (xy 186.795918 -113.249456) (xy 186.811194 -113.227672) (xy 186.846863 -113.188193)
			(xy 186.88767 -113.15405) (xy 186.932823 -113.125906) (xy 186.981447 -113.104305) (xy 187.032601 -113.089668)
			(xy 187.085291 -113.082278) (xy 187.111894 -113.081816) (xy 187.139126 -113.082337) (xy 187.193035 -113.090087)
			(xy 187.245292 -113.105429) (xy 187.294834 -113.128053) (xy 187.340653 -113.157496) (xy 187.381815 -113.19316)
			(xy 187.417483 -113.234319) (xy 187.44693 -113.280134) (xy 187.469558 -113.329674) (xy 187.484905 -113.38193)
			(xy 187.49266 -113.435838) (xy 187.493148 -113.46307) (xy 187.493148 -113.574068) (xy 187.492563 -113.603987)
			(xy 187.483196 -113.663088) (xy 187.464705 -113.719998) (xy 187.437543 -113.773316) (xy 187.402378 -113.821732)
			(xy 187.381642 -113.843308) (xy 187.342526 -113.88217) (xy 187.335639 -113.889538) (xy 187.327897 -113.908148)
			(xy 187.327908 -113.928305) (xy 187.335669 -113.946907) (xy 187.342526 -113.954306) (xy 187.381642 -113.993168)
			(xy 187.402372 -114.014746) (xy 187.437513 -114.063174) (xy 187.464663 -114.116494) (xy 187.483157 -114.173398)
			(xy 187.492542 -114.232491) (xy 187.493148 -114.262408) (xy 187.493148 -114.262916) (xy 187.492638 -114.290154)
			(xy 187.484887 -114.344077) (xy 187.469545 -114.396348) (xy 187.446923 -114.445906) (xy 187.417483 -114.491742)
			(xy 187.381821 -114.532925) (xy 187.340665 -114.568616) (xy 187.29485 -114.59809) (xy 187.245309 -114.620747)
			(xy 187.193049 -114.636128) (xy 187.139132 -114.643918) (xy 187.111894 -114.644424) (xy 187.080647 -114.643794)
			(xy 187.018994 -114.633581) (xy 186.989212 -114.624104) (xy 186.975242 -114.619278) (xy 186.947302 -114.625628)
			(xy 186.936888 -114.636042) (xy 186.930188 -114.64349) (xy 186.922548 -114.661983) (xy 186.922544 -114.681993)
			(xy 186.930175 -114.70049) (xy 186.936888 -114.707924) (xy 186.981592 -114.752628) (xy 187.002182 -114.774009)
			(xy 187.037133 -114.821986) (xy 187.051188 -114.848132) (xy 187.057538 -114.860578) (xy 187.081668 -114.875564)
			(xy 187.212478 -114.875564) (xy 187.303156 -114.934238) (xy 187.303156 -115.110514) (xy 187.212478 -115.169188)
			(xy 187.090304 -115.169188) (xy 187.07796 -115.171252) (xy 187.057435 -115.18552) (xy 187.051188 -115.196366)
			(xy 187.037158 -115.222584) (xy 187.002195 -115.270682) (xy 186.981592 -115.292124) (xy 186.887866 -115.38585)
			(xy 186.882024 -115.415822) (xy 186.887866 -115.430046) (xy 186.892135 -115.439055) (xy 186.906255 -115.453106)
			(xy 186.924645 -115.46076) (xy 186.934602 -115.461288) (xy 187.111894 -115.461288) (xy 187.139117 -115.461736)
			(xy 187.19301 -115.469482) (xy 187.245253 -115.484815) (xy 187.294783 -115.507425) (xy 187.340593 -115.536851)
			(xy 187.38175 -115.572495) (xy 187.417418 -115.613632) (xy 187.446871 -115.659425) (xy 187.469509 -115.708942)
			(xy 187.484872 -115.761176) (xy 187.492648 -115.815065) (xy 187.493148 -115.842288) (xy 187.493148 -116.642642)
			(xy 187.492662 -116.669875) (xy 187.484911 -116.723787) (xy 187.469566 -116.776047) (xy 187.44694 -116.825591)
			(xy 187.417493 -116.871411) (xy 187.381826 -116.912574) (xy 187.340663 -116.948241) (xy 187.294843 -116.977688)
			(xy 187.245299 -117.000314) (xy 187.193039 -117.015659) (xy 187.139127 -117.02341) (xy 187.084661 -117.02341)
			(xy 187.030749 -117.015659) (xy 186.978489 -117.000314) (xy 186.928945 -116.977688) (xy 186.883125 -116.948241)
			(xy 186.841962 -116.912574) (xy 186.806295 -116.871411) (xy 186.776848 -116.825591) (xy 186.754222 -116.776047)
			(xy 186.738877 -116.723787) (xy 186.731126 -116.669875) (xy 186.73064 -116.642642) (xy 186.73064 -116.275104)
			(xy 186.73011 -116.265102) (xy 186.722459 -116.246618) (xy 186.708319 -116.232466) (xy 186.689842 -116.224799)
			(xy 186.67984 -116.224304) (xy 186.037728 -116.224304) (xy 186.027657 -116.224717) (xy 186.009057 -116.232443)
			(xy 186.00166 -116.23929) (xy 185.728356 -116.512594) (xy 185.706964 -116.533173) (xy 185.658994 -116.56813)
			(xy 185.632852 -116.58219) (xy 185.620406 -116.58854) (xy 185.60542 -116.61267) (xy 185.60542 -116.74348)
			(xy 185.546746 -116.834412) (xy 185.37047 -116.834412) (xy 185.311796 -116.74348) (xy 185.311796 -116.621306)
			(xy 185.309692 -116.608973) (xy 185.295449 -116.588447) (xy 185.284618 -116.58219) (xy 185.258407 -116.568146)
			(xy 185.210305 -116.533193) (xy 185.18886 -116.512594) (xy 184.90057 -116.224304) (xy 184.89041 -116.224304)
			(xy 184.60212 -116.512594) (xy 184.580733 -116.533178) (xy 184.53276 -116.568132) (xy 184.506616 -116.58219)
			(xy 184.49417 -116.58854) (xy 184.479184 -116.61267) (xy 184.479184 -116.74348) (xy 184.42051 -116.834412)
			(xy 184.284112 -116.834412) (xy 184.273386 -116.836239) (xy 184.254827 -116.847553) (xy 184.248298 -116.856256)
			(xy 184.233015 -116.878035) (xy 184.197347 -116.917514) (xy 184.156541 -116.951657) (xy 184.111389 -116.979802)
			(xy 184.062766 -117.001402) (xy 184.011614 -117.016041) (xy 183.958925 -117.023433) (xy 183.932322 -117.023896)
			(xy 183.905091 -117.023348) (xy 183.851184 -117.015601) (xy 183.798928 -117.000261) (xy 183.749386 -116.97764)
			(xy 183.703569 -116.9482) (xy 183.662407 -116.912539) (xy 183.626738 -116.871383) (xy 183.59729 -116.82557)
			(xy 183.574662 -116.776032) (xy 183.559313 -116.723779) (xy 183.551557 -116.669873) (xy 183.551068 -116.642642)
			(xy 182.159148 -116.642642) (xy 182.159148 -116.709698) (xy 182.15967 -116.719445) (xy 182.167125 -116.737467)
			(xy 182.173626 -116.74475) (xy 182.60187 -117.172994) (xy 182.622605 -117.19457) (xy 182.657767 -117.242987)
			(xy 182.684926 -117.296306) (xy 182.703416 -117.353215) (xy 182.712781 -117.412315) (xy 182.713376 -117.442234)
			(xy 182.713376 -117.442742) (xy 182.712888 -117.469962) (xy 182.705139 -117.523848) (xy 182.689803 -117.576084)
			(xy 182.667194 -117.625608) (xy 182.63777 -117.671411) (xy 182.60213 -117.712564) (xy 182.560999 -117.748229)
			(xy 182.515213 -117.777681) (xy 182.465704 -117.800321) (xy 182.413477 -117.815689) (xy 182.359596 -117.823472)
			(xy 182.332376 -117.823996) (xy 182.331868 -117.823996) (xy 182.315612 -117.823742) (xy 182.315358 -117.823742)
			(xy 182.286551 -117.821985) (xy 182.229922 -117.81086) (xy 182.175622 -117.791312) (xy 182.150004 -117.778022)
			(xy 182.14975 -117.777768) (xy 182.142271 -117.774014) (xy 182.125814 -117.771042) (xy 182.117492 -117.771926)
			(xy 182.110634 -117.772942) (xy 182.09641 -117.780054) (xy 181.99354 -117.882924) (xy 181.986834 -117.890165)
			(xy 181.979252 -117.908369) (xy 181.978808 -117.91823) (xy 181.978808 -118.466362) (xy 181.979325 -118.476111)
			(xy 181.986778 -118.494136) (xy 181.993286 -118.501414) (xy 182.07355 -118.581678) (xy 182.080798 -118.588233)
			(xy 182.098841 -118.595686) (xy 182.108602 -118.596156)
		)
		(stroke
			(width 0)
			(type solid)
		)
		(fill yes)
		(layer "B.Cu")
		(net "GND")
	)
	(gr_poly
		(pts
			(arc
				(start 393.170664 -195.432172)
				(mid 393.189759 -195.42828)
				(end 393.20597 -195.41744)
			)
			(arc
				(start 393.369546 -195.253864)
				(mid 393.380452 -195.237681)
				(end 393.384278 -195.218558)
			)
			(arc
				(start 393.384278 -185.719212)
				(mid 393.38817 -185.700117)
				(end 393.39901 -185.683906)
			)
			(arc
				(start 393.623546 -185.45937)
				(mid 393.639729 -185.448464)
				(end 393.658852 -185.444638)
			)
			(xy 393.786614 -185.444638) (xy 393.786868 -185.444384)
			(arc
				(start 401.855178 -185.444384)
				(mid 401.874273 -185.440492)
				(end 401.890484 -185.429652)
			)
			(arc
				(start 402.066506 -185.25363)
				(mid 402.077412 -185.237447)
				(end 402.081238 -185.218324)
			)
			(arc
				(start 402.081238 -179.054252)
				(mid 402.08513 -179.035157)
				(end 402.09597 -179.018946)
			)
			(arc
				(start 402.513546 -178.60137)
				(mid 402.529729 -178.590464)
				(end 402.548852 -178.586638)
			)
			(xy 402.570696 -178.586638) (xy 402.57095 -178.586384)
			(arc
				(start 404.158958 -178.586384)
				(mid 404.178053 -178.582492)
				(end 404.194264 -178.571652)
			)
			(arc
				(start 404.488142 -178.277774)
				(mid 404.499048 -178.261591)
				(end 404.502874 -178.242468)
			)
			(arc
				(start 404.502874 -177.546254)
				(mid 404.506766 -177.527159)
				(end 404.517606 -177.510948)
			)
			(arc
				(start 405.077422 -176.951132)
				(mid 405.093605 -176.940226)
				(end 405.112728 -176.9364)
			)
			(arc
				(start 410.762704 -176.9364)
				(mid 410.781799 -176.932508)
				(end 410.79801 -176.921668)
			)
			(arc
				(start 410.895038 -176.82464)
				(mid 410.905944 -176.808457)
				(end 410.90977 -176.789334)
			)
			(xy 410.90977 -172.639228) (xy 410.910278 -172.638974)
			(arc
				(start 410.910278 -172.511212)
				(mid 410.91417 -172.492117)
				(end 410.92501 -172.475906)
			)
			(arc
				(start 411.275784 -172.125132)
				(mid 411.291967 -172.114226)
				(end 411.31109 -172.1104)
			)
			(arc
				(start 421.237156 -172.1104)
				(mid 421.256679 -172.114301)
				(end 421.273224 -172.125386)
			)
			(xy 422.912032 -173.764194)
			(arc
				(start 422.91254 -173.764702)
				(mid 422.928897 -173.775444)
				(end 422.9481 -173.77918)
			)
			(arc
				(start 425.178728 -173.77918)
				(mid 425.203871 -173.772522)
				(end 425.222416 -173.754288)
			)
			(xy 425.22267 -173.75378) (xy 425.222924 -173.753526) (xy 425.23029 -173.74362)
			(arc
				(start 426.723048 -172.250862)
				(mid 426.733954 -172.234679)
				(end 426.73778 -172.215556)
			)
			(xy 426.73778 -158.082488) (xy 426.253148 -157.597856) (xy 420.440612 -157.597856) (xy 420.42461 -157.613858)
			(xy 412.941516 -157.613858) (xy 412.492952 -158.062422) (xy 412.47314 -158.082234)
			(arc
				(start 412.47314 -159.460438)
				(mid 412.476905 -159.479629)
				(end 412.487618 -159.495998)
			)
			(xy 412.651194 -159.659574)
			(arc
				(start 412.651702 -159.660082)
				(mid 412.668059 -159.670824)
				(end 412.687262 -159.67456)
			)
			(arc
				(start 413.841438 -159.67456)
				(mid 413.860629 -159.670795)
				(end 413.876998 -159.660082)
			)
			(xy 414.24987 -159.28721)
			(arc
				(start 414.253934 -159.278066)
				(mid 414.335074 -159.158038)
				(end 414.455102 -159.076898)
			)
			(xy 414.464246 -159.072834)
			(arc
				(start 414.533334 -159.003746)
				(mid 414.549868 -158.992635)
				(end 414.569402 -158.98876)
			)
			(xy 416.275012 -158.98876)
			(arc
				(start 416.30092 -158.981648)
				(mid 416.394507 -158.942032)
				(end 416.49523 -158.928562)
			)
			(arc
				(start 416.49523 -158.928562)
				(mid 416.595938 -158.942085)
				(end 416.68954 -158.981648)
			)
			(xy 416.715448 -158.98876)
			(arc
				(start 418.051996 -158.98876)
				(mid 418.071519 -158.992661)
				(end 418.088064 -159.003746)
			)
			(arc
				(start 419.096952 -160.012634)
				(mid 419.108063 -160.029168)
				(end 419.111938 -160.048702)
			)
			(arc
				(start 419.111938 -162.99053)
				(mid 419.108037 -163.010053)
				(end 419.096952 -163.026598)
			)
			(arc
				(start 418.47262 -163.65093)
				(mid 418.456437 -163.661836)
				(end 418.437314 -163.665662)
			)
			(arc
				(start 416.725862 -163.665662)
				(mid 416.706767 -163.66177)
				(end 416.690556 -163.65093)
			)
			(xy 416.591496 -163.55187)
			(arc
				(start 416.585654 -163.548568)
				(mid 416.481108 -163.468202)
				(end 416.400742 -163.363656)
			)
			(xy 416.39744 -163.357814) (xy 416.381946 -163.34232) (xy 416.381946 -163.339018) (xy 416.37839 -163.32327)
			(xy 416.375342 -163.313872) (xy 416.374326 -163.311332)
			(arc
				(start 416.374072 -163.31057)
				(mid 416.332248 -163.104488)
				(end 416.377374 -162.89909)
			)
			(xy 416.381946 -162.88893) (xy 416.381946 -162.539934) (xy 416.37839 -162.52317) (xy 416.375342 -162.513772)
			(xy 416.374326 -162.511232)
			(arc
				(start 416.374072 -162.51047)
				(mid 416.342751 -162.411655)
				(end 416.332162 -162.30854)
			)
			(xy 416.332162 -161.675572) (xy 416.324542 -161.656776) (xy 416.317176 -161.649664)
			(arc
				(start 416.053778 -161.386266)
				(mid 416.037244 -161.375155)
				(end 416.01771 -161.37128)
			)
			(arc
				(start 414.702752 -161.37128)
				(mid 414.683657 -161.375172)
				(end 414.667446 -161.386012)
			)
			(arc
				(start 414.458658 -161.5948)
				(mid 414.447752 -161.610983)
				(end 414.443926 -161.630106)
			)
			(xy 414.443926 -163.60394) (xy 414.442402 -163.605464) (xy 414.442402 -163.62045) (xy 414.242504 -163.820348)
			(xy 414.227518 -163.820348)
			(arc
				(start 414.209738 -163.838128)
				(mid 414.193555 -163.849034)
				(end 414.174432 -163.85286)
			)
			(arc
				(start 410.57322 -163.85286)
				(mid 410.554125 -163.848968)
				(end 410.537914 -163.838128)
			)
			(arc
				(start 410.377386 -163.6776)
				(mid 410.366275 -163.661066)
				(end 410.3624 -163.641532)
			)
			(arc
				(start 410.3624 -162.847782)
				(mid 410.358499 -162.828259)
				(end 410.347414 -162.811714)
			)
			(xy 410.009086 -162.473386) (xy 410.001974 -162.46602) (xy 409.983178 -162.4584) (xy 408.66314 -162.4584)
			(xy 408.662632 -162.457892)
			(arc
				(start 404.899876 -162.457892)
				(mid 404.880781 -162.461784)
				(end 404.86457 -162.472624)
			)
			(arc
				(start 404.250906 -163.086288)
				(mid 404.24 -163.102471)
				(end 404.236174 -163.121594)
			)
			(arc
				(start 404.236174 -164.459158)
				(mid 404.239939 -164.478349)
				(end 404.250652 -164.494718)
			)
			(xy 404.277068 -164.521134)
			(arc
				(start 404.277576 -164.521642)
				(mid 404.293933 -164.532384)
				(end 404.313136 -164.53612)
			)
			(arc
				(start 405.50084 -164.53612)
				(mid 405.519935 -164.532228)
				(end 405.536146 -164.521388)
			)
			(xy 405.837136 -164.220398) (xy 405.844248 -164.206174)
			(arc
				(start 405.845518 -164.197792)
				(mid 405.973769 -163.964932)
				(end 406.222962 -163.872418)
			)
			(arc
				(start 406.222962 -163.872418)
				(mid 406.446457 -163.944736)
				(end 406.585166 -164.134292)
			)
			(xy 406.587706 -164.141912) (xy 406.596342 -164.154104)
			(arc
				(start 406.624028 -164.175186)
				(mid 406.638545 -164.18289)
				(end 406.654762 -164.1856)
			)
			(arc
				(start 407.660602 -164.1856)
				(mid 407.679793 -164.181835)
				(end 407.696162 -164.171122)
			)
			(arc
				(start 407.717498 -164.149786)
				(mid 407.727925 -164.134508)
				(end 407.73223 -164.116512)
			)
			(arc
				(start 407.73223 -164.116512)
				(mid 408.11323 -163.754809)
				(end 408.49423 -164.116512)
			)
			(arc
				(start 408.49423 -164.116512)
				(mid 408.498503 -164.134522)
				(end 408.508962 -164.149786)
			)
			(xy 408.52979 -164.170614)
			(arc
				(start 408.530298 -164.171122)
				(mid 408.546655 -164.181864)
				(end 408.565858 -164.1856)
			)
			(arc
				(start 409.550108 -164.1856)
				(mid 409.569203 -164.189492)
				(end 409.585414 -164.200332)
			)
			(arc
				(start 410.514546 -165.129464)
				(mid 410.525452 -165.145647)
				(end 410.529278 -165.16477)
			)
			(arc
				(start 410.529278 -168.279064)
				(mid 410.525386 -168.298159)
				(end 410.514546 -168.31437)
			)
			(arc
				(start 410.164788 -168.664128)
				(mid 410.148605 -168.675034)
				(end 410.129482 -168.67886)
			)
			(arc
				(start 408.53106 -168.67886)
				(mid 408.511965 -168.674968)
				(end 408.495754 -168.664128)
			)
			(xy 408.209496 -168.37787)
			(arc
				(start 408.203654 -168.374568)
				(mid 408.099108 -168.294202)
				(end 408.018742 -168.189656)
			)
			(xy 408.01544 -168.183814) (xy 407.999946 -168.16832) (xy 407.999946 -168.165018) (xy 407.99639 -168.14927)
			(xy 407.993342 -168.139872) (xy 407.992326 -168.137332)
			(arc
				(start 407.992072 -168.13657)
				(mid 407.950248 -167.930488)
				(end 407.995374 -167.72509)
			)
			(xy 407.999946 -167.71493) (xy 407.999946 -167.365934) (xy 407.99639 -167.34917) (xy 407.993342 -167.339772)
			(xy 407.992326 -167.337232)
			(arc
				(start 407.992072 -167.33647)
				(mid 407.960751 -167.237655)
				(end 407.950162 -167.13454)
			)
			(arc
				(start 407.950162 -166.579804)
				(mid 407.946261 -166.560281)
				(end 407.935176 -166.543736)
			)
			(xy 407.643838 -166.252144) (xy 407.617168 -166.223696) (xy 407.61031 -166.215568)
			(arc
				(start 407.582624 -166.20236)
				(mid 407.571861 -166.198581)
				(end 407.560526 -166.19728)
			)
			(arc
				(start 406.320752 -166.19728)
				(mid 406.301657 -166.201172)
				(end 406.285446 -166.212012)
			)
			(arc
				(start 406.087834 -166.409624)
				(mid 406.076928 -166.425807)
				(end 406.073102 -166.44493)
			)
			(arc
				(start 406.073102 -168.392602)
				(mid 406.072085 -168.402718)
				(end 406.069038 -168.412414)
			)
			(xy 406.065228 -168.421558) (xy 406.04694 -168.439846) (xy 406.04694 -168.444926)
			(arc
				(start 405.827738 -168.664128)
				(mid 405.811555 -168.675034)
				(end 405.792432 -168.67886)
			)
			(arc
				(start 401.15363 -168.67886)
				(mid 401.134535 -168.682752)
				(end 401.118324 -168.693592)
			)
			(arc
				(start 400.081496 -169.73042)
				(mid 400.065313 -169.741326)
				(end 400.04619 -169.745152)
			)
			(arc
				(start 396.165832 -169.745152)
				(mid 396.146737 -169.749044)
				(end 396.130526 -169.759884)
			)
			(arc
				(start 395.940026 -169.950384)
				(mid 395.92912 -169.966567)
				(end 395.925294 -169.98569)
			)
			(arc
				(start 395.925294 -172.977556)
				(mid 395.929059 -172.996747)
				(end 395.939772 -173.013116)
			)
			(xy 396.037308 -173.110652)
			(arc
				(start 396.037816 -173.11116)
				(mid 396.054173 -173.121902)
				(end 396.073376 -173.125638)
			)
			(arc
				(start 397.17472 -173.125638)
				(mid 397.193815 -173.121746)
				(end 397.210026 -173.110906)
			)
			(arc
				(start 397.307562 -173.01337)
				(mid 397.318468 -172.997187)
				(end 397.322294 -172.978064)
			)
			(arc
				(start 397.322294 -172.72635)
				(mid 397.326186 -172.707255)
				(end 397.337026 -172.691044)
			)
			(arc
				(start 397.788638 -172.239432)
				(mid 397.804821 -172.228526)
				(end 397.823944 -172.2247)
			)
			(arc
				(start 400.719036 -172.2247)
				(mid 400.738131 -172.228592)
				(end 400.754342 -172.239432)
			)
			(arc
				(start 402.006562 -173.491906)
				(mid 402.017468 -173.508089)
				(end 402.021294 -173.527212)
			)
			(arc
				(start 402.021294 -176.661064)
				(mid 402.017402 -176.680159)
				(end 402.006562 -176.69637)
			)
			(arc
				(start 401.655026 -177.047906)
				(mid 401.638843 -177.058812)
				(end 401.61972 -177.062638)
			)
			(arc
				(start 399.755868 -177.062638)
				(mid 399.736773 -177.058746)
				(end 399.720562 -177.047906)
			)
			(arc
				(start 399.623026 -176.95037)
				(mid 399.61212 -176.934187)
				(end 399.608294 -176.915064)
			)
			(xy 399.608294 -175.06061) (xy 399.600674 -175.041814) (xy 399.593308 -175.034702)
			(arc
				(start 399.35023 -174.791624)
				(mid 399.333696 -174.780513)
				(end 399.314162 -174.776638)
			)
			(arc
				(start 397.977868 -174.776638)
				(mid 397.958773 -174.78053)
				(end 397.942562 -174.79137)
			)
			(arc
				(start 397.845026 -174.888906)
				(mid 397.83412 -174.905089)
				(end 397.830294 -174.924212)
			)
			(arc
				(start 397.830294 -177.041048)
				(mid 397.826402 -177.060143)
				(end 397.815562 -177.076354)
			)
			(arc
				(start 397.59001 -177.301906)
				(mid 397.573827 -177.312812)
				(end 397.554704 -177.316638)
			)
			(arc
				(start 393.658852 -177.316638)
				(mid 393.639757 -177.312746)
				(end 393.623546 -177.301906)
			)
			(arc
				(start 392.464544 -176.142904)
				(mid 392.453433 -176.12637)
				(end 392.449558 -176.106836)
			)
			(xy 392.449558 -171.915074) (xy 392.441938 -171.896278) (xy 392.434572 -171.889166)
			(arc
				(start 390.541764 -169.996358)
				(mid 390.52523 -169.985247)
				(end 390.505696 -169.981372)
			)
			(xy 387.07822 -169.981372) (xy 387.059424 -169.988992) (xy 387.052312 -169.996358)
			(arc
				(start 386.536184 -170.512486)
				(mid 386.525073 -170.52902)
				(end 386.521198 -170.548554)
			)
			(arc
				(start 386.521198 -174.47387)
				(mid 386.524963 -174.493061)
				(end 386.535676 -174.50943)
			)
			(arc
				(start 387.51256 -175.486314)
				(mid 387.523671 -175.502848)
				(end 387.527546 -175.522382)
			)
			(arc
				(start 387.527546 -177.352706)
				(mid 387.526584 -177.362544)
				(end 387.523736 -177.37201)
			)
			(arc
				(start 387.516878 -177.387758)
				(mid 387.513869 -177.397462)
				(end 387.512814 -177.40757)
			)
			(arc
				(start 387.512814 -178.669442)
				(mid 387.516579 -178.688633)
				(end 387.527292 -178.705002)
			)
			(xy 387.548628 -178.726338)
			(arc
				(start 387.549136 -178.726846)
				(mid 387.565493 -178.737588)
				(end 387.584696 -178.741324)
			)
			(arc
				(start 388.815834 -178.741324)
				(mid 388.834929 -178.737432)
				(end 388.85114 -178.726592)
			)
			(arc
				(start 389.087868 -178.489864)
				(mid 389.098979 -178.47333)
				(end 389.102854 -178.453796)
			)
			(xy 389.102854 -178.44643) (xy 389.103108 -178.43119) (xy 389.103108 -178.423316)
			(arc
				(start 389.1026 -178.404012)
				(mid 389.214416 -178.134066)
				(end 389.484362 -178.02225)
			)
			(arc
				(start 389.484362 -178.02225)
				(mid 389.727472 -178.109666)
				(end 389.859266 -178.331876)
			)
			(xy 389.861044 -178.341274)
			(arc
				(start 389.866378 -178.349656)
				(mid 389.87189 -178.356798)
				(end 389.87857 -178.362864)
			)
			(arc
				(start 389.885936 -178.368452)
				(mid 389.89881 -178.375358)
				(end 389.913114 -178.378358)
			)
			(xy 389.914638 -178.378358) (xy 389.916162 -178.378358)
			(arc
				(start 390.922002 -178.378358)
				(mid 390.941193 -178.374593)
				(end 390.957562 -178.36388)
			)
			(arc
				(start 390.97839 -178.343052)
				(mid 390.984831 -178.335104)
				(end 390.989566 -178.326034)
			)
			(xy 390.993884 -178.315366) (xy 390.993376 -178.30419)
			(arc
				(start 390.992868 -178.28641)
				(mid 391.37463 -177.904648)
				(end 391.756392 -178.28641)
			)
			(xy 391.755884 -178.30419) (xy 391.755376 -178.315366)
			(arc
				(start 391.759694 -178.326034)
				(mid 391.764415 -178.335114)
				(end 391.77087 -178.343052)
			)
			(xy 391.79119 -178.363372)
			(arc
				(start 391.791698 -178.36388)
				(mid 391.808055 -178.374622)
				(end 391.827258 -178.378358)
			)
			(arc
				(start 392.901424 -178.378358)
				(mid 392.920519 -178.38225)
				(end 392.93673 -178.39309)
			)
			(arc
				(start 393.623546 -179.079906)
				(mid 393.634452 -179.096089)
				(end 393.638278 -179.115212)
			)
			(arc
				(start 393.638278 -182.146448)
				(mid 393.634386 -182.165543)
				(end 393.623546 -182.181754)
			)
			(arc
				(start 392.892788 -182.912512)
				(mid 392.876605 -182.923418)
				(end 392.857482 -182.927244)
			)
			(arc
				(start 391.729468 -182.927244)
				(mid 391.710373 -182.923352)
				(end 391.694162 -182.912512)
			)
			(arc
				(start 391.291826 -182.510176)
				(mid 391.28092 -182.493993)
				(end 391.277094 -182.47487)
			)
			(xy 391.277094 -182.389272) (xy 391.275062 -182.375302) (xy 391.273538 -182.370222)
			(arc
				(start 391.270998 -182.365396)
				(mid 391.226728 -182.250033)
				(end 391.211562 -182.127398)
			)
			(arc
				(start 391.211562 -182.127398)
				(mid 391.225986 -182.007142)
				(end 391.268458 -181.893718)
			)
			(xy 391.271252 -181.888384) (xy 391.277094 -181.865524) (xy 391.277094 -181.589172) (xy 391.271252 -181.566312)
			(arc
				(start 391.268458 -181.560978)
				(mid 391.226006 -181.447549)
				(end 391.211562 -181.327298)
			)
			(xy 391.211562 -180.713634) (xy 391.203942 -180.694838) (xy 391.196576 -180.687726)
			(arc
				(start 391.06348 -180.55463)
				(mid 391.046946 -180.543519)
				(end 391.027412 -180.539644)
			)
			(arc
				(start 389.494268 -180.539644)
				(mid 389.475173 -180.543536)
				(end 389.458962 -180.554376)
			)
			(arc
				(start 389.353806 -180.659532)
				(mid 389.3429 -180.675715)
				(end 389.339074 -180.694838)
			)
			(arc
				(start 389.339074 -182.64251)
				(mid 389.335182 -182.661605)
				(end 389.324342 -182.677816)
			)
			(arc
				(start 389.173466 -182.828692)
				(mid 389.157283 -182.839598)
				(end 389.13816 -182.843424)
			)
			(xy 389.009128 -182.843424) (xy 389.000746 -182.843932) (xy 385.554982 -182.843932) (xy 385.5466 -182.843424)
			(arc
				(start 383.230628 -182.843424)
				(mid 383.211533 -182.839532)
				(end 383.195322 -182.828692)
			)
			(arc
				(start 382.937766 -182.571136)
				(mid 382.92686 -182.554953)
				(end 382.923034 -182.53583)
			)
			(arc
				(start 382.923034 -182.340758)
				(mid 382.922097 -182.33079)
				(end 382.919224 -182.3212)
			)
			(arc
				(start 382.919224 -182.3212)
				(mid 382.8903 -182.226204)
				(end 382.880362 -182.127398)
			)
			(arc
				(start 382.880362 -182.127398)
				(mid 382.891227 -182.0236)
				(end 382.923034 -181.924198)
			)
			(arc
				(start 382.923034 -181.540658)
				(mid 382.922097 -181.53069)
				(end 382.919224 -181.5211)
			)
			(arc
				(start 382.919224 -181.5211)
				(mid 382.8903 -181.426104)
				(end 382.880362 -181.327298)
			)
			(xy 382.880362 -180.706014) (xy 382.872742 -180.687218) (xy 382.865376 -180.680106)
			(arc
				(start 382.69672 -180.51145)
				(mid 382.680186 -180.500339)
				(end 382.660652 -180.496464)
			)
			(arc
				(start 381.218948 -180.496464)
				(mid 381.199853 -180.500356)
				(end 381.183642 -180.511196)
			)
			(arc
				(start 381.088646 -180.606192)
				(mid 381.07774 -180.622375)
				(end 381.073914 -180.641498)
			)
			(arc
				(start 381.073914 -182.61457)
				(mid 381.070022 -182.633665)
				(end 381.059182 -182.649876)
			)
			(arc
				(start 380.875286 -182.833772)
				(mid 380.859103 -182.844678)
				(end 380.83998 -182.848504)
			)
			(xy 380.672848 -182.848504) (xy 380.664466 -182.849012) (xy 377.254262 -182.849012) (xy 377.24588 -182.848504)
			(arc
				(start 374.818148 -182.848504)
				(mid 374.799053 -182.844612)
				(end 374.782842 -182.833772)
			)
			(arc
				(start 374.461786 -182.512716)
				(mid 374.45088 -182.496533)
				(end 374.447054 -182.47741)
			)
			(xy 374.447054 -180.672486) (xy 374.439434 -180.65369) (xy 374.432068 -180.646578)
			(arc
				(start 374.30202 -180.51653)
				(mid 374.285486 -180.505419)
				(end 374.265952 -180.501544)
			)
			(arc
				(start 372.793768 -180.501544)
				(mid 372.774673 -180.505436)
				(end 372.758462 -180.516276)
			)
			(arc
				(start 372.638066 -180.636672)
				(mid 372.62716 -180.652855)
				(end 372.623334 -180.671978)
			)
			(arc
				(start 372.623334 -182.55107)
				(mid 372.619442 -182.570165)
				(end 372.608602 -182.586376)
			)
			(arc
				(start 372.389146 -182.805832)
				(mid 372.372963 -182.816738)
				(end 372.35384 -182.820564)
			)
			(arc
				(start 368.809778 -182.820564)
				(mid 368.790683 -182.816672)
				(end 368.774472 -182.805832)
			)
			(arc
				(start 368.254026 -182.285386)
				(mid 368.24312 -182.269203)
				(end 368.239294 -182.25008)
			)
			(xy 368.239294 -178.198272) (xy 368.231674 -178.179476) (xy 368.224308 -178.172364)
			(arc
				(start 367.872264 -177.82032)
				(mid 367.85573 -177.809209)
				(end 367.836196 -177.805334)
			)
			(arc
				(start 366.481868 -177.805334)
				(mid 366.462773 -177.801442)
				(end 366.446562 -177.790602)
			)
			(arc
				(start 366.219486 -177.563526)
				(mid 366.20858 -177.547343)
				(end 366.204754 -177.52822)
			)
			(arc
				(start 366.204754 -177.41392)
				(mid 366.204262 -177.406607)
				(end 366.202722 -177.399442)
			)
			(xy 366.200436 -177.39233)
			(arc
				(start 366.196626 -177.386234)
				(mid 366.136895 -177.254946)
				(end 366.116362 -177.112168)
			)
			(arc
				(start 366.116362 -177.111914)
				(mid 366.13689 -176.969144)
				(end 366.196626 -176.837848)
			)
			(xy 366.20069 -176.831498) (xy 366.204754 -176.818036)
			(arc
				(start 366.204754 -176.61382)
				(mid 366.204262 -176.606507)
				(end 366.202722 -176.599342)
			)
			(xy 366.200436 -176.59223)
			(arc
				(start 366.196626 -176.586134)
				(mid 366.136895 -176.454846)
				(end 366.116362 -176.312068)
			)
			(xy 366.116362 -175.6791) (xy 366.108742 -175.660304) (xy 366.101376 -175.653192)
			(arc
				(start 365.936784 -175.4886)
				(mid 365.92025 -175.477489)
				(end 365.900716 -175.473614)
			)
			(arc
				(start 364.498128 -175.473614)
				(mid 364.479033 -175.477506)
				(end 364.462822 -175.488346)
			)
			(arc
				(start 364.286546 -175.664622)
				(mid 364.27564 -175.680805)
				(end 364.271814 -175.699928)
			)
			(arc
				(start 364.271814 -177.61204)
				(mid 364.267922 -177.631135)
				(end 364.257082 -177.647346)
			)
			(arc
				(start 364.090966 -177.813462)
				(mid 364.074783 -177.824368)
				(end 364.05566 -177.828194)
			)
			(arc
				(start 360.388408 -177.828194)
				(mid 360.369313 -177.824302)
				(end 360.353102 -177.813462)
			)
			(arc
				(start 360.004106 -177.464466)
				(mid 359.9932 -177.448283)
				(end 359.989374 -177.42916)
			)
			(xy 359.989374 -169.800016) (xy 359.981754 -169.78122) (xy 359.974388 -169.774108)
			(arc
				(start 359.73512 -169.53484)
				(mid 359.718586 -169.523729)
				(end 359.699052 -169.519854)
			)
			(xy 358.155494 -169.519854) (xy 358.155494 -169.517314)
			(arc
				(start 357.921306 -169.283126)
				(mid 357.9104 -169.266943)
				(end 357.906574 -169.24782)
			)
			(xy 357.906574 -169.11447) (xy 357.904796 -169.101262) (xy 357.900224 -169.084244) (xy 357.89743 -169.078656)
			(xy 357.897176 -169.077894)
			(arc
				(start 357.895144 -169.074338)
				(mid 357.851072 -168.959204)
				(end 357.835962 -168.836848)
			)
			(arc
				(start 357.835962 -168.836848)
				(mid 357.851 -168.714351)
				(end 357.895144 -168.599104)
			)
			(xy 357.897176 -168.595548) (xy 357.89743 -168.594786) (xy 357.900224 -168.589198) (xy 357.906574 -168.565322)
			(xy 357.906574 -168.308274) (xy 357.900224 -168.284398) (xy 357.89743 -168.27881) (xy 357.897176 -168.278048)
			(arc
				(start 357.895144 -168.274492)
				(mid 357.851042 -168.159235)
				(end 357.835962 -168.036748)
			)
			(xy 357.835962 -167.407844) (xy 357.828342 -167.389048) (xy 357.820976 -167.381936)
			(arc
				(start 357.69804 -167.259)
				(mid 357.681506 -167.247889)
				(end 357.661972 -167.244014)
			)
			(arc
				(start 356.136448 -167.244014)
				(mid 356.117353 -167.247906)
				(end 356.101142 -167.258746)
			)
			(arc
				(start 355.973126 -167.386762)
				(mid 355.96222 -167.402945)
				(end 355.958394 -167.422068)
			)
			(arc
				(start 355.958394 -169.35196)
				(mid 355.954502 -169.371055)
				(end 355.943662 -169.387266)
			)
			(arc
				(start 355.775006 -169.555922)
				(mid 355.758823 -169.566828)
				(end 355.7397 -169.570654)
			)
			(arc
				(start 352.003868 -169.570654)
				(mid 351.984773 -169.566762)
				(end 351.968562 -169.555922)
			)
			(arc
				(start 351.759266 -169.346626)
				(mid 351.74836 -169.330443)
				(end 351.744534 -169.31132)
			)
			(xy 351.744534 -161.379916) (xy 351.736914 -161.36112) (xy 351.729548 -161.354008)
			(arc
				(start 351.38614 -161.0106)
				(mid 351.369606 -160.999489)
				(end 351.350072 -160.995614)
			)
			(arc
				(start 349.839788 -160.995614)
				(mid 349.820693 -160.991722)
				(end 349.804482 -160.980882)
			)
			(arc
				(start 349.635826 -160.812226)
				(mid 349.625925 -160.798119)
				(end 349.621348 -160.781492)
			)
			(arc
				(start 349.621348 -160.781492)
				(mid 349.619372 -160.77113)
				(end 349.615252 -160.761426)
			)
			(arc
				(start 349.615252 -160.761426)
				(mid 349.551937 -160.627119)
				(end 349.530162 -160.480248)
			)
			(arc
				(start 349.530162 -160.479994)
				(mid 349.551252 -160.335065)
				(end 349.612712 -160.202118)
			)
			(xy 349.61703 -160.196022) (xy 349.621094 -160.181798) (xy 349.621094 -159.978598) (xy 349.61703 -159.964374)
			(arc
				(start 349.612712 -159.958278)
				(mid 349.551218 -159.825474)
				(end 349.530162 -159.680656)
			)
			(xy 349.530162 -159.04718) (xy 349.522542 -159.028384) (xy 349.515176 -159.021272)
			(arc
				(start 349.396304 -158.9024)
				(mid 349.37977 -158.891289)
				(end 349.360236 -158.887414)
			)
			(arc
				(start 347.807788 -158.887414)
				(mid 347.788693 -158.891306)
				(end 347.772482 -158.902146)
			)
			(arc
				(start 347.695266 -158.979362)
				(mid 347.68436 -158.995545)
				(end 347.680534 -159.014668)
			)
			(arc
				(start 347.680534 -160.99028)
				(mid 347.676642 -161.009375)
				(end 347.665802 -161.025586)
			)
			(arc
				(start 347.481906 -161.209482)
				(mid 347.465723 -161.220388)
				(end 347.4466 -161.224214)
			)
			(arc
				(start 337.839812 -161.224214)
				(mid 337.820717 -161.228106)
				(end 337.804506 -161.238946)
			)
			(arc
				(start 337.647026 -161.396426)
				(mid 337.63612 -161.412609)
				(end 337.632294 -161.431732)
			)
			(arc
				(start 337.632294 -169.122852)
				(mid 337.636059 -169.142043)
				(end 337.646772 -169.158412)
			)
			(xy 337.965288 -169.476928)
			(arc
				(start 337.965796 -169.477436)
				(mid 337.982153 -169.488178)
				(end 338.001356 -169.491914)
			)
			(arc
				(start 348.83344 -169.491914)
				(mid 348.852535 -169.495806)
				(end 348.868746 -169.506646)
			)
			(arc
				(start 349.250762 -169.888662)
				(mid 349.261668 -169.904845)
				(end 349.265494 -169.923968)
			)
			(arc
				(start 349.265494 -170.657012)
				(mid 349.269259 -170.676203)
				(end 349.279972 -170.692572)
			)
			(xy 349.725488 -171.138088)
			(arc
				(start 349.725996 -171.138596)
				(mid 349.742353 -171.149338)
				(end 349.761556 -171.153074)
			)
			(arc
				(start 351.0788 -171.153074)
				(mid 351.097895 -171.156966)
				(end 351.114106 -171.167806)
			)
			(xy 351.474278 -171.527978) (xy 351.474278 -171.541694) (xy 351.474786 -171.541948)
			(arc
				(start 351.474786 -177.423064)
				(mid 351.478551 -177.442255)
				(end 351.489264 -177.458624)
			)
			(xy 351.681288 -177.650648)
			(arc
				(start 351.681796 -177.651156)
				(mid 351.698153 -177.661898)
				(end 351.717356 -177.665634)
			)
			(arc
				(start 357.8352 -177.665634)
				(mid 357.848787 -177.667514)
				(end 357.861362 -177.673)
			)
			(xy 357.870252 -177.678588) (xy 358.148382 -177.956464) (xy 358.148382 -177.957988) (xy 358.155494 -177.965354)
			(arc
				(start 358.155494 -178.937412)
				(mid 358.159259 -178.956603)
				(end 358.169972 -178.972972)
			)
			(xy 358.615488 -179.418488)
			(arc
				(start 358.615996 -179.418996)
				(mid 358.632353 -179.429738)
				(end 358.651556 -179.433474)
			)
			(arc
				(start 360.04754 -179.433474)
				(mid 360.066635 -179.437366)
				(end 360.082846 -179.448206)
			)
			(arc
				(start 360.476546 -179.841906)
				(mid 360.487452 -179.858089)
				(end 360.491278 -179.877212)
			)
			(xy 360.491278 -179.945792) (xy 360.491786 -179.9463)
			(arc
				(start 360.491786 -185.678064)
				(mid 360.495551 -185.697255)
				(end 360.506264 -185.713624)
			)
			(xy 360.825288 -186.032648)
			(arc
				(start 360.825796 -186.033156)
				(mid 360.842153 -186.043898)
				(end 360.861356 -186.047634)
			)
			(arc
				(start 366.9157 -186.047634)
				(mid 366.934795 -186.051526)
				(end 366.951006 -186.062366)
			)
			(arc
				(start 368.096546 -187.207906)
				(mid 368.107452 -187.224089)
				(end 368.111278 -187.243212)
			)
			(xy 368.111278 -187.273184) (xy 368.111786 -187.273946)
			(arc
				(start 368.111786 -190.885064)
				(mid 368.115551 -190.904255)
				(end 368.126264 -190.920624)
			)
			(xy 368.253518 -191.047878)
			(arc
				(start 368.254026 -191.048386)
				(mid 368.270383 -191.059128)
				(end 368.289586 -191.062864)
			)
			(arc
				(start 391.148316 -191.062864)
				(mid 391.167411 -191.066756)
				(end 391.183622 -191.077596)
			)
			(xy 391.21334 -191.107314)
			(arc
				(start 391.213848 -191.107822)
				(mid 391.230205 -191.118564)
				(end 391.249408 -191.1223)
			)
			(arc
				(start 391.249916 -191.1223)
				(mid 391.269011 -191.126192)
				(end 391.285222 -191.137032)
			)
			(arc
				(start 391.802874 -191.65443)
				(mid 391.81378 -191.670613)
				(end 391.817606 -191.689736)
			)
			(arc
				(start 391.817606 -195.350638)
				(mid 391.821371 -195.369829)
				(end 391.832084 -195.386198)
			)
			(xy 391.863072 -195.417186)
			(arc
				(start 391.86358 -195.417694)
				(mid 391.879937 -195.428436)
				(end 391.89914 -195.432172)
			)
		)
		(stroke
			(width 0)
			(type solid)
		)
		(fill yes)
		(layer "B.Cu")
		(net "GND")
	)
	(gr_poly
		(pts
			(arc
				(start 194.446144 -441.481972)
				(mid 194.482065 -441.467093)
				(end 194.496944 -441.431172)
			)
			(arc
				(start 194.496944 -441.17006)
				(mid 194.792217 -440.457207)
				(end 195.50507 -440.161934)
			)
			(arc
				(start 276.314916 -440.161934)
				(mid 277.027769 -440.457207)
				(end 277.323042 -441.17006)
			)
			(arc
				(start 277.323042 -441.431172)
				(mid 277.337921 -441.467093)
				(end 277.373842 -441.481972)
			)
			(arc
				(start 463.300064 -441.481972)
				(mid 464.355064 -441.044976)
				(end 464.79206 -439.989976)
			)
			(arc
				(start 464.79206 -409.528264)
				(mid 464.983018 -408.568632)
				(end 465.526628 -407.75509)
			)
			(arc
				(start 467.355174 -405.926544)
				(mid 467.678507 -405.442687)
				(end 467.792054 -404.871936)
			)
			(arc
				(start 467.792054 -82.82813)
				(mid 467.983012 -81.868498)
				(end 468.526622 -81.054956)
			)
			(arc
				(start 470.85504 -78.726538)
				(mid 471.178373 -78.242681)
				(end 471.29192 -77.67193)
			)
			(arc
				(start 471.29192 -13.780008)
				(mid 470.854924 -12.725008)
				(end 469.799924 -12.288012)
			)
			(arc
				(start 458.20203 -12.288012)
				(mid 456.428609 -11.553437)
				(end 455.694034 -9.780016)
			)
			(xy 455.694034 -3.638296)
			(arc
				(start 455.694034 -3.635756)
				(mid 455.682315 -3.605742)
				(end 455.654918 -3.588766)
			)
			(xy 455.541634 -3.561842) (xy 455.509884 -3.576574)
			(arc
				(start 455.501756 -3.592576)
				(mid 455.379677 -3.777305)
				(end 455.217784 -3.928364)
			)
			(xy 455.212704 -3.93192) (xy 455.205338 -3.940556)
			(arc
				(start 455.192384 -3.965702)
				(mid 455.188229 -3.976929)
				(end 455.186796 -3.988816)
			)
			(arc
				(start 455.186796 -9.780524)
				(mid 456.070027 -11.912452)
				(end 458.20203 -12.795504)
			)
			(arc
				(start 469.799924 -12.795504)
				(mid 470.496073 -13.083859)
				(end 470.784428 -13.780008)
			)
			(arc
				(start 470.784428 -77.672184)
				(mid 470.70959 -78.048688)
				(end 470.496392 -78.36789)
			)
			(arc
				(start 468.167974 -80.696308)
				(mid 467.514407 -81.674395)
				(end 467.284816 -82.82813)
			)
			(arc
				(start 467.284816 -358.942132)
				(mid 467.285511 -358.950507)
				(end 467.28761 -358.958642)
			)
			(arc
				(start 467.28761 -358.958642)
				(mid 467.515105 -359.848648)
				(end 467.591648 -360.764074)
			)
			(arc
				(start 467.591648 -360.764074)
				(mid 467.515108 -361.679501)
				(end 467.28761 -362.569506)
			)
			(arc
				(start 467.28761 -362.569506)
				(mid 467.285545 -362.577646)
				(end 467.284816 -362.586016)
			)
			(arc
				(start 467.284816 -404.871936)
				(mid 467.209909 -405.248606)
				(end 466.996526 -405.567896)
			)
			(arc
				(start 465.16798 -407.396442)
				(mid 464.51433 -408.374514)
				(end 464.284568 -409.528264)
			)
			(xy 464.284568 -435.048152)
			(arc
				(start 464.284822 -435.053232)
				(mid 464.3052 -435.326325)
				(end 464.312 -435.600094)
			)
			(arc
				(start 464.312 -435.600094)
				(mid 464.30521 -435.873863)
				(end 464.284822 -436.146956)
			)
			(xy 464.284568 -436.152036)
			(arc
				(start 464.284568 -439.989976)
				(mid 463.996213 -440.686125)
				(end 463.300064 -440.97448)
			)
			(xy 460.03083 -440.97448)
			(arc
				(start 460.019654 -440.97575)
				(mid 459.413496 -441.078274)
				(end 458.799692 -441.112656)
			)
			(arc
				(start 458.799692 -441.112656)
				(mid 458.186017 -441.078248)
				(end 457.579984 -440.97575)
			)
			(xy 457.568808 -440.97448) (xy 410.91104 -440.97448)
			(arc
				(start 410.90342 -440.976766)
				(mid 410.82774 -440.99441)
				(end 410.750258 -441.000388)
			)
			(arc
				(start 410.74975 -441.000388)
				(mid 410.672265 -440.994435)
				(end 410.596588 -440.976766)
			)
			(xy 410.588968 -440.97448) (xy 406.911048 -440.97448)
			(arc
				(start 406.903428 -440.976766)
				(mid 406.827748 -440.99441)
				(end 406.750266 -441.000388)
			)
			(arc
				(start 406.749758 -441.000388)
				(mid 406.672273 -440.994435)
				(end 406.596596 -440.976766)
			)
			(xy 406.588976 -440.97448) (xy 402.911056 -440.97448)
			(arc
				(start 402.903436 -440.976766)
				(mid 402.827756 -440.99441)
				(end 402.750274 -441.000388)
			)
			(arc
				(start 402.749766 -441.000388)
				(mid 402.672281 -440.994435)
				(end 402.596604 -440.976766)
			)
			(xy 402.588984 -440.97448) (xy 399.218404 -440.97448) (xy 399.205196 -440.97829)
			(arc
				(start 399.1991 -440.981846)
				(mid 399.167358 -440.995688)
				(end 399.13306 -441.000388)
			)
			(arc
				(start 398.366996 -441.000388)
				(mid 398.332719 -440.995614)
				(end 398.300956 -440.981846)
			)
			(xy 398.29486 -440.97829) (xy 398.281652 -440.97448) (xy 393.91082 -440.97448)
			(arc
				(start 393.9032 -440.976766)
				(mid 393.82752 -440.99441)
				(end 393.750038 -441.000388)
			)
			(arc
				(start 393.74953 -441.000388)
				(mid 393.672045 -440.994435)
				(end 393.596368 -440.976766)
			)
			(xy 393.588748 -440.97448) (xy 389.910828 -440.97448)
			(arc
				(start 389.903208 -440.976766)
				(mid 389.827528 -440.99441)
				(end 389.750046 -441.000388)
			)
			(arc
				(start 389.749538 -441.000388)
				(mid 389.672053 -440.994435)
				(end 389.596376 -440.976766)
			)
			(xy 389.588756 -440.97448) (xy 385.910836 -440.97448)
			(arc
				(start 385.903216 -440.976766)
				(mid 385.827536 -440.99441)
				(end 385.750054 -441.000388)
			)
			(arc
				(start 385.749546 -441.000388)
				(mid 385.672061 -440.994435)
				(end 385.596384 -440.976766)
			)
			(xy 385.588764 -440.97448) (xy 382.218184 -440.97448) (xy 382.204976 -440.97829)
			(arc
				(start 382.19888 -440.981846)
				(mid 382.167138 -440.995688)
				(end 382.13284 -441.000388)
			)
			(arc
				(start 381.366776 -441.000388)
				(mid 381.332499 -440.995614)
				(end 381.300736 -440.981846)
			)
			(xy 381.29464 -440.97829) (xy 381.281432 -440.97448) (xy 372.529608 -440.97448)
			(arc
				(start 372.518432 -440.97575)
				(mid 371.912401 -441.078265)
				(end 371.298724 -441.112656)
			)
			(arc
				(start 371.298724 -441.112656)
				(mid 370.685049 -441.078248)
				(end 370.079016 -440.97575)
			)
			(xy 370.06784 -440.97448) (xy 343.810844 -440.97448)
			(arc
				(start 343.803224 -440.976766)
				(mid 343.727544 -440.99441)
				(end 343.650062 -441.000388)
			)
			(arc
				(start 343.649554 -441.000388)
				(mid 343.572069 -440.994435)
				(end 343.496392 -440.976766)
			)
			(xy 343.488772 -440.97448) (xy 339.810852 -440.97448)
			(arc
				(start 339.803232 -440.976766)
				(mid 339.727552 -440.99441)
				(end 339.65007 -441.000388)
			)
			(arc
				(start 339.649562 -441.000388)
				(mid 339.572077 -440.994435)
				(end 339.4964 -440.976766)
			)
			(xy 339.48878 -440.97448) (xy 335.81086 -440.97448)
			(arc
				(start 335.80324 -440.976766)
				(mid 335.72756 -440.99441)
				(end 335.650078 -441.000388)
			)
			(arc
				(start 335.64957 -441.000388)
				(mid 335.572085 -440.994435)
				(end 335.496408 -440.976766)
			)
			(xy 335.488788 -440.97448) (xy 332.118208 -440.97448) (xy 332.105 -440.97829)
			(arc
				(start 332.098904 -440.981846)
				(mid 332.067162 -440.995688)
				(end 332.032864 -441.000388)
			)
			(arc
				(start 331.2668 -441.000388)
				(mid 331.232523 -440.995614)
				(end 331.20076 -440.981846)
			)
			(xy 331.194664 -440.97829) (xy 331.181456 -440.97448) (xy 326.810878 -440.97448)
			(arc
				(start 326.803258 -440.976766)
				(mid 326.727578 -440.99441)
				(end 326.650096 -441.000388)
			)
			(arc
				(start 326.649588 -441.000388)
				(mid 326.572103 -440.994435)
				(end 326.496426 -440.976766)
			)
			(xy 326.488806 -440.97448) (xy 322.810886 -440.97448)
			(arc
				(start 322.803266 -440.976766)
				(mid 322.727586 -440.99441)
				(end 322.650104 -441.000388)
			)
			(arc
				(start 322.649596 -441.000388)
				(mid 322.572111 -440.994435)
				(end 322.496434 -440.976766)
			)
			(xy 322.488814 -440.97448) (xy 318.810894 -440.97448)
			(arc
				(start 318.803274 -440.976766)
				(mid 318.727594 -440.99441)
				(end 318.650112 -441.000388)
			)
			(arc
				(start 318.649604 -441.000388)
				(mid 318.572119 -440.994435)
				(end 318.496442 -440.976766)
			)
			(xy 318.488822 -440.97448) (xy 315.118242 -440.97448) (xy 315.105034 -440.97829)
			(arc
				(start 315.098938 -440.981846)
				(mid 315.067318 -440.995653)
				(end 315.033152 -441.000388)
			)
			(arc
				(start 314.26658 -441.000388)
				(mid 314.232435 -440.99558)
				(end 314.200794 -440.981846)
			)
			(xy 314.194698 -440.97829) (xy 314.18149 -440.97448) (xy 294.78097 -440.97448)
			(arc
				(start 294.769794 -440.97575)
				(mid 294.163763 -441.078265)
				(end 293.550086 -441.112656)
			)
			(arc
				(start 293.550086 -441.112656)
				(mid 292.936411 -441.078248)
				(end 292.330378 -440.97575)
			)
			(xy 292.319202 -440.97448)
			(arc
				(start 277.817834 -440.97448)
				(mid 277.314992 -440.031472)
				(end 276.314916 -439.654696)
			)
			(arc
				(start 195.50507 -439.654696)
				(mid 194.504998 -440.031475)
				(end 194.002152 -440.97448)
			)
			(xy 180.979826 -440.97448) (xy 180.96865 -440.97575)
			(arc
				(start 180.965856 -440.976258)
				(mid 179.749958 -441.112027)
				(end 178.53406 -440.976258)
			)
			(xy 178.531266 -440.97575) (xy 178.52009 -440.97448) (xy 154.911044 -440.97448)
			(arc
				(start 154.903424 -440.976766)
				(mid 154.827744 -440.99441)
				(end 154.750262 -441.000388)
			)
			(arc
				(start 154.749754 -441.000388)
				(mid 154.672269 -440.994435)
				(end 154.596592 -440.976766)
			)
			(xy 154.588972 -440.97448) (xy 150.911052 -440.97448)
			(arc
				(start 150.903432 -440.976766)
				(mid 150.827752 -440.99441)
				(end 150.75027 -441.000388)
			)
			(arc
				(start 150.749762 -441.000388)
				(mid 150.672277 -440.994435)
				(end 150.5966 -440.976766)
			)
			(xy 150.58898 -440.97448) (xy 146.91106 -440.97448)
			(arc
				(start 146.90344 -440.976766)
				(mid 146.82776 -440.99441)
				(end 146.750278 -441.000388)
			)
			(arc
				(start 146.74977 -441.000388)
				(mid 146.672285 -440.994435)
				(end 146.596608 -440.976766)
			)
			(xy 146.588988 -440.97448) (xy 143.218408 -440.97448) (xy 143.2052 -440.97829)
			(arc
				(start 143.199104 -440.981846)
				(mid 143.167362 -440.995688)
				(end 143.133064 -441.000388)
			)
			(arc
				(start 142.367 -441.000388)
				(mid 142.332723 -440.995614)
				(end 142.30096 -440.981846)
			)
			(xy 142.294864 -440.97829) (xy 142.281656 -440.97448) (xy 137.910824 -440.97448)
			(arc
				(start 137.903204 -440.976766)
				(mid 137.827524 -440.99441)
				(end 137.750042 -441.000388)
			)
			(arc
				(start 137.749534 -441.000388)
				(mid 137.672049 -440.994435)
				(end 137.596372 -440.976766)
			)
			(xy 137.588752 -440.97448) (xy 133.910832 -440.97448)
			(arc
				(start 133.903212 -440.976766)
				(mid 133.827532 -440.99441)
				(end 133.75005 -441.000388)
			)
			(arc
				(start 133.749542 -441.000388)
				(mid 133.672057 -440.994435)
				(end 133.59638 -440.976766)
			)
			(xy 133.58876 -440.97448) (xy 129.91084 -440.97448)
			(arc
				(start 129.90322 -440.976766)
				(mid 129.82754 -440.99441)
				(end 129.750058 -441.000388)
			)
			(arc
				(start 129.74955 -441.000388)
				(mid 129.672065 -440.994435)
				(end 129.596388 -440.976766)
			)
			(xy 129.588768 -440.97448) (xy 126.218188 -440.97448) (xy 126.20498 -440.97829)
			(arc
				(start 126.198884 -440.981846)
				(mid 126.167142 -440.995688)
				(end 126.132844 -441.000388)
			)
			(arc
				(start 125.36678 -441.000388)
				(mid 125.332503 -440.995614)
				(end 125.30074 -440.981846)
			)
			(xy 125.294644 -440.97829) (xy 125.281436 -440.97448) (xy 101.730302 -440.97448) (xy 101.719126 -440.97575)
			(arc
				(start 101.716332 -440.976258)
				(mid 100.500434 -441.112027)
				(end 99.284536 -440.976258)
			)
			(xy 99.281742 -440.97575) (xy 99.270566 -440.97448) (xy 87.811102 -440.97448)
			(arc
				(start 87.803482 -440.976766)
				(mid 87.727802 -440.99441)
				(end 87.65032 -441.000388)
			)
			(arc
				(start 87.649812 -441.000388)
				(mid 87.572327 -440.994435)
				(end 87.49665 -440.976766)
			)
			(xy 87.48903 -440.97448) (xy 83.81111 -440.97448)
			(arc
				(start 83.80349 -440.976766)
				(mid 83.72781 -440.99441)
				(end 83.650328 -441.000388)
			)
			(arc
				(start 83.64982 -441.000388)
				(mid 83.572335 -440.994435)
				(end 83.496658 -440.976766)
			)
			(xy 83.489038 -440.97448) (xy 79.811118 -440.97448)
			(arc
				(start 79.803498 -440.976766)
				(mid 79.727818 -440.99441)
				(end 79.650336 -441.000388)
			)
			(arc
				(start 79.649828 -441.000388)
				(mid 79.572343 -440.994435)
				(end 79.496666 -440.976766)
			)
			(xy 79.489046 -440.97448) (xy 76.118466 -440.97448) (xy 76.105258 -440.97829)
			(arc
				(start 76.099162 -440.981846)
				(mid 76.067542 -440.995653)
				(end 76.033376 -441.000388)
			)
			(arc
				(start 75.266804 -441.000388)
				(mid 75.232659 -440.99558)
				(end 75.201018 -440.981846)
			)
			(xy 75.194922 -440.97829) (xy 75.181714 -440.97448) (xy 70.810882 -440.97448)
			(arc
				(start 70.803262 -440.976766)
				(mid 70.727582 -440.99441)
				(end 70.6501 -441.000388)
			)
			(arc
				(start 70.649592 -441.000388)
				(mid 70.572107 -440.994435)
				(end 70.49643 -440.976766)
			)
			(xy 70.48881 -440.97448) (xy 66.81089 -440.97448)
			(arc
				(start 66.80327 -440.976766)
				(mid 66.72759 -440.99441)
				(end 66.650108 -441.000388)
			)
			(arc
				(start 66.6496 -441.000388)
				(mid 66.572115 -440.994435)
				(end 66.496438 -440.976766)
			)
			(xy 66.488818 -440.97448) (xy 62.810898 -440.97448)
			(arc
				(start 62.803278 -440.976766)
				(mid 62.727598 -440.99441)
				(end 62.650116 -441.000388)
			)
			(arc
				(start 62.649608 -441.000388)
				(mid 62.572123 -440.994435)
				(end 62.496446 -440.976766)
			)
			(xy 62.488826 -440.97448) (xy 59.118246 -440.97448) (xy 59.105038 -440.97829)
			(arc
				(start 59.098942 -440.981846)
				(mid 59.067322 -440.995653)
				(end 59.033156 -441.000388)
			)
			(arc
				(start 58.266584 -441.000388)
				(mid 58.232439 -440.99558)
				(end 58.200798 -440.981846)
			)
			(xy 58.194702 -440.97829) (xy 58.181494 -440.97448) (xy 14.230604 -440.97448)
			(arc
				(start 14.219428 -440.97575)
				(mid 13.613397 -441.078265)
				(end 12.99972 -441.112656)
			)
			(arc
				(start 12.99972 -441.112656)
				(mid 12.385917 -441.078263)
				(end 11.779758 -440.97575)
			)
			(xy 11.768582 -440.97448)
			(arc
				(start 8.50011 -440.97448)
				(mid 7.803871 -440.686141)
				(end 7.515352 -439.989976)
			)
			(xy 7.515352 -436.156862)
			(arc
				(start 7.515098 -436.154322)
				(mid 7.494345 -435.878825)
				(end 7.487412 -435.602634)
			)
			(arc
				(start 7.487412 -435.597554)
				(mid 7.494336 -435.321363)
				(end 7.515098 -435.045866)
			)
			(xy 7.515352 -435.040786)
			(arc
				(start 7.515352 -409.528518)
				(mid 7.285694 -408.374511)
				(end 6.63194 -407.396188)
			)
			(arc
				(start 3.303778 -404.068026)
				(mid 3.090447 -403.748703)
				(end 3.015488 -403.372066)
			)
			(arc
				(start 3.015488 -81.32826)
				(mid 2.785816 -80.174473)
				(end 2.132076 -79.196438)
			)
			(arc
				(start 1.303528 -78.36789)
				(mid 1.090411 -78.048655)
				(end 1.015492 -77.672184)
			)
			(arc
				(start 1.015492 -13.780008)
				(mid 1.303847 -13.083859)
				(end 1.999996 -12.795504)
			)
			(arc
				(start 11.102086 -12.795504)
				(mid 13.234194 -11.912198)
				(end 14.11732 -9.780016)
			)
			(arc
				(start 14.11732 -3.98907)
				(mid 14.115908 -3.977177)
				(end 14.111732 -3.965956)
			)
			(xy 14.098778 -3.94081) (xy 14.091412 -3.932174)
			(arc
				(start 14.086332 -3.928618)
				(mid 13.924474 -3.77767)
				(end 13.80236 -3.593084)
			)
			(xy 13.794232 -3.577082) (xy 13.762482 -3.56235)
			(arc
				(start 13.649198 -3.589274)
				(mid 13.621781 -3.606233)
				(end 13.610082 -3.636264)
			)
			(xy 13.610082 -3.638804)
			(arc
				(start 13.610082 -9.780016)
				(mid 12.875507 -11.553437)
				(end 11.102086 -12.288012)
			)
			(arc
				(start 1.999996 -12.288012)
				(mid 0.944996 -12.725008)
				(end 0.508 -13.780008)
			)
			(arc
				(start 0.508 -77.67193)
				(mid 0.621601 -78.242658)
				(end 0.94488 -78.726538)
			)
			(arc
				(start 1.773428 -79.555086)
				(mid 2.317047 -80.368624)
				(end 2.507996 -81.32826)
			)
			(arc
				(start 2.507996 -403.371812)
				(mid 2.621533 -403.942691)
				(end 2.944876 -404.426674)
			)
			(arc
				(start 6.273292 -407.75509)
				(mid 6.817042 -408.568731)
				(end 7.008114 -409.528518)
			)
			(arc
				(start 7.008114 -439.989976)
				(mid 7.44511 -441.044976)
				(end 8.50011 -441.481972)
			)
		)
		(stroke
			(width 0)
			(type solid)
		)
		(fill yes)
		(layer "B.Cu")
		(net "GND")
	)
	(gr_poly
		(pts
			(xy 433.864258 -112.212628) (xy 433.874133 -112.212162) (xy 433.892423 -112.204711) (xy 433.899818 -112.19815)
			(xy 433.900072 -112.197896) (xy 436.971694 -109.126274) (xy 436.972202 -109.125766) (xy 436.978793 -109.118388)
			(xy 436.986257 -109.100089) (xy 436.98668 -109.090206) (xy 436.98668 -104.657144) (xy 436.986246 -104.647079)
			(xy 436.978515 -104.628491) (xy 436.971694 -104.621076) (xy 428.113952 -95.763334) (xy 428.10684 -95.755968)
			(xy 428.088044 -95.748348) (xy 418.127942 -95.748348) (xy 418.117878 -95.748783) (xy 418.099293 -95.756518)
			(xy 418.091874 -95.763334) (xy 414.622488 -99.23272) (xy 414.61452 -99.241685) (xy 414.607117 -99.264467)
			(xy 414.608264 -99.276408) (xy 414.62325 -99.36988) (xy 414.63722 -99.389438) (xy 414.648396 -99.395026)
			(xy 414.676219 -99.409771) (xy 414.727895 -99.44575) (xy 414.774152 -99.488473) (xy 414.814117 -99.537132)
			(xy 414.847035 -99.59081) (xy 414.872284 -99.648494) (xy 414.88939 -99.709094) (xy 414.898027 -99.771466)
			(xy 414.898586 -99.80295) (xy 414.898134 -99.832382) (xy 414.890592 -99.89076) (xy 414.875626 -99.947689)
			(xy 414.853483 -100.002229) (xy 414.82453 -100.053479) (xy 414.789243 -100.100593) (xy 414.748206 -100.142793)
			(xy 414.702096 -100.179382) (xy 414.651675 -100.209756) (xy 414.597775 -100.233414) (xy 414.569656 -100.242116)
			(xy 414.5534 -100.246942) (xy 414.53308 -100.273866) (xy 414.53308 -100.81133) (xy 414.533444 -100.820345)
			(xy 414.539697 -100.837256) (xy 414.545272 -100.84435) (xy 414.562484 -100.865192) (xy 414.591477 -100.910812)
			(xy 414.613744 -100.960065) (xy 414.62884 -101.011967) (xy 414.636464 -101.06548) (xy 414.636464 -101.119533)
			(xy 414.628838 -101.173045) (xy 414.61374 -101.224946) (xy 414.591471 -101.274199) (xy 414.562477 -101.319818)
			(xy 414.545272 -101.340666) (xy 414.539685 -101.347752) (xy 414.533435 -101.364669) (xy 414.53308 -101.373686)
			(xy 414.53308 -102.642167) (xy 429.419772 -102.642167) (xy 429.419772 -102.582233) (xy 429.427595 -102.522812)
			(xy 429.443106 -102.46492) (xy 429.46604 -102.409548) (xy 429.496006 -102.357643) (xy 429.53249 -102.310094)
			(xy 429.574868 -102.267712) (xy 429.622415 -102.231225) (xy 429.674318 -102.201256) (xy 429.729688 -102.178317)
			(xy 429.787579 -102.162801) (xy 429.846999 -102.154974) (xy 429.876966 -102.154482) (xy 429.907522 -102.154951)
			(xy 429.968088 -102.163102) (xy 430.027032 -102.179238) (xy 430.083305 -102.203072) (xy 430.135907 -102.234179)
			(xy 430.183904 -102.272007) (xy 430.226442 -102.315885) (xy 430.245012 -102.340156) (xy 430.25187 -102.3493)
			(xy 430.271174 -102.359714) (xy 430.371758 -102.366064) (xy 430.392332 -102.357936) (xy 430.40046 -102.349554)
			(xy 430.418551 -102.331152) (xy 430.458784 -102.298842) (xy 430.503008 -102.272255) (xy 430.550414 -102.251875)
			(xy 430.600137 -102.238077) (xy 430.651265 -102.231112) (xy 430.677066 -102.230682) (xy 430.704318 -102.231187)
			(xy 430.758266 -102.238939) (xy 430.810563 -102.25429) (xy 430.860142 -102.276928) (xy 430.905995 -102.306392)
			(xy 430.947188 -102.342081) (xy 430.982882 -102.38327) (xy 431.012351 -102.429119) (xy 431.034994 -102.478696)
			(xy 431.050352 -102.53099) (xy 431.05811 -102.584938) (xy 431.058574 -102.61219) (xy 431.058287 -102.634039)
			(xy 431.057668 -102.639451) (xy 431.370468 -102.639451) (xy 431.370468 -102.584949) (xy 431.378224 -102.531001)
			(xy 431.393579 -102.478706) (xy 431.41622 -102.429128) (xy 431.445685 -102.383277) (xy 431.481376 -102.342086)
			(xy 431.522566 -102.306394) (xy 431.568416 -102.276926) (xy 431.617993 -102.254284) (xy 431.670287 -102.238927)
			(xy 431.724235 -102.231169) (xy 431.751486 -102.230682) (xy 431.780039 -102.231158) (xy 431.836505 -102.239688)
			(xy 431.891067 -102.256544) (xy 431.942505 -102.28135) (xy 431.989668 -102.31355) (xy 432.031501 -102.352423)
			(xy 432.049682 -102.374446) (xy 432.056794 -102.383336) (xy 432.077114 -102.393242) (xy 432.177952 -102.395274)
			(xy 432.198526 -102.38613) (xy 432.205892 -102.377748) (xy 432.227746 -102.353461) (xy 432.277145 -102.310704)
			(xy 432.332122 -102.275405) (xy 432.39156 -102.248283) (xy 432.45425 -102.229889) (xy 432.518919 -102.220596)
			(xy 432.551586 -102.220014) (xy 432.581557 -102.220438) (xy 432.640987 -102.228261) (xy 432.698887 -102.243773)
			(xy 432.754266 -102.266711) (xy 432.806178 -102.296681) (xy 432.853734 -102.33317) (xy 432.89612 -102.375555)
			(xy 432.932611 -102.42311) (xy 432.962583 -102.475021) (xy 432.985522 -102.5304) (xy 433.001037 -102.5883)
			(xy 433.008861 -102.647729) (xy 433.008861 -102.707671) (xy 433.001037 -102.7671) (xy 432.985522 -102.825)
			(xy 432.962583 -102.880379) (xy 432.932611 -102.93229) (xy 432.89612 -102.979845) (xy 432.853734 -103.02223)
			(xy 432.806178 -103.058719) (xy 432.754266 -103.088689) (xy 432.698887 -103.111627) (xy 432.640987 -103.127139)
			(xy 432.581557 -103.134962) (xy 432.551586 -103.13543) (xy 432.522411 -103.13503) (xy 432.464533 -103.127612)
			(xy 432.408068 -103.112898) (xy 432.353931 -103.091126) (xy 432.303 -103.06265) (xy 432.256101 -103.027932)
			(xy 432.213996 -102.987534) (xy 432.177366 -102.942112) (xy 432.161696 -102.917498) (xy 432.155854 -102.907846)
			(xy 432.137058 -102.8954) (xy 432.037236 -102.881176) (xy 432.015646 -102.88778) (xy 432.00701 -102.8954)
			(xy 431.985895 -102.913822) (xy 431.939255 -102.944882) (xy 431.888572 -102.968781) (xy 431.834936 -102.985005)
			(xy 431.779504 -102.993204) (xy 431.751486 -102.993698) (xy 431.724235 -102.993231) (xy 431.670287 -102.985473)
			(xy 431.617993 -102.970116) (xy 431.568416 -102.947474) (xy 431.522566 -102.918006) (xy 431.481376 -102.882314)
			(xy 431.445685 -102.841123) (xy 431.41622 -102.795272) (xy 431.393579 -102.745694) (xy 431.378224 -102.693399)
			(xy 431.370468 -102.639451) (xy 431.057668 -102.639451) (xy 431.05332 -102.677454) (xy 431.048668 -102.698804)
			(xy 431.046128 -102.709472) (xy 431.050192 -102.7303) (xy 431.105818 -102.81031) (xy 431.124106 -102.821232)
			(xy 431.135028 -102.822756) (xy 431.16488 -102.82689) (xy 431.22321 -102.842048) (xy 431.279045 -102.864734)
			(xy 431.331418 -102.894554) (xy 431.379422 -102.930992) (xy 431.422227 -102.973418) (xy 431.45909 -103.021096)
			(xy 431.489374 -103.073202) (xy 431.512554 -103.128834) (xy 431.52823 -103.187027) (xy 431.536129 -103.246774)
			(xy 431.536602 -103.276908) (xy 431.536112 -103.306876) (xy 431.528289 -103.366298) (xy 431.512776 -103.424191)
			(xy 431.48984 -103.479564) (xy 431.459873 -103.53147) (xy 431.423386 -103.57902) (xy 431.381006 -103.6214)
			(xy 431.333456 -103.657887) (xy 431.28155 -103.687854) (xy 431.226177 -103.71079) (xy 431.168284 -103.726303)
			(xy 431.108862 -103.734126) (xy 431.048926 -103.734126) (xy 430.989504 -103.726303) (xy 430.931611 -103.71079)
			(xy 430.876238 -103.687854) (xy 430.824332 -103.657887) (xy 430.776782 -103.6214) (xy 430.734402 -103.57902)
			(xy 430.697915 -103.53147) (xy 430.667948 -103.479564) (xy 430.645012 -103.424191) (xy 430.629499 -103.366298)
			(xy 430.621676 -103.306876) (xy 430.621186 -103.276908) (xy 430.621618 -103.249425) (xy 430.628233 -103.194859)
			(xy 430.641332 -103.141476) (xy 430.65065 -103.115618) (xy 430.65446 -103.105204) (xy 430.65319 -103.084122)
			(xy 430.608232 -102.997508) (xy 430.591722 -102.9843) (xy 430.581054 -102.981506) (xy 430.555457 -102.97436)
			(xy 430.506387 -102.953951) (xy 430.46063 -102.926922) (xy 430.419071 -102.893798) (xy 430.40046 -102.874826)
			(xy 430.392332 -102.866444) (xy 430.371758 -102.858316) (xy 430.271174 -102.864666) (xy 430.25187 -102.87508)
			(xy 430.245012 -102.884224) (xy 430.226434 -102.908489) (xy 430.183905 -102.952374) (xy 430.135913 -102.990206)
			(xy 430.083311 -103.021312) (xy 430.027036 -103.045138) (xy 429.968089 -103.061261) (xy 429.907522 -103.069392)
			(xy 429.876966 -103.069898) (xy 429.846999 -103.069426) (xy 429.787579 -103.061599) (xy 429.729688 -103.046083)
			(xy 429.674318 -103.023144) (xy 429.622415 -102.993175) (xy 429.574868 -102.956688) (xy 429.53249 -102.914306)
			(xy 429.496006 -102.866757) (xy 429.46604 -102.814852) (xy 429.443106 -102.75948) (xy 429.427595 -102.701588)
			(xy 429.419772 -102.642167) (xy 414.53308 -102.642167) (xy 414.53308 -104.501188) (xy 418.035232 -104.501188)
			(xy 418.035683 -104.473817) (xy 418.043503 -104.419637) (xy 418.058996 -104.367134) (xy 418.081841 -104.317387)
			(xy 418.111569 -104.271421) (xy 418.129212 -104.25049) (xy 418.135308 -104.243378) (xy 418.141658 -104.22636)
			(xy 418.141658 -104.141016) (xy 418.135308 -104.123998) (xy 418.129212 -104.116886) (xy 418.111602 -104.095931)
			(xy 418.081885 -104.049965) (xy 418.059043 -104.000223) (xy 418.043546 -103.947727) (xy 418.03571 -103.893556)
			(xy 418.035232 -103.866188) (xy 418.035644 -103.838933) (xy 418.043403 -103.784978) (xy 418.058763 -103.732677)
			(xy 418.08141 -103.683094) (xy 418.110883 -103.637239) (xy 418.146582 -103.596045) (xy 418.187781 -103.560352)
			(xy 418.23364 -103.530885) (xy 418.283226 -103.508245) (xy 418.335529 -103.492892) (xy 418.389485 -103.48514)
			(xy 418.41674 -103.48468) (xy 418.442319 -103.485084) (xy 418.493018 -103.491932) (xy 418.542348 -103.505486)
			(xy 418.589428 -103.525504) (xy 418.633414 -103.551628) (xy 418.673519 -103.583389) (xy 418.691568 -103.60152)
			(xy 418.69868 -103.608886) (xy 418.717222 -103.617014) (xy 418.810186 -103.61803) (xy 418.828982 -103.61041)
			(xy 418.836348 -103.603044) (xy 418.857913 -103.582417) (xy 418.906289 -103.547481) (xy 418.959517 -103.520507)
			(xy 419.016298 -103.502155) (xy 419.075244 -103.492872) (xy 419.10508 -103.4923) (xy 419.132333 -103.492774)
			(xy 419.186284 -103.500528) (xy 419.238582 -103.515882) (xy 419.288162 -103.538523) (xy 419.334016 -103.56799)
			(xy 419.375209 -103.603682) (xy 419.410903 -103.644874) (xy 419.440371 -103.690727) (xy 419.463013 -103.740307)
			(xy 419.478369 -103.792605) (xy 419.486125 -103.846555) (xy 419.486588 -103.873808) (xy 419.48613 -103.901179)
			(xy 419.47831 -103.955358) (xy 419.46282 -104.007861) (xy 419.439976 -104.057608) (xy 419.41025 -104.103575)
			(xy 419.392608 -104.124506) (xy 419.386512 -104.131618) (xy 419.380162 -104.148636) (xy 419.380162 -104.23398)
			(xy 419.386512 -104.250998) (xy 419.392608 -104.25811) (xy 419.410266 -104.279026) (xy 419.439975 -104.325004)
			(xy 419.462807 -104.374755) (xy 419.478294 -104.427259) (xy 419.486117 -104.481438) (xy 419.486588 -104.508808)
			(xy 419.486152 -104.536062) (xy 419.478393 -104.590015) (xy 419.463035 -104.642314) (xy 419.440391 -104.691896)
			(xy 419.41092 -104.73775) (xy 419.375223 -104.778943) (xy 419.334028 -104.814637) (xy 419.288171 -104.844104)
			(xy 419.238588 -104.866745) (xy 419.186287 -104.882099) (xy 419.132334 -104.889854) (xy 419.10508 -104.890316)
			(xy 419.079501 -104.8899) (xy 419.028803 -104.883055) (xy 418.979473 -104.869503) (xy 418.932393 -104.849487)
			(xy 418.888407 -104.823365) (xy 418.848301 -104.791606) (xy 418.830252 -104.773476) (xy 418.82314 -104.76611)
			(xy 418.804598 -104.757982) (xy 418.711634 -104.756966) (xy 418.692838 -104.764586) (xy 418.685472 -104.771952)
			(xy 418.663898 -104.792569) (xy 418.615524 -104.827506) (xy 418.562298 -104.854482) (xy 418.50552 -104.872837)
			(xy 418.446576 -104.882123) (xy 418.41674 -104.882696) (xy 418.389488 -104.882207) (xy 418.335537 -104.874456)
			(xy 418.283239 -104.859104) (xy 418.233658 -104.836465) (xy 418.187804 -104.807) (xy 418.146611 -104.771309)
			(xy 418.110916 -104.730118) (xy 418.081448 -104.684267) (xy 418.058806 -104.634687) (xy 418.04345 -104.58239)
			(xy 418.035695 -104.52844) (xy 418.035232 -104.501188) (xy 414.53308 -104.501188) (xy 414.53308 -105.85729)
			(xy 429.831482 -105.85729) (xy 429.831482 -105.797354) (xy 429.839305 -105.737932) (xy 429.854818 -105.680039)
			(xy 429.877754 -105.624666) (xy 429.907721 -105.57276) (xy 429.944208 -105.52521) (xy 429.986588 -105.48283)
			(xy 430.034138 -105.446343) (xy 430.086044 -105.416376) (xy 430.141417 -105.39344) (xy 430.19931 -105.377927)
			(xy 430.258732 -105.370104) (xy 430.318668 -105.370104) (xy 430.37809 -105.377927) (xy 430.435983 -105.39344)
			(xy 430.491356 -105.416376) (xy 430.543262 -105.446343) (xy 430.590812 -105.48283) (xy 430.633192 -105.52521)
			(xy 430.669679 -105.57276) (xy 430.699646 -105.624666) (xy 430.70142 -105.628948) (xy 433.069492 -105.628948)
			(xy 433.069988 -105.601579) (xy 433.077799 -105.547401) (xy 433.093281 -105.494898) (xy 433.116116 -105.445151)
			(xy 433.145834 -105.399183) (xy 433.163472 -105.37825) (xy 433.169568 -105.371138) (xy 433.175918 -105.35412)
			(xy 433.175918 -105.268776) (xy 433.169568 -105.251758) (xy 433.163472 -105.244646) (xy 433.145837 -105.223711)
			(xy 433.116125 -105.177739) (xy 433.093289 -105.127992) (xy 433.077797 -105.075492) (xy 433.069967 -105.021317)
			(xy 433.069492 -104.993948) (xy 433.070012 -104.966037) (xy 433.078141 -104.910809) (xy 433.094231 -104.857355)
			(xy 433.117941 -104.806818) (xy 433.148762 -104.760275) (xy 433.186038 -104.718721) (xy 433.228972 -104.683044)
			(xy 433.276647 -104.654004) (xy 433.302156 -104.642666) (xy 433.311554 -104.638602) (xy 433.325778 -104.624378)
			(xy 433.360322 -104.538272) (xy 433.359814 -104.518206) (xy 433.356004 -104.508808) (xy 433.344149 -104.480056)
			(xy 433.327414 -104.420159) (xy 433.318952 -104.358547) (xy 433.318412 -104.327452) (xy 433.318902 -104.297484)
			(xy 433.326725 -104.238062) (xy 433.342238 -104.180169) (xy 433.365174 -104.124796) (xy 433.395141 -104.07289)
			(xy 433.431628 -104.02534) (xy 433.474008 -103.98296) (xy 433.521558 -103.946473) (xy 433.573464 -103.916506)
			(xy 433.628837 -103.89357) (xy 433.68673 -103.878057) (xy 433.746152 -103.870234) (xy 433.806088 -103.870234)
			(xy 433.86551 -103.878057) (xy 433.923403 -103.89357) (xy 433.978776 -103.916506) (xy 434.030682 -103.946473)
			(xy 434.078232 -103.98296) (xy 434.120612 -104.02534) (xy 434.157099 -104.07289) (xy 434.187066 -104.124796)
			(xy 434.210002 -104.180169) (xy 434.225515 -104.238062) (xy 434.233338 -104.297484) (xy 434.233828 -104.327452)
			(xy 434.233276 -104.359372) (xy 434.224433 -104.422595) (xy 434.206897 -104.483979) (xy 434.194458 -104.51338)
			(xy 434.19014 -104.522778) (xy 434.189632 -104.54259) (xy 434.222144 -104.628442) (xy 434.235606 -104.64292)
			(xy 434.24475 -104.646984) (xy 434.269318 -104.658747) (xy 434.315114 -104.688241) (xy 434.356251 -104.723945)
			(xy 434.391895 -104.765135) (xy 434.421321 -104.810973) (xy 434.443933 -104.860529) (xy 434.459269 -104.912796)
			(xy 434.46702 -104.966713) (xy 434.467508 -104.993948) (xy 434.467009 -105.021317) (xy 434.459199 -105.075495)
			(xy 434.443718 -105.127997) (xy 434.420883 -105.177745) (xy 434.391166 -105.223713) (xy 434.373528 -105.244646)
			(xy 434.367432 -105.251758) (xy 434.361082 -105.268776) (xy 434.361082 -105.35412) (xy 434.367432 -105.371138)
			(xy 434.373528 -105.37825) (xy 434.391161 -105.399187) (xy 434.420873 -105.445159) (xy 434.44371 -105.494905)
			(xy 434.459202 -105.547404) (xy 434.467033 -105.601579) (xy 434.467508 -105.628948) (xy 434.467067 -105.6562)
			(xy 434.459304 -105.71015) (xy 434.443943 -105.762445) (xy 434.421296 -105.812023) (xy 434.391825 -105.857873)
			(xy 434.356129 -105.899063) (xy 434.314934 -105.934753) (xy 434.269081 -105.964219) (xy 434.2195 -105.986859)
			(xy 434.167203 -106.002214) (xy 434.113252 -106.00997) (xy 434.086 -106.010456) (xy 434.058629 -106.010001)
			(xy 434.004449 -106.002182) (xy 433.951946 -105.986691) (xy 433.902199 -105.963847) (xy 433.856233 -105.934119)
			(xy 433.835302 -105.916476) (xy 433.82819 -105.91038) (xy 433.811172 -105.90403) (xy 433.725828 -105.90403)
			(xy 433.70881 -105.91038) (xy 433.701698 -105.916476) (xy 433.680774 -105.934126) (xy 433.6348 -105.963837)
			(xy 433.58505 -105.986671) (xy 433.532547 -106.00216) (xy 433.47837 -106.009984) (xy 433.451 -106.010456)
			(xy 433.423751 -106.009922) (xy 433.369807 -106.002167) (xy 433.317516 -105.986814) (xy 433.267942 -105.964177)
			(xy 433.222094 -105.934715) (xy 433.180905 -105.899029) (xy 433.145214 -105.857844) (xy 433.115746 -105.812)
			(xy 433.093102 -105.762429) (xy 433.077743 -105.71014) (xy 433.069981 -105.656197) (xy 433.069492 -105.628948)
			(xy 430.70142 -105.628948) (xy 430.722582 -105.680039) (xy 430.738095 -105.737932) (xy 430.745918 -105.797354)
			(xy 430.746408 -105.827322) (xy 430.745918 -105.85729) (xy 430.738095 -105.916712) (xy 430.722582 -105.974605)
			(xy 430.699646 -106.029978) (xy 430.669679 -106.081884) (xy 430.633192 -106.129434) (xy 430.590812 -106.171814)
			(xy 430.543262 -106.208301) (xy 430.491356 -106.238268) (xy 430.435983 -106.261204) (xy 430.37809 -106.276717)
			(xy 430.318668 -106.28454) (xy 430.258732 -106.28454) (xy 430.19931 -106.276717) (xy 430.141417 -106.261204)
			(xy 430.086044 -106.238268) (xy 430.034138 -106.208301) (xy 429.986588 -106.171814) (xy 429.944208 -106.129434)
			(xy 429.907721 -106.081884) (xy 429.877754 -106.029978) (xy 429.854818 -105.974605) (xy 429.839305 -105.916712)
			(xy 429.831482 -105.85729) (xy 414.53308 -105.85729) (xy 414.53308 -107.15117) (xy 428.855124 -107.15117)
			(xy 428.855614 -107.121202) (xy 428.863437 -107.06178) (xy 428.87895 -107.003887) (xy 428.901886 -106.948514)
			(xy 428.931853 -106.896608) (xy 428.96834 -106.849058) (xy 429.01072 -106.806678) (xy 429.05827 -106.770191)
			(xy 429.110176 -106.740224) (xy 429.165549 -106.717288) (xy 429.223442 -106.701775) (xy 429.282864 -106.693952)
			(xy 429.3428 -106.693952) (xy 429.402222 -106.701775) (xy 429.460115 -106.717288) (xy 429.515488 -106.740224)
			(xy 429.567394 -106.770191) (xy 429.614944 -106.806678) (xy 429.657324 -106.849058) (xy 429.693811 -106.896608)
			(xy 429.723778 -106.948514) (xy 429.746714 -107.003887) (xy 429.762227 -107.06178) (xy 429.77005 -107.121202)
			(xy 429.77054 -107.15117) (xy 429.770051 -107.181257) (xy 429.762165 -107.240911) (xy 429.748719 -107.290866)
			(xy 430.188352 -107.290866) (xy 430.188352 -107.23093) (xy 430.196175 -107.171508) (xy 430.211688 -107.113615)
			(xy 430.234624 -107.058242) (xy 430.264591 -107.006336) (xy 430.301078 -106.958786) (xy 430.343458 -106.916406)
			(xy 430.391008 -106.879919) (xy 430.442914 -106.849952) (xy 430.498287 -106.827016) (xy 430.55618 -106.811503)
			(xy 430.615602 -106.80368) (xy 430.675538 -106.80368) (xy 430.677574 -106.803948) (xy 433.265054 -106.803948)
			(xy 433.265054 -106.744012) (xy 433.272877 -106.68459) (xy 433.28839 -106.626697) (xy 433.311326 -106.571324)
			(xy 433.341293 -106.519418) (xy 433.37778 -106.471868) (xy 433.42016 -106.429488) (xy 433.46771 -106.393001)
			(xy 433.519616 -106.363034) (xy 433.574989 -106.340098) (xy 433.632882 -106.324585) (xy 433.692304 -106.316762)
			(xy 433.75224 -106.316762) (xy 433.811662 -106.324585) (xy 433.869555 -106.340098) (xy 433.924928 -106.363034)
			(xy 433.976834 -106.393001) (xy 434.024384 -106.429488) (xy 434.066764 -106.471868) (xy 434.103251 -106.519418)
			(xy 434.133218 -106.571324) (xy 434.156154 -106.626697) (xy 434.171667 -106.68459) (xy 434.17949 -106.744012)
			(xy 434.17998 -106.77398) (xy 434.17949 -106.803948) (xy 434.171667 -106.86337) (xy 434.156154 -106.921263)
			(xy 434.133218 -106.976636) (xy 434.103251 -107.028542) (xy 434.066764 -107.076092) (xy 434.024384 -107.118472)
			(xy 433.976834 -107.154959) (xy 433.924928 -107.184926) (xy 433.869555 -107.207862) (xy 433.811662 -107.223375)
			(xy 433.75224 -107.231198) (xy 433.692304 -107.231198) (xy 433.632882 -107.223375) (xy 433.574989 -107.207862)
			(xy 433.519616 -107.184926) (xy 433.46771 -107.154959) (xy 433.42016 -107.118472) (xy 433.37778 -107.076092)
			(xy 433.341293 -107.028542) (xy 433.311326 -106.976636) (xy 433.28839 -106.921263) (xy 433.272877 -106.86337)
			(xy 433.265054 -106.803948) (xy 430.677574 -106.803948) (xy 430.73496 -106.811503) (xy 430.792853 -106.827016)
			(xy 430.848226 -106.849952) (xy 430.900132 -106.879919) (xy 430.947682 -106.916406) (xy 430.990062 -106.958786)
			(xy 431.026549 -107.006336) (xy 431.056516 -107.058242) (xy 431.079452 -107.113615) (xy 431.094965 -107.171508)
			(xy 431.102788 -107.23093) (xy 431.103278 -107.260898) (xy 431.102788 -107.290866) (xy 431.094965 -107.350288)
			(xy 431.079452 -107.408181) (xy 431.056516 -107.463554) (xy 431.026549 -107.51546) (xy 430.990062 -107.56301)
			(xy 430.947682 -107.60539) (xy 430.900132 -107.641877) (xy 430.848226 -107.671844) (xy 430.838975 -107.675676)
			(xy 431.628278 -107.675676) (xy 431.628278 -107.61574) (xy 431.636101 -107.556318) (xy 431.651614 -107.498425)
			(xy 431.67455 -107.443052) (xy 431.704517 -107.391146) (xy 431.741004 -107.343596) (xy 431.783384 -107.301216)
			(xy 431.830934 -107.264729) (xy 431.88284 -107.234762) (xy 431.938213 -107.211826) (xy 431.996106 -107.196313)
			(xy 432.055528 -107.18849) (xy 432.115464 -107.18849) (xy 432.174886 -107.196313) (xy 432.232779 -107.211826)
			(xy 432.288152 -107.234762) (xy 432.340058 -107.264729) (xy 432.387608 -107.301216) (xy 432.429988 -107.343596)
			(xy 432.466475 -107.391146) (xy 432.496442 -107.443052) (xy 432.519378 -107.498425) (xy 432.534891 -107.556318)
			(xy 432.542714 -107.61574) (xy 432.543204 -107.645708) (xy 432.542714 -107.675676) (xy 432.534891 -107.735098)
			(xy 432.519378 -107.792991) (xy 432.496442 -107.848364) (xy 432.466475 -107.90027) (xy 432.429988 -107.94782)
			(xy 432.387608 -107.9902) (xy 432.340058 -108.026687) (xy 432.288152 -108.056654) (xy 432.232779 -108.07959)
			(xy 432.174886 -108.095103) (xy 432.115464 -108.102926) (xy 432.055528 -108.102926) (xy 431.996106 -108.095103)
			(xy 431.938213 -108.07959) (xy 431.88284 -108.056654) (xy 431.830934 -108.026687) (xy 431.783384 -107.9902)
			(xy 431.741004 -107.94782) (xy 431.704517 -107.90027) (xy 431.67455 -107.848364) (xy 431.651614 -107.792991)
			(xy 431.636101 -107.735098) (xy 431.628278 -107.675676) (xy 430.838975 -107.675676) (xy 430.792853 -107.69478)
			(xy 430.73496 -107.710293) (xy 430.675538 -107.718116) (xy 430.615602 -107.718116) (xy 430.55618 -107.710293)
			(xy 430.498287 -107.69478) (xy 430.442914 -107.671844) (xy 430.391008 -107.641877) (xy 430.343458 -107.60539)
			(xy 430.301078 -107.56301) (xy 430.264591 -107.51546) (xy 430.234624 -107.463554) (xy 430.211688 -107.408181)
			(xy 430.196175 -107.350288) (xy 430.188352 -107.290866) (xy 429.748719 -107.290866) (xy 429.746525 -107.299017)
			(xy 429.723402 -107.35457) (xy 429.693195 -107.406612) (xy 429.656425 -107.454244) (xy 429.635412 -107.475782)
			(xy 429.628688 -107.483239) (xy 429.621117 -107.501817) (xy 429.62068 -107.51185) (xy 429.62068 -108.101892)
			(xy 429.636174 -108.12653) (xy 429.649636 -108.13288) (xy 429.668721 -108.142409) (xy 429.703245 -108.167453)
			(xy 429.73247 -108.198517) (xy 429.755361 -108.234504) (xy 429.771111 -108.274141) (xy 429.779161 -108.316025)
			(xy 429.779684 -108.33735) (xy 429.779684 -108.604812) (xy 429.77054 -108.604812) (xy 429.76052 -108.605253)
			(xy 429.742001 -108.612912) (xy 429.727827 -108.627078) (xy 429.720158 -108.645592) (xy 429.71974 -108.655612)
			(xy 429.71974 -109.130084) (xy 429.728884 -109.130084) (xy 429.738889 -109.130601) (xy 429.757377 -109.138252)
			(xy 429.77153 -109.152396) (xy 429.779193 -109.17088) (xy 429.779684 -109.180884) (xy 429.779684 -109.188504)
			(xy 429.780055 -109.19855) (xy 429.787641 -109.217147) (xy 429.794416 -109.224572) (xy 430.099978 -109.52988)
			(xy 430.116731 -109.547336) (xy 430.145172 -109.586473) (xy 430.16714 -109.629576) (xy 430.182096 -109.675586)
			(xy 430.184888 -109.693198) (xy 433.258958 -109.693198) (xy 433.258958 -109.633262) (xy 433.266781 -109.57384)
			(xy 433.282294 -109.515947) (xy 433.30523 -109.460574) (xy 433.335197 -109.408668) (xy 433.371684 -109.361118)
			(xy 433.414064 -109.318738) (xy 433.461614 -109.282251) (xy 433.51352 -109.252284) (xy 433.568893 -109.229348)
			(xy 433.626786 -109.213835) (xy 433.686208 -109.206012) (xy 433.746144 -109.206012) (xy 433.805566 -109.213835)
			(xy 433.863459 -109.229348) (xy 433.918832 -109.252284) (xy 433.970738 -109.282251) (xy 434.018288 -109.318738)
			(xy 434.060668 -109.361118) (xy 434.097155 -109.408668) (xy 434.127122 -109.460574) (xy 434.150058 -109.515947)
			(xy 434.165571 -109.57384) (xy 434.173394 -109.633262) (xy 434.173884 -109.66323) (xy 434.173394 -109.693198)
			(xy 434.165571 -109.75262) (xy 434.150058 -109.810513) (xy 434.127122 -109.865886) (xy 434.097155 -109.917792)
			(xy 434.060668 -109.965342) (xy 434.018288 -110.007722) (xy 433.970738 -110.044209) (xy 433.918832 -110.074176)
			(xy 433.863459 -110.097112) (xy 433.805566 -110.112625) (xy 433.746144 -110.120448) (xy 433.686208 -110.120448)
			(xy 433.626786 -110.112625) (xy 433.568893 -110.097112) (xy 433.51352 -110.074176) (xy 433.461614 -110.044209)
			(xy 433.414064 -110.007722) (xy 433.371684 -109.965342) (xy 433.335197 -109.917792) (xy 433.30523 -109.865886)
			(xy 433.282294 -109.810513) (xy 433.266781 -109.75262) (xy 433.258958 -109.693198) (xy 430.184888 -109.693198)
			(xy 430.18967 -109.723368) (xy 430.190148 -109.747558) (xy 430.190148 -110.579408) (xy 430.190526 -110.589453)
			(xy 430.198108 -110.608049) (xy 430.20488 -110.615476) (xy 430.225895 -110.637012) (xy 430.262665 -110.684645)
			(xy 430.292873 -110.736688) (xy 430.315997 -110.792241) (xy 430.33164 -110.850346) (xy 430.33953 -110.910001)
			(xy 430.340008 -110.940088) (xy 430.339518 -110.970056) (xy 430.331695 -111.029478) (xy 430.316182 -111.087371)
			(xy 430.293246 -111.142744) (xy 430.263279 -111.19465) (xy 430.226792 -111.2422) (xy 430.184412 -111.28458)
			(xy 430.136862 -111.321067) (xy 430.084956 -111.351034) (xy 430.029583 -111.37397) (xy 429.97169 -111.389483)
			(xy 429.912268 -111.397306) (xy 429.852332 -111.397306) (xy 429.79291 -111.389483) (xy 429.735017 -111.37397)
			(xy 429.679644 -111.351034) (xy 429.627738 -111.321067) (xy 429.580188 -111.28458) (xy 429.537808 -111.2422)
			(xy 429.501321 -111.19465) (xy 429.471354 -111.142744) (xy 429.448418 -111.087371) (xy 429.432905 -111.029478)
			(xy 429.425082 -110.970056) (xy 429.424592 -110.940088) (xy 429.424926 -110.914503) (xy 429.430604 -110.863649)
			(xy 429.44192 -110.813747) (xy 429.449992 -110.789466) (xy 429.45431 -110.77702) (xy 429.449992 -110.751366)
			(xy 429.379126 -110.663482) (xy 429.354996 -110.65383) (xy 429.341788 -110.655354) (xy 429.330276 -110.656671)
			(xy 429.307146 -110.65807) (xy 429.29556 -110.658148) (xy 429.268314 -110.657579) (xy 429.214376 -110.649819)
			(xy 429.162091 -110.634462) (xy 429.112524 -110.611821) (xy 429.066684 -110.582357) (xy 429.025503 -110.546669)
			(xy 428.989819 -110.505484) (xy 428.96036 -110.45964) (xy 428.937724 -110.410071) (xy 428.922373 -110.357785)
			(xy 428.914618 -110.303847) (xy 428.914618 -110.249353) (xy 428.922373 -110.195415) (xy 428.937724 -110.143129)
			(xy 428.96036 -110.09356) (xy 428.989819 -110.047716) (xy 429.025503 -110.006531) (xy 429.066684 -109.970843)
			(xy 429.112524 -109.941379) (xy 429.162091 -109.918738) (xy 429.214376 -109.903381) (xy 429.268314 -109.895621)
			(xy 429.29556 -109.895132) (xy 429.32209 -109.895603) (xy 429.374641 -109.90294) (xy 429.42567 -109.917478)
			(xy 429.474197 -109.938938) (xy 429.496982 -109.952536) (xy 429.509174 -109.96041) (xy 429.523652 -109.96041)
			(xy 429.533669 -109.959941) (xy 429.552183 -109.952289) (xy 429.566357 -109.938132) (xy 429.57403 -109.919626)
			(xy 429.574452 -109.90961) (xy 429.574452 -109.896148) (xy 429.574097 -109.886101) (xy 429.566499 -109.867504)
			(xy 429.55972 -109.86008) (xy 429.337978 -109.638338) (xy 429.330575 -109.631501) (xy 429.311978 -109.623778)
			(xy 429.30191 -109.623352) (xy 429.252634 -109.623352) (xy 429.252634 -109.623606) (xy 429.230306 -109.62325)
			(xy 429.186457 -109.614834) (xy 429.145109 -109.597987) (xy 429.107864 -109.573363) (xy 429.076169 -109.541916)
			(xy 429.051252 -109.504866) (xy 429.03408 -109.463651) (xy 429.025319 -109.41987) (xy 429.024796 -109.397546)
			(xy 429.024796 -109.130084) (xy 429.03394 -109.130084) (xy 429.043952 -109.129644) (xy 429.062448 -109.121969)
			(xy 429.0766 -109.107801) (xy 429.084255 -109.089297) (xy 429.08474 -109.079284) (xy 429.08474 -108.604812)
			(xy 429.075596 -108.604812) (xy 429.06559 -108.604315) (xy 429.0471 -108.596657) (xy 429.032948 -108.582507)
			(xy 429.025286 -108.564018) (xy 429.024796 -108.554012) (xy 429.024796 -108.486956) (xy 429.022002 -108.478828)
			(xy 429.014049 -108.454381) (xy 429.005497 -108.403693) (xy 429.004984 -108.37799) (xy 429.004984 -107.51185)
			(xy 429.004619 -107.501804) (xy 428.997027 -107.483208) (xy 428.990252 -107.475782) (xy 428.969222 -107.454259)
			(xy 428.932453 -107.406624) (xy 428.902246 -107.354579) (xy 428.879124 -107.299023) (xy 428.863485 -107.240915)
			(xy 428.855599 -107.181258) (xy 428.855124 -107.15117) (xy 414.53308 -107.15117) (xy 414.53308 -110.4265)
			(xy 418.726872 -110.4265) (xy 418.730943 -110.370878) (xy 418.743069 -110.316441) (xy 418.762992 -110.26435)
			(xy 418.790288 -110.215715) (xy 418.824374 -110.171572) (xy 418.864523 -110.132863) (xy 418.909881 -110.100412)
			(xy 418.959481 -110.074911) (xy 419.012265 -110.056904) (xy 419.067108 -110.046774) (xy 419.122842 -110.044737)
			(xy 419.178279 -110.050837) (xy 419.232236 -110.064943) (xy 419.283565 -110.086755) (xy 419.331171 -110.115809)
			(xy 419.374039 -110.151484) (xy 419.411256 -110.193021) (xy 419.442029 -110.239534) (xy 419.465701 -110.290031)
			(xy 419.472002 -110.310973) (xy 419.686619 -110.310973) (xy 419.686619 -110.251027) (xy 419.694444 -110.191593)
			(xy 419.709961 -110.133689) (xy 419.732902 -110.078305) (xy 419.762877 -110.026391) (xy 419.799372 -109.978833)
			(xy 419.841763 -109.936446) (xy 419.889324 -109.899955) (xy 419.941241 -109.869985) (xy 419.996627 -109.847048)
			(xy 420.054532 -109.831537) (xy 420.113967 -109.823717) (xy 420.14394 -109.82325) (xy 420.172928 -109.823718)
			(xy 420.23044 -109.831044) (xy 420.286566 -109.845574) (xy 420.340409 -109.867075) (xy 420.391105 -109.895202)
			(xy 420.437843 -109.929507) (xy 420.479875 -109.969439) (xy 420.516529 -110.014359) (xy 420.547217 -110.063548)
			(xy 420.559738 -110.089696) (xy 420.566252 -110.102644) (xy 420.585293 -110.124479) (xy 420.609692 -110.140101)
			(xy 420.637492 -110.148256) (xy 420.666463 -110.148291) (xy 420.694283 -110.140203) (xy 420.718719 -110.12464)
			(xy 420.728648 -110.11408) (xy 420.746838 -110.093874) (xy 420.787991 -110.058345) (xy 420.833771 -110.029018)
			(xy 420.883251 -110.006487) (xy 420.935428 -109.99121) (xy 420.989246 -109.983495) (xy 421.01643 -109.983016)
			(xy 421.043682 -109.983456) (xy 421.097629 -109.991216) (xy 421.149924 -110.006575) (xy 421.1995 -110.029219)
			(xy 421.24535 -110.058688) (xy 421.286539 -110.094382) (xy 421.32223 -110.135574) (xy 421.351695 -110.181426)
			(xy 421.374335 -110.231004) (xy 421.38969 -110.2833) (xy 421.397446 -110.337248) (xy 421.397446 -110.391752)
			(xy 421.38969 -110.4457) (xy 421.374335 -110.497996) (xy 421.351695 -110.547574) (xy 421.32223 -110.593426)
			(xy 421.286539 -110.634618) (xy 421.24535 -110.670312) (xy 421.1995 -110.699781) (xy 421.149924 -110.722425)
			(xy 421.097629 -110.737784) (xy 421.043682 -110.745544) (xy 421.01643 -110.746032) (xy 420.987929 -110.745559)
			(xy 420.931563 -110.737063) (xy 420.87709 -110.72027) (xy 420.825724 -110.695555) (xy 420.77861 -110.663468)
			(xy 420.736798 -110.624725) (xy 420.701219 -110.580188) (xy 420.686484 -110.555786) (xy 420.678709 -110.543551)
			(xy 420.657698 -110.523606) (xy 420.631932 -110.510362) (xy 420.603484 -110.504887) (xy 420.574643 -110.507619)
			(xy 420.54773 -110.51834) (xy 420.52491 -110.536187) (xy 420.51605 -110.547658) (xy 420.497513 -110.572558)
			(xy 420.454849 -110.617648) (xy 420.406485 -110.656562) (xy 420.353308 -110.688587) (xy 420.296292 -110.713135)
			(xy 420.236483 -110.729756) (xy 420.174978 -110.738147) (xy 420.14394 -110.738666) (xy 420.113967 -110.738283)
			(xy 420.054532 -110.730463) (xy 419.996627 -110.714952) (xy 419.941241 -110.692015) (xy 419.889324 -110.662045)
			(xy 419.841763 -110.625554) (xy 419.799372 -110.583167) (xy 419.762877 -110.535609) (xy 419.732902 -110.483695)
			(xy 419.709961 -110.428311) (xy 419.694444 -110.370407) (xy 419.686619 -110.310973) (xy 419.472002 -110.310973)
			(xy 419.481769 -110.343438) (xy 419.489889 -110.398614) (xy 419.490398 -110.4265) (xy 419.489889 -110.454386)
			(xy 419.481769 -110.509562) (xy 419.465701 -110.562969) (xy 419.442029 -110.613466) (xy 419.411256 -110.659979)
			(xy 419.374039 -110.701516) (xy 419.331171 -110.737191) (xy 419.283565 -110.766245) (xy 419.232236 -110.788057)
			(xy 419.178279 -110.802163) (xy 419.122842 -110.808263) (xy 419.067108 -110.806226) (xy 419.012265 -110.796096)
			(xy 418.959481 -110.778089) (xy 418.909881 -110.752588) (xy 418.864523 -110.720137) (xy 418.824374 -110.681428)
			(xy 418.790288 -110.637285) (xy 418.762992 -110.58865) (xy 418.743069 -110.536559) (xy 418.730943 -110.482122)
			(xy 418.726872 -110.4265) (xy 414.53308 -110.4265) (xy 414.53308 -111.330486) (xy 414.533551 -111.340358)
			(xy 414.54101 -111.358641) (xy 414.547558 -111.366046) (xy 414.547812 -111.3663) (xy 415.379154 -112.197642)
			(xy 415.379662 -112.19815) (xy 415.387043 -112.204731) (xy 415.405343 -112.212179) (xy 415.415222 -112.212628)
		)
		(stroke
			(width 0)
			(type solid)
		)
		(fill yes)
		(layer "B.Cu")
		(net "GND")
	)
	(gr_poly
		(pts
			(xy 205.014322 -367.87328) (xy 205.02439 -367.872852) (xy 205.042987 -367.86513) (xy 205.05039 -367.858294)
			(xy 205.565502 -367.343182) (xy 205.572345 -367.335782) (xy 205.580073 -367.317184) (xy 205.580488 -367.307114)
			(xy 205.580488 -350.340422) (xy 205.580925 -350.330358) (xy 205.588658 -350.311773) (xy 205.595474 -350.304354)
			(xy 206.615792 -349.284036) (xy 206.622629 -349.276635) (xy 206.630342 -349.258036) (xy 206.630778 -349.247968)
			(xy 206.630778 -347.226382) (xy 206.630867 -347.221362) (xy 206.63278 -347.211508) (xy 206.634588 -347.206824)
			(xy 206.642716 -347.187774) (xy 206.643972 -347.184145) (xy 206.645501 -347.176619) (xy 206.645764 -347.172788)
			(xy 206.645764 -344.622374) (xy 206.645764 -344.621612) (xy 206.643478 -344.6018) (xy 206.555594 -344.6018)
			(xy 206.548482 -344.602308) (xy 206.538576 -344.60434) (xy 206.525368 -344.608912) (xy 206.518764 -344.612214)
			(xy 206.513176 -344.617802) (xy 206.491671 -344.638604) (xy 206.444197 -344.675018) (xy 206.392381 -344.704932)
			(xy 206.337107 -344.727836) (xy 206.279319 -344.743339) (xy 206.220003 -344.751177) (xy 206.190088 -344.75166)
			(xy 206.189834 -344.75166) (xy 206.159867 -344.751193) (xy 206.100444 -344.743374) (xy 206.042551 -344.727866)
			(xy 205.987177 -344.704933) (xy 205.935271 -344.674968) (xy 205.88772 -344.638484) (xy 205.845338 -344.596106)
			(xy 205.808851 -344.548557) (xy 205.778882 -344.496653) (xy 205.755945 -344.441281) (xy 205.740432 -344.383389)
			(xy 205.732609 -344.323967) (xy 205.732609 -344.264033) (xy 205.740432 -344.204611) (xy 205.755945 -344.146719)
			(xy 205.778882 -344.091347) (xy 205.808851 -344.039443) (xy 205.845338 -343.991894) (xy 205.88772 -343.949516)
			(xy 205.935271 -343.913032) (xy 205.987177 -343.883067) (xy 206.042551 -343.860134) (xy 206.100444 -343.844626)
			(xy 206.159867 -343.836807) (xy 206.189834 -343.836244) (xy 206.219471 -343.836715) (xy 206.278248 -343.844374)
			(xy 206.335544 -343.859558) (xy 206.390399 -343.882015) (xy 206.441895 -343.911367) (xy 206.489169 -343.947123)
			(xy 206.510636 -343.967562) (xy 206.51089 -343.967816) (xy 206.5147 -343.971372) (xy 206.526384 -343.978992)
			(xy 206.532353 -343.982273) (xy 206.545484 -343.985869) (xy 206.552292 -343.986104) (xy 206.643478 -343.986104)
			(xy 206.645764 -343.966292) (xy 206.645764 -343.281) (xy 206.645344 -343.270981) (xy 206.637673 -343.252471)
			(xy 206.623499 -343.238307) (xy 206.604983 -343.230649) (xy 206.594964 -343.2302) (xy 203.205588 -343.2302)
			(xy 203.198034 -343.230479) (xy 203.183577 -343.234872) (xy 203.17714 -343.238836) (xy 203.153455 -343.254175)
			(xy 203.102518 -343.278454) (xy 203.048558 -343.294959) (xy 202.992755 -343.303328) (xy 202.964542 -343.30386)
			(xy 202.964034 -343.30386) (xy 202.937729 -343.303421) (xy 202.885618 -343.296194) (xy 202.834995 -343.281872)
			(xy 202.78682 -343.260728) (xy 202.74201 -343.233163) (xy 202.701414 -343.199699) (xy 202.665804 -343.160973)
			(xy 202.635854 -343.11772) (xy 202.612134 -343.070761) (xy 202.595095 -343.020987) (xy 202.589638 -342.99525)
			(xy 202.589638 -342.994996) (xy 202.587889 -342.987717) (xy 202.580799 -342.974539) (xy 202.575668 -342.969088)
			(xy 202.334622 -342.728296) (xy 202.317851 -342.710856) (xy 202.289411 -342.671715) (xy 202.267444 -342.628608)
			(xy 202.252491 -342.582595) (xy 202.24492 -342.534809) (xy 202.244452 -342.510618) (xy 202.244452 -342.232488)
			(xy 202.24403 -342.222472) (xy 202.236356 -342.203967) (xy 202.222182 -342.18981) (xy 202.203669 -342.182159)
			(xy 202.193652 -342.181688) (xy 201.940668 -342.181688) (xy 201.930664 -342.182182) (xy 201.912181 -342.189846)
			(xy 201.898035 -342.203998) (xy 201.890378 -342.222484) (xy 201.889868 -342.232488) (xy 201.889868 -342.241632)
			(xy 201.622152 -342.241632) (xy 201.599862 -342.241111) (xy 201.556146 -342.232375) (xy 201.514987 -342.215249)
			(xy 201.477977 -342.190397) (xy 201.446548 -342.15878) (xy 201.421916 -342.121623) (xy 201.405036 -342.080362)
			(xy 201.39656 -342.036595) (xy 201.396092 -342.014302) (xy 201.396092 -341.889334) (xy 201.395657 -341.879269)
			(xy 201.387924 -341.860683) (xy 201.381106 -341.853266) (xy 200.939146 -341.411052) (xy 200.921927 -341.392941)
			(xy 200.894193 -341.351379) (xy 200.875089 -341.30521) (xy 200.865349 -341.256203) (xy 200.864724 -341.23122)
			(xy 200.864724 -340.230714) (xy 200.864217 -340.220664) (xy 200.856494 -340.202105) (xy 200.849738 -340.194646)
			(xy 199.804274 -339.149182) (xy 199.796878 -339.142331) (xy 199.778279 -339.134593) (xy 199.768206 -339.134196)
			(xy 199.063864 -339.134196) (xy 199.052022 -339.134823) (xy 199.030843 -339.145426) (xy 199.023224 -339.154516)
			(xy 199.004642 -339.178478) (xy 198.962179 -339.221763) (xy 198.91437 -339.25906) (xy 198.862055 -339.289717)
			(xy 198.806149 -339.313196) (xy 198.747631 -339.329087) (xy 198.687528 -339.337109) (xy 198.65721 -339.33765)
			(xy 198.627238 -339.337181) (xy 198.567806 -339.329358) (xy 198.509904 -339.313845) (xy 198.454522 -339.290906)
			(xy 198.402608 -339.260934) (xy 198.355051 -339.224443) (xy 198.312663 -339.182057) (xy 198.276171 -339.1345)
			(xy 198.246199 -339.082587) (xy 198.223259 -339.027205) (xy 198.207744 -338.969304) (xy 198.199919 -338.909872)
			(xy 198.199919 -338.849928) (xy 198.207744 -338.790496) (xy 198.223259 -338.732595) (xy 198.246199 -338.677213)
			(xy 198.276171 -338.6253) (xy 198.312663 -338.577743) (xy 198.355051 -338.535357) (xy 198.402608 -338.498866)
			(xy 198.454522 -338.468894) (xy 198.509904 -338.445955) (xy 198.567806 -338.430442) (xy 198.627238 -338.422619)
			(xy 198.65721 -338.422234) (xy 198.687532 -338.422722) (xy 198.747646 -338.430728) (xy 198.806173 -338.446612)
			(xy 198.862087 -338.470094) (xy 198.914404 -338.500763) (xy 198.962208 -338.53808) (xy 199.004659 -338.581389)
			(xy 199.023224 -338.605368) (xy 199.030824 -338.614481) (xy 199.052014 -338.625094) (xy 199.063864 -338.625688)
			(xy 199.894698 -338.625688) (xy 199.919681 -338.626299) (xy 199.968689 -338.636041) (xy 200.014856 -338.655152)
			(xy 200.056411 -338.682898) (xy 200.07453 -338.70011) (xy 201.29881 -339.92439) (xy 201.316036 -339.942498)
			(xy 201.343784 -339.984057) (xy 201.362902 -340.030227) (xy 201.372655 -340.079237) (xy 201.373232 -340.104222)
			(xy 201.373232 -340.151621) (xy 203.152802 -340.151621) (xy 203.152808 -340.091689) (xy 203.160637 -340.03227)
			(xy 203.176154 -339.974381) (xy 203.199095 -339.919013) (xy 203.229066 -339.867113) (xy 203.265555 -339.819569)
			(xy 203.307938 -339.777195) (xy 203.355489 -339.740715) (xy 203.407395 -339.710754) (xy 203.462768 -339.687824)
			(xy 203.52066 -339.672319) (xy 203.58008 -339.664502) (xy 203.640013 -339.664508) (xy 203.699432 -339.672337)
			(xy 203.75732 -339.687854) (xy 203.812688 -339.710795) (xy 203.864588 -339.740767) (xy 203.912132 -339.777256)
			(xy 203.954506 -339.819639) (xy 203.990986 -339.867191) (xy 204.020947 -339.919097) (xy 204.043876 -339.974469)
			(xy 204.059382 -340.032361) (xy 204.067198 -340.091782) (xy 204.067664 -340.121748) (xy 204.067664 -340.122256)
			(xy 204.066955 -340.157903) (xy 204.055857 -340.228328) (xy 204.045566 -340.262464) (xy 204.042953 -340.271494)
			(xy 204.043917 -340.290259) (xy 204.051597 -340.307407) (xy 204.058012 -340.31428) (xy 204.425296 -340.681564)
			(xy 204.437541 -340.694418) (xy 204.45723 -340.723954) (xy 204.470788 -340.75676) (xy 204.477698 -340.791578)
			(xy 204.478128 -340.809326) (xy 204.478128 -341.444326) (xy 204.478576 -341.454498) (xy 204.486508 -341.473235)
			(xy 204.501081 -341.487433) (xy 204.510386 -341.49157) (xy 204.531262 -341.500429) (xy 204.569309 -341.525088)
			(xy 204.601683 -341.55683) (xy 204.627088 -341.594383) (xy 204.644506 -341.636243) (xy 204.653238 -341.680733)
			(xy 204.653642 -341.703406) (xy 204.653388 -341.703406) (xy 204.653388 -342.002618) (xy 204.653642 -342.002618)
			(xy 204.653306 -342.024948) (xy 204.644896 -342.068803) (xy 204.628051 -342.110157) (xy 204.603425 -342.147406)
			(xy 204.571974 -342.179104) (xy 204.534918 -342.20402) (xy 204.493696 -342.221187) (xy 204.449909 -342.229938)
			(xy 204.427582 -342.230456) (xy 204.16012 -342.230456) (xy 204.16012 -342.221312) (xy 204.159603 -342.211308)
			(xy 204.151951 -342.19282) (xy 204.137807 -342.178667) (xy 204.119324 -342.171004) (xy 204.10932 -342.170512)
			(xy 203.945744 -342.170512) (xy 203.935727 -342.170045) (xy 203.917213 -342.162391) (xy 203.90304 -342.148234)
			(xy 203.895366 -342.129728) (xy 203.894944 -342.119712) (xy 203.894944 -341.586312) (xy 203.89533 -341.576286)
			(xy 203.903005 -341.557761) (xy 203.917188 -341.543587) (xy 203.935718 -341.535924) (xy 203.945744 -341.535512)
			(xy 204.06614 -341.535512) (xy 204.076149 -341.535045) (xy 204.094639 -341.527374) (xy 204.10879 -341.513216)
			(xy 204.11645 -341.494721) (xy 204.11694 -341.484712) (xy 204.11694 -340.905338) (xy 204.116511 -340.895269)
			(xy 204.108794 -340.87667) (xy 204.101954 -340.86927) (xy 203.802488 -340.569804) (xy 203.795544 -340.563495)
			(xy 203.77843 -340.555856) (xy 203.759715 -340.554865) (xy 203.750672 -340.557358) (xy 203.716535 -340.567647)
			(xy 203.646111 -340.578753) (xy 203.610464 -340.579456) (xy 203.609956 -340.579456) (xy 203.57999 -340.578892)
			(xy 203.520571 -340.571064) (xy 203.462682 -340.555546) (xy 203.407314 -340.532606) (xy 203.355414 -340.502635)
			(xy 203.30787 -340.466146) (xy 203.265496 -340.423763) (xy 203.229016 -340.376212) (xy 203.199055 -340.324306)
			(xy 203.176125 -340.268933) (xy 203.160619 -340.211041) (xy 203.152802 -340.151621) (xy 201.373232 -340.151621)
			(xy 201.373232 -341.104728) (xy 201.373661 -341.114795) (xy 201.381386 -341.133389) (xy 201.388218 -341.140796)
			(xy 201.719688 -341.472266) (xy 201.727084 -341.479118) (xy 201.745683 -341.486862) (xy 201.755756 -341.487252)
			(xy 201.839068 -341.487252) (xy 201.849083 -341.487734) (xy 201.867594 -341.495386) (xy 201.881769 -341.509538)
			(xy 201.88945 -341.528037) (xy 201.889868 -341.538052) (xy 201.889868 -341.547196) (xy 202.363832 -341.547196)
			(xy 202.373835 -341.546702) (xy 202.392315 -341.539037) (xy 202.406457 -341.524885) (xy 202.414109 -341.506399)
			(xy 202.414632 -341.496396) (xy 202.414632 -341.487252) (xy 202.682348 -341.487252) (xy 202.704639 -341.487773)
			(xy 202.748355 -341.496509) (xy 202.789516 -341.513635) (xy 202.826528 -341.538486) (xy 202.857959 -341.570103)
			(xy 202.882593 -341.60726) (xy 202.899476 -341.648521) (xy 202.907955 -341.692288) (xy 202.908408 -341.714582)
			(xy 202.908408 -342.013794) (xy 202.908408 -342.014302) (xy 202.907963 -342.037112) (xy 202.899071 -342.081852)
			(xy 202.881407 -342.123908) (xy 202.869038 -342.14308) (xy 202.86853 -342.143588) (xy 202.864466 -342.149938)
			(xy 202.860148 -342.163908) (xy 202.860148 -342.362028) (xy 202.860601 -342.372053) (xy 202.8682 -342.390604)
			(xy 202.87488 -342.398096) (xy 203.01077 -342.533986) (xy 203.016226 -342.539114) (xy 203.029395 -342.546221)
			(xy 203.036678 -342.547956) (xy 203.036932 -342.547956) (xy 203.061847 -342.553223) (xy 203.110104 -342.569486)
			(xy 203.155772 -342.592015) (xy 203.17714 -342.605868) (xy 203.183544 -342.609905) (xy 203.198021 -342.61431)
			(xy 203.205588 -342.614504) (xy 206.594964 -342.614504) (xy 206.60499 -342.614091) (xy 206.62352 -342.606427)
			(xy 206.637705 -342.592254) (xy 206.645383 -342.57373) (xy 206.645764 -342.563704) (xy 206.645764 -332.268322)
			(xy 206.645666 -332.263445) (xy 206.643873 -332.253857) (xy 206.642208 -332.249272) (xy 206.638398 -332.240128)
			(xy 205.715616 -331.317346) (xy 205.712766 -331.314639) (xy 205.706389 -331.310043) (xy 205.702916 -331.308202)
			(xy 205.697488 -331.305623) (xy 205.685809 -331.302809) (xy 205.679802 -331.302614) (xy 197.15353 -331.302614)
			(xy 197.143465 -331.302179) (xy 197.124878 -331.294448) (xy 197.117462 -331.287628) (xy 196.463412 -330.633578)
			(xy 196.456568 -330.626179) (xy 196.448839 -330.607581) (xy 196.448426 -330.59751) (xy 196.448426 -327.251314)
			(xy 196.448327 -327.246437) (xy 196.446531 -327.236851) (xy 196.44487 -327.232264) (xy 196.44106 -327.22312)
			(xy 196.267578 -327.049638) (xy 196.264726 -327.046933) (xy 196.258347 -327.042342) (xy 196.254878 -327.040494)
			(xy 196.249452 -327.037909) (xy 196.237772 -327.035081) (xy 196.231764 -327.034906) (xy 170.568366 -327.034906)
			(xy 170.563488 -327.035001) (xy 170.553898 -327.036788) (xy 170.549316 -327.038462) (xy 170.540172 -327.042272)
			(xy 170.279314 -327.30313) (xy 170.27661 -327.305983) (xy 170.272022 -327.312364) (xy 170.27017 -327.31583)
			(xy 170.267587 -327.321257) (xy 170.264762 -327.332936) (xy 170.264582 -327.338944) (xy 170.264582 -332.723236)
			(xy 170.264152 -332.733303) (xy 170.256426 -332.751896) (xy 170.249596 -332.759304) (xy 167.434768 -335.574132)
			(xy 167.432062 -335.576983) (xy 167.42747 -335.583362) (xy 167.425624 -335.586832) (xy 167.423039 -335.592258)
			(xy 167.420211 -335.603938) (xy 167.420036 -335.609946) (xy 167.420036 -341.96528) (xy 170.50258 -341.96528)
			(xy 170.50258 -335.827624) (xy 170.502997 -335.817553) (xy 170.510721 -335.798954) (xy 170.517566 -335.791556)
			(xy 173.61535 -332.693518) (xy 173.622775 -332.68671) (xy 173.641355 -332.678971) (xy 173.651418 -332.678532)
			(xy 195.771008 -332.678532) (xy 195.781079 -332.678945) (xy 195.799677 -332.686673) (xy 195.807076 -332.693518)
			(xy 196.322442 -333.208884) (xy 196.329273 -333.216291) (xy 196.336997 -333.234885) (xy 196.337428 -333.244952)
			(xy 196.337428 -342.044528) (xy 196.337036 -342.054601) (xy 196.329294 -342.0732) (xy 196.322442 -342.080596)
			(xy 196.017896 -342.385142) (xy 196.010496 -342.391982) (xy 195.991897 -342.399701) (xy 195.981828 -342.400128)
			(xy 170.937174 -342.400128) (xy 170.927101 -342.399735) (xy 170.908502 -342.391994) (xy 170.901106 -342.385142)
			(xy 170.517566 -342.001348) (xy 170.51075 -341.993929) (xy 170.503017 -341.975344) (xy 170.50258 -341.96528)
			(xy 167.420036 -341.96528) (xy 167.420036 -342.917526) (xy 167.420227 -342.92382) (xy 167.423313 -342.936025)
			(xy 167.426132 -342.941656) (xy 167.43852 -342.965617) (xy 167.457177 -343.016227) (xy 167.468523 -343.068959)
			(xy 167.472334 -343.122763) (xy 167.468534 -343.176568) (xy 167.457197 -343.229302) (xy 167.43855 -343.279916)
			(xy 167.426132 -343.30386) (xy 167.423304 -343.309488) (xy 167.420216 -343.321694) (xy 167.420036 -343.32799)
			(xy 167.420036 -345.6305) (xy 167.420511 -345.640467) (xy 167.428086 -345.658905) (xy 167.434768 -345.666314)
			(xy 167.455545 -345.68783) (xy 167.491908 -345.735318) (xy 167.521772 -345.787141) (xy 167.544628 -345.842414)
			(xy 167.560085 -345.900194) (xy 167.56788 -345.959496) (xy 167.568372 -345.989402) (xy 167.56787 -346.018967)
			(xy 167.560183 -346.077596) (xy 167.545013 -346.134749) (xy 167.522613 -346.189473) (xy 167.493356 -346.240859)
			(xy 167.475916 -346.264738) (xy 167.471223 -346.271537) (xy 167.466051 -346.287215) (xy 167.465756 -346.295472)
			(xy 167.465756 -346.302076) (xy 167.694608 -346.302076) (xy 167.698679 -346.246454) (xy 167.710805 -346.192017)
			(xy 167.730728 -346.139926) (xy 167.758024 -346.091291) (xy 167.79211 -346.047148) (xy 167.832259 -346.008439)
			(xy 167.877617 -345.975988) (xy 167.927217 -345.950487) (xy 167.980001 -345.93248) (xy 168.034844 -345.92235)
			(xy 168.090578 -345.920313) (xy 168.146015 -345.926413) (xy 168.199972 -345.940519) (xy 168.251301 -345.962331)
			(xy 168.298907 -345.991385) (xy 168.341775 -346.02706) (xy 168.378992 -346.068597) (xy 168.409765 -346.11511)
			(xy 168.433437 -346.165607) (xy 168.449505 -346.219014) (xy 168.457625 -346.27419) (xy 168.458134 -346.302076)
			(xy 168.457625 -346.329962) (xy 168.449505 -346.385138) (xy 168.433437 -346.438545) (xy 168.409765 -346.489042)
			(xy 168.378992 -346.535555) (xy 168.341775 -346.577092) (xy 168.298907 -346.612767) (xy 168.251301 -346.641821)
			(xy 168.199972 -346.663633) (xy 168.146015 -346.677739) (xy 168.090578 -346.683839) (xy 168.034844 -346.681802)
			(xy 167.980001 -346.671672) (xy 167.927217 -346.653665) (xy 167.877617 -346.628164) (xy 167.832259 -346.595713)
			(xy 167.79211 -346.557004) (xy 167.758024 -346.512861) (xy 167.730728 -346.464226) (xy 167.710805 -346.412135)
			(xy 167.698679 -346.357698) (xy 167.694608 -346.302076) (xy 167.465756 -346.302076) (xy 167.465756 -346.781628)
			(xy 200.011792 -346.781628) (xy 200.011792 -343.539572) (xy 200.012179 -343.529498) (xy 200.019924 -343.510899)
			(xy 200.026778 -343.503504) (xy 200.311004 -343.219278) (xy 200.318406 -343.21244) (xy 200.337004 -343.20472)
			(xy 200.347072 -343.204292) (xy 201.633328 -343.204292) (xy 201.643402 -343.204679) (xy 201.662001 -343.212424)
			(xy 201.669396 -343.219278) (xy 202.258422 -343.808304) (xy 202.26526 -343.815706) (xy 202.27298 -343.834304)
			(xy 202.273408 -343.844372) (xy 202.273408 -346.832428) (xy 202.273021 -346.842502) (xy 202.265276 -346.861101)
			(xy 202.258422 -346.868496) (xy 202.024996 -347.101922) (xy 202.017594 -347.10876) (xy 201.998996 -347.11648)
			(xy 201.988928 -347.116908) (xy 200.347072 -347.116908) (xy 200.336998 -347.116521) (xy 200.318399 -347.108776)
			(xy 200.311004 -347.101922) (xy 200.026778 -346.817696) (xy 200.01994 -346.810294) (xy 200.01222 -346.791696)
			(xy 200.011792 -346.781628) (xy 167.465756 -346.781628) (xy 167.465756 -346.822014) (xy 167.485568 -346.848938)
			(xy 167.501824 -346.853764) (xy 167.521429 -346.86017) (xy 167.558085 -346.879067) (xy 167.590706 -346.904298)
			(xy 167.618212 -346.935026) (xy 167.63969 -346.970231) (xy 167.654429 -347.008748) (xy 167.661939 -347.049298)
			(xy 167.662352 -347.069918) (xy 167.662352 -347.268848) (xy 203.547 -347.268848) (xy 203.547 -347.214352)
			(xy 203.554755 -347.160411) (xy 203.570108 -347.108122) (xy 203.592745 -347.05855) (xy 203.622206 -347.012704)
			(xy 203.657892 -346.971517) (xy 203.699075 -346.935828) (xy 203.744918 -346.906362) (xy 203.794488 -346.88372)
			(xy 203.846775 -346.868363) (xy 203.900716 -346.860603) (xy 203.927964 -346.860114) (xy 203.955334 -346.860598)
			(xy 204.009512 -346.868411) (xy 204.062015 -346.883896) (xy 204.111762 -346.906733) (xy 204.15773 -346.936454)
			(xy 204.178662 -346.954094) (xy 204.178916 -346.954348) (xy 204.18599 -346.959953) (xy 204.202917 -346.966188)
			(xy 204.211936 -346.96654) (xy 204.278992 -346.96654) (xy 204.28801 -346.966192) (xy 204.304928 -346.95994)
			(xy 204.312012 -346.954348) (xy 204.312012 -346.954094) (xy 204.312266 -346.954094) (xy 204.333199 -346.936456)
			(xy 204.379172 -346.906745) (xy 204.428919 -346.883908) (xy 204.481419 -346.868417) (xy 204.535595 -346.860588)
			(xy 204.562964 -346.860114) (xy 204.589876 -346.860595) (xy 204.643163 -346.868196) (xy 204.694856 -346.883196)
			(xy 204.743935 -346.905299) (xy 204.766926 -346.919296) (xy 204.76718 -346.919296) (xy 204.775203 -346.923891)
			(xy 204.793311 -346.927542) (xy 204.802486 -346.926408) (xy 204.869288 -346.915486) (xy 204.878413 -346.913542)
			(xy 204.894436 -346.904011) (xy 204.90053 -346.896944) (xy 204.91875 -346.875108) (xy 204.960565 -346.836565)
			(xy 205.007637 -346.804656) (xy 205.058924 -346.780086) (xy 205.11329 -346.763401) (xy 205.16953 -346.75497)
			(xy 205.197964 -346.75445) (xy 205.225212 -346.755012) (xy 205.279155 -346.762762) (xy 205.331446 -346.778111)
			(xy 205.38102 -346.800744) (xy 205.426869 -346.830203) (xy 205.468058 -346.865887) (xy 205.50375 -346.907069)
			(xy 205.533218 -346.952911) (xy 205.555862 -347.002481) (xy 205.571221 -347.054768) (xy 205.578983 -347.10871)
			(xy 205.579472 -347.135958) (xy 205.578988 -347.163328) (xy 205.571176 -347.217506) (xy 205.555691 -347.270009)
			(xy 205.532853 -347.319757) (xy 205.503132 -347.365724) (xy 205.485492 -347.386656) (xy 205.485238 -347.38691)
			(xy 205.479634 -347.393984) (xy 205.473399 -347.410911) (xy 205.473046 -347.41993) (xy 205.473046 -347.486986)
			(xy 205.4734 -347.496003) (xy 205.479649 -347.512921) (xy 205.485238 -347.520006) (xy 205.485492 -347.520006)
			(xy 205.485492 -347.52026) (xy 205.503125 -347.541197) (xy 205.532838 -347.587169) (xy 205.555675 -347.636915)
			(xy 205.571168 -347.689414) (xy 205.578997 -347.743589) (xy 205.579472 -347.770958) (xy 205.578986 -347.798209)
			(xy 205.57123 -347.852157) (xy 205.555875 -347.904452) (xy 205.533233 -347.954029) (xy 205.503767 -347.999879)
			(xy 205.468076 -348.04107) (xy 205.426885 -348.076761) (xy 205.381035 -348.106227) (xy 205.331458 -348.128869)
			(xy 205.279163 -348.144224) (xy 205.225215 -348.15198) (xy 205.170713 -348.15198) (xy 205.116765 -348.144224)
			(xy 205.06447 -348.128869) (xy 205.014893 -348.106227) (xy 204.969043 -348.076761) (xy 204.927852 -348.04107)
			(xy 204.892161 -347.999879) (xy 204.862695 -347.954029) (xy 204.840053 -347.904452) (xy 204.824698 -347.852157)
			(xy 204.816942 -347.798209) (xy 204.816456 -347.770958) (xy 204.816456 -347.770704) (xy 204.816596 -347.756361)
			(xy 204.818759 -347.727756) (xy 204.820774 -347.713554) (xy 204.822806 -347.700346) (xy 204.813408 -347.675708)
			(xy 204.736446 -347.611192) (xy 204.729468 -347.605905) (xy 204.713039 -347.599903) (xy 204.695548 -347.599767)
			(xy 204.68717 -347.602302) (xy 204.657048 -347.612043) (xy 204.594616 -347.62251) (xy 204.562964 -347.62313)
			(xy 204.535592 -347.622702) (xy 204.481411 -347.614878) (xy 204.428907 -347.599381) (xy 204.37916 -347.57653)
			(xy 204.333196 -347.546796) (xy 204.312266 -347.52915) (xy 204.312012 -347.528896) (xy 204.304927 -347.523308)
			(xy 204.288009 -347.517062) (xy 204.278992 -347.516704) (xy 204.211936 -347.516704) (xy 204.202921 -347.517077)
			(xy 204.186004 -347.523313) (xy 204.178916 -347.528896) (xy 204.178916 -347.52915) (xy 204.178662 -347.52915)
			(xy 204.157711 -347.546766) (xy 204.111744 -347.576483) (xy 204.062002 -347.599324) (xy 204.009505 -347.61482)
			(xy 203.955332 -347.622654) (xy 203.927964 -347.62313) (xy 203.900716 -347.622597) (xy 203.846775 -347.614837)
			(xy 203.794488 -347.59948) (xy 203.744918 -347.576838) (xy 203.699075 -347.547372) (xy 203.657892 -347.511683)
			(xy 203.622206 -347.470496) (xy 203.592745 -347.42465) (xy 203.570108 -347.375078) (xy 203.554755 -347.322789)
			(xy 203.547 -347.268848) (xy 167.662352 -347.268848) (xy 167.662352 -347.28658) (xy 167.661935 -347.2966)
			(xy 167.654267 -347.315116) (xy 167.640092 -347.329283) (xy 167.621573 -347.336941) (xy 167.611552 -347.33738)
			(xy 167.602408 -347.33738) (xy 167.602408 -347.631512) (xy 167.602898 -347.641517) (xy 167.61056 -347.660004)
			(xy 167.624713 -347.674151) (xy 167.643202 -347.681806) (xy 167.653208 -347.682312) (xy 167.875712 -347.682312)
			(xy 167.882662 -347.682067) (xy 167.896049 -347.678324) (xy 167.902128 -347.674946) (xy 167.924641 -347.661745)
			(xy 167.972484 -347.640897) (xy 168.022718 -347.626746) (xy 168.074409 -347.619557) (xy 168.100502 -347.619066)
			(xy 168.127755 -347.619552) (xy 168.181706 -347.627309) (xy 168.234004 -347.642666) (xy 168.283585 -347.665308)
			(xy 168.329438 -347.694777) (xy 168.370631 -347.730471) (xy 168.406324 -347.771664) (xy 168.435793 -347.817517)
			(xy 168.458435 -347.867098) (xy 168.473791 -347.919396) (xy 168.481548 -347.973347) (xy 168.481548 -348.027853)
			(xy 168.473791 -348.081804) (xy 168.458435 -348.134102) (xy 168.435793 -348.183683) (xy 168.406324 -348.229536)
			(xy 168.370631 -348.270729) (xy 168.329438 -348.306423) (xy 168.283585 -348.335892) (xy 168.234004 -348.358534)
			(xy 168.181706 -348.373891) (xy 168.127755 -348.381648) (xy 168.100502 -348.382082) (xy 168.074154 -348.381657)
			(xy 168.021958 -348.374434) (xy 167.971254 -348.360085) (xy 167.923013 -348.338884) (xy 167.90035 -348.32544)
			(xy 167.894245 -348.321935) (xy 167.880715 -348.318064) (xy 167.87368 -348.31782) (xy 167.569896 -348.31782)
			(xy 167.556688 -348.321376) (xy 167.550846 -348.324932) (xy 167.530759 -348.336137) (xy 167.487233 -348.350983)
			(xy 167.464486 -348.354396) (xy 167.445182 -348.356936) (xy 167.420036 -348.385384) (xy 167.420036 -349.219266)
			(xy 167.420472 -349.22933) (xy 167.428207 -349.247914) (xy 167.435022 -349.255334) (xy 167.503856 -349.324168)
			(xy 167.511277 -349.330956) (xy 167.529874 -349.338571) (xy 167.539924 -349.3389) (xy 167.623236 -349.3389)
			(xy 167.633239 -349.339394) (xy 167.651718 -349.34706) (xy 167.66586 -349.361212) (xy 167.673513 -349.379697)
			(xy 167.674036 -349.3897) (xy 167.674036 -349.398844) (xy 168.163494 -349.398844) (xy 168.169076 -349.398697)
			(xy 168.17997 -349.39626) (xy 168.185084 -349.394018) (xy 168.1988 -349.387922) (xy 168.1988 -349.368618)
			(xy 168.228518 -349.3389) (xy 168.466516 -349.3389) (xy 168.488834 -349.339472) (xy 168.53259 -349.3483)
			(xy 168.553384 -349.356426) (xy 168.562782 -349.360236) (xy 168.815004 -349.360236) (xy 168.823386 -349.357442)
			(xy 168.854606 -349.346936) (xy 168.919486 -349.335574) (xy 168.952418 -349.334836) (xy 168.979665 -349.335323)
			(xy 169.033605 -349.343081) (xy 169.085891 -349.358436) (xy 169.13546 -349.381076) (xy 169.181303 -349.410539)
			(xy 169.222487 -349.446226) (xy 169.258172 -349.487411) (xy 169.287633 -349.533255) (xy 169.31027 -349.582826)
			(xy 169.325623 -349.635113) (xy 169.333378 -349.689053) (xy 169.333378 -349.743547) (xy 169.325623 -349.797487)
			(xy 169.31027 -349.849774) (xy 169.287633 -349.899345) (xy 169.258172 -349.945189) (xy 169.222487 -349.986374)
			(xy 169.181303 -350.022061) (xy 169.13546 -350.051524) (xy 169.085891 -350.074164) (xy 169.033605 -350.089519)
			(xy 168.979665 -350.097277) (xy 168.952418 -350.097852) (xy 168.919483 -350.097138) (xy 168.854602 -350.08577)
			(xy 168.823386 -350.075246) (xy 168.815004 -350.072452) (xy 168.562782 -350.072452) (xy 168.553384 -350.076262)
			(xy 168.532597 -350.084413) (xy 168.488837 -350.093243) (xy 168.466516 -350.093788) (xy 168.228518 -350.093788)
			(xy 168.1988 -350.06407) (xy 168.1988 -350.044766) (xy 168.185084 -350.03867) (xy 168.179971 -350.036426)
			(xy 168.169076 -350.033982) (xy 168.163494 -350.033844) (xy 167.724836 -350.033844) (xy 167.714813 -350.034258)
			(xy 167.696292 -350.041923) (xy 167.682119 -350.056098) (xy 167.674456 -350.074621) (xy 167.674036 -350.084644)
			(xy 167.674036 -350.093788) (xy 167.470836 -350.093788) (xy 167.460809 -350.094201) (xy 167.442278 -350.101864)
			(xy 167.428091 -350.116037) (xy 167.420411 -350.134561) (xy 167.420036 -350.144588) (xy 167.420036 -350.3041)
			(xy 167.420456 -350.314119) (xy 167.428127 -350.332629) (xy 167.442301 -350.346793) (xy 167.460817 -350.354451)
			(xy 167.470836 -350.3549) (xy 167.623236 -350.3549) (xy 167.633239 -350.355394) (xy 167.651718 -350.36306)
			(xy 167.66586 -350.377212) (xy 167.673513 -350.395697) (xy 167.674036 -350.4057) (xy 167.674036 -350.414844)
			(xy 168.163494 -350.414844) (xy 168.169076 -350.414697) (xy 168.17997 -350.41226) (xy 168.185084 -350.410018)
			(xy 168.1988 -350.403922) (xy 168.1988 -350.384618) (xy 168.228518 -350.3549) (xy 168.466516 -350.3549)
			(xy 168.488834 -350.355472) (xy 168.53259 -350.3643) (xy 168.553384 -350.372426) (xy 168.562782 -350.376236)
			(xy 168.815004 -350.376236) (xy 168.823386 -350.373442) (xy 168.854606 -350.362936) (xy 168.919486 -350.351574)
			(xy 168.952418 -350.350836) (xy 168.979665 -350.351323) (xy 169.033605 -350.359081) (xy 169.085891 -350.374436)
			(xy 169.13546 -350.397076) (xy 169.181303 -350.426539) (xy 169.222487 -350.462226) (xy 169.258172 -350.503411)
			(xy 169.287633 -350.549255) (xy 169.31027 -350.598826) (xy 169.325623 -350.651113) (xy 169.333378 -350.705053)
			(xy 169.333378 -350.759547) (xy 169.325623 -350.813487) (xy 169.31027 -350.865774) (xy 169.287633 -350.915345)
			(xy 169.258172 -350.961189) (xy 169.222487 -351.002374) (xy 169.181303 -351.038061) (xy 169.13546 -351.067524)
			(xy 169.085891 -351.090164) (xy 169.033605 -351.105519) (xy 168.979665 -351.113277) (xy 168.952418 -351.113852)
			(xy 168.919483 -351.113138) (xy 168.854602 -351.10177) (xy 168.823386 -351.091246) (xy 168.815004 -351.088452)
			(xy 168.562782 -351.088452) (xy 168.553384 -351.092262) (xy 168.532597 -351.100413) (xy 168.488837 -351.109243)
			(xy 168.466516 -351.109788) (xy 168.228518 -351.109788) (xy 168.1988 -351.08007) (xy 168.1988 -351.060766)
			(xy 168.185084 -351.05467) (xy 168.179971 -351.052426) (xy 168.169076 -351.049982) (xy 168.163494 -351.049844)
			(xy 167.724836 -351.049844) (xy 167.714813 -351.050258) (xy 167.696292 -351.057923) (xy 167.682119 -351.072098)
			(xy 167.674456 -351.090621) (xy 167.674036 -351.100644) (xy 167.674036 -351.109788) (xy 167.470836 -351.109788)
			(xy 167.460809 -351.110201) (xy 167.442278 -351.117864) (xy 167.428091 -351.132037) (xy 167.420411 -351.150561)
			(xy 167.420036 -351.160588) (xy 167.420036 -352.262694) (xy 167.420209 -352.268702) (xy 167.423043 -352.280379)
			(xy 167.425624 -352.285808) (xy 167.427464 -352.289282) (xy 167.432058 -352.29566) (xy 167.434768 -352.298508)
			(xy 170.343068 -355.206808) (xy 170.345919 -355.209514) (xy 170.352298 -355.214107) (xy 170.355768 -355.215952)
			(xy 170.361195 -355.218535) (xy 170.372875 -355.221355) (xy 170.378882 -355.22154) (xy 175.891698 -355.22154)
			(xy 175.897706 -355.221367) (xy 175.909384 -355.218536) (xy 175.914812 -355.215952) (xy 175.918285 -355.214111)
			(xy 175.924662 -355.209515) (xy 175.927512 -355.206808) (xy 178.537108 -352.597212) (xy 178.539813 -352.59436)
			(xy 178.544403 -352.587981) (xy 178.546252 -352.584512) (xy 178.548832 -352.579085) (xy 178.551648 -352.567405)
			(xy 178.55184 -352.561398) (xy 178.55184 -351.943162) (xy 178.552271 -351.933096) (xy 178.56 -351.914505)
			(xy 178.566826 -351.907094) (xy 179.038504 -351.435416) (xy 179.045902 -351.428569) (xy 179.0645 -351.420833)
			(xy 179.074572 -351.42043) (xy 180.822092 -351.42043) (xy 180.832162 -351.420852) (xy 180.850766 -351.428568)
			(xy 180.85816 -351.435416) (xy 181.088538 -351.665794) (xy 181.095392 -351.673189) (xy 181.103139 -351.691788)
			(xy 181.103524 -351.701862) (xy 181.103524 -353.370388) (xy 181.104286 -353.37877) (xy 181.105796 -353.386377)
			(xy 181.112776 -353.400218) (xy 181.118002 -353.405948) (xy 181.160928 -353.448874) (xy 181.166634 -353.454208)
			(xy 181.180473 -353.461433) (xy 181.188106 -353.463098) (xy 181.2179 -353.468992) (xy 181.275708 -353.48762)
			(xy 181.330542 -353.513735) (xy 181.356254 -353.5299) (xy 181.362534 -353.533695) (xy 181.376605 -353.537828)
			(xy 181.38394 -353.538028) (xy 182.74411 -353.538028) (xy 182.752238 -353.537266) (xy 182.752746 -353.537266)
			(xy 182.760263 -353.535662) (xy 182.773945 -353.52868) (xy 182.77967 -353.52355) (xy 182.913528 -353.389692)
			(xy 182.918727 -353.383943) (xy 182.925709 -353.370112) (xy 182.927244 -353.362514) (xy 182.928006 -353.354132)
			(xy 182.928006 -351.636838) (xy 182.928441 -351.626773) (xy 182.936172 -351.608185) (xy 182.942992 -351.60077)
			(xy 183.023764 -351.519998) (xy 183.030452 -351.51259) (xy 183.038039 -351.494153) (xy 183.038496 -351.484184)
			(xy 183.038496 -351.467674) (xy 183.038924 -351.457606) (xy 183.046645 -351.439008) (xy 183.053482 -351.431606)
			(xy 183.209946 -351.275142) (xy 183.217345 -351.268298) (xy 183.235944 -351.260574) (xy 183.246014 -351.260156)
			(xy 186.901328 -351.260156) (xy 186.911395 -351.260586) (xy 186.929986 -351.268314) (xy 186.937396 -351.275142)
			(xy 187.01893 -351.356676) (xy 187.019946 -351.357692) (xy 187.02724 -351.363966) (xy 187.04513 -351.371)
			(xy 187.054744 -351.371408) (xy 189.194694 -351.371408) (xy 189.204765 -351.37183) (xy 189.22337 -351.379544)
			(xy 189.230762 -351.386394) (xy 189.502288 -351.65792) (xy 189.509133 -351.665319) (xy 189.516862 -351.683917)
			(xy 189.517274 -351.693988) (xy 189.517274 -353.4029) (xy 189.518036 -353.411282) (xy 189.519546 -353.41889)
			(xy 189.526523 -353.432733) (xy 189.531752 -353.43846) (xy 189.649354 -353.556062) (xy 189.655103 -353.561261)
			(xy 189.668935 -353.56824) (xy 189.676532 -353.569778) (xy 189.684914 -353.57054) (xy 191.157606 -353.57054)
			(xy 191.165734 -353.569778) (xy 191.166242 -353.569778) (xy 191.173759 -353.568175) (xy 191.187444 -353.561195)
			(xy 191.193166 -353.556062) (xy 191.294512 -353.454716) (xy 191.299704 -353.448964) (xy 191.306668 -353.435129)
			(xy 191.308228 -353.427538) (xy 191.30899 -353.419156) (xy 191.30899 -351.68586) (xy 191.30942 -351.675793)
			(xy 191.317143 -351.657198) (xy 191.323976 -351.649792) (xy 191.350392 -351.623376) (xy 191.357073 -351.615965)
			(xy 191.364648 -351.597529) (xy 191.365124 -351.587562) (xy 191.365124 -351.493074) (xy 191.365552 -351.483006)
			(xy 191.373276 -351.464411) (xy 191.38011 -351.457006) (xy 191.536574 -351.300542) (xy 191.543974 -351.293703)
			(xy 191.562573 -351.285988) (xy 191.572642 -351.285556) (xy 191.66713 -351.285556) (xy 191.677094 -351.285075)
			(xy 191.695524 -351.277492) (xy 191.702944 -351.270824) (xy 191.97828 -350.995488) (xy 191.985679 -350.988645)
			(xy 192.004278 -350.980925) (xy 192.014348 -350.980502) (xy 197.534276 -350.980502) (xy 197.996048 -351.442274)
			(xy 197.996048 -352.949002) (xy 197.996048 -363.382814) (xy 197.995621 -363.392882) (xy 197.987897 -363.411478)
			(xy 197.981062 -363.418882) (xy 197.958964 -363.44098) (xy 197.952123 -363.44838) (xy 197.944408 -363.466979)
			(xy 197.943978 -363.477048) (xy 197.943978 -363.6391) (xy 197.943554 -363.64917) (xy 197.935838 -363.667772)
			(xy 197.928992 -363.675168) (xy 197.365366 -364.238794) (xy 197.357966 -364.245636) (xy 197.339368 -364.253359)
			(xy 197.329298 -364.25378) (xy 190.668402 -364.25378) (xy 190.662394 -364.253953) (xy 190.650716 -364.256785)
			(xy 190.645288 -364.259368) (xy 190.641813 -364.261206) (xy 190.635431 -364.265797) (xy 190.632588 -364.268512)
			(xy 190.301372 -364.599728) (xy 190.298666 -364.602579) (xy 190.294073 -364.608957) (xy 190.292228 -364.612428)
			(xy 190.289642 -364.617854) (xy 190.286813 -364.629534) (xy 190.28664 -364.635542) (xy 190.28664 -366.78616)
			(xy 190.29172 -366.79124) (xy 190.29172 -367.527078) (xy 190.291891 -367.533087) (xy 190.294721 -367.544766)
			(xy 190.297308 -367.550192) (xy 190.299146 -367.553667) (xy 190.303738 -367.560048) (xy 190.306452 -367.562892)
			(xy 190.602108 -367.858548) (xy 190.604959 -367.861254) (xy 190.611337 -367.865848) (xy 190.614808 -367.867692)
			(xy 190.620234 -367.870279) (xy 190.631914 -367.873111) (xy 190.637922 -367.87328)
		)
		(stroke
			(width 0)
			(type solid)
		)
		(fill yes)
		(layer "B.Cu")
		(net "GND")
	)
	(gr_poly
		(pts
			(xy 156.10332 -320.298064) (xy 156.113388 -320.297636) (xy 156.131984 -320.289913) (xy 156.139388 -320.283078)
			(xy 157.305248 -319.117218) (xy 157.312087 -319.109818) (xy 157.3198 -319.091219) (xy 157.320234 -319.08115)
			(xy 157.320234 -314.297314) (xy 157.319793 -314.287252) (xy 157.31205 -314.268677) (xy 157.305248 -314.261246)
			(xy 153.390346 -310.346344) (xy 153.383629 -310.339107) (xy 153.376021 -310.320903) (xy 153.375614 -310.311038)
			(xy 153.375614 -304.363374) (xy 153.375187 -304.353306) (xy 153.367467 -304.334707) (xy 153.360628 -304.327306)
			(xy 145.41754 -296.384218) (xy 145.410428 -296.376852) (xy 145.391632 -296.369232) (xy 143.840708 -296.369232)
			(xy 143.830872 -296.368693) (xy 143.812713 -296.361104) (xy 143.805402 -296.3545) (xy 143.1036 -295.652698)
			(xy 143.096488 -295.645332) (xy 143.077692 -295.637712) (xy 129.772156 -295.637712) (xy 129.76209 -295.638144)
			(xy 129.743498 -295.64587) (xy 129.736088 -295.652698) (xy 129.577846 -295.81094) (xy 129.571142 -295.818182)
			(xy 129.563565 -295.836386) (xy 129.563114 -295.846246) (xy 129.563114 -296.510964) (xy 130.966464 -296.510964)
			(xy 130.96695 -296.483713) (xy 130.974706 -296.429765) (xy 130.990061 -296.37747) (xy 131.012703 -296.327893)
			(xy 131.042169 -296.282043) (xy 131.07786 -296.240852) (xy 131.119051 -296.205161) (xy 131.164901 -296.175695)
			(xy 131.214478 -296.153053) (xy 131.266773 -296.137698) (xy 131.320721 -296.129942) (xy 131.375223 -296.129942)
			(xy 131.429171 -296.137698) (xy 131.481466 -296.153053) (xy 131.531043 -296.175695) (xy 131.576893 -296.205161)
			(xy 131.618084 -296.240852) (xy 131.653775 -296.282043) (xy 131.683241 -296.327893) (xy 131.705883 -296.37747)
			(xy 131.721238 -296.429765) (xy 131.728994 -296.483713) (xy 131.72948 -296.510964) (xy 131.728973 -296.53924)
			(xy 131.720624 -296.595172) (xy 131.704118 -296.649261) (xy 131.679815 -296.700324) (xy 131.664456 -296.72407)
			(xy 131.660138 -296.73042) (xy 131.65582 -296.744898) (xy 131.65582 -296.867326) (xy 131.656196 -296.877371)
			(xy 131.66378 -296.895967) (xy 131.670552 -296.903394) (xy 134.66191 -299.894752) (xy 134.669396 -299.901439)
			(xy 134.687952 -299.909033) (xy 134.697978 -299.909484) (xy 144.209008 -299.909484) (xy 144.233198 -299.909978)
			(xy 144.280981 -299.917546) (xy 144.326993 -299.932494) (xy 144.370101 -299.954455) (xy 144.409244 -299.982887)
			(xy 144.426686 -299.999654) (xy 148.254212 -303.82718) (xy 148.270943 -303.844642) (xy 148.299321 -303.883798)
			(xy 148.321231 -303.926907) (xy 148.336135 -303.972911) (xy 148.343667 -304.020679) (xy 148.344128 -304.044858)
			(xy 148.344128 -313.02706) (xy 148.344699 -313.037039) (xy 148.352422 -313.055451) (xy 148.366539 -313.069571)
			(xy 148.384949 -313.077298) (xy 148.394928 -313.07786) (xy 148.652484 -313.07786) (xy 148.672969 -313.078312)
			(xy 148.713273 -313.085661) (xy 148.751598 -313.100141) (xy 148.786692 -313.12128) (xy 148.802344 -313.134502)
			(xy 148.809453 -313.140385) (xy 148.826654 -313.147023) (xy 148.835872 -313.147456) (xy 149.1869 -313.147456)
			(xy 149.196104 -313.146958) (xy 149.213289 -313.140331) (xy 149.220428 -313.134502) (xy 149.23608 -313.121275)
			(xy 149.271163 -313.100109) (xy 149.309489 -313.085619) (xy 149.349801 -313.07828) (xy 149.370288 -313.07786)
			(xy 149.558502 -313.07786) (xy 149.583902 -313.060842) (xy 149.589744 -313.046364) (xy 149.593116 -313.036936)
			(xy 149.59313 -313.016933) (xy 149.585522 -312.998433) (xy 149.578822 -312.990992) (xy 149.217634 -312.630058)
			(xy 149.200834 -312.612643) (xy 149.172395 -312.573497) (xy 149.150429 -312.530383) (xy 149.135479 -312.484364)
			(xy 149.127913 -312.436573) (xy 149.127464 -312.41238) (xy 149.127464 -311.285382) (xy 149.127904 -311.261189)
			(xy 149.135476 -311.213399) (xy 149.150431 -311.167382) (xy 149.1724 -311.124271) (xy 149.200844 -311.085128)
			(xy 149.217634 -311.067704) (xy 149.302724 -310.982614) (xy 149.309434 -310.975214) (xy 149.317069 -310.956777)
			(xy 149.317069 -310.936823) (xy 149.309434 -310.918386) (xy 149.302724 -310.910986) (xy 149.302724 -310.910732)
			(xy 149.30247 -310.910478) (xy 149.300438 -310.9087) (xy 149.193758 -310.80202) (xy 149.176992 -310.784574)
			(xy 149.148547 -310.745437) (xy 149.126575 -310.702331) (xy 149.111617 -310.656319) (xy 149.104041 -310.608533)
			(xy 149.103588 -310.584342) (xy 149.103588 -310.310022) (xy 149.1041 -310.285833) (xy 149.111663 -310.23805)
			(xy 149.126607 -310.192038) (xy 149.148564 -310.14893) (xy 149.176993 -310.109787) (xy 149.193758 -310.092344)
			(xy 149.290786 -309.995316) (xy 149.297556 -309.987955) (xy 149.305208 -309.969494) (xy 149.305209 -309.949509)
			(xy 149.297558 -309.931047) (xy 149.290786 -309.923688) (xy 149.193758 -309.82666) (xy 149.176964 -309.80924)
			(xy 149.148522 -309.770096) (xy 149.126555 -309.726984) (xy 149.111604 -309.680966) (xy 149.104037 -309.633175)
			(xy 149.103588 -309.608982) (xy 149.103588 -304.275744) (xy 149.103225 -304.265698) (xy 149.095631 -304.247102)
			(xy 149.088856 -304.239676) (xy 144.454372 -299.605192) (xy 144.446887 -299.598503) (xy 144.428331 -299.590909)
			(xy 144.418304 -299.59046) (xy 135.05942 -299.59046) (xy 135.03523 -299.589965) (xy 134.987446 -299.5824)
			(xy 134.941433 -299.567453) (xy 134.898325 -299.545492) (xy 134.859183 -299.517058) (xy 134.841742 -299.50029)
			(xy 132.235702 -296.893996) (xy 132.22224 -296.886884) (xy 132.214874 -296.88536) (xy 132.189141 -296.879888)
			(xy 132.139366 -296.862851) (xy 132.092407 -296.839134) (xy 132.049153 -296.809187) (xy 132.010426 -296.773578)
			(xy 131.976962 -296.732983) (xy 131.949397 -296.688174) (xy 131.928252 -296.640001) (xy 131.91393 -296.589379)
			(xy 131.906703 -296.537269) (xy 131.906264 -296.510964) (xy 131.906744 -296.483713) (xy 131.914505 -296.429767)
			(xy 131.929863 -296.377474) (xy 131.952506 -296.327898) (xy 131.981974 -296.282049) (xy 132.017666 -296.24086)
			(xy 132.058856 -296.205169) (xy 132.104705 -296.175703) (xy 132.154281 -296.15306) (xy 132.206575 -296.137703)
			(xy 132.260521 -296.129944) (xy 132.287772 -296.129456) (xy 132.314073 -296.12993) (xy 132.366173 -296.137178)
			(xy 132.416783 -296.151513) (xy 132.464946 -296.172663) (xy 132.509747 -296.200227) (xy 132.550338 -296.233683)
			(xy 132.585949 -296.272397) (xy 132.615906 -296.315635) (xy 132.63964 -296.362578) (xy 132.656702 -296.412336)
			(xy 132.662168 -296.438066) (xy 132.663692 -296.445432) (xy 132.670804 -296.458894) (xy 132.722874 -296.510964)
			(xy 133.786372 -296.510964) (xy 133.786858 -296.483713) (xy 133.794614 -296.429765) (xy 133.809969 -296.37747)
			(xy 133.832611 -296.327893) (xy 133.862077 -296.282043) (xy 133.897768 -296.240852) (xy 133.938959 -296.205161)
			(xy 133.984809 -296.175695) (xy 134.034386 -296.153053) (xy 134.086681 -296.137698) (xy 134.140629 -296.129942)
			(xy 134.195131 -296.129942) (xy 134.249079 -296.137698) (xy 134.301374 -296.153053) (xy 134.350951 -296.175695)
			(xy 134.396801 -296.205161) (xy 134.437992 -296.240852) (xy 134.473683 -296.282043) (xy 134.503149 -296.327893)
			(xy 134.525791 -296.37747) (xy 134.541146 -296.429765) (xy 134.548902 -296.483713) (xy 134.549388 -296.510964)
			(xy 134.548821 -296.540803) (xy 134.5395 -296.599749) (xy 134.530846 -296.628312) (xy 134.526528 -296.641774)
			(xy 134.533132 -296.669714) (xy 135.77951 -297.916092) (xy 135.786991 -297.922785) (xy 135.805551 -297.930374)
			(xy 135.815578 -297.930824) (xy 144.881854 -297.930824) (xy 144.906045 -297.931277) (xy 144.953831 -297.938853)
			(xy 144.999844 -297.953811) (xy 145.042951 -297.97578) (xy 145.082092 -298.004222) (xy 145.099532 -298.020994)
			(xy 151.502872 -304.424334) (xy 151.51964 -304.441762) (xy 151.54801 -304.480928) (xy 151.569913 -304.524047)
			(xy 151.584808 -304.570057) (xy 151.592332 -304.617831) (xy 151.592788 -304.642012) (xy 151.592788 -310.802782)
			(xy 151.593199 -310.812853) (xy 151.600927 -310.831452) (xy 151.607774 -310.83885) (xy 153.176732 -312.407554)
			(xy 153.193455 -312.425024) (xy 153.221833 -312.464178) (xy 153.243744 -312.507286) (xy 153.258651 -312.553287)
			(xy 153.266186 -312.601053) (xy 153.266648 -312.625232) (xy 153.266648 -313.249564) (xy 153.267114 -313.258772)
			(xy 153.273763 -313.275956) (xy 153.279602 -313.283092) (xy 153.292859 -313.298719) (xy 153.314019 -313.333812)
			(xy 153.328501 -313.372145) (xy 153.33583 -313.412462) (xy 153.336244 -313.432952) (xy 153.336244 -313.700668)
			(xy 153.3271 -313.700668) (xy 153.317096 -313.701187) (xy 153.298611 -313.708841) (xy 153.284459 -313.722984)
			(xy 153.276794 -313.741465) (xy 153.2763 -313.751468) (xy 153.2763 -314.225432) (xy 153.285444 -314.225432)
			(xy 153.295458 -314.225853) (xy 153.313957 -314.233533) (xy 153.32811 -314.247707) (xy 153.335762 -314.266217)
			(xy 153.336244 -314.276232) (xy 153.336244 -314.493148) (xy 153.336123 -314.504333) (xy 153.333964 -314.526599)
			(xy 153.331926 -314.537598) (xy 153.330723 -314.545526) (xy 153.332658 -314.561435) (xy 153.335736 -314.56884)
			(xy 153.34472 -314.589196) (xy 153.357393 -314.631847) (xy 153.363794 -314.675879) (xy 153.364184 -314.698126)
			(xy 153.364184 -314.992004) (xy 153.364685 -315.00201) (xy 153.372342 -315.020499) (xy 153.386491 -315.034651)
			(xy 153.404978 -315.042313) (xy 153.414984 -315.042804) (xy 153.61666 -315.042804) (xy 153.626678 -315.042348)
			(xy 153.645193 -315.034692) (xy 153.659367 -315.02053) (xy 153.667039 -315.002022) (xy 153.66746 -314.992004)
			(xy 153.66746 -314.676536) (xy 153.666992 -314.667328) (xy 153.660345 -314.650144) (xy 153.654506 -314.643008)
			(xy 153.64125 -314.62738) (xy 153.62009 -314.592288) (xy 153.605608 -314.553955) (xy 153.598278 -314.513638)
			(xy 153.597864 -314.493148) (xy 153.597864 -314.225432) (xy 153.607008 -314.225432) (xy 153.617012 -314.224919)
			(xy 153.635498 -314.217263) (xy 153.649649 -314.203118) (xy 153.657314 -314.184636) (xy 153.657808 -314.174632)
			(xy 153.657808 -313.700668) (xy 153.648664 -313.700668) (xy 153.63865 -313.700241) (xy 153.620151 -313.692563)
			(xy 153.605999 -313.678391) (xy 153.598346 -313.659883) (xy 153.597864 -313.649868) (xy 153.597864 -313.432952)
			(xy 153.598278 -313.412466) (xy 153.605639 -313.37216) (xy 153.62013 -313.333835) (xy 153.641279 -313.298742)
			(xy 153.654506 -313.283092) (xy 153.660374 -313.275972) (xy 153.667021 -313.258779) (xy 153.66746 -313.249564)
			(xy 153.66746 -312.530998) (xy 153.667046 -312.520927) (xy 153.659319 -312.502329) (xy 153.652474 -312.49493)
			(xy 152.107138 -310.949848) (xy 152.090334 -310.932437) (xy 152.061895 -310.89329) (xy 152.03993 -310.850175)
			(xy 152.024981 -310.804155) (xy 152.017416 -310.756364) (xy 152.016968 -310.73217) (xy 152.016968 -304.544984)
			(xy 152.016589 -304.53494) (xy 152.009007 -304.516343) (xy 152.002236 -304.508916) (xy 145.102072 -297.608752)
			(xy 145.094592 -297.602057) (xy 145.076032 -297.594468) (xy 145.066004 -297.59402) (xy 135.908542 -297.59402)
			(xy 135.884351 -297.593556) (xy 135.836566 -297.585981) (xy 135.790554 -297.571025) (xy 135.747447 -297.549058)
			(xy 135.708305 -297.52062) (xy 135.690864 -297.50385) (xy 135.085328 -296.89806) (xy 135.070088 -296.890694)
			(xy 135.061706 -296.889678) (xy 135.034298 -296.885909) (xy 134.980928 -296.871335) (xy 134.930221 -296.849206)
			(xy 134.883242 -296.819986) (xy 134.840975 -296.784288) (xy 134.804307 -296.74286) (xy 134.774006 -296.696571)
			(xy 134.750708 -296.646391) (xy 134.7349 -296.593372) (xy 134.726916 -296.538626) (xy 134.726426 -296.510964)
			(xy 134.726844 -296.48371) (xy 134.734607 -296.429758) (xy 134.749968 -296.37746) (xy 134.772616 -296.327881)
			(xy 134.802089 -296.282029) (xy 134.837788 -296.240838) (xy 134.878985 -296.205147) (xy 134.924842 -296.175682)
			(xy 134.974426 -296.153044) (xy 135.026727 -296.137692) (xy 135.08068 -296.129939) (xy 135.107934 -296.129456)
			(xy 135.135484 -296.129935) (xy 135.190013 -296.137853) (xy 135.242835 -296.153535) (xy 135.292851 -296.176654)
			(xy 135.33902 -296.206729) (xy 135.380381 -296.243134) (xy 135.416074 -296.285111) (xy 135.445355 -296.331787)
			(xy 135.467616 -296.382191) (xy 135.475472 -296.408602) (xy 135.47725 -296.415206) (xy 135.4836 -296.426128)
			(xy 136.021064 -296.963592) (xy 136.028527 -296.970309) (xy 136.0471 -296.977884) (xy 136.057132 -296.978324)
			(xy 145.214594 -296.978324) (xy 145.238784 -296.978815) (xy 145.286568 -296.986382) (xy 145.332581 -297.00133)
			(xy 145.375689 -297.023292) (xy 145.41483 -297.051726) (xy 145.432272 -297.068494) (xy 152.542494 -304.178716)
			(xy 152.559267 -304.196154) (xy 152.587705 -304.235295) (xy 152.609669 -304.278404) (xy 152.62462 -304.324417)
			(xy 152.632189 -304.372203) (xy 152.632664 -304.396394) (xy 152.632664 -310.58358) (xy 152.633001 -310.593629)
			(xy 152.640611 -310.612226) (xy 152.647396 -310.619648) (xy 154.192732 -312.16473) (xy 154.209491 -312.182166)
			(xy 154.237864 -312.22133) (xy 154.259769 -312.264446) (xy 154.274667 -312.310455) (xy 154.282192 -312.358227)
			(xy 154.282648 -312.382408) (xy 154.282648 -313.249564) (xy 154.283114 -313.258772) (xy 154.289763 -313.275956)
			(xy 154.295602 -313.283092) (xy 154.308859 -313.298719) (xy 154.330019 -313.333812) (xy 154.344501 -313.372145)
			(xy 154.35183 -313.412462) (xy 154.352244 -313.432952) (xy 154.352244 -313.700668) (xy 154.3431 -313.700668)
			(xy 154.333096 -313.701187) (xy 154.314611 -313.708841) (xy 154.300459 -313.722984) (xy 154.292794 -313.741465)
			(xy 154.2923 -313.751468) (xy 154.2923 -314.225432) (xy 154.301444 -314.225432) (xy 154.311458 -314.225853)
			(xy 154.329957 -314.233533) (xy 154.34411 -314.247707) (xy 154.351762 -314.266217) (xy 154.352244 -314.276232)
			(xy 154.352244 -314.493148) (xy 154.351828 -314.513634) (xy 154.344467 -314.55394) (xy 154.329977 -314.592265)
			(xy 154.308828 -314.627357) (xy 154.295602 -314.643008) (xy 154.289736 -314.650129) (xy 154.283088 -314.667321)
			(xy 154.282648 -314.676536) (xy 154.282648 -315.241432) (xy 154.28242 -315.25866) (xy 154.278605 -315.292904)
			(xy 154.275028 -315.309758) (xy 154.27198 -315.322966) (xy 154.279346 -315.347604) (xy 154.566112 -315.63437)
			(xy 154.582839 -315.651836) (xy 154.611217 -315.690991) (xy 154.633128 -315.7341) (xy 154.648033 -315.780102)
			(xy 154.655567 -315.827869) (xy 154.656028 -315.852048) (xy 154.656028 -316.145672) (xy 154.656461 -316.155741)
			(xy 154.664176 -316.174339) (xy 154.671014 -316.18174) (xy 154.673046 -316.183772) (xy 154.680158 -316.190884)
			(xy 154.698954 -316.198504) (xy 154.751786 -316.198504) (xy 154.76601 -316.19444) (xy 154.772106 -316.19063)
			(xy 154.790832 -316.179039) (xy 154.830876 -316.16071) (xy 154.873123 -316.148276) (xy 154.916711 -316.141989)
			(xy 154.93873 -316.141608) (xy 155.144216 -316.141608) (xy 155.174188 -316.111636) (xy 155.174188 -316.097412)
			(xy 155.174698 -316.087407) (xy 155.182351 -316.068917) (xy 155.196497 -316.054764) (xy 155.214983 -316.047102)
			(xy 155.224988 -316.046612) (xy 155.75788 -316.046612) (xy 155.767901 -316.047036) (xy 155.78642 -316.054702)
			(xy 155.800593 -316.068873) (xy 155.808262 -316.087391) (xy 155.80868 -316.097412) (xy 155.80868 -316.311788)
			(xy 155.817824 -316.311788) (xy 155.82782 -316.312299) (xy 155.846276 -316.319993) (xy 155.860414 -316.334134)
			(xy 155.868103 -316.352592) (xy 155.868624 -316.362588) (xy 155.868624 -316.57925) (xy 155.868102 -316.601561)
			(xy 155.859368 -316.64532) (xy 155.842227 -316.686518) (xy 155.817346 -316.723559) (xy 155.785688 -316.755006)
			(xy 155.748482 -316.779639) (xy 155.70717 -316.796504) (xy 155.663354 -316.804946) (xy 155.64104 -316.80531)
			(xy 155.64104 -316.805056) (xy 155.591764 -316.805056) (xy 155.581691 -316.805448) (xy 155.563092 -316.81319)
			(xy 155.555696 -316.820042) (xy 155.0289 -317.346838) (xy 155.022194 -317.354309) (xy 155.014613 -317.372876)
			(xy 155.014168 -317.382906) (xy 155.014168 -317.455296) (xy 155.014691 -317.465299) (xy 155.022343 -317.483785)
			(xy 155.036485 -317.497937) (xy 155.054965 -317.505602) (xy 155.064968 -317.506096) (xy 155.21432 -317.506096)
			(xy 155.231015 -317.506617) (xy 155.263269 -317.515253) (xy 155.292195 -317.531932) (xy 155.315827 -317.555521)
			(xy 155.332559 -317.584417) (xy 155.341252 -317.616656) (xy 155.341828 -317.63335) (xy 155.341828 -319.43675)
			(xy 155.341399 -319.453464) (xy 155.332725 -319.485746) (xy 155.315983 -319.514679) (xy 155.292315 -319.538285)
			(xy 155.26334 -319.554952) (xy 155.231035 -319.563543) (xy 155.21432 -319.564004) (xy 154.19832 -319.564004)
			(xy 154.181627 -319.563448) (xy 154.149374 -319.554822) (xy 154.120448 -319.53815) (xy 154.096815 -319.514568)
			(xy 154.080082 -319.485677) (xy 154.071388 -319.453442) (xy 154.070812 -319.43675) (xy 154.070812 -317.63335)
			(xy 154.0713 -317.616641) (xy 154.079969 -317.584368) (xy 154.096702 -317.555441) (xy 154.120357 -317.531837)
			(xy 154.149319 -317.515165) (xy 154.18161 -317.506565) (xy 154.19832 -317.506096) (xy 154.347672 -317.506096)
			(xy 154.357692 -317.505657) (xy 154.376209 -317.497996) (xy 154.390382 -317.483829) (xy 154.398053 -317.465316)
			(xy 154.398472 -317.455296) (xy 154.398472 -317.234316) (xy 154.39887 -317.212488) (xy 154.40503 -317.169269)
			(xy 154.417243 -317.127356) (xy 154.425904 -317.107316) (xy 154.431238 -317.095632) (xy 154.42946 -317.070232)
			(xy 154.37104 -316.977014) (xy 154.348942 -316.964314) (xy 154.336242 -316.963806) (xy 154.306805 -316.962582)
			(xy 154.248594 -316.953482) (xy 154.192033 -316.936986) (xy 154.138057 -316.913366) (xy 154.087559 -316.883013)
			(xy 154.041375 -316.84643) (xy 154.000268 -316.804221) (xy 153.96492 -316.757086) (xy 153.935914 -316.705802)
			(xy 153.913731 -316.65122) (xy 153.898737 -316.594242) (xy 153.89118 -316.535811) (xy 153.890726 -316.506352)
			(xy 153.89124 -316.476266) (xy 153.899122 -316.416613) (xy 153.914757 -316.358508) (xy 153.937876 -316.302955)
			(xy 153.968079 -316.250913) (xy 154.004844 -316.20328) (xy 154.025854 -316.18174) (xy 154.032663 -316.174315)
			(xy 154.040402 -316.155735) (xy 154.04084 -316.145672) (xy 154.04084 -316.000638) (xy 154.040411 -315.990569)
			(xy 154.032694 -315.97197) (xy 154.025854 -315.96457) (xy 153.81351 -315.752226) (xy 153.806097 -315.745402)
			(xy 153.787508 -315.737672) (xy 153.777442 -315.73724) (xy 153.718768 -315.73724) (xy 153.718768 -315.728096)
			(xy 153.718383 -315.71807) (xy 153.710706 -315.699547) (xy 153.696522 -315.685374) (xy 153.677994 -315.67771)
			(xy 153.667968 -315.677296) (xy 153.414984 -315.677296) (xy 153.404976 -315.677775) (xy 153.386484 -315.685439)
			(xy 153.372332 -315.699594) (xy 153.364672 -315.718088) (xy 153.364184 -315.728096) (xy 153.364184 -316.348872)
			(xy 153.36452 -316.358921) (xy 153.37213 -316.377518) (xy 153.378916 -316.38494) (xy 153.399902 -316.406504)
			(xy 153.436677 -316.45413) (xy 153.46689 -316.506166) (xy 153.490021 -316.561714) (xy 153.505668 -316.619815)
			(xy 153.513564 -316.679466) (xy 153.514044 -316.709552) (xy 153.513494 -316.739518) (xy 153.505677 -316.798939)
			(xy 153.490172 -316.856831) (xy 153.467242 -316.912204) (xy 153.43728 -316.964111) (xy 153.4008 -317.011662)
			(xy 153.358425 -317.054045) (xy 153.31088 -317.090534) (xy 153.25898 -317.120504) (xy 153.203611 -317.143444)
			(xy 153.145722 -317.158961) (xy 153.086302 -317.166789) (xy 153.056336 -317.16726) (xy 153.028528 -317.166829)
			(xy 152.973323 -317.160091) (xy 152.919342 -317.146709) (xy 152.867381 -317.126881) (xy 152.818207 -317.1009)
			(xy 152.772547 -317.069148) (xy 152.751536 -317.050928) (xy 152.744302 -317.045061) (xy 152.726922 -317.038415)
			(xy 152.708314 -317.038371) (xy 152.699466 -317.041276) (xy 152.672963 -317.050749) (xy 152.617622 -317.060971)
			(xy 152.589484 -317.061596) (xy 152.5651 -317.061596) (xy 152.555093 -317.062088) (xy 152.536602 -317.069747)
			(xy 152.522449 -317.083899) (xy 152.514789 -317.102389) (xy 152.5143 -317.112396) (xy 152.5143 -317.455296)
			(xy 152.514723 -317.465317) (xy 152.522391 -317.483834) (xy 152.536563 -317.498006) (xy 152.555079 -317.505676)
			(xy 152.5651 -317.506096) (xy 152.714452 -317.506096) (xy 152.731144 -317.506676) (xy 152.763396 -317.515296)
			(xy 152.792322 -317.531962) (xy 152.815956 -317.55554) (xy 152.832689 -317.584428) (xy 152.841384 -317.616659)
			(xy 152.84196 -317.63335) (xy 152.84196 -319.43675) (xy 152.8415 -319.453461) (xy 152.832828 -319.485739)
			(xy 152.816091 -319.514668) (xy 152.79243 -319.538273) (xy 152.763462 -319.554943) (xy 152.731164 -319.563539)
			(xy 152.714452 -319.564004) (xy 151.698452 -319.564004) (xy 151.681756 -319.563508) (xy 151.6495 -319.554865)
			(xy 151.620574 -319.53818) (xy 151.596943 -319.514587) (xy 151.580212 -319.485687) (xy 151.571519 -319.453445)
			(xy 151.570944 -319.43675) (xy 151.570944 -317.63335) (xy 151.5714 -317.616639) (xy 151.580072 -317.58436)
			(xy 151.59681 -317.555431) (xy 151.620472 -317.531825) (xy 151.649441 -317.515156) (xy 151.68174 -317.506561)
			(xy 151.698452 -317.506096) (xy 151.847804 -317.506096) (xy 151.857812 -317.505615) (xy 151.876305 -317.497953)
			(xy 151.890458 -317.483798) (xy 151.898117 -317.465304) (xy 151.898604 -317.455296) (xy 151.898604 -317.22441)
			(xy 151.898281 -317.214359) (xy 151.890662 -317.195762) (xy 151.883872 -317.188342) (xy 151.820372 -317.124842)
			(xy 151.812971 -317.118003) (xy 151.794373 -317.110281) (xy 151.784304 -317.109856) (xy 151.735028 -317.109856)
			(xy 151.735028 -317.11011) (xy 151.712718 -317.109684) (xy 151.668911 -317.101241) (xy 151.627607 -317.084379)
			(xy 151.590406 -317.059753) (xy 151.558749 -317.028317) (xy 151.533865 -316.991289) (xy 151.516715 -316.950104)
			(xy 151.507966 -316.906357) (xy 151.507444 -316.88405) (xy 151.507444 -316.616588) (xy 151.516588 -316.616588)
			(xy 151.52661 -316.61617) (xy 151.545129 -316.608502) (xy 151.559302 -316.594329) (xy 151.56697 -316.57581)
			(xy 151.567388 -316.565788) (xy 151.567388 -316.402212) (xy 151.567898 -316.392207) (xy 151.575551 -316.373717)
			(xy 151.589697 -316.359564) (xy 151.608183 -316.351902) (xy 151.618188 -316.351412) (xy 152.172416 -316.351412)
			(xy 152.20188 -316.381384) (xy 152.20188 -316.395608) (xy 152.202443 -316.40559) (xy 152.210158 -316.424011)
			(xy 152.224279 -316.438135) (xy 152.242698 -316.445854) (xy 152.25268 -316.446408) (xy 152.467564 -316.446408)
			(xy 152.479756 -316.443106) (xy 152.485598 -316.440058) (xy 152.508465 -316.428051) (xy 152.557207 -316.410981)
			(xy 152.608113 -316.402276) (xy 152.633934 -316.401704) (xy 152.705816 -316.401704) (xy 152.724612 -316.394084)
			(xy 152.731724 -316.386972) (xy 152.733756 -316.38494) (xy 152.740466 -316.377472) (xy 152.748046 -316.358902)
			(xy 152.748488 -316.348872) (xy 152.748488 -315.65977) (xy 152.74417 -315.645292) (xy 152.739852 -315.638942)
			(xy 152.727312 -315.619757) (xy 152.709517 -315.577525) (xy 152.700604 -315.532573) (xy 152.700228 -315.509656)
			(xy 152.700228 -315.210444) (xy 152.700658 -315.187535) (xy 152.709603 -315.142604) (xy 152.727381 -315.100381)
			(xy 152.739852 -315.081158) (xy 152.74417 -315.074808) (xy 152.748488 -315.06033) (xy 152.748488 -314.846462)
			(xy 152.748126 -314.836843) (xy 152.741061 -314.818953) (xy 152.734772 -314.811664) (xy 152.717292 -314.792275)
			(xy 152.688498 -314.748736) (xy 152.667469 -314.70096) (xy 152.660604 -314.675774) (xy 152.658777 -314.669154)
			(xy 152.652087 -314.657167) (xy 152.647396 -314.652152) (xy 152.632241 -314.636101) (xy 152.607847 -314.599316)
			(xy 152.59103 -314.558507) (xy 152.582425 -314.515216) (xy 152.581864 -314.493148) (xy 152.581864 -314.225432)
			(xy 152.591008 -314.225432) (xy 152.601012 -314.224919) (xy 152.619498 -314.217263) (xy 152.633649 -314.203118)
			(xy 152.641314 -314.184636) (xy 152.641808 -314.174632) (xy 152.641808 -313.921648) (xy 152.641341 -313.911631)
			(xy 152.633689 -313.893116) (xy 152.619531 -313.878943) (xy 152.601025 -313.87127) (xy 152.591008 -313.870848)
			(xy 152.40889 -313.870848) (xy 152.398845 -313.871225) (xy 152.380249 -313.878808) (xy 152.372822 -313.88558)
			(xy 151.864314 -314.394088) (xy 151.857489 -314.4015) (xy 151.84976 -314.42009) (xy 151.849328 -314.430156)
			(xy 151.849328 -314.81141) (xy 151.849637 -314.818986) (xy 151.854164 -314.83345) (xy 151.858218 -314.839858)
			(xy 151.873554 -314.863618) (xy 151.897866 -314.914675) (xy 151.914377 -314.96876) (xy 151.922727 -315.024689)
			(xy 151.923242 -315.052964) (xy 151.922756 -315.080215) (xy 151.915 -315.134163) (xy 151.899645 -315.186458)
			(xy 151.877003 -315.236035) (xy 151.847537 -315.281885) (xy 151.811846 -315.323076) (xy 151.770655 -315.358767)
			(xy 151.724805 -315.388233) (xy 151.675228 -315.410875) (xy 151.622933 -315.42623) (xy 151.568985 -315.433986)
			(xy 151.514483 -315.433986) (xy 151.460535 -315.42623) (xy 151.40824 -315.410875) (xy 151.358663 -315.388233)
			(xy 151.312813 -315.358767) (xy 151.271622 -315.323076) (xy 151.235931 -315.281885) (xy 151.206465 -315.236035)
			(xy 151.183823 -315.186458) (xy 151.168468 -315.134163) (xy 151.160712 -315.080215) (xy 151.160226 -315.052964)
			(xy 151.160746 -315.024689) (xy 151.169091 -314.968757) (xy 151.185593 -314.914668) (xy 151.209892 -314.863604)
			(xy 151.22525 -314.839858) (xy 151.229317 -314.833458) (xy 151.233829 -314.818987) (xy 151.23414 -314.81141)
			(xy 151.23414 -314.281566) (xy 151.234509 -314.257379) (xy 151.242018 -314.209592) (xy 151.256923 -314.163572)
			(xy 151.278856 -314.120457) (xy 151.307275 -314.081312) (xy 151.324056 -314.063888) (xy 152.042622 -313.345322)
			(xy 152.06006 -313.328549) (xy 152.099201 -313.300111) (xy 152.14231 -313.278146) (xy 152.188323 -313.263195)
			(xy 152.236109 -313.255626) (xy 152.2603 -313.255152) (xy 152.60066 -313.255152) (xy 152.610685 -313.254747)
			(xy 152.62921 -313.247081) (xy 152.643385 -313.232903) (xy 152.651048 -313.214377) (xy 152.65146 -313.204352)
			(xy 152.65146 -312.773822) (xy 152.651033 -312.763753) (xy 152.643315 -312.745154) (xy 152.636474 -312.737754)
			(xy 151.067516 -311.16905) (xy 151.050804 -311.15157) (xy 151.022423 -311.11242) (xy 151.000509 -311.069315)
			(xy 150.9856 -311.023315) (xy 150.978063 -310.97555) (xy 150.9776 -310.951372) (xy 150.9776 -304.790602)
			(xy 150.9772 -304.780529) (xy 150.969465 -304.76193) (xy 150.962614 -304.754534) (xy 144.769332 -298.561252)
			(xy 144.761866 -298.55454) (xy 144.743295 -298.54696) (xy 144.733264 -298.54652) (xy 135.666988 -298.54652)
			(xy 135.642798 -298.546027) (xy 135.595015 -298.538459) (xy 135.549003 -298.52351) (xy 135.505895 -298.50155)
			(xy 135.466752 -298.473117) (xy 135.44931 -298.45635) (xy 133.950202 -296.957242) (xy 133.934212 -296.940644)
			(xy 133.906863 -296.90355) (xy 133.885343 -296.862795) (xy 133.870134 -296.81929) (xy 133.861575 -296.774005)
			(xy 133.860286 -296.750994) (xy 133.859799 -296.743955) (xy 133.855411 -296.730549) (xy 133.85165 -296.724578)
			(xy 133.836205 -296.700799) (xy 133.811786 -296.649625) (xy 133.795218 -296.595398) (xy 133.786867 -296.539315)
			(xy 133.786372 -296.510964) (xy 132.722874 -296.510964) (xy 135.171942 -298.960032) (xy 135.179419 -298.96673)
			(xy 135.197982 -298.974318) (xy 135.20801 -298.974764) (xy 144.566894 -298.974764) (xy 144.591086 -298.975219)
			(xy 144.638876 -298.982788) (xy 144.684892 -298.997739) (xy 144.728003 -299.019705) (xy 144.767147 -299.048145)
			(xy 144.784572 -299.064934) (xy 149.629114 -303.909476) (xy 149.645873 -303.926928) (xy 149.67432 -303.966064)
			(xy 149.696294 -304.009167) (xy 149.711254 -304.055178) (xy 149.71883 -304.102963) (xy 149.719284 -304.127154)
			(xy 149.719284 -309.357268) (xy 149.719745 -309.367285) (xy 149.727402 -309.385798) (xy 149.741561 -309.399971)
			(xy 149.760067 -309.407645) (xy 149.770084 -309.408068) (xy 149.890734 -309.408068) (xy 149.91492 -309.408458)
			(xy 149.962705 -309.415964) (xy 150.008724 -309.430866) (xy 150.05184 -309.452793) (xy 150.090987 -309.481206)
			(xy 150.108412 -309.497984) (xy 150.215092 -309.604664) (xy 150.231812 -309.622136) (xy 150.260192 -309.661289)
			(xy 150.282105 -309.704396) (xy 150.297011 -309.750398) (xy 150.304546 -309.798163) (xy 150.305008 -309.822342)
			(xy 150.305008 -310.096662) (xy 150.304579 -310.120847) (xy 150.297083 -310.16863) (xy 150.282191 -310.214649)
			(xy 150.260272 -310.257765) (xy 150.231867 -310.296914) (xy 150.215092 -310.31434) (xy 150.118064 -310.411368)
			(xy 150.111373 -310.418783) (xy 150.103737 -310.437213) (xy 150.103732 -310.457162) (xy 150.111359 -310.475596)
			(xy 150.118064 -310.482996) (xy 150.215092 -310.580024) (xy 150.231841 -310.59747) (xy 150.260217 -310.63663)
			(xy 150.282124 -310.679743) (xy 150.297024 -310.725751) (xy 150.304551 -310.773522) (xy 150.305008 -310.797702)
			(xy 150.305008 -311.072022) (xy 150.304617 -311.096208) (xy 150.297112 -311.143994) (xy 150.282211 -311.190013)
			(xy 150.260283 -311.233128) (xy 150.23187 -311.272275) (xy 150.215092 -311.2897) (xy 150.108412 -311.39638)
			(xy 150.090965 -311.413127) (xy 150.051804 -311.4415) (xy 150.00869 -311.463406) (xy 149.962684 -311.478307)
			(xy 149.914914 -311.485837) (xy 149.890734 -311.486296) (xy 149.79396 -311.486296) (xy 149.78395 -311.486755)
			(xy 149.765458 -311.494427) (xy 149.751307 -311.508589) (xy 149.743648 -311.527086) (xy 149.74316 -311.537096)
			(xy 149.74316 -312.26379) (xy 149.743492 -312.27384) (xy 149.751106 -312.292436) (xy 149.757892 -312.299858)
			(xy 150.518114 -313.059826) (xy 150.530649 -313.072742) (xy 150.552932 -313.101009) (xy 150.562564 -313.116214)
			(xy 150.564808 -313.119777) (xy 150.570299 -313.126161) (xy 150.573486 -313.128914) (xy 150.588873 -313.141992)
			(xy 150.615124 -313.172674) (xy 150.6355 -313.207535) (xy 150.649354 -313.245464) (xy 150.656244 -313.285251)
			(xy 150.656544 -313.305444) (xy 150.656544 -313.604656) (xy 150.656169 -313.626969) (xy 150.647726 -313.670784)
			(xy 150.630861 -313.712094) (xy 150.606229 -313.749299) (xy 150.574784 -313.780957) (xy 150.537746 -313.80584)
			(xy 150.49655 -313.822984) (xy 150.452794 -313.831724) (xy 150.430484 -313.83224) (xy 150.162768 -313.83224)
			(xy 150.162768 -313.823096) (xy 150.162383 -313.81307) (xy 150.154706 -313.794547) (xy 150.140522 -313.780374)
			(xy 150.121994 -313.77271) (xy 150.111968 -313.772296) (xy 149.858984 -313.772296) (xy 149.848976 -313.772775)
			(xy 149.830484 -313.780439) (xy 149.816332 -313.794594) (xy 149.808672 -313.813088) (xy 149.808184 -313.823096)
			(xy 149.808184 -314.123832) (xy 149.837648 -314.153804) (xy 149.851872 -314.153804) (xy 149.861866 -314.154342)
			(xy 149.880325 -314.162022) (xy 149.894465 -314.176155) (xy 149.902153 -314.19461) (xy 149.902672 -314.204604)
			(xy 149.902672 -314.501784) (xy 149.903942 -314.507372) (xy 149.907404 -314.523919) (xy 149.9111 -314.557524)
			(xy 149.911308 -314.574428) (xy 149.911308 -315.296296) (xy 149.911854 -315.30628) (xy 149.91957 -315.324707)
			(xy 149.933697 -315.338832) (xy 149.952124 -315.346547) (xy 149.962108 -315.347096) (xy 150.896828 -315.347096)
			(xy 150.913523 -315.34761) (xy 150.945778 -315.356247) (xy 150.974704 -315.372928) (xy 150.998336 -315.396519)
			(xy 151.015067 -315.425416) (xy 151.023761 -315.457655) (xy 151.024336 -315.47435) (xy 151.024336 -316.69355)
			(xy 151.0239 -316.710263) (xy 151.015226 -316.742544) (xy 150.998485 -316.771476) (xy 150.974819 -316.795082)
			(xy 150.945845 -316.81175) (xy 150.913542 -316.820342) (xy 150.896828 -316.820804) (xy 149.398228 -316.820804)
			(xy 149.389338 -316.82055) (xy 149.380956 -316.820042) (xy 149.365462 -316.823852) (xy 149.300692 -316.865254)
			(xy 149.290532 -316.877446) (xy 149.287484 -316.88532) (xy 149.279444 -316.905122) (xy 149.258703 -316.94249)
			(xy 149.232983 -316.976621) (xy 149.218142 -316.992) (xy 148.919184 -317.290704) (xy 148.912504 -317.298196)
			(xy 148.904905 -317.316747) (xy 148.904452 -317.326772) (xy 148.904452 -318.29375) (xy 148.904 -318.310462)
			(xy 148.895328 -318.34274) (xy 148.878589 -318.371671) (xy 148.854927 -318.395276) (xy 148.825956 -318.411945)
			(xy 148.793657 -318.42054) (xy 148.776944 -318.421004) (xy 147.278344 -318.421004) (xy 147.261652 -318.420427)
			(xy 147.2294 -318.411806) (xy 147.200473 -318.39514) (xy 147.17684 -318.371561) (xy 147.160107 -318.342673)
			(xy 147.151412 -318.310441) (xy 147.150836 -318.29375) (xy 147.150836 -317.07455) (xy 147.1513 -317.057839)
			(xy 147.159971 -317.025562) (xy 147.176708 -316.996633) (xy 147.200368 -316.973028) (xy 147.229335 -316.956358)
			(xy 147.261632 -316.947762) (xy 147.278344 -316.947296) (xy 148.371306 -316.947296) (xy 148.381379 -316.946901)
			(xy 148.399979 -316.939162) (xy 148.407374 -316.93231) (xy 148.677884 -316.6618) (xy 148.684571 -316.654314)
			(xy 148.692164 -316.635758) (xy 148.692616 -316.625732) (xy 148.692616 -315.411104) (xy 148.692241 -315.401059)
			(xy 148.684658 -315.382462) (xy 148.677884 -315.375036) (xy 148.304758 -315.002164) (xy 148.287899 -314.984618)
			(xy 148.259372 -314.945201) (xy 148.237405 -314.901785) (xy 148.222545 -314.855453) (xy 148.218398 -314.831476)
			(xy 148.21535 -314.81268) (xy 148.187156 -314.788296) (xy 148.1709 -314.788296) (xy 148.160855 -314.787944)
			(xy 148.142268 -314.780331) (xy 148.128067 -314.766128) (xy 148.120456 -314.747542) (xy 148.1201 -314.737496)
			(xy 148.1201 -314.524898) (xy 148.119702 -314.514825) (xy 148.111965 -314.496226) (xy 148.105114 -314.48883)
			(xy 147.504658 -313.888628) (xy 147.488535 -313.871862) (xy 147.461032 -313.83435) (xy 147.439471 -313.793135)
			(xy 147.431506 -313.77128) (xy 147.429812 -313.766713) (xy 147.424959 -313.758269) (xy 147.421854 -313.754516)
			(xy 147.408743 -313.738831) (xy 147.387882 -313.703677) (xy 147.373664 -313.665351) (xy 147.366553 -313.625097)
			(xy 147.366228 -313.604656) (xy 147.366228 -313.305444) (xy 147.366631 -313.283132) (xy 147.375073 -313.239321)
			(xy 147.391935 -313.198014) (xy 147.416564 -313.16081) (xy 147.448004 -313.129153) (xy 147.485037 -313.104269)
			(xy 147.526228 -313.087123) (xy 147.56998 -313.078379) (xy 147.592288 -313.07786) (xy 147.643342 -313.07786)
			(xy 147.653415 -313.077467) (xy 147.672013 -313.069725) (xy 147.67941 -313.062874) (xy 147.713954 -313.02833)
			(xy 147.720767 -313.020908) (xy 147.728504 -313.002326) (xy 147.72894 -312.992262) (xy 147.72894 -304.193448)
			(xy 147.728506 -304.183379) (xy 147.720793 -304.164781) (xy 147.713954 -304.15738) (xy 144.096486 -300.539912)
			(xy 144.089006 -300.533218) (xy 144.070445 -300.525629) (xy 144.060418 -300.52518) (xy 134.549388 -300.52518)
			(xy 134.525198 -300.524699) (xy 134.477413 -300.51713) (xy 134.4314 -300.502179) (xy 134.388293 -300.480215)
			(xy 134.349151 -300.451779) (xy 134.33171 -300.43501) (xy 131.130294 -297.233594) (xy 131.113522 -297.216153)
			(xy 131.085076 -297.177015) (xy 131.063105 -297.133908) (xy 131.048148 -297.087895) (xy 131.040575 -297.040108)
			(xy 131.040124 -297.015916) (xy 131.040124 -296.752518) (xy 131.039861 -296.744962) (xy 131.035459 -296.730504)
			(xy 131.031488 -296.72407) (xy 131.016122 -296.700328) (xy 130.991817 -296.649265) (xy 130.975314 -296.595174)
			(xy 130.966974 -296.53924) (xy 130.966464 -296.510964) (xy 129.563114 -296.510964) (xy 129.563114 -296.59199)
			(xy 129.563536 -296.602061) (xy 129.571249 -296.620666) (xy 129.5781 -296.628058) (xy 134.132828 -301.182786)
			(xy 134.140227 -301.18963) (xy 134.158826 -301.197356) (xy 134.168896 -301.197772) (xy 141.399514 -301.197772)
			(xy 141.412468 -301.195486) (xy 141.415516 -301.19447) (xy 141.424152 -301.19193) (xy 141.539214 -301.158402)
			(xy 141.542516 -301.157386) (xy 141.54912 -301.154592) (xy 141.553627 -301.152584) (xy 141.56182 -301.14709)
			(xy 141.565376 -301.14367) (xy 141.669262 -301.039784) (xy 141.676497 -301.033063) (xy 141.694702 -301.025452)
			(xy 141.704568 -301.025052) (xy 144.04848 -301.025052) (xy 144.058318 -301.025589) (xy 144.076481 -301.033173)
			(xy 144.083786 -301.039784) (xy 144.989804 -301.945802) (xy 144.991582 -301.947326) (xy 145.056945 -302.00484)
			(xy 145.182891 -302.125079) (xy 145.303127 -302.251028) (xy 145.360644 -302.316388) (xy 145.361914 -302.317912)
			(xy 146.457162 -303.41316) (xy 146.463878 -303.420398) (xy 146.471483 -303.438602) (xy 146.471894 -303.448466)
			(xy 146.471894 -318.97193) (xy 146.472499 -318.98326) (xy 146.482258 -319.003709) (xy 146.49069 -319.0113)
			(xy 146.514357 -319.031159) (xy 146.556658 -319.076186) (xy 146.592519 -319.126493) (xy 146.62129 -319.181165)
			(xy 146.642447 -319.23921) (xy 146.655606 -319.299573) (xy 146.658584 -319.330324) (xy 146.659346 -319.339468)
			(xy 146.666712 -319.35547) (xy 147.59432 -320.283078) (xy 147.601719 -320.289924) (xy 147.620317 -320.297654)
			(xy 147.630388 -320.298064)
		)
		(stroke
			(width 0)
			(type solid)
		)
		(fill yes)
		(layer "B.Cu")
		(net "GND")
	)
	(gr_poly
		(pts
			(xy 90.641424 -76.951332) (xy 90.650029 -76.951003) (xy 90.666264 -76.945295) (xy 90.673174 -76.940156)
			(xy 90.695919 -76.922437) (xy 90.745693 -76.89334) (xy 90.799281 -76.87207) (xy 90.85546 -76.85911)
			(xy 90.91295 -76.854757) (xy 90.97044 -76.85911) (xy 91.026619 -76.87207) (xy 91.080207 -76.89334)
			(xy 91.129981 -76.922437) (xy 91.152726 -76.940156) (xy 91.15965 -76.94527) (xy 91.175876 -76.950982)
			(xy 91.184476 -76.951332) (xy 93.097604 -76.951332) (xy 93.109633 -76.950668) (xy 93.131106 -76.939813)
			(xy 93.138752 -76.930504) (xy 93.155408 -76.90844) (xy 93.19404 -76.868898) (xy 93.237978 -76.83535)
			(xy 93.286299 -76.808498) (xy 93.337992 -76.788905) (xy 93.391972 -76.776983) (xy 93.447108 -76.772981)
			(xy 93.502244 -76.776983) (xy 93.556224 -76.788905) (xy 93.607917 -76.808498) (xy 93.656238 -76.83535)
			(xy 93.700176 -76.868898) (xy 93.738808 -76.90844) (xy 93.755464 -76.930504) (xy 93.763083 -76.939852)
			(xy 93.784567 -76.95073) (xy 93.796612 -76.951332) (xy 99.366832 -76.951332) (xy 99.375214 -76.95057)
			(xy 99.382817 -76.949053) (xy 99.396645 -76.94206) (xy 99.402392 -76.936854) (xy 100.587556 -75.75169)
			(xy 100.594406 -75.744293) (xy 100.602143 -75.725695) (xy 100.602542 -75.715622) (xy 100.602542 -55.36692)
			(xy 100.602007 -55.355899) (xy 100.592798 -55.335872) (xy 100.584762 -55.328312) (xy 100.564125 -55.31011)
			(xy 100.527787 -55.268787) (xy 100.497767 -55.22267) (xy 100.47469 -55.172716) (xy 100.459033 -55.119963)
			(xy 100.451123 -55.065507) (xy 100.451124 -55.01048) (xy 100.459036 -54.956025) (xy 100.474694 -54.903272)
			(xy 100.497774 -54.853319) (xy 100.527795 -54.807203) (xy 100.564134 -54.765881) (xy 100.584762 -54.747668)
			(xy 100.592786 -54.740097) (xy 100.602 -54.720079) (xy 100.602542 -54.70906) (xy 100.602542 -53.983382)
			(xy 100.594922 -53.964586) (xy 100.587556 -53.957474) (xy 99.014534 -52.384452) (xy 99.007134 -52.37761)
			(xy 98.988536 -52.369892) (xy 98.978466 -52.369466) (xy 87.10803 -52.369466) (xy 87.089234 -52.377086)
			(xy 87.082122 -52.384452) (xy 84.367624 -55.09895) (xy 84.360818 -55.106431) (xy 84.353212 -55.125155)
			(xy 84.353395 -55.145363) (xy 84.356956 -55.15483) (xy 84.356956 -55.155084) (xy 84.402422 -55.256938)
			(xy 84.429092 -55.273194) (xy 84.445094 -55.272178) (xy 84.47024 -55.271416) (xy 88.148922 -55.271416)
			(xy 88.175211 -55.271819) (xy 88.227417 -55.278063) (xy 88.253062 -55.283862) (xy 88.282637 -55.291523)
			(xy 88.339502 -55.313859) (xy 88.39277 -55.343776) (xy 88.441437 -55.380708) (xy 88.463374 -55.401972)
			(xy 88.73363 -55.672228) (xy 88.75391 -55.693132) (xy 88.789385 -55.739323) (xy 88.818522 -55.789753)
			(xy 88.84082 -55.843558) (xy 88.855897 -55.899815) (xy 88.863496 -55.957559) (xy 88.863932 -55.98668)
			(xy 88.863886 -55.998194) (xy 88.862743 -56.021193) (xy 88.861646 -56.032654) (xy 88.861392 -56.035448)
			(xy 88.861392 -56.03748) (xy 88.857532 -56.066699) (xy 88.843095 -56.123842) (xy 88.821246 -56.178582)
			(xy 88.792368 -56.229961) (xy 88.756965 -56.277081) (xy 88.715656 -56.319121) (xy 88.669162 -56.355343)
			(xy 88.618297 -56.385117) (xy 88.563949 -56.407921) (xy 88.507067 -56.423357) (xy 88.448647 -56.431154)
			(xy 88.419178 -56.431688) (xy 88.392889 -56.431285) (xy 88.340683 -56.425041) (xy 88.315038 -56.419242)
			(xy 88.285463 -56.411581) (xy 88.228598 -56.389245) (xy 88.17533 -56.359329) (xy 88.126662 -56.322397)
			(xy 88.104726 -56.301132) (xy 87.98179 -56.17845) (xy 87.980266 -56.176926) (xy 87.979758 -56.176418)
			(xy 87.972358 -56.169576) (xy 87.95376 -56.161854) (xy 87.94369 -56.161432) (xy 87.772748 -56.161432)
			(xy 87.748618 -56.176418) (xy 87.742014 -56.189626) (xy 87.695024 -56.284114) (xy 87.697818 -56.312816)
			(xy 87.706454 -56.3245) (xy 87.724767 -56.349551) (xy 87.753875 -56.404349) (xy 87.77373 -56.463136)
			(xy 87.783808 -56.524362) (xy 87.784432 -56.555386) (xy 87.783946 -56.582637) (xy 87.77619 -56.636585)
			(xy 87.760835 -56.68888) (xy 87.738193 -56.738457) (xy 87.708727 -56.784307) (xy 87.673036 -56.825498)
			(xy 87.631845 -56.861189) (xy 87.591576 -56.887068) (xy 89.943899 -56.887068) (xy 89.943899 -56.827132)
			(xy 89.951723 -56.767708) (xy 89.967236 -56.709814) (xy 89.990174 -56.654441) (xy 90.020144 -56.602535)
			(xy 90.056633 -56.554986) (xy 90.099016 -56.512606) (xy 90.146569 -56.476122) (xy 90.198477 -56.446157)
			(xy 90.253852 -56.423223) (xy 90.311747 -56.407715) (xy 90.371172 -56.399896) (xy 90.40114 -56.39943)
			(xy 90.433638 -56.400019) (xy 90.497977 -56.409247) (xy 90.560367 -56.427468) (xy 90.619559 -56.454319)
			(xy 90.647266 -56.471312) (xy 90.655648 -56.476646) (xy 90.67419 -56.480202) (xy 90.761312 -56.4642)
			(xy 90.777568 -56.454294) (xy 90.78341 -56.44642) (xy 90.789227 -56.438652) (xy 90.801552 -56.423658)
			(xy 90.808048 -56.416448) (xy 90.814398 -56.40959) (xy 90.821256 -56.392572) (xy 90.823288 -56.30672)
			(xy 90.816938 -56.289194) (xy 90.811096 -56.282082) (xy 90.794181 -56.261331) (xy 90.765678 -56.216014)
			(xy 90.743784 -56.16716) (xy 90.728928 -56.115727) (xy 90.721402 -56.062723) (xy 90.720926 -56.035956)
			(xy 90.721337 -56.008702) (xy 90.7291 -55.95475) (xy 90.744463 -55.902452) (xy 90.767112 -55.852872)
			(xy 90.796586 -55.80702) (xy 90.832285 -55.76583) (xy 90.873483 -55.730139) (xy 90.919341 -55.700674)
			(xy 90.968925 -55.678036) (xy 91.021226 -55.662684) (xy 91.07518 -55.654931) (xy 91.102434 -55.654448)
			(xy 91.129806 -55.654882) (xy 91.183986 -55.662706) (xy 91.23649 -55.678202) (xy 91.286237 -55.701051)
			(xy 91.332202 -55.730783) (xy 91.353132 -55.748428) (xy 91.360244 -55.754524) (xy 91.377262 -55.760874)
			(xy 91.462606 -55.760874) (xy 91.479624 -55.754524) (xy 91.486736 -55.748428) (xy 91.507685 -55.73081)
			(xy 91.553653 -55.701094) (xy 91.603396 -55.678253) (xy 91.655893 -55.662758) (xy 91.710066 -55.654924)
			(xy 91.737434 -55.654448) (xy 91.764684 -55.654946) (xy 91.818629 -55.662706) (xy 91.870921 -55.678063)
			(xy 91.920495 -55.700705) (xy 91.966343 -55.730171) (xy 92.007532 -55.765861) (xy 92.043223 -55.807049)
			(xy 92.07269 -55.852896) (xy 92.095333 -55.90247) (xy 92.110692 -55.954761) (xy 92.118453 -56.008706)
			(xy 92.118942 -56.035956) (xy 92.118464 -56.063326) (xy 92.110651 -56.117505) (xy 92.095166 -56.170009)
			(xy 92.072326 -56.219756) (xy 92.042603 -56.265723) (xy 92.024962 -56.286654) (xy 92.018866 -56.293766)
			(xy 92.012516 -56.310784) (xy 92.012516 -56.385202) (xy 92.440488 -56.385202) (xy 92.440488 -56.325266)
			(xy 92.448311 -56.265844) (xy 92.463824 -56.207951) (xy 92.48676 -56.152578) (xy 92.516727 -56.100672)
			(xy 92.553214 -56.053122) (xy 92.595594 -56.010742) (xy 92.643144 -55.974255) (xy 92.69505 -55.944288)
			(xy 92.750423 -55.921352) (xy 92.808316 -55.905839) (xy 92.867738 -55.898016) (xy 92.927674 -55.898016)
			(xy 92.987096 -55.905839) (xy 93.044989 -55.921352) (xy 93.100362 -55.944288) (xy 93.152268 -55.974255)
			(xy 93.199818 -56.010742) (xy 93.242198 -56.053122) (xy 93.278685 -56.100672) (xy 93.308652 -56.152578)
			(xy 93.331588 -56.207951) (xy 93.347101 -56.265844) (xy 93.354924 -56.325266) (xy 93.355414 -56.355234)
			(xy 93.354924 -56.385202) (xy 93.347101 -56.444624) (xy 93.338658 -56.476134) (xy 95.330754 -56.476134)
			(xy 95.330754 -56.416198) (xy 95.338577 -56.356776) (xy 95.35409 -56.298883) (xy 95.377026 -56.24351)
			(xy 95.406993 -56.191604) (xy 95.44348 -56.144054) (xy 95.48586 -56.101674) (xy 95.53341 -56.065187)
			(xy 95.585316 -56.03522) (xy 95.640689 -56.012284) (xy 95.698582 -55.996771) (xy 95.758004 -55.988948)
			(xy 95.81794 -55.988948) (xy 95.877362 -55.996771) (xy 95.935255 -56.012284) (xy 95.990628 -56.03522)
			(xy 96.042534 -56.065187) (xy 96.090084 -56.101674) (xy 96.132464 -56.144054) (xy 96.168951 -56.191604)
			(xy 96.198918 -56.24351) (xy 96.221854 -56.298883) (xy 96.237367 -56.356776) (xy 96.24519 -56.416198)
			(xy 96.24568 -56.446166) (xy 96.24519 -56.476134) (xy 96.237367 -56.535556) (xy 96.221854 -56.593449)
			(xy 96.198918 -56.648822) (xy 96.168951 -56.700728) (xy 96.132464 -56.748278) (xy 96.090084 -56.790658)
			(xy 96.042534 -56.827145) (xy 95.990628 -56.857112) (xy 95.935255 -56.880048) (xy 95.877362 -56.895561)
			(xy 95.81794 -56.903384) (xy 95.758004 -56.903384) (xy 95.698582 -56.895561) (xy 95.640689 -56.880048)
			(xy 95.585316 -56.857112) (xy 95.53341 -56.827145) (xy 95.48586 -56.790658) (xy 95.44348 -56.748278)
			(xy 95.406993 -56.700728) (xy 95.377026 -56.648822) (xy 95.35409 -56.593449) (xy 95.338577 -56.535556)
			(xy 95.330754 -56.476134) (xy 93.338658 -56.476134) (xy 93.331588 -56.502517) (xy 93.308652 -56.55789)
			(xy 93.278685 -56.609796) (xy 93.242198 -56.657346) (xy 93.199818 -56.699726) (xy 93.152268 -56.736213)
			(xy 93.100362 -56.76618) (xy 93.044989 -56.789116) (xy 92.987096 -56.804629) (xy 92.927674 -56.812452)
			(xy 92.867738 -56.812452) (xy 92.808316 -56.804629) (xy 92.750423 -56.789116) (xy 92.69505 -56.76618)
			(xy 92.643144 -56.736213) (xy 92.595594 -56.699726) (xy 92.553214 -56.657346) (xy 92.516727 -56.609796)
			(xy 92.48676 -56.55789) (xy 92.463824 -56.502517) (xy 92.448311 -56.444624) (xy 92.440488 -56.385202)
			(xy 92.012516 -56.385202) (xy 92.012516 -56.396128) (xy 92.018866 -56.413146) (xy 92.024962 -56.420258)
			(xy 92.042589 -56.4412) (xy 92.072304 -56.487169) (xy 92.095143 -56.536914) (xy 92.110637 -56.589413)
			(xy 92.118467 -56.643587) (xy 92.118942 -56.670956) (xy 92.118404 -56.698206) (xy 92.110654 -56.752153)
			(xy 92.095305 -56.804447) (xy 92.07267 -56.854025) (xy 92.04321 -56.899876) (xy 92.007524 -56.941069)
			(xy 91.966339 -56.976763) (xy 91.920493 -57.006233) (xy 91.87092 -57.028878) (xy 91.818629 -57.044237)
			(xy 91.764684 -57.051998) (xy 91.737434 -57.052464) (xy 91.709558 -57.051985) (xy 91.6544 -57.043873)
			(xy 91.601011 -57.027817) (xy 91.550529 -57.004159) (xy 91.504029 -56.973402) (xy 91.482926 -56.955182)
			(xy 91.475814 -56.948832) (xy 91.458542 -56.942228) (xy 91.370912 -56.942736) (xy 91.353894 -56.949594)
			(xy 91.346782 -56.956198) (xy 91.325525 -56.974907) (xy 91.278569 -57.006553) (xy 91.22745 -57.030907)
			(xy 91.173291 -57.047436) (xy 91.117284 -57.055775) (xy 91.088972 -57.056274) (xy 91.062831 -57.05586)
			(xy 91.011041 -57.048713) (xy 90.960709 -57.034569) (xy 90.936572 -57.024524) (xy 90.927682 -57.020714)
			(xy 90.908632 -57.019952) (xy 90.825066 -57.049416) (xy 90.810842 -57.061608) (xy 90.80627 -57.070244)
			(xy 90.791314 -57.097512) (xy 90.755166 -57.148119) (xy 90.712501 -57.193367) (xy 90.664103 -57.232423)
			(xy 90.610864 -57.264569) (xy 90.553764 -57.289212) (xy 90.493853 -57.305899) (xy 90.432235 -57.314322)
			(xy 90.40114 -57.314846) (xy 90.371172 -57.314304) (xy 90.311747 -57.306485) (xy 90.253852 -57.290977)
			(xy 90.198477 -57.268043) (xy 90.146569 -57.238078) (xy 90.099016 -57.201594) (xy 90.056633 -57.159214)
			(xy 90.020144 -57.111665) (xy 89.990174 -57.059759) (xy 89.967236 -57.004386) (xy 89.951723 -56.946492)
			(xy 89.943899 -56.887068) (xy 87.591576 -56.887068) (xy 87.585995 -56.890655) (xy 87.536418 -56.913297)
			(xy 87.484123 -56.928652) (xy 87.430175 -56.936408) (xy 87.375673 -56.936408) (xy 87.321725 -56.928652)
			(xy 87.26943 -56.913297) (xy 87.219853 -56.890655) (xy 87.174003 -56.861189) (xy 87.132812 -56.825498)
			(xy 87.097121 -56.784307) (xy 87.067655 -56.738457) (xy 87.045013 -56.68888) (xy 87.029658 -56.636585)
			(xy 87.021902 -56.582637) (xy 87.021416 -56.555386) (xy 87.022049 -56.524364) (xy 87.032137 -56.463143)
			(xy 87.051998 -56.404362) (xy 87.081106 -56.349568) (xy 87.099394 -56.3245) (xy 87.10803 -56.312816)
			(xy 87.110824 -56.284114) (xy 87.063834 -56.189626) (xy 87.05723 -56.176418) (xy 87.0331 -56.161432)
			(xy 84.675472 -56.161432) (xy 84.665405 -56.161861) (xy 84.646811 -56.169586) (xy 84.639404 -56.176418)
			(xy 84.635086 -56.180736) (xy 84.630514 -56.185308) (xy 83.730592 -57.084976) (xy 83.701382 -57.1119)
			(xy 83.699604 -57.113424) (xy 82.593942 -58.219086) (xy 82.587104 -58.226487) (xy 82.581937 -58.238953)
			(xy 88.174775 -58.238953) (xy 88.174775 -58.184447) (xy 88.182533 -58.130496) (xy 88.197889 -58.078199)
			(xy 88.220533 -58.028619) (xy 88.250002 -57.982767) (xy 88.285697 -57.941576) (xy 88.326891 -57.905884)
			(xy 88.372746 -57.876419) (xy 88.422327 -57.853779) (xy 88.474626 -57.838426) (xy 88.528577 -57.830673)
			(xy 88.55583 -57.830212) (xy 88.583965 -57.830665) (xy 88.639624 -57.838934) (xy 88.693466 -57.855288)
			(xy 88.744321 -57.879373) (xy 88.791087 -57.910667) (xy 88.83275 -57.948489) (xy 88.868406 -57.992021)
			(xy 88.897281 -58.040318) (xy 88.918749 -58.092332) (xy 88.932346 -58.146935) (xy 88.93556 -58.17489)
			(xy 88.937431 -58.188774) (xy 88.9476 -58.21486) (xy 88.964476 -58.237201) (xy 88.986788 -58.254115)
			(xy 89.012857 -58.264329) (xy 89.040721 -58.267074) (xy 89.068282 -58.262143) (xy 89.093466 -58.249909)
			(xy 89.104216 -58.24093) (xy 89.12946 -58.219308) (xy 89.185043 -58.182862) (xy 89.245311 -58.154835)
			(xy 89.308999 -58.135817) (xy 89.374767 -58.126208) (xy 89.408 -58.125614) (xy 89.437969 -58.12606)
			(xy 89.497394 -58.133884) (xy 89.55529 -58.149397) (xy 89.610666 -58.172334) (xy 89.630044 -58.183522)
			(xy 93.60584 -58.183522) (xy 93.60584 -58.123586) (xy 93.613663 -58.064164) (xy 93.629176 -58.006271)
			(xy 93.652112 -57.950898) (xy 93.682079 -57.898992) (xy 93.718566 -57.851442) (xy 93.760946 -57.809062)
			(xy 93.808496 -57.772575) (xy 93.860402 -57.742608) (xy 93.915775 -57.719672) (xy 93.973668 -57.704159)
			(xy 94.03309 -57.696336) (xy 94.093026 -57.696336) (xy 94.152448 -57.704159) (xy 94.210341 -57.719672)
			(xy 94.265714 -57.742608) (xy 94.31762 -57.772575) (xy 94.36517 -57.809062) (xy 94.40755 -57.851442)
			(xy 94.428876 -57.879234) (xy 99.010722 -57.879234) (xy 99.014793 -57.823612) (xy 99.026919 -57.769175)
			(xy 99.046842 -57.717084) (xy 99.074138 -57.668449) (xy 99.108224 -57.624306) (xy 99.148373 -57.585597)
			(xy 99.193731 -57.553146) (xy 99.243331 -57.527645) (xy 99.296115 -57.509638) (xy 99.350958 -57.499508)
			(xy 99.406692 -57.497471) (xy 99.462129 -57.503571) (xy 99.516086 -57.517677) (xy 99.567415 -57.539489)
			(xy 99.615021 -57.568543) (xy 99.657889 -57.604218) (xy 99.695106 -57.645755) (xy 99.725879 -57.692268)
			(xy 99.749551 -57.742765) (xy 99.765619 -57.796172) (xy 99.773739 -57.851348) (xy 99.774248 -57.879234)
			(xy 99.773739 -57.90712) (xy 99.765619 -57.962296) (xy 99.749551 -58.015703) (xy 99.725879 -58.0662)
			(xy 99.695106 -58.112713) (xy 99.657889 -58.15425) (xy 99.615021 -58.189925) (xy 99.567415 -58.218979)
			(xy 99.516086 -58.240791) (xy 99.462129 -58.254897) (xy 99.406692 -58.260997) (xy 99.350958 -58.25896)
			(xy 99.296115 -58.24883) (xy 99.243331 -58.230823) (xy 99.193731 -58.205322) (xy 99.148373 -58.172871)
			(xy 99.108224 -58.134162) (xy 99.074138 -58.090019) (xy 99.046842 -58.041384) (xy 99.026919 -57.989293)
			(xy 99.014793 -57.934856) (xy 99.010722 -57.879234) (xy 94.428876 -57.879234) (xy 94.444037 -57.898992)
			(xy 94.474004 -57.950898) (xy 94.49694 -58.006271) (xy 94.512453 -58.064164) (xy 94.520276 -58.123586)
			(xy 94.520766 -58.153554) (xy 94.520276 -58.183522) (xy 94.512453 -58.242944) (xy 94.49694 -58.300837)
			(xy 94.474004 -58.35621) (xy 94.444037 -58.408116) (xy 94.40755 -58.455666) (xy 94.36517 -58.498046)
			(xy 94.31762 -58.534533) (xy 94.265714 -58.5645) (xy 94.210341 -58.587436) (xy 94.152448 -58.602949)
			(xy 94.093026 -58.610772) (xy 94.03309 -58.610772) (xy 93.973668 -58.602949) (xy 93.915775 -58.587436)
			(xy 93.860402 -58.5645) (xy 93.808496 -58.534533) (xy 93.760946 -58.498046) (xy 93.718566 -58.455666)
			(xy 93.682079 -58.408116) (xy 93.652112 -58.35621) (xy 93.629176 -58.300837) (xy 93.613663 -58.242944)
			(xy 93.60584 -58.183522) (xy 89.630044 -58.183522) (xy 89.662574 -58.202303) (xy 89.710126 -58.238791)
			(xy 89.752509 -58.281174) (xy 89.788997 -58.328726) (xy 89.818966 -58.380634) (xy 89.841903 -58.43601)
			(xy 89.857416 -58.493906) (xy 89.86524 -58.553331) (xy 89.86524 -58.613269) (xy 89.857416 -58.672694)
			(xy 89.841903 -58.73059) (xy 89.818966 -58.785966) (xy 89.788997 -58.837874) (xy 89.752509 -58.885426)
			(xy 89.710126 -58.927809) (xy 89.662574 -58.964297) (xy 89.610666 -58.994266) (xy 89.55529 -59.017203)
			(xy 89.497394 -59.032716) (xy 89.437969 -59.04054) (xy 89.408 -59.04103) (xy 89.378449 -59.040569)
			(xy 89.319837 -59.032986) (xy 89.262688 -59.01792) (xy 89.207955 -58.995622) (xy 89.156548 -58.966463)
			(xy 89.109323 -58.930929) (xy 89.067065 -58.88961) (xy 89.030479 -58.843195) (xy 89.000172 -58.792456)
			(xy 88.97665 -58.738238) (xy 88.960304 -58.681442) (xy 88.951406 -58.623015) (xy 88.950292 -58.593482)
			(xy 88.949511 -58.579518) (xy 88.941292 -58.552796) (xy 88.926135 -58.529303) (xy 88.905175 -58.510801)
			(xy 88.879984 -58.498676) (xy 88.852449 -58.493836) (xy 88.824632 -58.496643) (xy 88.798619 -58.506888)
			(xy 88.787224 -58.514996) (xy 88.76721 -58.52977) (xy 88.724078 -58.554556) (xy 88.67809 -58.573524)
			(xy 88.630027 -58.586353) (xy 88.580703 -58.592824) (xy 88.55583 -58.593228) (xy 88.528577 -58.592727)
			(xy 88.474626 -58.584974) (xy 88.422327 -58.569621) (xy 88.372746 -58.546981) (xy 88.326891 -58.517516)
			(xy 88.285697 -58.481824) (xy 88.250002 -58.440633) (xy 88.220533 -58.394781) (xy 88.197889 -58.345201)
			(xy 88.182533 -58.292904) (xy 88.174775 -58.238953) (xy 82.581937 -58.238953) (xy 82.579395 -58.245086)
			(xy 82.578956 -58.255154) (xy 82.578956 -59.43092) (xy 86.459312 -59.43092) (xy 86.463383 -59.375298)
			(xy 86.475509 -59.320861) (xy 86.495432 -59.26877) (xy 86.522728 -59.220135) (xy 86.556814 -59.175992)
			(xy 86.596963 -59.137283) (xy 86.642321 -59.104832) (xy 86.691921 -59.079331) (xy 86.744705 -59.061324)
			(xy 86.799548 -59.051194) (xy 86.855282 -59.049157) (xy 86.910719 -59.055257) (xy 86.964676 -59.069363)
			(xy 87.016005 -59.091175) (xy 87.063611 -59.120229) (xy 87.106479 -59.155904) (xy 87.143696 -59.197441)
			(xy 87.174469 -59.243954) (xy 87.198141 -59.294451) (xy 87.214209 -59.347858) (xy 87.222329 -59.403034)
			(xy 87.222838 -59.43092) (xy 87.222329 -59.458806) (xy 87.214209 -59.513982) (xy 87.198141 -59.567389)
			(xy 87.174469 -59.617886) (xy 87.143696 -59.664399) (xy 87.106479 -59.705936) (xy 87.063611 -59.741611)
			(xy 87.016005 -59.770665) (xy 86.964676 -59.792477) (xy 86.910719 -59.806583) (xy 86.855282 -59.812683)
			(xy 86.799548 -59.810646) (xy 86.744705 -59.800516) (xy 86.691921 -59.782509) (xy 86.642321 -59.757008)
			(xy 86.596963 -59.724557) (xy 86.556814 -59.685848) (xy 86.522728 -59.641705) (xy 86.495432 -59.59307)
			(xy 86.475509 -59.540979) (xy 86.463383 -59.486542) (xy 86.459312 -59.43092) (xy 82.578956 -59.43092)
			(xy 82.578956 -59.88329) (xy 88.950782 -59.88329) (xy 88.950782 -59.823354) (xy 88.958605 -59.763932)
			(xy 88.974118 -59.706039) (xy 88.997054 -59.650666) (xy 89.027021 -59.59876) (xy 89.063508 -59.55121)
			(xy 89.105888 -59.50883) (xy 89.153438 -59.472343) (xy 89.205344 -59.442376) (xy 89.260717 -59.41944)
			(xy 89.31861 -59.403927) (xy 89.378032 -59.396104) (xy 89.437968 -59.396104) (xy 89.49739 -59.403927)
			(xy 89.555283 -59.41944) (xy 89.610656 -59.442376) (xy 89.662562 -59.472343) (xy 89.710112 -59.50883)
			(xy 89.752492 -59.55121) (xy 89.788979 -59.59876) (xy 89.818946 -59.650666) (xy 89.841882 -59.706039)
			(xy 89.857395 -59.763932) (xy 89.865218 -59.823354) (xy 89.865417 -59.835538) (xy 93.61219 -59.835538)
			(xy 93.61219 -59.775602) (xy 93.620013 -59.71618) (xy 93.635526 -59.658287) (xy 93.658462 -59.602914)
			(xy 93.688429 -59.551008) (xy 93.724916 -59.503458) (xy 93.767296 -59.461078) (xy 93.814846 -59.424591)
			(xy 93.866752 -59.394624) (xy 93.922125 -59.371688) (xy 93.980018 -59.356175) (xy 94.03944 -59.348352)
			(xy 94.099376 -59.348352) (xy 94.158798 -59.356175) (xy 94.216691 -59.371688) (xy 94.272064 -59.394624)
			(xy 94.32397 -59.424591) (xy 94.37152 -59.461078) (xy 94.4139 -59.503458) (xy 94.450387 -59.551008)
			(xy 94.480354 -59.602914) (xy 94.50329 -59.658287) (xy 94.518803 -59.71618) (xy 94.526626 -59.775602)
			(xy 94.527116 -59.80557) (xy 94.526626 -59.835538) (xy 94.518803 -59.89496) (xy 94.50329 -59.952853)
			(xy 94.480354 -60.008226) (xy 94.450387 -60.060132) (xy 94.4139 -60.107682) (xy 94.37152 -60.150062)
			(xy 94.32397 -60.186549) (xy 94.272064 -60.216516) (xy 94.216691 -60.239452) (xy 94.158798 -60.254965)
			(xy 94.099376 -60.262788) (xy 94.03944 -60.262788) (xy 93.980018 -60.254965) (xy 93.922125 -60.239452)
			(xy 93.866752 -60.216516) (xy 93.814846 -60.186549) (xy 93.767296 -60.150062) (xy 93.724916 -60.107682)
			(xy 93.688429 -60.060132) (xy 93.658462 -60.008226) (xy 93.635526 -59.952853) (xy 93.620013 -59.89496)
			(xy 93.61219 -59.835538) (xy 89.865417 -59.835538) (xy 89.865708 -59.853322) (xy 89.865218 -59.88329)
			(xy 89.857395 -59.942712) (xy 89.841882 -60.000605) (xy 89.818946 -60.055978) (xy 89.788979 -60.107884)
			(xy 89.752492 -60.155434) (xy 89.710112 -60.197814) (xy 89.662562 -60.234301) (xy 89.610656 -60.264268)
			(xy 89.555283 -60.287204) (xy 89.49739 -60.302717) (xy 89.437968 -60.31054) (xy 89.378032 -60.31054)
			(xy 89.31861 -60.302717) (xy 89.260717 -60.287204) (xy 89.205344 -60.264268) (xy 89.153438 -60.234301)
			(xy 89.105888 -60.197814) (xy 89.063508 -60.155434) (xy 89.027021 -60.107884) (xy 88.997054 -60.055978)
			(xy 88.974118 -60.000605) (xy 88.958605 -59.942712) (xy 88.950782 -59.88329) (xy 82.578956 -59.88329)
			(xy 82.578956 -61.72708) (xy 82.57944 -61.737094) (xy 82.587094 -61.7556) (xy 82.601247 -61.76977)
			(xy 82.619743 -61.777447) (xy 82.629756 -61.77788) (xy 93.904308 -61.77788) (xy 93.912138 -61.776762)
			(xy 93.926619 -61.770424) (xy 93.932756 -61.765434) (xy 94.105984 -61.592206) (xy 94.473014 -61.224922)
			(xy 94.479717 -61.217481) (xy 94.487332 -61.19898) (xy 94.487323 -61.178974) (xy 94.483936 -61.16955)
			(xy 94.47784 -61.155326) (xy 94.452694 -61.138308) (xy 94.22384 -61.138308) (xy 94.213814 -61.138721)
			(xy 94.195285 -61.146384) (xy 94.181102 -61.160558) (xy 94.173427 -61.179082) (xy 94.17304 -61.189108)
			(xy 94.17304 -61.198252) (xy 93.90507 -61.198252) (xy 93.885604 -61.1978) (xy 93.847262 -61.191042)
			(xy 93.810643 -61.177817) (xy 93.776831 -61.158516) (xy 93.76156 -61.146436) (xy 93.75521 -61.141102)
			(xy 93.730318 -61.131958) (xy 93.72603 -61.130435) (xy 93.717086 -61.128769) (xy 93.712538 -61.128656)
			(xy 93.246702 -61.128656) (xy 93.222228 -61.128138) (xy 93.173909 -61.120306) (xy 93.127436 -61.104934)
			(xy 93.105478 -61.094112) (xy 93.100398 -61.091318) (xy 93.088206 -61.08827) (xy 93.082257 -61.086898)
			(xy 93.070051 -61.086762) (xy 93.064076 -61.088016) (xy 93.053916 -61.090302) (xy 93.04909 -61.092842)
			(xy 93.018154 -61.106895) (xy 92.953166 -61.12672) (xy 92.885959 -61.136704) (xy 92.851986 -61.137292)
			(xy 92.82202 -61.136801) (xy 92.762601 -61.128977) (xy 92.704711 -61.113464) (xy 92.649342 -61.090527)
			(xy 92.59744 -61.06056) (xy 92.549893 -61.024075) (xy 92.507516 -60.981696) (xy 92.471032 -60.934148)
			(xy 92.441066 -60.882245) (xy 92.418132 -60.826875) (xy 92.402621 -60.768985) (xy 92.394798 -60.709566)
			(xy 92.394798 -60.649634) (xy 92.402621 -60.590215) (xy 92.418132 -60.532325) (xy 92.441066 -60.476955)
			(xy 92.471032 -60.425052) (xy 92.507516 -60.377504) (xy 92.549893 -60.335125) (xy 92.59744 -60.29864)
			(xy 92.649342 -60.268673) (xy 92.704711 -60.245736) (xy 92.762601 -60.230223) (xy 92.82202 -60.222399)
			(xy 92.851986 -60.221876) (xy 92.880151 -60.222307) (xy 92.936054 -60.229219) (xy 92.990686 -60.24294)
			(xy 93.043221 -60.263264) (xy 93.092864 -60.289882) (xy 93.138865 -60.322392) (xy 93.180528 -60.360302)
			(xy 93.199204 -60.381388) (xy 93.202418 -60.384411) (xy 93.209701 -60.38939) (xy 93.213682 -60.391294)
			(xy 93.225074 -60.395666) (xy 93.247196 -60.405969) (xy 93.257878 -60.411868) (xy 93.275753 -60.422381)
			(xy 93.308761 -60.447486) (xy 93.323664 -60.461906) (xy 93.340174 -60.47867) (xy 93.340428 -60.47867)
			(xy 93.351858 -60.4901) (xy 93.352112 -60.490608) (xy 93.36024 -60.498482) (xy 93.367622 -60.505063)
			(xy 93.38592 -60.512514) (xy 93.3958 -60.51296) (xy 93.712538 -60.51296) (xy 93.717086 -60.512839)
			(xy 93.726032 -60.511183) (xy 93.730318 -60.509658) (xy 93.75521 -60.500514) (xy 93.76156 -60.49518)
			(xy 93.776825 -60.483093) (xy 93.810641 -60.463798) (xy 93.847261 -60.450577) (xy 93.885604 -60.443822)
			(xy 93.90507 -60.443364) (xy 94.143068 -60.443364) (xy 94.188026 -60.488322) (xy 94.195422 -60.495173)
			(xy 94.214021 -60.50291) (xy 94.224094 -60.503308) (xy 94.647258 -60.503308) (xy 94.657263 -60.502891)
			(xy 94.675744 -60.495218) (xy 94.689858 -60.481034) (xy 94.697439 -60.462515) (xy 94.697804 -60.452508)
			(xy 94.697804 -60.443364) (xy 94.96552 -60.443364) (xy 94.987812 -60.443882) (xy 95.031532 -60.452615)
			(xy 95.072697 -60.469738) (xy 95.109712 -60.494589) (xy 95.141146 -60.526206) (xy 95.165782 -60.563365)
			(xy 95.182666 -60.604629) (xy 95.191144 -60.648399) (xy 95.19158 -60.670694) (xy 95.19158 -60.86221)
			(xy 96.14103 -60.86221) (xy 96.145101 -60.806588) (xy 96.157227 -60.752151) (xy 96.17715 -60.70006)
			(xy 96.204446 -60.651425) (xy 96.238532 -60.607282) (xy 96.278681 -60.568573) (xy 96.324039 -60.536122)
			(xy 96.373639 -60.510621) (xy 96.426423 -60.492614) (xy 96.481266 -60.482484) (xy 96.537 -60.480447)
			(xy 96.592437 -60.486547) (xy 96.646394 -60.500653) (xy 96.697723 -60.522465) (xy 96.745329 -60.551519)
			(xy 96.788197 -60.587194) (xy 96.825414 -60.628731) (xy 96.856187 -60.675244) (xy 96.879859 -60.725741)
			(xy 96.895927 -60.779148) (xy 96.904047 -60.834324) (xy 96.904556 -60.86221) (xy 96.904047 -60.890096)
			(xy 96.895927 -60.945272) (xy 96.879859 -60.998679) (xy 96.856187 -61.049176) (xy 96.825414 -61.095689)
			(xy 96.788197 -61.137226) (xy 96.745329 -61.172901) (xy 96.697723 -61.201955) (xy 96.646394 -61.223767)
			(xy 96.592437 -61.237873) (xy 96.537 -61.243973) (xy 96.481266 -61.241936) (xy 96.426423 -61.231806)
			(xy 96.373639 -61.213799) (xy 96.324039 -61.188298) (xy 96.278681 -61.155847) (xy 96.238532 -61.117138)
			(xy 96.204446 -61.072995) (xy 96.17715 -61.02436) (xy 96.157227 -60.972269) (xy 96.145101 -60.917832)
			(xy 96.14103 -60.86221) (xy 95.19158 -60.86221) (xy 95.19158 -60.970668) (xy 95.191138 -60.99348)
			(xy 95.182255 -61.038225) (xy 95.164601 -61.080288) (xy 95.15221 -61.099446) (xy 95.147638 -61.10605)
			(xy 95.14332 -61.120274) (xy 95.14332 -61.29782) (xy 95.142868 -61.322012) (xy 95.135296 -61.3698)
			(xy 95.120341 -61.415814) (xy 95.098371 -61.458922) (xy 95.069928 -61.498063) (xy 95.05315 -61.515498)
			(xy 94.52864 -62.039754) (xy 94.265496 -62.303152) (xy 94.248072 -62.319932) (xy 94.208926 -62.348348)
			(xy 94.165811 -62.370278) (xy 94.119791 -62.38518) (xy 94.072005 -62.392686) (xy 94.047818 -62.393068)
			(xy 82.624676 -62.393068) (xy 82.615385 -62.394467) (xy 82.598661 -62.402992) (xy 82.586109 -62.41695)
			(xy 82.579398 -62.434481) (xy 82.578956 -62.443868) (xy 82.578956 -62.567566) (xy 82.57946 -62.57799)
			(xy 82.587717 -62.597135) (xy 82.594958 -62.60465) (xy 82.649568 -62.655704) (xy 82.657546 -62.662452)
			(xy 82.677223 -62.669415) (xy 82.687668 -62.669166) (xy 82.687922 -62.669166) (xy 82.714084 -62.66815)
			(xy 82.741337 -62.668635) (xy 82.795289 -62.676389) (xy 82.847588 -62.691742) (xy 82.89717 -62.714382)
			(xy 82.943025 -62.743847) (xy 82.984221 -62.779538) (xy 83.019918 -62.820728) (xy 83.04939 -62.866579)
			(xy 83.072037 -62.916158) (xy 83.087399 -62.968454) (xy 83.095161 -63.022405) (xy 83.095592 -63.049658)
			(xy 83.09504 -63.07877) (xy 83.086193 -63.136319) (xy 83.068712 -63.191858) (xy 83.043004 -63.2441)
			(xy 83.009663 -63.291834) (xy 82.969462 -63.333953) (xy 82.946748 -63.352172) (xy 82.942176 -63.355728)
			(xy 82.935318 -63.363856) (xy 82.932778 -63.368936) (xy 82.930289 -63.374003) (xy 82.927336 -63.384896)
			(xy 82.926936 -63.390526) (xy 82.923888 -63.46825) (xy 82.92384 -63.473857) (xy 82.925888 -63.48488)
			(xy 82.927952 -63.490094) (xy 82.93227 -63.500508) (xy 82.940652 -63.508128) (xy 82.960166 -63.526276)
			(xy 82.994439 -63.567084) (xy 83.022693 -63.612268) (xy 83.044376 -63.660948) (xy 83.059067 -63.712174)
			(xy 83.066478 -63.764947) (xy 83.06689 -63.791592) (xy 83.066406 -63.81882) (xy 83.058663 -63.872723)
			(xy 83.043334 -63.924977) (xy 83.020731 -63.97452) (xy 82.991311 -64.020346) (xy 82.955675 -64.061522)
			(xy 82.914545 -64.097213) (xy 82.868758 -64.126692) (xy 82.819244 -64.14936) (xy 82.76701 -64.164757)
			(xy 82.713117 -64.17257) (xy 82.68589 -64.1731) (xy 82.681064 -64.1731) (xy 82.670142 -64.175132)
			(xy 82.662803 -64.176871) (xy 82.649501 -64.183964) (xy 82.64398 -64.189102) (xy 82.593942 -64.238632)
			(xy 82.587096 -64.24603) (xy 82.579367 -64.264629) (xy 82.578956 -64.2747) (xy 82.578956 -71.20763)
			(xy 98.65563 -71.20763) (xy 98.659701 -71.152008) (xy 98.671827 -71.097571) (xy 98.69175 -71.04548)
			(xy 98.719046 -70.996845) (xy 98.753132 -70.952702) (xy 98.793281 -70.913993) (xy 98.838639 -70.881542)
			(xy 98.888239 -70.856041) (xy 98.941023 -70.838034) (xy 98.995866 -70.827904) (xy 99.0516 -70.825867)
			(xy 99.107037 -70.831967) (xy 99.160994 -70.846073) (xy 99.212323 -70.867885) (xy 99.259929 -70.896939)
			(xy 99.302797 -70.932614) (xy 99.340014 -70.974151) (xy 99.370787 -71.020664) (xy 99.394459 -71.071161)
			(xy 99.410527 -71.124568) (xy 99.418647 -71.179744) (xy 99.419156 -71.20763) (xy 99.418647 -71.235516)
			(xy 99.410527 -71.290692) (xy 99.394459 -71.344099) (xy 99.370787 -71.394596) (xy 99.340014 -71.441109)
			(xy 99.302797 -71.482646) (xy 99.259929 -71.518321) (xy 99.212323 -71.547375) (xy 99.160994 -71.569187)
			(xy 99.107037 -71.583293) (xy 99.0516 -71.589393) (xy 98.995866 -71.587356) (xy 98.941023 -71.577226)
			(xy 98.888239 -71.559219) (xy 98.838639 -71.533718) (xy 98.793281 -71.501267) (xy 98.753132 -71.462558)
			(xy 98.719046 -71.418415) (xy 98.69175 -71.36978) (xy 98.671827 -71.317689) (xy 98.659701 -71.263252)
			(xy 98.65563 -71.20763) (xy 82.578956 -71.20763) (xy 82.578956 -72.136) (xy 84.961982 -72.136) (xy 84.966053 -72.080378)
			(xy 84.978179 -72.025941) (xy 84.998102 -71.97385) (xy 85.025398 -71.925215) (xy 85.059484 -71.881072)
			(xy 85.099633 -71.842363) (xy 85.144991 -71.809912) (xy 85.194591 -71.784411) (xy 85.247375 -71.766404)
			(xy 85.302218 -71.756274) (xy 85.357952 -71.754237) (xy 85.413389 -71.760337) (xy 85.467346 -71.774443)
			(xy 85.486744 -71.782686) (xy 87.002618 -71.782686) (xy 87.006689 -71.727064) (xy 87.018815 -71.672627)
			(xy 87.038738 -71.620536) (xy 87.066034 -71.571901) (xy 87.10012 -71.527758) (xy 87.140269 -71.489049)
			(xy 87.185627 -71.456598) (xy 87.235227 -71.431097) (xy 87.288011 -71.41309) (xy 87.342854 -71.40296)
			(xy 87.398588 -71.400923) (xy 87.454025 -71.407023) (xy 87.507982 -71.421129) (xy 87.559311 -71.442941)
			(xy 87.606917 -71.471995) (xy 87.649785 -71.50767) (xy 87.687002 -71.549207) (xy 87.717775 -71.59572)
			(xy 87.741447 -71.646217) (xy 87.757515 -71.699624) (xy 87.765635 -71.7548) (xy 87.766144 -71.782686)
			(xy 87.765635 -71.810572) (xy 87.757515 -71.865748) (xy 87.741447 -71.919155) (xy 87.717775 -71.969652)
			(xy 87.687002 -72.016165) (xy 87.649785 -72.057702) (xy 87.606917 -72.093377) (xy 87.559311 -72.122431)
			(xy 87.507982 -72.144243) (xy 87.454025 -72.158349) (xy 87.398588 -72.164449) (xy 87.342854 -72.162412)
			(xy 87.288011 -72.152282) (xy 87.235227 -72.134275) (xy 87.185627 -72.108774) (xy 87.140269 -72.076323)
			(xy 87.10012 -72.037614) (xy 87.066034 -71.993471) (xy 87.038738 -71.944836) (xy 87.018815 -71.892745)
			(xy 87.006689 -71.838308) (xy 87.002618 -71.782686) (xy 85.486744 -71.782686) (xy 85.518675 -71.796255)
			(xy 85.566281 -71.825309) (xy 85.609149 -71.860984) (xy 85.646366 -71.902521) (xy 85.677139 -71.949034)
			(xy 85.700811 -71.999531) (xy 85.716879 -72.052938) (xy 85.724999 -72.108114) (xy 85.725508 -72.136)
			(xy 85.724999 -72.163886) (xy 85.723272 -72.175624) (xy 98.901756 -72.175624) (xy 98.905827 -72.120002)
			(xy 98.917953 -72.065565) (xy 98.937876 -72.013474) (xy 98.965172 -71.964839) (xy 98.999258 -71.920696)
			(xy 99.039407 -71.881987) (xy 99.084765 -71.849536) (xy 99.134365 -71.824035) (xy 99.187149 -71.806028)
			(xy 99.241992 -71.795898) (xy 99.297726 -71.793861) (xy 99.353163 -71.799961) (xy 99.40712 -71.814067)
			(xy 99.458449 -71.835879) (xy 99.506055 -71.864933) (xy 99.548923 -71.900608) (xy 99.58614 -71.942145)
			(xy 99.616913 -71.988658) (xy 99.640585 -72.039155) (xy 99.656653 -72.092562) (xy 99.664773 -72.147738)
			(xy 99.665282 -72.175624) (xy 99.664773 -72.20351) (xy 99.656653 -72.258686) (xy 99.640585 -72.312093)
			(xy 99.616913 -72.36259) (xy 99.58614 -72.409103) (xy 99.548923 -72.45064) (xy 99.506055 -72.486315)
			(xy 99.458449 -72.515369) (xy 99.40712 -72.537181) (xy 99.353163 -72.551287) (xy 99.297726 -72.557387)
			(xy 99.241992 -72.55535) (xy 99.187149 -72.54522) (xy 99.134365 -72.527213) (xy 99.084765 -72.501712)
			(xy 99.039407 -72.469261) (xy 98.999258 -72.430552) (xy 98.965172 -72.386409) (xy 98.937876 -72.337774)
			(xy 98.917953 -72.285683) (xy 98.905827 -72.231246) (xy 98.901756 -72.175624) (xy 85.723272 -72.175624)
			(xy 85.716879 -72.219062) (xy 85.700811 -72.272469) (xy 85.677139 -72.322966) (xy 85.646366 -72.369479)
			(xy 85.609149 -72.411016) (xy 85.566281 -72.446691) (xy 85.518675 -72.475745) (xy 85.467346 -72.497557)
			(xy 85.413389 -72.511663) (xy 85.357952 -72.517763) (xy 85.302218 -72.515726) (xy 85.247375 -72.505596)
			(xy 85.194591 -72.487589) (xy 85.144991 -72.462088) (xy 85.099633 -72.429637) (xy 85.059484 -72.390928)
			(xy 85.025398 -72.346785) (xy 84.998102 -72.29815) (xy 84.978179 -72.246059) (xy 84.966053 -72.191622)
			(xy 84.961982 -72.136) (xy 82.578956 -72.136) (xy 82.578956 -72.266556) (xy 82.579391 -72.27662)
			(xy 82.587126 -72.295205) (xy 82.593942 -72.302624) (xy 85.785576 -75.494258) (xy 92.753311 -75.494258)
			(xy 92.753311 -75.439742) (xy 92.76107 -75.385782) (xy 92.776429 -75.333476) (xy 92.799077 -75.283887)
			(xy 92.828552 -75.238027) (xy 92.864253 -75.196829) (xy 92.905455 -75.161131) (xy 92.951317 -75.131661)
			(xy 93.000907 -75.109017) (xy 93.053216 -75.093663) (xy 93.107176 -75.085909) (xy 93.134434 -75.085448)
			(xy 93.161806 -75.085882) (xy 93.215986 -75.093706) (xy 93.26849 -75.109202) (xy 93.318237 -75.132051)
			(xy 93.364202 -75.161783) (xy 93.385132 -75.179428) (xy 93.392244 -75.185524) (xy 93.409262 -75.191874)
			(xy 93.494606 -75.191874) (xy 93.511624 -75.185524) (xy 93.518736 -75.179428) (xy 93.54185 -75.160632)
			(xy 93.549724 -75.155044) (xy 93.55963 -75.139296) (xy 93.576648 -75.053698) (xy 93.5736 -75.03541)
			(xy 93.568774 -75.027282) (xy 93.555984 -75.005049) (xy 93.535845 -74.957877) (xy 93.522215 -74.90843)
			(xy 93.515341 -74.857602) (xy 93.514926 -74.831956) (xy 93.515419 -74.804587) (xy 93.523229 -74.750408)
			(xy 93.538712 -74.697905) (xy 93.561548 -74.648158) (xy 93.591267 -74.60219) (xy 93.608906 -74.581258)
			(xy 93.615002 -74.574146) (xy 93.621352 -74.557128) (xy 93.621352 -74.471784) (xy 93.615002 -74.454766)
			(xy 93.608906 -74.447654) (xy 93.59128 -74.426712) (xy 93.561566 -74.380742) (xy 93.538727 -74.330997)
			(xy 93.523233 -74.278498) (xy 93.515402 -74.224324) (xy 93.514926 -74.196956) (xy 93.515412 -74.169705)
			(xy 93.523168 -74.115757) (xy 93.538523 -74.063462) (xy 93.561165 -74.013885) (xy 93.590631 -73.968035)
			(xy 93.626322 -73.926844) (xy 93.667513 -73.891153) (xy 93.713363 -73.861687) (xy 93.76294 -73.839045)
			(xy 93.815235 -73.82369) (xy 93.869183 -73.815934) (xy 93.923685 -73.815934) (xy 93.977633 -73.82369)
			(xy 94.029928 -73.839045) (xy 94.079505 -73.861687) (xy 94.125355 -73.891153) (xy 94.166546 -73.926844)
			(xy 94.202237 -73.968035) (xy 94.231703 -74.013885) (xy 94.254345 -74.063462) (xy 94.2697 -74.115757)
			(xy 94.277456 -74.169705) (xy 94.277942 -74.196956) (xy 94.277464 -74.224326) (xy 94.269651 -74.278505)
			(xy 94.254166 -74.331009) (xy 94.231326 -74.380756) (xy 94.201603 -74.426723) (xy 94.183962 -74.447654)
			(xy 94.177866 -74.454766) (xy 94.171516 -74.471784) (xy 94.171516 -74.557128) (xy 94.177866 -74.574146)
			(xy 94.183962 -74.581258) (xy 94.201589 -74.6022) (xy 94.231304 -74.648169) (xy 94.254143 -74.697914)
			(xy 94.269637 -74.750413) (xy 94.277467 -74.804587) (xy 94.277942 -74.831956) (xy 94.27736 -74.861599)
			(xy 94.268201 -74.920173) (xy 94.250096 -74.976627) (xy 94.223481 -75.029602) (xy 94.188995 -75.077826)
			(xy 94.147468 -75.120138) (xy 94.124018 -75.13828) (xy 94.116144 -75.143868) (xy 94.106238 -75.159616)
			(xy 94.08922 -75.245214) (xy 94.092268 -75.263502) (xy 94.097094 -75.27163) (xy 94.109895 -75.293856)
			(xy 94.130031 -75.341031) (xy 94.143657 -75.39048) (xy 94.150528 -75.44131) (xy 94.150942 -75.466956)
			(xy 94.150404 -75.494206) (xy 94.142654 -75.548153) (xy 94.127305 -75.600447) (xy 94.10467 -75.650025)
			(xy 94.07521 -75.695876) (xy 94.039524 -75.737069) (xy 93.998339 -75.772763) (xy 93.952493 -75.802233)
			(xy 93.90292 -75.824878) (xy 93.850629 -75.840237) (xy 93.796684 -75.847998) (xy 93.769434 -75.848464)
			(xy 93.742064 -75.847987) (xy 93.687885 -75.840173) (xy 93.635382 -75.824687) (xy 93.585635 -75.801848)
			(xy 93.539668 -75.772125) (xy 93.518736 -75.754484) (xy 93.511624 -75.748388) (xy 93.494606 -75.742038)
			(xy 93.409262 -75.742038) (xy 93.392244 -75.748388) (xy 93.385132 -75.754484) (xy 93.364197 -75.772119)
			(xy 93.318225 -75.801832) (xy 93.268478 -75.824669) (xy 93.215978 -75.840161) (xy 93.161803 -75.84799)
			(xy 93.134434 -75.848464) (xy 93.107176 -75.848091) (xy 93.053216 -75.840337) (xy 93.000907 -75.824983)
			(xy 92.951317 -75.802339) (xy 92.905455 -75.772869) (xy 92.864253 -75.737171) (xy 92.828552 -75.695973)
			(xy 92.799077 -75.650113) (xy 92.776429 -75.600524) (xy 92.76107 -75.548218) (xy 92.753311 -75.494258)
			(xy 85.785576 -75.494258) (xy 87.227664 -76.936346) (xy 87.235063 -76.943188) (xy 87.253662 -76.950908)
			(xy 87.263732 -76.951332)
		)
		(stroke
			(width 0)
			(type solid)
		)
		(fill yes)
		(layer "B.Cu")
		(net "GND")
	)
	(gr_poly
		(pts
			(xy 262.295894 -104.57561) (xy 262.305429 -104.575229) (xy 262.323185 -104.568276) (xy 262.337156 -104.555299)
			(xy 262.345398 -104.538104) (xy 262.34644 -104.52862) (xy 262.34644 -104.528112) (xy 262.349684 -104.496845)
			(xy 262.362912 -104.435391) (xy 262.383611 -104.376035) (xy 262.411466 -104.319681) (xy 262.446053 -104.267189)
			(xy 262.486843 -104.219358) (xy 262.533216 -104.176917) (xy 262.584464 -104.140514) (xy 262.639808 -104.110702)
			(xy 262.698403 -104.087936) (xy 262.759356 -104.072564) (xy 262.821739 -104.064818) (xy 262.884601 -104.064818)
			(xy 262.946984 -104.072564) (xy 263.007937 -104.087936) (xy 263.066532 -104.110702) (xy 263.121876 -104.140514)
			(xy 263.173124 -104.176917) (xy 263.219497 -104.219358) (xy 263.260287 -104.267189) (xy 263.294874 -104.319681)
			(xy 263.322729 -104.376035) (xy 263.343428 -104.435391) (xy 263.356656 -104.496845) (xy 263.3599 -104.528112)
			(xy 263.3599 -104.52862) (xy 263.361023 -104.538074) (xy 263.369295 -104.555206) (xy 263.383237 -104.568151)
			(xy 263.400935 -104.575132) (xy 263.410446 -104.57561) (xy 270.376396 -104.57561) (xy 270.386275 -104.575154)
			(xy 270.40458 -104.567717) (xy 270.411956 -104.561132) (xy 270.41221 -104.560878) (xy 271.697958 -103.27513)
			(xy 271.705358 -103.26829) (xy 271.723957 -103.260572) (xy 271.734026 -103.260144) (xy 285.75 -103.260144)
			(xy 285.760011 -103.259657) (xy 285.77851 -103.251999) (xy 285.792674 -103.237847) (xy 285.800348 -103.219354)
			(xy 285.8008 -103.209344) (xy 285.8008 -98.783394) (xy 285.800376 -98.773324) (xy 285.79266 -98.754721)
			(xy 285.785814 -98.747326) (xy 279.535382 -92.496894) (xy 279.52827 -92.489528) (xy 279.509474 -92.481908)
			(xy 257.103372 -92.481908) (xy 257.077972 -92.498672) (xy 257.071876 -92.512896) (xy 257.05846 -92.543072)
			(xy 257.024948 -92.599977) (xy 256.984353 -92.652065) (xy 256.937358 -92.698462) (xy 256.884753 -92.738385)
			(xy 256.827423 -92.771164) (xy 256.766332 -92.796247) (xy 256.702509 -92.813212) (xy 256.637028 -92.821773)
			(xy 256.604008 -92.822268) (xy 256.591286 -92.82219) (xy 256.565874 -92.820921) (xy 256.553208 -92.819728)
			(xy 256.553208 -92.819982) (xy 256.523509 -92.816556) (xy 256.465137 -92.803631) (xy 256.408683 -92.783951)
			(xy 256.354925 -92.757788) (xy 256.304605 -92.725504) (xy 256.258417 -92.687543) (xy 256.216998 -92.644429)
			(xy 256.198624 -92.620846) (xy 256.19202 -92.61221) (xy 256.173732 -92.60205) (xy 256.07899 -92.592398)
			(xy 256.059178 -92.598748) (xy 256.05105 -92.60586) (xy 256.030047 -92.623667) (xy 255.983887 -92.653688)
			(xy 255.933894 -92.676768) (xy 255.881105 -92.69243) (xy 255.826614 -92.700349) (xy 255.799082 -92.700856)
			(xy 255.791462 -92.700856) (xy 255.778254 -92.700094) (xy 255.753624 -92.698358) (xy 255.705083 -92.689311)
			(xy 255.68148 -92.68206) (xy 255.667764 -92.677488) (xy 255.640078 -92.684092) (xy 254.677418 -93.646752)
			(xy 254.670814 -93.674184) (xy 254.674878 -93.687646) (xy 254.683329 -93.715909) (xy 254.69518 -93.773702)
			(xy 254.701161 -93.832393) (xy 254.701548 -93.86189) (xy 254.701015 -93.897227) (xy 254.692498 -93.967387)
			(xy 254.675586 -94.036008) (xy 254.650526 -94.102091) (xy 254.629396 -94.142353) (xy 275.700683 -94.142353)
			(xy 275.700683 -94.087847) (xy 275.708441 -94.033896) (xy 275.723798 -93.981599) (xy 275.746442 -93.932019)
			(xy 275.775912 -93.886167) (xy 275.811608 -93.844977) (xy 275.852803 -93.809286) (xy 275.898658 -93.779821)
			(xy 275.94824 -93.757183) (xy 276.000539 -93.741832) (xy 276.054491 -93.73408) (xy 276.081744 -93.73362)
			(xy 276.107324 -93.73406) (xy 276.158025 -93.7409) (xy 276.207358 -93.754453) (xy 276.254438 -93.774474)
			(xy 276.298422 -93.800606) (xy 276.318726 -93.81617) (xy 276.326854 -93.82252) (xy 276.347174 -93.828108)
			(xy 276.441154 -93.814392) (xy 276.458934 -93.803216) (xy 276.46503 -93.79458) (xy 276.482904 -93.769807)
			(xy 276.523657 -93.724298) (xy 276.569567 -93.683997) (xy 276.619972 -93.649485) (xy 276.674149 -93.621258)
			(xy 276.731316 -93.599722) (xy 276.790651 -93.585188) (xy 276.8513 -93.577865) (xy 276.881844 -93.57741)
			(xy 276.913804 -93.577879) (xy 276.977221 -93.585895) (xy 277.039132 -93.601796) (xy 277.098562 -93.625331)
			(xy 277.154575 -93.656128) (xy 277.206286 -93.693703) (xy 277.25288 -93.737461) (xy 277.293623 -93.786715)
			(xy 277.327872 -93.840686) (xy 277.355087 -93.898524) (xy 277.374838 -93.959317) (xy 277.386815 -94.022105)
			(xy 277.390829 -94.0859) (xy 277.386815 -94.149695) (xy 277.374838 -94.212483) (xy 277.355087 -94.273276)
			(xy 277.327872 -94.331114) (xy 277.293623 -94.385085) (xy 277.25288 -94.434339) (xy 277.206286 -94.478097)
			(xy 277.154575 -94.515672) (xy 277.098562 -94.546469) (xy 277.039132 -94.570004) (xy 276.977221 -94.585905)
			(xy 276.913804 -94.593921) (xy 276.881844 -94.594426) (xy 276.849577 -94.593969) (xy 276.785562 -94.585804)
			(xy 276.723095 -94.5696) (xy 276.663183 -94.545618) (xy 276.60679 -94.514244) (xy 276.554822 -94.475982)
			(xy 276.508117 -94.431448) (xy 276.487382 -94.40672) (xy 276.480778 -94.398592) (xy 276.462236 -94.38894)
			(xy 276.367494 -94.382082) (xy 276.347682 -94.38894) (xy 276.339808 -94.396052) (xy 276.318573 -94.414855)
			(xy 276.27159 -94.446627) (xy 276.220421 -94.471091) (xy 276.166193 -94.487709) (xy 276.110102 -94.496114)
			(xy 276.081744 -94.496636) (xy 276.054491 -94.49612) (xy 276.000539 -94.488368) (xy 275.94824 -94.473017)
			(xy 275.898658 -94.450379) (xy 275.852803 -94.420914) (xy 275.811608 -94.385223) (xy 275.775912 -94.344033)
			(xy 275.746442 -94.298181) (xy 275.723798 -94.248601) (xy 275.708441 -94.196304) (xy 275.700683 -94.142353)
			(xy 254.629396 -94.142353) (xy 254.617684 -94.164671) (xy 254.577539 -94.222837) (xy 254.530675 -94.27574)
			(xy 254.477776 -94.322608) (xy 254.419614 -94.362758) (xy 254.357037 -94.395606) (xy 254.290956 -94.420671)
			(xy 254.222336 -94.437589) (xy 254.152177 -94.446112) (xy 254.11684 -94.446598) (xy 254.087342 -94.44622)
			(xy 254.028648 -94.440252) (xy 253.970856 -94.428394) (xy 253.942596 -94.419928) (xy 253.929134 -94.415864)
			(xy 253.901702 -94.422468) (xy 253.678944 -94.645226) (xy 253.675896 -94.682056) (xy 253.686564 -94.697296)
			(xy 253.707031 -94.727035) (xy 253.741272 -94.790592) (xy 253.767422 -94.857884) (xy 253.785083 -94.927884)
			(xy 253.793986 -94.999527) (xy 253.794514 -95.035624) (xy 253.793979 -95.070959) (xy 253.785458 -95.141114)
			(xy 253.768544 -95.209731) (xy 253.743481 -95.275808) (xy 253.710638 -95.338383) (xy 253.670491 -95.396543)
			(xy 253.623627 -95.44944) (xy 253.570729 -95.496302) (xy 253.512567 -95.536447) (xy 253.449992 -95.569289)
			(xy 253.383913 -95.594349) (xy 253.315296 -95.611262) (xy 253.245141 -95.61978) (xy 253.209806 -95.620332)
			(xy 253.173711 -95.619779) (xy 253.102072 -95.610864) (xy 253.032074 -95.593204) (xy 252.964779 -95.56707)
			(xy 252.90121 -95.532856) (xy 252.871478 -95.512382) (xy 252.86396 -95.507578) (xy 252.846745 -95.502942)
			(xy 252.828983 -95.50447) (xy 252.812813 -95.511978) (xy 252.8062 -95.51797) (xy 251.91085 -96.41332)
			(xy 251.903484 -96.420432) (xy 251.895864 -96.439228) (xy 251.895864 -98.802952) (xy 267.622528 -98.802952)
			(xy 267.622964 -98.770401) (xy 267.630194 -98.705702) (xy 267.64457 -98.642207) (xy 267.665914 -98.580703)
			(xy 267.693961 -98.521953) (xy 267.728364 -98.466684) (xy 267.768697 -98.415581) (xy 267.81446 -98.369277)
			(xy 267.865086 -98.328347) (xy 267.892276 -98.310446) (xy 267.90142 -98.30435) (xy 267.913358 -98.286316)
			(xy 267.92809 -98.18878) (xy 267.922248 -98.167952) (xy 267.915136 -98.159316) (xy 267.898278 -98.13865)
			(xy 267.869998 -98.09343) (xy 267.848293 -98.044712) (xy 267.833584 -97.993446) (xy 267.826161 -97.940631)
			(xy 267.826166 -97.887296) (xy 267.8336 -97.834482) (xy 267.848318 -97.783219) (xy 267.870033 -97.734505)
			(xy 267.898321 -97.689291) (xy 267.915136 -97.668588) (xy 267.922248 -97.659952) (xy 267.92809 -97.639124)
			(xy 267.913358 -97.541588) (xy 267.90142 -97.523554) (xy 267.892276 -97.517458) (xy 267.865114 -97.499516)
			(xy 267.814493 -97.458587) (xy 267.768733 -97.412287) (xy 267.728402 -97.361188) (xy 267.693998 -97.305925)
			(xy 267.665948 -97.24718) (xy 267.644599 -97.185683) (xy 267.630216 -97.122194) (xy 267.622977 -97.057501)
			(xy 267.622528 -97.024952) (xy 267.623023 -96.990925) (xy 267.630923 -96.923332) (xy 267.646617 -96.857114)
			(xy 267.669893 -96.793165) (xy 267.700435 -96.73235) (xy 267.737831 -96.675493) (xy 267.781574 -96.623361)
			(xy 267.831074 -96.57666) (xy 267.885661 -96.536022) (xy 267.944597 -96.501995) (xy 268.007085 -96.475041)
			(xy 268.072279 -96.455523) (xy 268.139298 -96.443705) (xy 268.207236 -96.439749) (xy 268.275174 -96.443705)
			(xy 268.342193 -96.455523) (xy 268.407387 -96.475041) (xy 268.469875 -96.501995) (xy 268.528811 -96.536022)
			(xy 268.571432 -96.567752) (xy 270.723614 -96.567752) (xy 270.724109 -96.533725) (xy 270.732009 -96.466132)
			(xy 270.747703 -96.399914) (xy 270.770979 -96.335965) (xy 270.801521 -96.27515) (xy 270.838917 -96.218293)
			(xy 270.88266 -96.166161) (xy 270.93216 -96.11946) (xy 270.986747 -96.078822) (xy 271.045683 -96.044795)
			(xy 271.108171 -96.017841) (xy 271.173365 -95.998323) (xy 271.240384 -95.986505) (xy 271.308322 -95.982549)
			(xy 271.37626 -95.986505) (xy 271.443279 -95.998323) (xy 271.508473 -96.017841) (xy 271.570961 -96.044795)
			(xy 271.629897 -96.078822) (xy 271.684484 -96.11946) (xy 271.733984 -96.166161) (xy 271.777727 -96.218293)
			(xy 271.815123 -96.27515) (xy 271.845665 -96.335965) (xy 271.868941 -96.399914) (xy 271.884635 -96.466132)
			(xy 271.892535 -96.533725) (xy 271.89303 -96.567752) (xy 271.892571 -96.600302) (xy 271.885341 -96.665)
			(xy 271.870966 -96.728493) (xy 271.849624 -96.789995) (xy 271.82158 -96.848745) (xy 271.78718 -96.904014)
			(xy 271.74685 -96.955117) (xy 271.701092 -97.001422) (xy 271.65047 -97.042355) (xy 271.623282 -97.060258)
			(xy 271.614138 -97.066354) (xy 271.6022 -97.084388) (xy 271.587468 -97.181924) (xy 271.59331 -97.202752)
			(xy 271.600422 -97.211388) (xy 271.617238 -97.232089) (xy 271.645531 -97.277298) (xy 271.667247 -97.326009)
			(xy 271.681962 -97.377272) (xy 271.683459 -97.387918) (xy 272.212308 -97.387918) (xy 272.212783 -97.360754)
			(xy 272.220488 -97.306974) (xy 272.235744 -97.254832) (xy 272.258243 -97.205382) (xy 272.287531 -97.159623)
			(xy 272.323013 -97.118483) (xy 272.363974 -97.082792) (xy 272.409583 -97.053273) (xy 272.43405 -97.041462)
			(xy 272.44421 -97.036636) (xy 272.458688 -97.019872) (xy 272.485866 -96.92386) (xy 272.48231 -96.902016)
			(xy 272.47596 -96.892618) (xy 272.457259 -96.863676) (xy 272.425968 -96.802283) (xy 272.402111 -96.737637)
			(xy 272.386018 -96.670635) (xy 272.377912 -96.602206) (xy 272.377408 -96.567752) (xy 272.377903 -96.533725)
			(xy 272.385803 -96.466132) (xy 272.401497 -96.399914) (xy 272.424773 -96.335965) (xy 272.455315 -96.27515)
			(xy 272.492711 -96.218293) (xy 272.536454 -96.166161) (xy 272.585954 -96.11946) (xy 272.640541 -96.078822)
			(xy 272.699477 -96.044795) (xy 272.761965 -96.017841) (xy 272.827159 -95.998323) (xy 272.894178 -95.986505)
			(xy 272.962116 -95.982549) (xy 273.030054 -95.986505) (xy 273.097073 -95.998323) (xy 273.162267 -96.017841)
			(xy 273.224755 -96.044795) (xy 273.283691 -96.078822) (xy 273.338278 -96.11946) (xy 273.387778 -96.166161)
			(xy 273.431521 -96.218293) (xy 273.468917 -96.27515) (xy 273.499459 -96.335965) (xy 273.522735 -96.399914)
			(xy 273.538429 -96.466132) (xy 273.546329 -96.533725) (xy 273.546824 -96.567752) (xy 273.54627 -96.602682)
			(xy 273.537928 -96.672042) (xy 273.521383 -96.739914) (xy 273.496869 -96.805332) (xy 273.464736 -96.867363)
			(xy 273.425442 -96.925124) (xy 273.379545 -96.977792) (xy 273.327701 -97.024617) (xy 273.270647 -97.064932)
			(xy 273.209196 -97.098162) (xy 273.144225 -97.123834) (xy 273.076657 -97.141582) (xy 273.042126 -97.146872)
			(xy 273.03095 -97.148396) (xy 273.012408 -97.160334) (xy 272.95856 -97.244408) (xy 272.955512 -97.266252)
			(xy 272.958814 -97.277174) (xy 272.966527 -97.304208) (xy 272.974809 -97.35981) (xy 272.975021 -97.371365)
			(xy 273.405594 -97.371365) (xy 273.405594 -97.307443) (xy 273.413605 -97.244025) (xy 273.429502 -97.182111)
			(xy 273.453034 -97.122678) (xy 273.483828 -97.066663) (xy 273.521401 -97.014948) (xy 273.565158 -96.968351)
			(xy 273.614411 -96.927606) (xy 273.668382 -96.893355) (xy 273.726221 -96.866138) (xy 273.787014 -96.846385)
			(xy 273.849804 -96.834407) (xy 273.9136 -96.830394) (xy 273.977396 -96.834407) (xy 274.040186 -96.846385)
			(xy 274.100979 -96.866138) (xy 274.158818 -96.893355) (xy 274.212789 -96.927606) (xy 274.262042 -96.968351)
			(xy 274.305799 -97.014948) (xy 274.343372 -97.066663) (xy 274.374166 -97.122678) (xy 274.397698 -97.182111)
			(xy 274.413595 -97.244025) (xy 274.421606 -97.307443) (xy 274.422108 -97.339404) (xy 274.421606 -97.371365)
			(xy 274.413595 -97.434783) (xy 274.397698 -97.496697) (xy 274.374166 -97.55613) (xy 274.343372 -97.612145)
			(xy 274.305799 -97.66386) (xy 274.262042 -97.710457) (xy 274.212789 -97.751202) (xy 274.158818 -97.785453)
			(xy 274.100979 -97.81267) (xy 274.040186 -97.832423) (xy 273.977396 -97.844401) (xy 273.9136 -97.848415)
			(xy 273.849804 -97.844401) (xy 273.787014 -97.832423) (xy 273.726221 -97.81267) (xy 273.668382 -97.785453)
			(xy 273.614411 -97.751202) (xy 273.565158 -97.710457) (xy 273.521401 -97.66386) (xy 273.483828 -97.612145)
			(xy 273.453034 -97.55613) (xy 273.429502 -97.496697) (xy 273.413605 -97.434783) (xy 273.405594 -97.371365)
			(xy 272.975021 -97.371365) (xy 272.975324 -97.387918) (xy 272.974838 -97.415169) (xy 272.967082 -97.469117)
			(xy 272.951727 -97.521412) (xy 272.929085 -97.570989) (xy 272.899619 -97.616839) (xy 272.863928 -97.65803)
			(xy 272.822737 -97.693721) (xy 272.776887 -97.723187) (xy 272.72731 -97.745829) (xy 272.675015 -97.761184)
			(xy 272.621067 -97.76894) (xy 272.566565 -97.76894) (xy 272.512617 -97.761184) (xy 272.460322 -97.745829)
			(xy 272.410745 -97.723187) (xy 272.364895 -97.693721) (xy 272.323704 -97.65803) (xy 272.288013 -97.616839)
			(xy 272.258547 -97.570989) (xy 272.235905 -97.521412) (xy 272.22055 -97.469117) (xy 272.212794 -97.415169)
			(xy 272.212308 -97.387918) (xy 271.683459 -97.387918) (xy 271.689388 -97.430086) (xy 271.68983 -97.456752)
			(xy 271.689344 -97.484003) (xy 271.681588 -97.537951) (xy 271.666233 -97.590246) (xy 271.643591 -97.639823)
			(xy 271.614125 -97.685673) (xy 271.578434 -97.726864) (xy 271.537243 -97.762555) (xy 271.491393 -97.792021)
			(xy 271.441816 -97.814663) (xy 271.389521 -97.830018) (xy 271.335573 -97.837774) (xy 271.281071 -97.837774)
			(xy 271.227123 -97.830018) (xy 271.174828 -97.814663) (xy 271.125251 -97.792021) (xy 271.079401 -97.762555)
			(xy 271.03821 -97.726864) (xy 271.002519 -97.685673) (xy 270.973053 -97.639823) (xy 270.950411 -97.590246)
			(xy 270.935056 -97.537951) (xy 270.9273 -97.484003) (xy 270.926814 -97.456752) (xy 270.927244 -97.430086)
			(xy 270.934688 -97.377276) (xy 270.949411 -97.326017) (xy 270.971126 -97.277306) (xy 270.999411 -97.232092)
			(xy 271.016222 -97.211388) (xy 271.023334 -97.202752) (xy 271.029176 -97.181924) (xy 271.014444 -97.084388)
			(xy 271.002506 -97.066354) (xy 270.993362 -97.060258) (xy 270.966197 -97.042321) (xy 270.915577 -97.001391)
			(xy 270.869817 -96.95509) (xy 270.829486 -96.90399) (xy 270.795083 -96.848726) (xy 270.767033 -96.789982)
			(xy 270.745685 -96.728484) (xy 270.731302 -96.664995) (xy 270.724063 -96.600301) (xy 270.723614 -96.567752)
			(xy 268.571432 -96.567752) (xy 268.583398 -96.57666) (xy 268.632898 -96.623361) (xy 268.676641 -96.675493)
			(xy 268.714037 -96.73235) (xy 268.744579 -96.793165) (xy 268.767855 -96.857114) (xy 268.783549 -96.923332)
			(xy 268.791449 -96.990925) (xy 268.791944 -97.024952) (xy 268.791478 -97.057502) (xy 268.784249 -97.122199)
			(xy 268.769875 -97.185692) (xy 268.748533 -97.247194) (xy 268.720489 -97.305943) (xy 268.68609 -97.361212)
			(xy 268.645762 -97.412316) (xy 268.600004 -97.458621) (xy 268.549384 -97.499555) (xy 268.522196 -97.517458)
			(xy 268.513052 -97.523554) (xy 268.501114 -97.541588) (xy 268.486382 -97.639124) (xy 268.492224 -97.659952)
			(xy 268.499336 -97.668588) (xy 268.516098 -97.689328) (xy 268.544377 -97.734537) (xy 268.566084 -97.783243)
			(xy 268.580797 -97.834497) (xy 268.588228 -97.887301) (xy 268.588233 -97.940625) (xy 268.580812 -97.993431)
			(xy 268.566109 -98.044688) (xy 268.544411 -98.093398) (xy 268.516141 -98.138612) (xy 268.499336 -98.159316)
			(xy 268.492224 -98.167952) (xy 268.486382 -98.18878) (xy 268.501114 -98.286316) (xy 268.513052 -98.30435)
			(xy 268.522196 -98.310446) (xy 268.549376 -98.32836) (xy 268.599994 -98.369295) (xy 268.645751 -98.415601)
			(xy 268.68608 -98.466703) (xy 268.706762 -98.49993) (xy 272.274538 -98.49993) (xy 272.275033 -98.465903)
			(xy 272.282933 -98.39831) (xy 272.298627 -98.332092) (xy 272.321903 -98.268143) (xy 272.352445 -98.207328)
			(xy 272.389841 -98.150471) (xy 272.433584 -98.098339) (xy 272.483084 -98.051638) (xy 272.537671 -98.011)
			(xy 272.596607 -97.976973) (xy 272.659095 -97.950019) (xy 272.724289 -97.930501) (xy 272.791308 -97.918683)
			(xy 272.859246 -97.914727) (xy 272.927184 -97.918683) (xy 272.994203 -97.930501) (xy 273.059397 -97.950019)
			(xy 273.121885 -97.976973) (xy 273.180821 -98.011) (xy 273.235408 -98.051638) (xy 273.284908 -98.098339)
			(xy 273.328651 -98.150471) (xy 273.366047 -98.207328) (xy 273.396589 -98.268143) (xy 273.419865 -98.332092)
			(xy 273.435559 -98.39831) (xy 273.443459 -98.465903) (xy 273.443954 -98.49993) (xy 273.4434 -98.535296)
			(xy 273.434871 -98.605513) (xy 273.41793 -98.674186) (xy 273.392824 -98.740313) (xy 273.35992 -98.802926)
			(xy 273.3197 -98.861111) (xy 273.272751 -98.914015) (xy 273.246596 -98.937826) (xy 273.238214 -98.945446)
			(xy 273.229324 -98.965258) (xy 273.230086 -99.064064) (xy 273.23923 -99.083876) (xy 273.247612 -99.090988)
			(xy 273.254724 -99.097338) (xy 273.263614 -99.105212) (xy 273.28495 -99.111562) (xy 273.385788 -99.096322)
			(xy 273.40433 -99.083622) (xy 273.410426 -99.073716) (xy 273.427996 -99.04498) (xy 273.468723 -98.991329)
			(xy 273.515344 -98.942715) (xy 273.567243 -98.899779) (xy 273.623733 -98.863092) (xy 273.684063 -98.833139)
			(xy 273.747436 -98.810316) (xy 273.813012 -98.794928) (xy 273.879922 -98.787176) (xy 273.9136 -98.786696)
			(xy 273.947627 -98.787183) (xy 274.01522 -98.795083) (xy 274.081439 -98.810777) (xy 274.145389 -98.834053)
			(xy 274.206204 -98.864595) (xy 274.263062 -98.901991) (xy 274.315194 -98.945735) (xy 274.361895 -98.995236)
			(xy 274.402534 -99.049823) (xy 274.436561 -99.108759) (xy 274.463515 -99.171247) (xy 274.483033 -99.236442)
			(xy 274.494851 -99.303462) (xy 274.498808 -99.3714) (xy 274.494851 -99.439338) (xy 274.483033 -99.506358)
			(xy 274.463515 -99.571553) (xy 274.436561 -99.634041) (xy 274.402534 -99.692977) (xy 274.361895 -99.747564)
			(xy 274.315194 -99.797065) (xy 274.263062 -99.840809) (xy 274.206204 -99.878205) (xy 274.145389 -99.908747)
			(xy 274.081439 -99.932023) (xy 274.01522 -99.947717) (xy 273.947627 -99.955617) (xy 273.9136 -99.956112)
			(xy 273.880578 -99.955665) (xy 273.814957 -99.948213) (xy 273.750593 -99.933417) (xy 273.688305 -99.911463)
			(xy 273.628887 -99.882632) (xy 273.573096 -99.847291) (xy 273.52164 -99.80589) (xy 273.475177 -99.758955)
			(xy 273.434297 -99.707085) (xy 273.416522 -99.679252) (xy 273.410172 -99.669346) (xy 273.391376 -99.6569)
			(xy 273.290284 -99.643692) (xy 273.268948 -99.65055) (xy 273.260566 -99.658678) (xy 273.239217 -99.678016)
			(xy 273.191776 -99.710686) (xy 273.139963 -99.735849) (xy 273.084954 -99.752934) (xy 273.028001 -99.761552)
			(xy 272.9992 -99.762056) (xy 272.971951 -99.761522) (xy 272.918007 -99.753767) (xy 272.865716 -99.738414)
			(xy 272.816142 -99.715777) (xy 272.770294 -99.686315) (xy 272.729105 -99.650629) (xy 272.693414 -99.609444)
			(xy 272.663946 -99.5636) (xy 272.641302 -99.514029) (xy 272.625943 -99.46174) (xy 272.618181 -99.407797)
			(xy 272.617692 -99.380548) (xy 272.618139 -99.354503) (xy 272.625211 -99.302894) (xy 272.63923 -99.252726)
			(xy 272.659937 -99.204927) (xy 272.673064 -99.182428) (xy 272.678906 -99.172776) (xy 272.681446 -99.151186)
			(xy 272.651474 -99.056952) (xy 272.636996 -99.04095) (xy 272.626836 -99.036378) (xy 272.595842 -99.022444)
			(xy 272.537035 -98.988386) (xy 272.482572 -98.94774) (xy 272.43319 -98.901054) (xy 272.389553 -98.848957)
			(xy 272.352251 -98.792153) (xy 272.321786 -98.731406) (xy 272.298569 -98.667538) (xy 272.282914 -98.601408)
			(xy 272.275032 -98.533909) (xy 272.274538 -98.49993) (xy 268.706762 -98.49993) (xy 268.720481 -98.52197)
			(xy 268.748529 -98.580717) (xy 268.769876 -98.642217) (xy 268.784257 -98.705707) (xy 268.791496 -98.770403)
			(xy 268.791944 -98.802952) (xy 268.791449 -98.836979) (xy 268.783549 -98.904572) (xy 268.767855 -98.97079)
			(xy 268.759976 -98.992436) (xy 271.10004 -98.992436) (xy 271.104111 -98.936814) (xy 271.116237 -98.882377)
			(xy 271.13616 -98.830286) (xy 271.163456 -98.781651) (xy 271.197542 -98.737508) (xy 271.237691 -98.698799)
			(xy 271.283049 -98.666348) (xy 271.332649 -98.640847) (xy 271.385433 -98.62284) (xy 271.440276 -98.61271)
			(xy 271.49601 -98.610673) (xy 271.551447 -98.616773) (xy 271.605404 -98.630879) (xy 271.656733 -98.652691)
			(xy 271.704339 -98.681745) (xy 271.747207 -98.71742) (xy 271.784424 -98.758957) (xy 271.815197 -98.80547)
			(xy 271.838869 -98.855967) (xy 271.854937 -98.909374) (xy 271.863057 -98.96455) (xy 271.863566 -98.992436)
			(xy 271.863057 -99.020322) (xy 271.854937 -99.075498) (xy 271.838869 -99.128905) (xy 271.815197 -99.179402)
			(xy 271.784424 -99.225915) (xy 271.747207 -99.267452) (xy 271.704339 -99.303127) (xy 271.656733 -99.332181)
			(xy 271.605404 -99.353993) (xy 271.551447 -99.368099) (xy 271.49601 -99.374199) (xy 271.440276 -99.372162)
			(xy 271.385433 -99.362032) (xy 271.332649 -99.344025) (xy 271.283049 -99.318524) (xy 271.237691 -99.286073)
			(xy 271.197542 -99.247364) (xy 271.163456 -99.203221) (xy 271.13616 -99.154586) (xy 271.116237 -99.102495)
			(xy 271.104111 -99.048058) (xy 271.10004 -98.992436) (xy 268.759976 -98.992436) (xy 268.744579 -99.034739)
			(xy 268.714037 -99.095554) (xy 268.676641 -99.152411) (xy 268.632898 -99.204543) (xy 268.583398 -99.251244)
			(xy 268.528811 -99.291882) (xy 268.469875 -99.325909) (xy 268.407387 -99.352863) (xy 268.342193 -99.372381)
			(xy 268.275174 -99.384199) (xy 268.207236 -99.388156) (xy 268.139298 -99.384199) (xy 268.072279 -99.372381)
			(xy 268.007085 -99.352863) (xy 267.944597 -99.325909) (xy 267.885661 -99.291882) (xy 267.831074 -99.251244)
			(xy 267.781574 -99.204543) (xy 267.737831 -99.152411) (xy 267.700435 -99.095554) (xy 267.669893 -99.034739)
			(xy 267.646617 -98.97079) (xy 267.630923 -98.904572) (xy 267.623023 -98.836979) (xy 267.622528 -98.802952)
			(xy 251.895864 -98.802952) (xy 251.895864 -99.3775) (xy 251.89544 -99.387569) (xy 251.887722 -99.406171)
			(xy 251.880878 -99.413568) (xy 251.064565 -100.229881) (xy 253.319274 -100.229881) (xy 253.319274 -100.165959)
			(xy 253.327285 -100.102541) (xy 253.343182 -100.040627) (xy 253.366714 -99.981194) (xy 253.397508 -99.925179)
			(xy 253.435081 -99.873464) (xy 253.478838 -99.826867) (xy 253.528091 -99.786122) (xy 253.582062 -99.751871)
			(xy 253.639901 -99.724654) (xy 253.700694 -99.704901) (xy 253.763484 -99.692923) (xy 253.82728 -99.68891)
			(xy 253.891076 -99.692923) (xy 253.953866 -99.704901) (xy 254.014659 -99.724654) (xy 254.072498 -99.751871)
			(xy 254.126469 -99.786122) (xy 254.175722 -99.826867) (xy 254.219479 -99.873464) (xy 254.257052 -99.925179)
			(xy 254.287846 -99.981194) (xy 254.311378 -100.040627) (xy 254.327275 -100.102541) (xy 254.335286 -100.165959)
			(xy 254.335788 -100.19792) (xy 254.335286 -100.229881) (xy 254.327275 -100.293299) (xy 254.311378 -100.355213)
			(xy 254.287846 -100.414646) (xy 254.257052 -100.470661) (xy 254.219479 -100.522376) (xy 254.175722 -100.568973)
			(xy 254.126469 -100.609718) (xy 254.084582 -100.6363) (xy 255.208792 -100.6363) (xy 255.212806 -100.572504)
			(xy 255.224784 -100.509715) (xy 255.244537 -100.448921) (xy 255.271754 -100.391083) (xy 255.306005 -100.337112)
			(xy 255.34675 -100.28786) (xy 255.393347 -100.244102) (xy 255.445061 -100.20653) (xy 255.501076 -100.175736)
			(xy 255.56051 -100.152205) (xy 255.622423 -100.136308) (xy 255.685841 -100.128297) (xy 255.717802 -100.127816)
			(xy 255.74766 -100.12821) (xy 255.806965 -100.135208) (xy 255.865041 -100.149109) (xy 255.921088 -100.16972)
			(xy 255.974332 -100.196758) (xy 256.024042 -100.229849) (xy 256.06953 -100.268538) (xy 256.090166 -100.290122)
			(xy 256.096516 -100.29698) (xy 256.112772 -100.305108) (xy 256.197862 -100.313998) (xy 256.215388 -100.309426)
			(xy 256.223262 -100.303838) (xy 256.247514 -100.28742) (xy 256.299986 -100.261414) (xy 256.355815 -100.243728)
			(xy 256.41369 -100.234777) (xy 256.442972 -100.234242) (xy 256.47023 -100.234603) (xy 256.524191 -100.242358)
			(xy 256.576499 -100.257713) (xy 256.626089 -100.280357) (xy 256.671952 -100.309828) (xy 256.713153 -100.345527)
			(xy 256.748855 -100.386726) (xy 256.778329 -100.432586) (xy 256.800977 -100.482175) (xy 256.816336 -100.534482)
			(xy 256.824095 -100.588442) (xy 256.824095 -100.642958) (xy 256.816336 -100.696918) (xy 256.800977 -100.749225)
			(xy 256.778329 -100.798814) (xy 256.748855 -100.844674) (xy 256.713153 -100.885873) (xy 256.671952 -100.921572)
			(xy 256.626089 -100.951043) (xy 256.576499 -100.973687) (xy 256.524191 -100.989042) (xy 256.47023 -100.996797)
			(xy 256.442972 -100.997258) (xy 256.4164 -100.996777) (xy 256.36377 -100.98941) (xy 256.312672 -100.974808)
			(xy 256.264096 -100.953254) (xy 256.241296 -100.9396) (xy 256.233168 -100.93452) (xy 256.215388 -100.930964)
			(xy 256.13106 -100.94468) (xy 256.115312 -100.95357) (xy 256.109216 -100.960936) (xy 256.088464 -100.98519)
			(xy 256.048749 -101.022404) (xy 260.660388 -101.022404) (xy 260.660825 -100.995572) (xy 260.668318 -100.942434)
			(xy 260.683186 -100.890872) (xy 260.705134 -100.841902) (xy 260.73373 -100.796492) (xy 260.768408 -100.755539)
			(xy 260.808485 -100.719851) (xy 260.853168 -100.690133) (xy 260.901575 -100.666971) (xy 260.952751 -100.650822)
			(xy 261.005685 -100.642007) (xy 261.032498 -100.640896) (xy 261.046722 -100.640642) (xy 261.070598 -100.625402)
			(xy 261.122668 -100.518214) (xy 261.119874 -100.490274) (xy 261.111238 -100.47859) (xy 261.092106 -100.452148)
			(xy 261.060064 -100.395287) (xy 261.03556 -100.334794) (xy 261.018997 -100.271663) (xy 261.010647 -100.206932)
			(xy 261.010146 -100.174298) (xy 261.010573 -100.143172) (xy 261.018192 -100.081386) (xy 261.03329 -100.020992)
			(xy 261.055642 -99.96289) (xy 261.084916 -99.907948) (xy 261.120672 -99.856988) (xy 261.162378 -99.81077)
			(xy 261.20941 -99.769984) (xy 261.261065 -99.735241) (xy 261.316574 -99.707057) (xy 261.34568 -99.696016)
			(xy 261.35584 -99.69246) (xy 261.37108 -99.677982) (xy 261.408672 -99.590352) (xy 261.408418 -99.56927)
			(xy 261.4041 -99.559618) (xy 261.393892 -99.5353) (xy 261.379505 -99.48456) (xy 261.372267 -99.432318)
			(xy 261.371842 -99.405948) (xy 261.372328 -99.378697) (xy 261.380084 -99.324749) (xy 261.395439 -99.272454)
			(xy 261.418081 -99.222877) (xy 261.447547 -99.177027) (xy 261.483238 -99.135836) (xy 261.524429 -99.100145)
			(xy 261.570279 -99.070679) (xy 261.619856 -99.048037) (xy 261.672151 -99.032682) (xy 261.726099 -99.024926)
			(xy 261.780601 -99.024926) (xy 261.834549 -99.032682) (xy 261.886844 -99.048037) (xy 261.936421 -99.070679)
			(xy 261.982271 -99.100145) (xy 262.023462 -99.135836) (xy 262.059153 -99.177027) (xy 262.088619 -99.222877)
			(xy 262.111261 -99.272454) (xy 262.126616 -99.324749) (xy 262.134372 -99.378697) (xy 262.134858 -99.405948)
			(xy 262.13437 -99.433417) (xy 262.126496 -99.487789) (xy 262.110903 -99.540468) (xy 262.087914 -99.590365)
			(xy 262.058004 -99.636448) (xy 262.021793 -99.677764) (xy 261.980029 -99.713457) (xy 261.957058 -99.728528)
			(xy 261.948168 -99.734116) (xy 261.93623 -99.751642) (xy 261.91845 -99.845368) (xy 261.923022 -99.865688)
			(xy 261.929372 -99.874324) (xy 261.947891 -99.900539) (xy 261.978926 -99.956723) (xy 262.002635 -100.016369)
			(xy 262.018642 -100.078526) (xy 262.02669 -100.142205) (xy 262.027162 -100.174298) (xy 262.02676 -100.205032)
			(xy 262.019351 -100.266051) (xy 262.00464 -100.325733) (xy 261.984237 -100.37953) (xy 274.848064 -100.37953)
			(xy 274.852135 -100.323908) (xy 274.864261 -100.269471) (xy 274.884184 -100.21738) (xy 274.91148 -100.168745)
			(xy 274.945566 -100.124602) (xy 274.985715 -100.085893) (xy 275.031073 -100.053442) (xy 275.080673 -100.027941)
			(xy 275.133457 -100.009934) (xy 275.1883 -99.999804) (xy 275.244034 -99.997767) (xy 275.299471 -100.003867)
			(xy 275.353428 -100.017973) (xy 275.404757 -100.039785) (xy 275.452363 -100.068839) (xy 275.495231 -100.104514)
			(xy 275.532448 -100.146051) (xy 275.563221 -100.192564) (xy 275.586893 -100.243061) (xy 275.602961 -100.296468)
			(xy 275.611081 -100.351644) (xy 275.61159 -100.37953) (xy 275.611081 -100.407416) (xy 275.60898 -100.421694)
			(xy 279.51125 -100.421694) (xy 279.515321 -100.366072) (xy 279.527447 -100.311635) (xy 279.54737 -100.259544)
			(xy 279.574666 -100.210909) (xy 279.608752 -100.166766) (xy 279.648901 -100.128057) (xy 279.694259 -100.095606)
			(xy 279.743859 -100.070105) (xy 279.796643 -100.052098) (xy 279.851486 -100.041968) (xy 279.90722 -100.039931)
			(xy 279.962657 -100.046031) (xy 280.016614 -100.060137) (xy 280.067943 -100.081949) (xy 280.115549 -100.111003)
			(xy 280.158417 -100.146678) (xy 280.195634 -100.188215) (xy 280.226407 -100.234728) (xy 280.250079 -100.285225)
			(xy 280.266147 -100.338632) (xy 280.274267 -100.393808) (xy 280.274776 -100.421694) (xy 280.274267 -100.44958)
			(xy 280.266147 -100.504756) (xy 280.250079 -100.558163) (xy 280.226407 -100.60866) (xy 280.195634 -100.655173)
			(xy 280.158417 -100.69671) (xy 280.115549 -100.732385) (xy 280.067943 -100.761439) (xy 280.016614 -100.783251)
			(xy 279.962657 -100.797357) (xy 279.90722 -100.803457) (xy 279.851486 -100.80142) (xy 279.796643 -100.79129)
			(xy 279.743859 -100.773283) (xy 279.694259 -100.747782) (xy 279.648901 -100.715331) (xy 279.608752 -100.676622)
			(xy 279.574666 -100.632479) (xy 279.54737 -100.583844) (xy 279.527447 -100.531753) (xy 279.515321 -100.477316)
			(xy 279.51125 -100.421694) (xy 275.60898 -100.421694) (xy 275.602961 -100.462592) (xy 275.586893 -100.515999)
			(xy 275.563221 -100.566496) (xy 275.532448 -100.613009) (xy 275.495231 -100.654546) (xy 275.452363 -100.690221)
			(xy 275.404757 -100.719275) (xy 275.353428 -100.741087) (xy 275.299471 -100.755193) (xy 275.244034 -100.761293)
			(xy 275.1883 -100.759256) (xy 275.133457 -100.749126) (xy 275.080673 -100.731119) (xy 275.031073 -100.705618)
			(xy 274.985715 -100.673167) (xy 274.945566 -100.634458) (xy 274.91148 -100.590315) (xy 274.884184 -100.54168)
			(xy 274.864261 -100.489589) (xy 274.852135 -100.435152) (xy 274.848064 -100.37953) (xy 261.984237 -100.37953)
			(xy 261.982843 -100.383206) (xy 261.954276 -100.437632) (xy 261.919356 -100.488218) (xy 261.878594 -100.534225)
			(xy 261.832583 -100.574984) (xy 261.781994 -100.609898) (xy 261.727565 -100.638461) (xy 261.670091 -100.660253)
			(xy 261.610408 -100.674959) (xy 261.549388 -100.682363) (xy 261.518654 -100.682806) (xy 261.50657 -100.682743)
			(xy 261.48243 -100.681598) (xy 261.470394 -100.68052) (xy 261.455916 -100.67925) (xy 261.43077 -100.691442)
			(xy 261.366254 -100.791518) (xy 261.365492 -100.819712) (xy 261.372604 -100.832158) (xy 261.384659 -100.853954)
			(xy 261.403666 -100.899993) (xy 261.416519 -100.948115) (xy 261.423001 -100.9975) (xy 261.423404 -101.022404)
			(xy 261.422918 -101.049655) (xy 261.415162 -101.103603) (xy 261.399807 -101.155898) (xy 261.377165 -101.205475)
			(xy 261.347699 -101.251325) (xy 261.312008 -101.292516) (xy 261.270817 -101.328207) (xy 261.224967 -101.357673)
			(xy 261.17539 -101.380315) (xy 261.123095 -101.39567) (xy 261.069147 -101.403426) (xy 261.014645 -101.403426)
			(xy 260.960697 -101.39567) (xy 260.908402 -101.380315) (xy 260.858825 -101.357673) (xy 260.812975 -101.328207)
			(xy 260.771784 -101.292516) (xy 260.736093 -101.251325) (xy 260.706627 -101.205475) (xy 260.683985 -101.155898)
			(xy 260.66863 -101.103603) (xy 260.660874 -101.049655) (xy 260.660388 -101.022404) (xy 256.048749 -101.022404)
			(xy 256.041884 -101.028837) (xy 255.990208 -101.066312) (xy 255.934248 -101.097024) (xy 255.874884 -101.120491)
			(xy 255.813051 -101.136343) (xy 255.749719 -101.144333) (xy 255.717802 -101.144832) (xy 255.685841 -101.144303)
			(xy 255.622423 -101.136292) (xy 255.56051 -101.120395) (xy 255.501076 -101.096864) (xy 255.445061 -101.06607)
			(xy 255.393347 -101.028498) (xy 255.34675 -100.98474) (xy 255.306005 -100.935488) (xy 255.271754 -100.881517)
			(xy 255.244537 -100.823679) (xy 255.224784 -100.762885) (xy 255.212806 -100.700096) (xy 255.208792 -100.6363)
			(xy 254.084582 -100.6363) (xy 254.072498 -100.643969) (xy 254.014659 -100.671186) (xy 253.953866 -100.690939)
			(xy 253.891076 -100.702917) (xy 253.82728 -100.706931) (xy 253.763484 -100.702917) (xy 253.700694 -100.690939)
			(xy 253.639901 -100.671186) (xy 253.582062 -100.643969) (xy 253.528091 -100.609718) (xy 253.478838 -100.568973)
			(xy 253.435081 -100.522376) (xy 253.397508 -100.470661) (xy 253.366714 -100.414646) (xy 253.343182 -100.355213)
			(xy 253.327285 -100.293299) (xy 253.319274 -100.229881) (xy 251.064565 -100.229881) (xy 249.84202 -101.452426)
			(xy 249.834654 -101.459538) (xy 249.827034 -101.478334) (xy 249.827034 -102.413299) (xy 274.463751 -102.413299)
			(xy 274.463751 -102.345245) (xy 274.471651 -102.277652) (xy 274.487345 -102.211434) (xy 274.510621 -102.147485)
			(xy 274.541163 -102.08667) (xy 274.578559 -102.029813) (xy 274.622302 -101.977681) (xy 274.671802 -101.93098)
			(xy 274.726389 -101.890342) (xy 274.785325 -101.856315) (xy 274.847813 -101.829361) (xy 274.913007 -101.809843)
			(xy 274.980026 -101.798025) (xy 275.047964 -101.794069) (xy 275.115902 -101.798025) (xy 275.182921 -101.809843)
			(xy 275.248115 -101.829361) (xy 275.310603 -101.856315) (xy 275.369539 -101.890342) (xy 275.424126 -101.93098)
			(xy 275.473626 -101.977681) (xy 275.517369 -102.029813) (xy 275.554765 -102.08667) (xy 275.585307 -102.147485)
			(xy 275.608583 -102.211434) (xy 275.624277 -102.277652) (xy 275.632177 -102.345245) (xy 275.632672 -102.379272)
			(xy 275.632177 -102.413299) (xy 275.624277 -102.480892) (xy 275.608583 -102.54711) (xy 275.585307 -102.611059)
			(xy 275.554765 -102.671874) (xy 275.517369 -102.728731) (xy 275.473626 -102.780863) (xy 275.424126 -102.827564)
			(xy 275.369539 -102.868202) (xy 275.310603 -102.902229) (xy 275.248115 -102.929183) (xy 275.182921 -102.948701)
			(xy 275.115902 -102.960519) (xy 275.047964 -102.964476) (xy 274.980026 -102.960519) (xy 274.913007 -102.948701)
			(xy 274.847813 -102.929183) (xy 274.785325 -102.902229) (xy 274.726389 -102.868202) (xy 274.671802 -102.827564)
			(xy 274.622302 -102.780863) (xy 274.578559 -102.728731) (xy 274.541163 -102.671874) (xy 274.510621 -102.611059)
			(xy 274.487345 -102.54711) (xy 274.471651 -102.480892) (xy 274.463751 -102.413299) (xy 249.827034 -102.413299)
			(xy 249.827034 -102.85095) (xy 259.059932 -102.85095) (xy 259.064003 -102.795328) (xy 259.076129 -102.740891)
			(xy 259.096052 -102.6888) (xy 259.123348 -102.640165) (xy 259.157434 -102.596022) (xy 259.197583 -102.557313)
			(xy 259.242941 -102.524862) (xy 259.292541 -102.499361) (xy 259.345325 -102.481354) (xy 259.400168 -102.471224)
			(xy 259.455902 -102.469187) (xy 259.511339 -102.475287) (xy 259.565296 -102.489393) (xy 259.616625 -102.511205)
			(xy 259.664231 -102.540259) (xy 259.707099 -102.575934) (xy 259.744316 -102.617471) (xy 259.775089 -102.663984)
			(xy 259.798761 -102.714481) (xy 259.814829 -102.767888) (xy 259.822949 -102.823064) (xy 259.823458 -102.85095)
			(xy 259.822949 -102.878836) (xy 259.814829 -102.934012) (xy 259.798761 -102.987419) (xy 259.775089 -103.037916)
			(xy 259.744316 -103.084429) (xy 259.707099 -103.125966) (xy 259.664231 -103.161641) (xy 259.616625 -103.190695)
			(xy 259.565296 -103.212507) (xy 259.511339 -103.226613) (xy 259.455902 -103.232713) (xy 259.400168 -103.230676)
			(xy 259.345325 -103.220546) (xy 259.292541 -103.202539) (xy 259.242941 -103.177038) (xy 259.197583 -103.144587)
			(xy 259.157434 -103.105878) (xy 259.123348 -103.061735) (xy 259.096052 -103.0131) (xy 259.076129 -102.961009)
			(xy 259.064003 -102.906572) (xy 259.059932 -102.85095) (xy 249.827034 -102.85095) (xy 249.827034 -103.272844)
			(xy 264.004296 -103.272844) (xy 264.008367 -103.217222) (xy 264.020493 -103.162785) (xy 264.040416 -103.110694)
			(xy 264.067712 -103.062059) (xy 264.101798 -103.017916) (xy 264.141947 -102.979207) (xy 264.187305 -102.946756)
			(xy 264.236905 -102.921255) (xy 264.289689 -102.903248) (xy 264.344532 -102.893118) (xy 264.400266 -102.891081)
			(xy 264.455703 -102.897181) (xy 264.50966 -102.911287) (xy 264.560989 -102.933099) (xy 264.608595 -102.962153)
			(xy 264.651463 -102.997828) (xy 264.68868 -103.039365) (xy 264.719453 -103.085878) (xy 264.743125 -103.136375)
			(xy 264.759193 -103.189782) (xy 264.767313 -103.244958) (xy 264.767822 -103.272844) (xy 264.767313 -103.30073)
			(xy 264.767087 -103.302265) (xy 266.828264 -103.302265) (xy 266.828264 -103.238343) (xy 266.836275 -103.174925)
			(xy 266.852172 -103.113011) (xy 266.875704 -103.053578) (xy 266.906498 -102.997563) (xy 266.944071 -102.945848)
			(xy 266.987828 -102.899251) (xy 267.037081 -102.858506) (xy 267.091052 -102.824255) (xy 267.148891 -102.797038)
			(xy 267.209684 -102.777285) (xy 267.272474 -102.765307) (xy 267.33627 -102.761294) (xy 267.400066 -102.765307)
			(xy 267.462856 -102.777285) (xy 267.523649 -102.797038) (xy 267.581488 -102.824255) (xy 267.635459 -102.858506)
			(xy 267.684712 -102.899251) (xy 267.728469 -102.945848) (xy 267.766042 -102.997563) (xy 267.796836 -103.053578)
			(xy 267.820368 -103.113011) (xy 267.836265 -103.174925) (xy 267.844276 -103.238343) (xy 267.844714 -103.26624)
			(xy 269.227806 -103.26624) (xy 269.231877 -103.210618) (xy 269.244003 -103.156181) (xy 269.263926 -103.10409)
			(xy 269.291222 -103.055455) (xy 269.325308 -103.011312) (xy 269.365457 -102.972603) (xy 269.410815 -102.940152)
			(xy 269.460415 -102.914651) (xy 269.513199 -102.896644) (xy 269.568042 -102.886514) (xy 269.623776 -102.884477)
			(xy 269.679213 -102.890577) (xy 269.73317 -102.904683) (xy 269.784499 -102.926495) (xy 269.832105 -102.955549)
			(xy 269.874973 -102.991224) (xy 269.91219 -103.032761) (xy 269.942963 -103.079274) (xy 269.966635 -103.129771)
			(xy 269.982703 -103.183178) (xy 269.990823 -103.238354) (xy 269.991332 -103.26624) (xy 269.990823 -103.294126)
			(xy 269.982703 -103.349302) (xy 269.966635 -103.402709) (xy 269.942963 -103.453206) (xy 269.91219 -103.499719)
			(xy 269.874973 -103.541256) (xy 269.832105 -103.576931) (xy 269.784499 -103.605985) (xy 269.73317 -103.627797)
			(xy 269.679213 -103.641903) (xy 269.623776 -103.648003) (xy 269.568042 -103.645966) (xy 269.513199 -103.635836)
			(xy 269.460415 -103.617829) (xy 269.410815 -103.592328) (xy 269.365457 -103.559877) (xy 269.325308 -103.521168)
			(xy 269.291222 -103.477025) (xy 269.263926 -103.42839) (xy 269.244003 -103.376299) (xy 269.231877 -103.321862)
			(xy 269.227806 -103.26624) (xy 267.844714 -103.26624) (xy 267.844778 -103.270304) (xy 267.844276 -103.302265)
			(xy 267.836265 -103.365683) (xy 267.820368 -103.427597) (xy 267.796836 -103.48703) (xy 267.766042 -103.543045)
			(xy 267.728469 -103.59476) (xy 267.684712 -103.641357) (xy 267.635459 -103.682102) (xy 267.581488 -103.716353)
			(xy 267.523649 -103.74357) (xy 267.462856 -103.763323) (xy 267.400066 -103.775301) (xy 267.33627 -103.779315)
			(xy 267.272474 -103.775301) (xy 267.209684 -103.763323) (xy 267.148891 -103.74357) (xy 267.091052 -103.716353)
			(xy 267.037081 -103.682102) (xy 266.987828 -103.641357) (xy 266.944071 -103.59476) (xy 266.906498 -103.543045)
			(xy 266.875704 -103.48703) (xy 266.852172 -103.427597) (xy 266.836275 -103.365683) (xy 266.828264 -103.302265)
			(xy 264.767087 -103.302265) (xy 264.759193 -103.355906) (xy 264.743125 -103.409313) (xy 264.719453 -103.45981)
			(xy 264.68868 -103.506323) (xy 264.651463 -103.54786) (xy 264.608595 -103.583535) (xy 264.560989 -103.612589)
			(xy 264.50966 -103.634401) (xy 264.455703 -103.648507) (xy 264.400266 -103.654607) (xy 264.344532 -103.65257)
			(xy 264.289689 -103.64244) (xy 264.236905 -103.624433) (xy 264.187305 -103.598932) (xy 264.141947 -103.566481)
			(xy 264.101798 -103.527772) (xy 264.067712 -103.483629) (xy 264.040416 -103.434994) (xy 264.020493 -103.382903)
			(xy 264.008367 -103.328466) (xy 264.004296 -103.272844) (xy 249.827034 -103.272844) (xy 249.827034 -104.236266)
			(xy 249.827501 -104.246141) (xy 249.834949 -104.264433) (xy 249.841512 -104.271826) (xy 249.841766 -104.27208)
			(xy 250.13031 -104.560624) (xy 250.130818 -104.561132) (xy 250.138196 -104.567722) (xy 250.156496 -104.575188)
			(xy 250.166378 -104.57561)
		)
		(stroke
			(width 0)
			(type solid)
		)
		(fill yes)
		(layer "B.Cu")
		(net "PVDD18_S5_P0")
	)
	(gr_poly
		(pts
			(xy 315.807344 -402.843238) (xy 315.814588 -402.84161) (xy 315.827756 -402.834767) (xy 315.833252 -402.829776)
			(xy 315.911484 -402.751544) (xy 315.917913 -402.744544) (xy 315.925519 -402.727142) (xy 315.92629 -402.708166)
			(xy 315.920123 -402.690204) (xy 315.914278 -402.68271) (xy 315.910976 -402.679408) (xy 315.906689 -402.675389)
			(xy 315.896683 -402.669234) (xy 315.891164 -402.667216) (xy 315.880496 -402.66366) (xy 315.8744 -402.664676)
			(xy 315.868304 -402.665438) (xy 315.855422 -402.667203) (xy 315.829489 -402.669108) (xy 315.816488 -402.669248)
			(xy 315.816234 -402.669248) (xy 315.790573 -402.668772) (xy 315.739777 -402.661434) (xy 315.690541 -402.646946)
			(xy 315.643866 -402.625602) (xy 315.600702 -402.597835) (xy 315.561927 -402.564212) (xy 315.528328 -402.525415)
			(xy 315.500589 -402.482234) (xy 315.479274 -402.435545) (xy 315.464817 -402.3863) (xy 315.457512 -402.3355)
			(xy 315.457078 -402.309838) (xy 315.457649 -402.281278) (xy 315.466724 -402.224884) (xy 315.484605 -402.170634)
			(xy 315.510841 -402.119896) (xy 315.544772 -402.073946) (xy 315.564774 -402.053552) (xy 315.571886 -402.04644)
			(xy 315.575696 -402.037296) (xy 315.577615 -402.032695) (xy 315.579799 -402.022972) (xy 315.580014 -402.017992)
			(xy 315.580268 -401.998942) (xy 315.579912 -401.987998) (xy 315.571086 -401.967983) (xy 315.56325 -401.960334)
			(xy 315.543446 -401.942141) (xy 315.508637 -401.901151) (xy 315.479926 -401.855681) (xy 315.457882 -401.80663)
			(xy 315.442943 -401.754971) (xy 315.435403 -401.701726) (xy 315.43498 -401.674838) (xy 315.43498 -400.810984)
			(xy 315.435479 -400.782913) (xy 315.443711 -400.727379) (xy 315.459995 -400.673651) (xy 315.483978 -400.62289)
			(xy 315.515143 -400.576194) (xy 315.552817 -400.53457) (xy 315.574172 -400.516344) (xy 315.582808 -400.509486)
			(xy 315.59246 -400.489928) (xy 315.592714 -400.478752) (xy 315.593222 -400.461226) (xy 315.593209 -400.456357)
			(xy 315.591548 -400.446765) (xy 315.58992 -400.442176) (xy 315.586872 -400.43354) (xy 315.580014 -400.42592)
			(xy 315.564702 -400.40831) (xy 315.538867 -400.369448) (xy 315.518984 -400.327231) (xy 315.505478 -400.282562)
			(xy 315.49864 -400.2364) (xy 315.498226 -400.213068) (xy 315.498226 -400.212814) (xy 315.49869 -400.187823)
			(xy 315.506507 -400.138456) (xy 315.521952 -400.090921) (xy 315.544643 -400.046387) (xy 315.574022 -400.005951)
			(xy 315.609366 -399.970609) (xy 315.649804 -399.941233) (xy 315.694339 -399.918544) (xy 315.741876 -399.903103)
			(xy 315.791243 -399.895288) (xy 315.816234 -399.894806) (xy 315.816234 -399.894552) (xy 315.838118 -399.894949)
			(xy 315.881464 -399.901023) (xy 315.923563 -399.912997) (xy 315.943742 -399.921476) (xy 315.943996 -399.921476)
			(xy 315.949923 -399.923843) (xy 315.962515 -399.925893) (xy 315.968888 -399.92554) (xy 315.980826 -399.924524)
			(xy 316.0649 -399.86966) (xy 316.074277 -399.862045) (xy 316.085265 -399.840571) (xy 316.085982 -399.828512)
			(xy 316.085982 -398.248886) (xy 316.086285 -398.241629) (xy 316.09042 -398.227711) (xy 316.09411 -398.221454)
			(xy 316.098174 -398.215358) (xy 316.102238 -398.201388) (xy 316.102238 -398.19072) (xy 316.101799 -398.180658)
			(xy 316.094057 -398.16208) (xy 316.087252 -398.154652) (xy 316.08014 -398.14754) (xy 316.070742 -398.14373)
			(xy 316.047876 -398.133862) (xy 316.005281 -398.108062) (xy 315.96723 -398.075935) (xy 315.934655 -398.038268)
			(xy 315.908353 -397.995981) (xy 315.888967 -397.950109) (xy 315.882528 -397.926052) (xy 315.88202 -397.924274)
			(xy 315.566298 -397.378174) (xy 315.562234 -397.373856) (xy 315.546043 -397.356148) (xy 315.518666 -397.316746)
			(xy 315.497574 -397.27365) (xy 315.483255 -397.227857) (xy 315.476041 -397.180422) (xy 315.47562 -397.156432)
			(xy 315.475795 -397.142383) (xy 315.478335 -397.114401) (xy 315.4807 -397.100552) (xy 315.481912 -397.091276)
			(xy 315.478383 -397.072919) (xy 315.473842 -397.064738) (xy 315.457078 -397.037814) (xy 315.45187 -397.030116)
			(xy 315.437146 -397.018797) (xy 315.428376 -397.015716) (xy 315.406745 -397.008924) (xy 315.36552 -396.99006)
			(xy 315.327397 -396.965524) (xy 315.293151 -396.935815) (xy 315.278008 -396.918942) (xy 315.275527 -396.916188)
			(xy 315.269922 -396.911337) (xy 315.266832 -396.90929) (xy 315.254767 -396.901234) (xy 315.234812 -396.880189)
			(xy 315.220739 -396.85483) (xy 315.213439 -396.826762) (xy 315.212984 -396.812262) (xy 315.212984 -396.800324)
			(xy 315.21146 -396.79372) (xy 315.206266 -396.773348) (xy 315.200666 -396.731682) (xy 315.200284 -396.710662)
			(xy 315.200658 -396.689642) (xy 315.206268 -396.647976) (xy 315.21146 -396.627604) (xy 315.212984 -396.621)
			(xy 315.212984 -396.507462) (xy 315.213476 -396.492471) (xy 315.221235 -396.463511) (xy 315.236215 -396.43754)
			(xy 315.257399 -396.416324) (xy 315.283346 -396.401303) (xy 315.312294 -396.3935) (xy 315.327284 -396.392908)
			(xy 315.509402 -396.392908) (xy 315.50991 -396.392654) (xy 315.526674 -396.392654) (xy 315.527182 -396.392908)
			(xy 315.68898 -396.392908) (xy 315.699005 -396.392492) (xy 315.71753 -396.384826) (xy 315.73171 -396.370653)
			(xy 315.739386 -396.352132) (xy 315.73978 -396.342108) (xy 315.73978 -395.388592) (xy 315.739355 -395.378523)
			(xy 315.731636 -395.359922) (xy 315.724794 -395.352524) (xy 315.650626 -395.278356) (xy 315.643226 -395.271515)
			(xy 315.624627 -395.263799) (xy 315.614558 -395.26337) (xy 315.04001 -395.26337) (xy 315.034002 -395.263542)
			(xy 315.022323 -395.266372) (xy 315.016896 -395.268958) (xy 315.013423 -395.270799) (xy 315.007046 -395.275395)
			(xy 315.004196 -395.278102) (xy 314.730638 -395.55166) (xy 314.72793 -395.55451) (xy 314.723332 -395.560886)
			(xy 314.721494 -395.56436) (xy 314.718913 -395.569787) (xy 314.716093 -395.581467) (xy 314.715906 -395.587474)
			(xy 314.715906 -396.832328) (xy 314.716128 -396.839136) (xy 314.719743 -396.852263) (xy 314.723018 -396.858236)
			(xy 314.72632 -396.863824) (xy 314.736226 -396.873222) (xy 314.742576 -396.876778) (xy 314.765158 -396.889637)
			(xy 314.806184 -396.921529) (xy 314.841494 -396.959652) (xy 314.870155 -397.002997) (xy 314.891408 -397.050415)
			(xy 314.898532 -397.075406) (xy 314.903612 -397.087852) (xy 315.215778 -397.627602) (xy 315.219842 -397.63192)
			(xy 315.235998 -397.64959) (xy 315.263328 -397.688901) (xy 315.2844 -397.731892) (xy 315.298733 -397.777574)
			(xy 315.305995 -397.824897) (xy 315.306456 -397.848836) (xy 315.306456 -397.849344) (xy 315.305966 -397.874131)
			(xy 315.298205 -397.923094) (xy 315.28288 -397.97024) (xy 315.260369 -398.014408) (xy 315.231226 -398.054511)
			(xy 315.196169 -398.089562) (xy 315.15606 -398.118698) (xy 315.111888 -398.141201) (xy 315.064739 -398.156518)
			(xy 315.015775 -398.164271) (xy 314.990988 -398.164812) (xy 314.965595 -398.164303) (xy 314.915464 -398.156171)
			(xy 314.867281 -398.140119) (xy 314.822289 -398.116561) (xy 314.781649 -398.086103) (xy 314.746408 -398.049533)
			(xy 314.717477 -398.007793) (xy 314.6956 -397.96196) (xy 314.687966 -397.937736) (xy 314.686442 -397.931894)
			(xy 314.481718 -397.577564) (xy 314.475325 -397.567645) (xy 314.455734 -397.554541) (xy 314.444126 -397.552418)
			(xy 314.432442 -397.550894) (xy 314.410344 -397.558514) (xy 314.122308 -397.84655) (xy 314.11931 -397.849642)
			(xy 314.114338 -397.856673) (xy 314.112402 -397.86052) (xy 314.108592 -397.868648) (xy 314.10783 -397.877792)
			(xy 314.104951 -397.904018) (xy 314.091622 -397.955063) (xy 314.070054 -398.00321) (xy 314.040838 -398.047138)
			(xy 314.004776 -398.085645) (xy 313.984132 -398.102074) (xy 313.983878 -398.102328) (xy 313.979333 -398.105984)
			(xy 313.971882 -398.114957) (xy 313.969146 -398.120108) (xy 313.966606 -398.125188) (xy 313.964066 -398.136364)
			(xy 313.964066 -398.149064) (xy 314.003944 -398.185386) (xy 314.011281 -398.191538) (xy 314.02917 -398.198319)
			(xy 314.038742 -398.198594) (xy 314.041282 -398.198594) (xy 314.041536 -398.198848) (xy 314.340748 -398.198848)
			(xy 314.341002 -398.198594) (xy 314.358051 -398.198828) (xy 314.39174 -398.204066) (xy 314.408058 -398.209008)
			(xy 314.415678 -398.211548) (xy 314.445142 -398.211548) (xy 314.458505 -398.211987) (xy 314.484321 -398.2189)
			(xy 314.507475 -398.232247) (xy 314.526396 -398.251121) (xy 314.539801 -398.274242) (xy 314.546779 -398.300041)
			(xy 314.54725 -398.313402) (xy 314.54725 -398.35201) (xy 314.548774 -398.35836) (xy 314.551975 -398.371527)
			(xy 314.55542 -398.398405) (xy 314.555632 -398.411954) (xy 314.555632 -398.666716) (xy 314.54725 -398.666716)
			(xy 314.54725 -398.770602) (xy 314.546768 -398.785252) (xy 314.538456 -398.81335) (xy 314.522514 -398.837934)
			(xy 314.51169 -398.847818) (xy 314.511182 -398.848326) (xy 314.504578 -398.854168) (xy 314.495688 -398.87398)
			(xy 314.495688 -398.881092) (xy 314.49527 -398.891114) (xy 314.487601 -398.909631) (xy 314.473428 -398.923803)
			(xy 314.45491 -398.931471) (xy 314.444888 -398.931892) (xy 314.014866 -398.931892) (xy 314.004862 -398.932386)
			(xy 313.986381 -398.940051) (xy 313.972237 -398.954203) (xy 313.964581 -398.972688) (xy 313.964066 -398.982692)
			(xy 313.964066 -399.024602) (xy 315.009784 -399.024602) (xy 315.009784 -398.542002) (xy 315.01027 -398.514769)
			(xy 315.018021 -398.460857) (xy 315.033366 -398.408597) (xy 315.055992 -398.359053) (xy 315.085439 -398.313233)
			(xy 315.121106 -398.27207) (xy 315.162269 -398.236403) (xy 315.208089 -398.206956) (xy 315.257633 -398.18433)
			(xy 315.309893 -398.168985) (xy 315.363805 -398.161234) (xy 315.418271 -398.161234) (xy 315.472183 -398.168985)
			(xy 315.524443 -398.18433) (xy 315.573987 -398.206956) (xy 315.619807 -398.236403) (xy 315.66097 -398.27207)
			(xy 315.696637 -398.313233) (xy 315.726084 -398.359053) (xy 315.74871 -398.408597) (xy 315.764055 -398.460857)
			(xy 315.771806 -398.514769) (xy 315.772292 -398.542002) (xy 315.772292 -399.024602) (xy 315.771806 -399.051835)
			(xy 315.764055 -399.105747) (xy 315.74871 -399.158007) (xy 315.726084 -399.207551) (xy 315.696637 -399.253371)
			(xy 315.66097 -399.294534) (xy 315.619807 -399.330201) (xy 315.573987 -399.359648) (xy 315.524443 -399.382274)
			(xy 315.472183 -399.397619) (xy 315.418271 -399.40537) (xy 315.363805 -399.40537) (xy 315.309893 -399.397619)
			(xy 315.257633 -399.382274) (xy 315.208089 -399.359648) (xy 315.162269 -399.330201) (xy 315.121106 -399.294534)
			(xy 315.085439 -399.253371) (xy 315.055992 -399.207551) (xy 315.033366 -399.158007) (xy 315.018021 -399.105747)
			(xy 315.01027 -399.051835) (xy 315.009784 -399.024602) (xy 313.964066 -399.024602) (xy 313.964066 -399.827496)
			(xy 313.963643 -399.837566) (xy 313.955926 -399.856168) (xy 313.94908 -399.863564) (xy 313.831732 -399.980912)
			(xy 313.826909 -399.985465) (xy 313.81546 -399.992151) (xy 313.809126 -399.99412) (xy 313.801144 -399.996623)
			(xy 313.787279 -400.005961) (xy 313.781948 -400.012408) (xy 313.73445 -400.0754) (xy 313.730132 -400.081242)
			(xy 313.726718 -400.085972) (xy 313.721971 -400.096624) (xy 313.720734 -400.102324) (xy 313.718702 -400.113754)
			(xy 313.720988 -400.122136) (xy 313.72774 -400.146641) (xy 313.734251 -400.197049) (xy 313.733942 -400.222466)
			(xy 313.732529 -400.250382) (xy 313.721142 -400.305102) (xy 313.700381 -400.356995) (xy 313.670882 -400.404468)
			(xy 313.652662 -400.425666) (xy 313.645804 -400.433032) (xy 313.642502 -400.441922) (xy 313.640987 -400.446468)
			(xy 313.639455 -400.455926) (xy 313.639454 -400.460718) (xy 313.639962 -400.479514) (xy 313.639962 -400.480022)
			(xy 313.640216 -400.489928) (xy 313.649614 -400.508978) (xy 313.658504 -400.516344) (xy 313.679916 -400.534561)
			(xy 313.717675 -400.576207) (xy 313.748922 -400.622939) (xy 313.772981 -400.673745) (xy 313.789334 -400.72753)
			(xy 313.797627 -400.783131) (xy 313.798204 -400.811238) (xy 313.798204 -401.674838) (xy 314.234576 -401.674838)
			(xy 314.234576 -400.811238) (xy 314.23499 -400.785717) (xy 314.241781 -400.73513) (xy 314.255259 -400.685901)
			(xy 314.275184 -400.63891) (xy 314.3012 -400.594997) (xy 314.332841 -400.554947) (xy 314.350908 -400.536918)
			(xy 314.357512 -400.530568) (xy 314.365386 -400.513804) (xy 314.372244 -400.42846) (xy 314.367164 -400.41068)
			(xy 314.361576 -400.403314) (xy 314.346731 -400.382562) (xy 314.323093 -400.33735) (xy 314.30699 -400.28894)
			(xy 314.298836 -400.238577) (xy 314.29833 -400.213068) (xy 314.29833 -400.212814) (xy 314.29882 -400.187825)
			(xy 314.306639 -400.138462) (xy 314.322083 -400.09093) (xy 314.344773 -400.046398) (xy 314.374149 -400.005965)
			(xy 314.409489 -399.970625) (xy 314.449922 -399.941249) (xy 314.494454 -399.918559) (xy 314.541986 -399.903115)
			(xy 314.591349 -399.895296) (xy 314.641327 -399.895296) (xy 314.69069 -399.903115) (xy 314.738222 -399.918559)
			(xy 314.782754 -399.941249) (xy 314.823187 -399.970625) (xy 314.858527 -400.005965) (xy 314.887903 -400.046398)
			(xy 314.910593 -400.09093) (xy 314.926037 -400.138462) (xy 314.933856 -400.187825) (xy 314.934346 -400.212814)
			(xy 314.934346 -400.213068) (xy 314.933844 -400.238577) (xy 314.925668 -400.288935) (xy 314.909568 -400.337346)
			(xy 314.885956 -400.382572) (xy 314.8711 -400.403314) (xy 314.865512 -400.41068) (xy 314.860432 -400.42846)
			(xy 314.86729 -400.513804) (xy 314.875164 -400.530568) (xy 314.881768 -400.536918) (xy 314.899805 -400.554974)
			(xy 314.931435 -400.595026) (xy 314.957445 -400.638936) (xy 314.977372 -400.68592) (xy 314.990861 -400.735141)
			(xy 314.99767 -400.78572) (xy 314.9981 -400.811238) (xy 314.9981 -401.674838) (xy 314.99771 -401.700177)
			(xy 314.990996 -401.750409) (xy 314.97769 -401.79931) (xy 314.958028 -401.846019) (xy 314.932355 -401.889714)
			(xy 314.901123 -401.929625) (xy 314.883292 -401.947634) (xy 314.876434 -401.954492) (xy 314.868306 -401.972018)
			(xy 314.864496 -402.060664) (xy 314.870846 -402.078952) (xy 314.877196 -402.086318) (xy 314.892711 -402.105051)
			(xy 314.918823 -402.14609) (xy 314.938876 -402.190405) (xy 314.952469 -402.237108) (xy 314.959328 -402.285263)
			(xy 314.959746 -402.309584) (xy 314.959746 -402.309838) (xy 314.959266 -402.335537) (xy 314.951605 -402.386361)
			(xy 314.936456 -402.435475) (xy 314.914155 -402.481783) (xy 314.885202 -402.52425) (xy 314.850242 -402.561927)
			(xy 314.810058 -402.593973) (xy 314.765546 -402.619672) (xy 314.717701 -402.638449) (xy 314.667592 -402.649887)
			(xy 314.616338 -402.653728) (xy 314.565084 -402.649887) (xy 314.514975 -402.638449) (xy 314.46713 -402.619672)
			(xy 314.422618 -402.593973) (xy 314.382434 -402.561927) (xy 314.347474 -402.52425) (xy 314.318521 -402.481783)
			(xy 314.29622 -402.435475) (xy 314.281071 -402.386361) (xy 314.27341 -402.335537) (xy 314.27293 -402.309838)
			(xy 314.27293 -402.309584) (xy 314.273363 -402.285266) (xy 314.280248 -402.23712) (xy 314.29385 -402.190425)
			(xy 314.313898 -402.146114) (xy 314.339991 -402.10507) (xy 314.35548 -402.086318) (xy 314.36183 -402.078952)
			(xy 314.36818 -402.060664) (xy 314.36437 -401.972018) (xy 314.356242 -401.954492) (xy 314.349384 -401.947634)
			(xy 314.331569 -401.929611) (xy 314.300341 -401.889701) (xy 314.27467 -401.846009) (xy 314.25501 -401.799302)
			(xy 314.241706 -401.750405) (xy 314.234993 -401.700176) (xy 314.234576 -401.674838) (xy 313.798204 -401.674838)
			(xy 313.797787 -401.700176) (xy 313.791073 -401.750404) (xy 313.777769 -401.799302) (xy 313.758108 -401.846007)
			(xy 313.732437 -401.889699) (xy 313.701207 -401.929608) (xy 313.683396 -401.947634) (xy 313.676538 -401.954492)
			(xy 313.66841 -401.972018) (xy 313.6646 -402.060664) (xy 313.67095 -402.078952) (xy 313.6773 -402.086318)
			(xy 313.69279 -402.10507) (xy 313.718884 -402.146113) (xy 313.738933 -402.190425) (xy 313.752536 -402.23712)
			(xy 313.759422 -402.285266) (xy 313.75985 -402.309584) (xy 313.75985 -402.309838) (xy 313.75937 -402.335537)
			(xy 313.751709 -402.386361) (xy 313.73656 -402.435475) (xy 313.714259 -402.481783) (xy 313.685306 -402.52425)
			(xy 313.650346 -402.561927) (xy 313.610162 -402.593973) (xy 313.56565 -402.619672) (xy 313.517805 -402.638449)
			(xy 313.467696 -402.649887) (xy 313.416442 -402.653728) (xy 313.365188 -402.649887) (xy 313.315079 -402.638449)
			(xy 313.267234 -402.619672) (xy 313.222722 -402.593973) (xy 313.182538 -402.561927) (xy 313.147578 -402.52425)
			(xy 313.118625 -402.481783) (xy 313.096324 -402.435475) (xy 313.081175 -402.386361) (xy 313.073514 -402.335537)
			(xy 313.073034 -402.309838) (xy 313.073034 -402.309584) (xy 313.073452 -402.285264) (xy 313.080313 -402.23711)
			(xy 313.093908 -402.190408) (xy 313.113965 -402.146096) (xy 313.140081 -402.105061) (xy 313.155584 -402.086318)
			(xy 313.161934 -402.078952) (xy 313.168284 -402.060664) (xy 313.164474 -401.972018) (xy 313.156346 -401.954492)
			(xy 313.149488 -401.947634) (xy 313.131658 -401.929625) (xy 313.100428 -401.889713) (xy 313.074756 -401.846018)
			(xy 313.055095 -401.799309) (xy 313.04179 -401.750409) (xy 313.035076 -401.700177) (xy 313.03468 -401.674838)
			(xy 313.03468 -400.811238) (xy 313.035184 -400.783138) (xy 313.043438 -400.727548) (xy 313.059757 -400.673769)
			(xy 313.083789 -400.622967) (xy 313.115014 -400.57624) (xy 313.152756 -400.534599) (xy 313.174126 -400.516344)
			(xy 313.182762 -400.509486) (xy 313.192414 -400.489928) (xy 313.192668 -400.478752) (xy 313.193176 -400.461226)
			(xy 313.193163 -400.456357) (xy 313.1915 -400.446765) (xy 313.189874 -400.442176) (xy 313.186826 -400.43354)
			(xy 313.179968 -400.42592) (xy 313.164846 -400.408517) (xy 313.139258 -400.370166) (xy 313.11947 -400.328526)
			(xy 313.105897 -400.284466) (xy 313.098822 -400.238909) (xy 313.09818 -400.215862) (xy 313.09818 -400.21256)
			(xy 313.098558 -400.190487) (xy 313.104681 -400.146768) (xy 313.110372 -400.125438) (xy 313.113674 -400.113754)
			(xy 313.111642 -400.102324) (xy 313.110393 -400.096568) (xy 313.105654 -400.08579) (xy 313.102244 -400.080988)
			(xy 313.053222 -400.016218) (xy 313.045667 -400.007157) (xy 313.024615 -399.996573) (xy 313.012836 -399.995898)
			(xy 312.619644 -399.995898) (xy 312.607864 -399.996562) (xy 312.586812 -400.007154) (xy 312.579258 -400.016218)
			(xy 312.530236 -400.080988) (xy 312.526806 -400.085778) (xy 312.522063 -400.096561) (xy 312.520838 -400.102324)
			(xy 312.518806 -400.113754) (xy 312.522108 -400.125438) (xy 312.527711 -400.146462) (xy 312.533834 -400.189538)
			(xy 312.5343 -400.21129) (xy 312.5343 -400.215862) (xy 312.533675 -400.238887) (xy 312.526598 -400.284398)
			(xy 312.513021 -400.328411) (xy 312.493229 -400.37) (xy 312.467637 -400.408295) (xy 312.452512 -400.425666)
			(xy 312.445908 -400.433032) (xy 312.442606 -400.441668) (xy 312.441003 -400.446324) (xy 312.439458 -400.456049)
			(xy 312.439558 -400.460972) (xy 312.44032 -400.479768) (xy 312.44032 -400.480276) (xy 312.440574 -400.489674)
			(xy 312.450226 -400.509486) (xy 312.458608 -400.516344) (xy 312.479973 -400.534559) (xy 312.517643 -400.576189)
			(xy 312.548807 -400.622888) (xy 312.572793 -400.67365) (xy 312.589083 -400.727378) (xy 312.597326 -400.782913)
			(xy 312.5978 -400.810984) (xy 312.5978 -401.674838) (xy 312.597249 -401.703955) (xy 312.5884 -401.761513)
			(xy 312.570912 -401.81706) (xy 312.545193 -401.869307) (xy 312.511837 -401.917042) (xy 312.492136 -401.93849)
			(xy 312.485532 -401.945348) (xy 312.47842 -401.961858) (xy 312.47461 -402.047202) (xy 312.480198 -402.064474)
			(xy 312.485786 -402.071586) (xy 312.503127 -402.09448) (xy 312.530725 -402.144842) (xy 312.54956 -402.199094)
			(xy 312.559108 -402.255724) (xy 312.5597 -402.284438) (xy 312.55922 -402.310137) (xy 312.551559 -402.360961)
			(xy 312.53641 -402.410075) (xy 312.514109 -402.456383) (xy 312.485156 -402.49885) (xy 312.450196 -402.536527)
			(xy 312.410012 -402.568573) (xy 312.3655 -402.594272) (xy 312.317655 -402.613049) (xy 312.267546 -402.624487)
			(xy 312.216292 -402.628328) (xy 312.165038 -402.624487) (xy 312.114929 -402.613049) (xy 312.067084 -402.594272)
			(xy 312.022572 -402.568573) (xy 311.982388 -402.536527) (xy 311.947428 -402.49885) (xy 311.918475 -402.456383)
			(xy 311.896174 -402.410075) (xy 311.881025 -402.360961) (xy 311.873364 -402.310137) (xy 311.872884 -402.284438)
			(xy 311.87346 -402.255722) (xy 311.883005 -402.199088) (xy 311.901836 -402.14483) (xy 311.929428 -402.09446)
			(xy 311.946798 -402.071586) (xy 311.952386 -402.064474) (xy 311.957974 -402.047202) (xy 311.954164 -401.961858)
			(xy 311.947052 -401.945348) (xy 311.940448 -401.93849) (xy 311.920731 -401.917054) (xy 311.887367 -401.869319)
			(xy 311.86164 -401.81707) (xy 311.844148 -401.76152) (xy 311.835297 -401.703958) (xy 311.834784 -401.674838)
			(xy 311.834784 -400.810984) (xy 311.835283 -400.782913) (xy 311.843515 -400.727379) (xy 311.859799 -400.673651)
			(xy 311.883782 -400.622891) (xy 311.914948 -400.576194) (xy 311.952622 -400.534571) (xy 311.973976 -400.516344)
			(xy 311.982358 -400.509486) (xy 311.99201 -400.489674) (xy 311.992264 -400.480022) (xy 311.993026 -400.460972)
			(xy 311.993069 -400.456053) (xy 311.991525 -400.446338) (xy 311.989978 -400.441668) (xy 311.986676 -400.433032)
			(xy 311.980072 -400.425666) (xy 311.964962 -400.408284) (xy 311.93939 -400.369981) (xy 311.919605 -400.328393)
			(xy 311.906019 -400.284388) (xy 311.898916 -400.238884) (xy 311.898284 -400.215862) (xy 311.898284 -400.21256)
			(xy 311.898662 -400.190487) (xy 311.904782 -400.146767) (xy 311.910476 -400.125438) (xy 311.913778 -400.113754)
			(xy 311.911746 -400.102324) (xy 311.910498 -400.096568) (xy 311.905758 -400.085789) (xy 311.902348 -400.080988)
			(xy 311.853326 -400.016218) (xy 311.845771 -400.007157) (xy 311.824719 -399.996571) (xy 311.81294 -399.995898)
			(xy 311.501282 -399.995898) (xy 311.491213 -399.995471) (xy 311.472614 -399.987752) (xy 311.465214 -399.980912)
			(xy 311.313322 -399.82902) (xy 311.306486 -399.821618) (xy 311.298777 -399.80302) (xy 311.298336 -399.792952)
			(xy 311.298336 -398.188942) (xy 311.298087 -398.181528) (xy 311.293836 -398.167323) (xy 311.289954 -398.161002)
			(xy 311.28589 -398.154652) (xy 311.27446 -398.145254) (xy 311.267348 -398.142206) (xy 311.244882 -398.13224)
			(xy 311.203071 -398.106409) (xy 311.165734 -398.07445) (xy 311.133761 -398.037125) (xy 311.107915 -397.995324)
			(xy 311.08881 -397.950042) (xy 311.082436 -397.926306) (xy 311.081928 -397.924274) (xy 310.770778 -397.386048)
			(xy 310.768492 -397.383508) (xy 310.750748 -397.365452) (xy 310.720643 -397.324754) (xy 310.697371 -397.279799)
			(xy 310.68152 -397.231724) (xy 310.67349 -397.181743) (xy 310.672988 -397.156432) (xy 310.673242 -397.144748)
			(xy 310.673496 -397.13408) (xy 310.669686 -397.124428) (xy 310.667655 -397.119559) (xy 310.661891 -397.110726)
			(xy 310.658256 -397.106902) (xy 310.125618 -396.574264) (xy 310.118775 -396.566864) (xy 310.111051 -396.548266)
			(xy 310.110632 -396.538196) (xy 310.110632 -395.581632) (xy 310.110463 -395.575623) (xy 310.107637 -395.563942)
			(xy 310.105044 -395.558518) (xy 310.103205 -395.555044) (xy 310.098611 -395.548665) (xy 310.0959 -395.545818)
			(xy 309.846726 -395.296644) (xy 309.843876 -395.293936) (xy 309.8375 -395.28934) (xy 309.834026 -395.2875)
			(xy 309.828598 -395.28492) (xy 309.816919 -395.282103) (xy 309.810912 -395.281912) (xy 308.589426 -395.281912)
			(xy 308.584346 -395.282166) (xy 308.574976 -395.283491) (xy 308.558144 -395.292112) (xy 308.55158 -395.29893)
			(xy 308.500526 -395.361414) (xy 308.497005 -395.365872) (xy 308.491875 -395.376004) (xy 308.490366 -395.38148)
			(xy 308.487826 -395.392148) (xy 308.490112 -395.403578) (xy 308.492988 -395.419038) (xy 308.496037 -395.450338)
			(xy 308.496208 -395.466062) (xy 308.495827 -395.487871) (xy 308.489833 -395.531077) (xy 308.48427 -395.552168)
			(xy 308.483508 -395.555724) (xy 308.483508 -395.567662) (xy 308.483063 -395.582076) (xy 308.475913 -395.610004)
			(xy 308.46205 -395.635281) (xy 308.442344 -395.656323) (xy 308.430422 -395.664436) (xy 308.429406 -395.669008)
			(xy 308.428551 -395.674321) (xy 308.428802 -395.685079) (xy 308.429914 -395.690344) (xy 308.446678 -395.764258)
			(xy 308.448044 -395.76947) (xy 308.452651 -395.779207) (xy 308.455822 -395.783562) (xy 308.462172 -395.791944)
			(xy 308.471824 -395.797278) (xy 308.495973 -395.811242) (xy 308.539402 -395.846248) (xy 308.558184 -395.866874)
			(xy 308.560665 -395.869628) (xy 308.566271 -395.874478) (xy 308.56936 -395.876526) (xy 308.581497 -395.884615)
			(xy 308.601572 -395.905763) (xy 308.615721 -395.931259) (xy 308.623046 -395.959483) (xy 308.623462 -395.974062)
			(xy 308.623462 -395.986508) (xy 308.62524 -395.992858) (xy 308.630352 -396.013176) (xy 308.635826 -396.054714)
			(xy 308.636162 -396.075662) (xy 308.636162 -396.07998) (xy 308.635891 -396.091591) (xy 308.633854 -396.114728)
			(xy 308.632098 -396.126208) (xy 308.630581 -396.135255) (xy 308.626642 -396.153173) (xy 308.624224 -396.162022)
			(xy 308.623462 -396.16507) (xy 308.623462 -396.621254) (xy 308.624224 -396.624302) (xy 308.629346 -396.64354)
			(xy 308.635331 -396.682898) (xy 308.636162 -396.702788) (xy 308.636162 -396.710662) (xy 309.200296 -396.710662)
			(xy 309.200663 -396.689641) (xy 309.206273 -396.647975) (xy 309.211472 -396.627604) (xy 309.212996 -396.621)
			(xy 309.212996 -396.507462) (xy 309.213499 -396.492469) (xy 309.221255 -396.463502) (xy 309.236232 -396.437523)
			(xy 309.257411 -396.416294) (xy 309.283355 -396.401258) (xy 309.312304 -396.393434) (xy 309.327296 -396.392908)
			(xy 309.509414 -396.392908) (xy 309.509922 -396.392654) (xy 309.526686 -396.392654) (xy 309.527194 -396.392908)
			(xy 309.708804 -396.392908) (xy 309.723835 -396.393377) (xy 309.752874 -396.401148) (xy 309.778918 -396.416161)
			(xy 309.800196 -396.437396) (xy 309.815262 -396.463409) (xy 309.823093 -396.492432) (xy 309.823612 -396.507462)
			(xy 309.823612 -396.621) (xy 309.825136 -396.627604) (xy 309.830328 -396.647976) (xy 309.835938 -396.689642)
			(xy 309.836312 -396.710662) (xy 309.836312 -396.71117) (xy 309.836141 -396.725795) (xy 309.833475 -396.754924)
			(xy 309.830978 -396.769336) (xy 309.829618 -396.77851) (xy 309.832889 -396.796752) (xy 309.837328 -396.804896)
			(xy 309.853838 -396.83182) (xy 309.85901 -396.839597) (xy 309.873734 -396.85106) (xy 309.88254 -396.854172)
			(xy 309.907428 -396.862216) (xy 309.954307 -396.885411) (xy 309.996718 -396.916019) (xy 310.0335 -396.953203)
			(xy 310.063646 -396.995944) (xy 310.086329 -397.043072) (xy 310.094122 -397.06804) (xy 310.095646 -397.073882)
			(xy 310.41594 -397.627602) (xy 310.420004 -397.63192) (xy 310.436196 -397.649638) (xy 310.463622 -397.689026)
			(xy 310.484767 -397.732113) (xy 310.499143 -397.777905) (xy 310.50642 -397.825346) (xy 310.506872 -397.849344)
			(xy 310.506405 -397.874807) (xy 310.498205 -397.92507) (xy 310.482041 -397.973364) (xy 310.458332 -398.018436)
			(xy 310.427693 -398.059117) (xy 310.390921 -398.09435) (xy 310.37022 -398.109186) (xy 310.361712 -398.115627)
			(xy 310.350517 -398.133768) (xy 310.347646 -398.154892) (xy 310.353594 -398.175363) (xy 310.367337 -398.19166)
			(xy 310.38651 -398.200978) (xy 310.397144 -398.201896) (xy 310.40705 -398.201388) (xy 310.4155 -398.200098)
			(xy 310.432539 -398.198701) (xy 310.441086 -398.198594) (xy 310.44134 -398.198848) (xy 310.740552 -398.198848)
			(xy 310.740806 -398.198594) (xy 310.761851 -398.199028) (xy 310.80317 -398.207018) (xy 310.842125 -398.222944)
			(xy 310.877208 -398.246189) (xy 310.907059 -398.275854) (xy 310.930524 -398.31079) (xy 310.946695 -398.349644)
			(xy 310.954944 -398.390912) (xy 310.955436 -398.411954) (xy 310.955436 -398.666716) (xy 310.946292 -398.666716)
			(xy 310.936268 -398.667113) (xy 310.917748 -398.674789) (xy 310.903576 -398.688968) (xy 310.895909 -398.707492)
			(xy 310.895492 -398.717516) (xy 310.895492 -398.881092) (xy 310.895074 -398.891114) (xy 310.887405 -398.909632)
			(xy 310.873232 -398.923805) (xy 310.854714 -398.931474) (xy 310.844692 -398.931892) (xy 310.3372 -398.931892)
			(xy 310.327178 -398.93148) (xy 310.308659 -398.923809) (xy 310.294487 -398.909634) (xy 310.286818 -398.891114)
			(xy 310.2864 -398.881092) (xy 310.2864 -398.717516) (xy 310.285968 -398.707496) (xy 310.278303 -398.688979)
			(xy 310.264134 -398.674806) (xy 310.24562 -398.667136) (xy 310.2356 -398.666716) (xy 310.226456 -398.666716)
			(xy 310.226456 -398.411446) (xy 310.227236 -398.385723) (xy 310.239572 -398.335777) (xy 310.25084 -398.31264)
			(xy 310.256682 -398.30121) (xy 310.256428 -398.27581) (xy 310.20893 -398.190212) (xy 310.202227 -398.179418)
			(xy 310.18089 -398.165687) (xy 310.16829 -398.16405) (xy 310.144414 -398.161891) (xy 310.097669 -398.151257)
			(xy 310.053072 -398.13367) (xy 310.011651 -398.109537) (xy 309.974359 -398.079412) (xy 309.942057 -398.04399)
			(xy 309.915487 -398.004088) (xy 309.895263 -397.960623) (xy 309.888128 -397.937736) (xy 309.886604 -397.931894)
			(xy 309.56631 -397.378174) (xy 309.562246 -397.373856) (xy 309.546085 -397.356123) (xy 309.518718 -397.316721)
			(xy 309.497627 -397.273631) (xy 309.4833 -397.227845) (xy 309.476066 -397.180419) (xy 309.475632 -397.156432)
			(xy 309.475814 -397.142384) (xy 309.478354 -397.114402) (xy 309.480712 -397.100552) (xy 309.482033 -397.091272)
			(xy 309.478506 -397.072876) (xy 309.473854 -397.064738) (xy 309.45709 -397.037814) (xy 309.451897 -397.030103)
			(xy 309.437165 -397.018784) (xy 309.428388 -397.015716) (xy 309.406767 -397.008901) (xy 309.365552 -396.990024)
			(xy 309.32743 -396.965493) (xy 309.293173 -396.935804) (xy 309.27802 -396.918942) (xy 309.275558 -396.916169)
			(xy 309.269945 -396.911323) (xy 309.266844 -396.90929) (xy 309.254781 -396.901231) (xy 309.234824 -396.880188)
			(xy 309.22075 -396.85483) (xy 309.213449 -396.826762) (xy 309.212996 -396.812262) (xy 309.212996 -396.800324)
			(xy 309.211472 -396.79372) (xy 309.206266 -396.773351) (xy 309.200665 -396.731683) (xy 309.200296 -396.710662)
			(xy 308.636162 -396.710662) (xy 308.636162 -396.71498) (xy 308.635908 -396.725648) (xy 308.635908 -396.726156)
			(xy 308.635283 -396.736503) (xy 308.632865 -396.757093) (xy 308.631082 -396.767304) (xy 308.63032 -396.77594)
			(xy 308.630482 -396.783024) (xy 308.634215 -396.796687) (xy 308.637686 -396.802864) (xy 308.64937 -396.82166)
			(xy 308.651844 -396.825615) (xy 308.657984 -396.832637) (xy 308.661562 -396.83563) (xy 308.682644 -396.851632)
			(xy 308.688232 -396.85341) (xy 308.713386 -396.86207) (xy 308.760609 -396.886561) (xy 308.803103 -396.918562)
			(xy 308.839686 -396.957182) (xy 308.86934 -397.001346) (xy 308.891239 -397.049825) (xy 308.898544 -397.075406)
			(xy 308.903624 -397.087852) (xy 309.21579 -397.627602) (xy 309.219854 -397.63192) (xy 309.236014 -397.649588)
			(xy 309.263351 -397.688897) (xy 309.28443 -397.731887) (xy 309.298766 -397.777571) (xy 309.30603 -397.824896)
			(xy 309.306468 -397.848836) (xy 309.306468 -397.849344) (xy 309.305988 -397.874796) (xy 309.297828 -397.925042)
			(xy 309.281712 -397.973328) (xy 309.258057 -398.018402) (xy 309.227476 -398.059097) (xy 309.190761 -398.094357)
			(xy 309.17007 -398.109186) (xy 309.161581 -398.115674) (xy 309.150399 -398.13385) (xy 309.147565 -398.155001)
			(xy 309.153569 -398.175479) (xy 309.167374 -398.191752) (xy 309.1866 -398.201013) (xy 309.197248 -398.201896)
			(xy 309.2069 -398.201388) (xy 309.215411 -398.200072) (xy 309.232578 -398.198669) (xy 309.24119 -398.198594)
			(xy 309.241444 -398.198848) (xy 309.540656 -398.198848) (xy 309.54091 -398.198594) (xy 309.561958 -398.198955)
			(xy 309.603284 -398.206949) (xy 309.642243 -398.222883) (xy 309.677326 -398.246138) (xy 309.707176 -398.275815)
			(xy 309.730634 -398.310764) (xy 309.746793 -398.34963) (xy 309.755027 -398.390908) (xy 309.75554 -398.411954)
			(xy 309.75554 -398.615916) (xy 309.75505 -398.625924) (xy 309.747389 -398.644418) (xy 309.733238 -398.658575)
			(xy 309.714748 -398.666245) (xy 309.70474 -398.666716) (xy 309.695596 -398.666716) (xy 309.695596 -398.881092)
			(xy 309.695178 -398.891114) (xy 309.687509 -398.909633) (xy 309.673336 -398.923807) (xy 309.654818 -398.931477)
			(xy 309.644796 -398.931892) (xy 309.137304 -398.931892) (xy 309.127283 -398.931473) (xy 309.108766 -398.923804)
			(xy 309.094594 -398.909631) (xy 309.086926 -398.891113) (xy 309.086504 -398.881092) (xy 309.086504 -398.717516)
			(xy 309.086087 -398.707492) (xy 309.07842 -398.688969) (xy 309.064248 -398.674791) (xy 309.045728 -398.667117)
			(xy 309.035704 -398.666716) (xy 309.02656 -398.666716) (xy 309.02656 -398.411446) (xy 309.027356 -398.385725)
			(xy 309.039681 -398.335778) (xy 309.050944 -398.31264) (xy 309.056786 -398.30121) (xy 309.056532 -398.27581)
			(xy 309.009034 -398.190212) (xy 309.002325 -398.179424) (xy 308.980992 -398.165693) (xy 308.968394 -398.16405)
			(xy 308.944508 -398.161882) (xy 308.897743 -398.151243) (xy 308.853124 -398.133655) (xy 308.811677 -398.109525)
			(xy 308.774354 -398.079406) (xy 308.742013 -398.043991) (xy 308.715397 -398.004094) (xy 308.69512 -397.960632)
			(xy 308.687978 -397.937736) (xy 308.686454 -397.931894) (xy 308.371494 -397.387064) (xy 308.36997 -397.385794)
			(xy 308.355492 -397.383508) (xy 308.348172 -397.382647) (xy 308.333587 -397.38472) (xy 308.32679 -397.387572)
			(xy 308.242462 -397.425672) (xy 308.23662 -397.428974) (xy 308.229517 -397.433785) (xy 308.218784 -397.447154)
			(xy 308.213095 -397.463328) (xy 308.212744 -397.4719) (xy 308.212744 -398.160748) (xy 308.213257 -398.171583)
			(xy 308.222206 -398.19132) (xy 308.230016 -398.198848) (xy 308.34076 -398.198848) (xy 308.341014 -398.198594)
			(xy 308.362062 -398.198955) (xy 308.403387 -398.20695) (xy 308.442345 -398.222884) (xy 308.477428 -398.24614)
			(xy 308.507277 -398.275817) (xy 308.530735 -398.310765) (xy 308.546894 -398.349631) (xy 308.555127 -398.390908)
			(xy 308.555644 -398.411954) (xy 308.555644 -398.666716) (xy 308.553104 -398.666716) (xy 308.528212 -398.726406)
			(xy 308.529228 -398.728438) (xy 308.531105 -398.73183) (xy 308.535702 -398.738072) (xy 308.538372 -398.740884)
			(xy 308.821836 -399.024348) (xy 308.828682 -399.031746) (xy 308.836409 -399.050345) (xy 308.836822 -399.060416)
			(xy 308.836822 -399.962878) (xy 308.836871 -399.966749) (xy 308.838022 -399.974403) (xy 308.839108 -399.978118)
			(xy 308.840935 -399.983444) (xy 308.846569 -399.993191) (xy 308.850284 -399.997422) (xy 308.867729 -400.017124)
			(xy 308.896515 -400.061173) (xy 308.917656 -400.109359) (xy 308.930576 -400.160369) (xy 308.934921 -400.21281)
			(xy 308.930572 -400.265251) (xy 308.91765 -400.31626) (xy 308.896505 -400.364446) (xy 308.867716 -400.408492)
			(xy 308.850284 -400.428206) (xy 308.84368 -400.435572) (xy 308.840378 -400.444208) (xy 308.838756 -400.448672)
			(xy 308.836974 -400.458002) (xy 308.836822 -400.46275) (xy 308.836822 -400.486118) (xy 308.846728 -400.506692)
			(xy 308.855872 -400.514058) (xy 308.877671 -400.532275) (xy 308.916153 -400.574065) (xy 308.948011 -400.621101)
			(xy 308.972541 -400.672341) (xy 308.989201 -400.726652) (xy 308.99762 -400.782833) (xy 308.998112 -400.811238)
			(xy 308.998112 -401.674838) (xy 309.434484 -401.674838) (xy 309.434484 -400.811238) (xy 309.434896 -400.785717)
			(xy 309.441687 -400.73513) (xy 309.455165 -400.685901) (xy 309.475091 -400.63891) (xy 309.501107 -400.594997)
			(xy 309.532749 -400.554947) (xy 309.550816 -400.536918) (xy 309.55742 -400.530568) (xy 309.565294 -400.513804)
			(xy 309.572152 -400.42846) (xy 309.567072 -400.41068) (xy 309.561484 -400.403314) (xy 309.546628 -400.38257)
			(xy 309.522995 -400.337354) (xy 309.506896 -400.288942) (xy 309.498744 -400.238578) (xy 309.498238 -400.213068)
			(xy 309.498238 -400.212814) (xy 309.498728 -400.187825) (xy 309.506547 -400.138462) (xy 309.521991 -400.09093)
			(xy 309.544681 -400.046398) (xy 309.574057 -400.005965) (xy 309.609397 -399.970625) (xy 309.64983 -399.941249)
			(xy 309.694362 -399.918559) (xy 309.741894 -399.903115) (xy 309.791257 -399.895296) (xy 309.841235 -399.895296)
			(xy 309.890598 -399.903115) (xy 309.93813 -399.918559) (xy 309.982662 -399.941249) (xy 310.023095 -399.970625)
			(xy 310.058435 -400.005965) (xy 310.087811 -400.046398) (xy 310.110501 -400.09093) (xy 310.125945 -400.138462)
			(xy 310.133764 -400.187825) (xy 310.134254 -400.212814) (xy 310.134254 -400.213068) (xy 310.13375 -400.238577)
			(xy 310.125575 -400.288935) (xy 310.109475 -400.337346) (xy 310.085864 -400.382571) (xy 310.071008 -400.403314)
			(xy 310.06542 -400.41068) (xy 310.06034 -400.42846) (xy 310.067198 -400.513804) (xy 310.075072 -400.530568)
			(xy 310.081676 -400.536918) (xy 310.099714 -400.554973) (xy 310.131344 -400.595025) (xy 310.157354 -400.638936)
			(xy 310.177281 -400.68592) (xy 310.190769 -400.735141) (xy 310.197578 -400.78572) (xy 310.198008 -400.811238)
			(xy 310.198008 -401.674838) (xy 310.198 -401.675346) (xy 310.634888 -401.675346) (xy 310.634888 -400.81073)
			(xy 310.635332 -400.785262) (xy 310.642134 -400.734783) (xy 310.655594 -400.685658) (xy 310.675474 -400.638762)
			(xy 310.701418 -400.594929) (xy 310.732966 -400.554939) (xy 310.750966 -400.536918) (xy 310.75757 -400.530568)
			(xy 310.765444 -400.513804) (xy 310.772302 -400.42846) (xy 310.767222 -400.41068) (xy 310.761634 -400.403314)
			(xy 310.746784 -400.382566) (xy 310.723148 -400.337352) (xy 310.707047 -400.288941) (xy 310.698894 -400.238577)
			(xy 310.698388 -400.213068) (xy 310.698388 -400.212814) (xy 310.698878 -400.187825) (xy 310.706697 -400.138462)
			(xy 310.722141 -400.09093) (xy 310.744831 -400.046398) (xy 310.774207 -400.005965) (xy 310.809547 -399.970625)
			(xy 310.84998 -399.941249) (xy 310.894512 -399.918559) (xy 310.942044 -399.903115) (xy 310.991407 -399.895296)
			(xy 311.041385 -399.895296) (xy 311.090748 -399.903115) (xy 311.13828 -399.918559) (xy 311.182812 -399.941249)
			(xy 311.223245 -399.970625) (xy 311.258585 -400.005965) (xy 311.287961 -400.046398) (xy 311.310651 -400.09093)
			(xy 311.326095 -400.138462) (xy 311.333914 -400.187825) (xy 311.334404 -400.212814) (xy 311.334404 -400.213068)
			(xy 311.33391 -400.238577) (xy 311.325733 -400.288936) (xy 311.309631 -400.337348) (xy 311.286016 -400.382572)
			(xy 311.271158 -400.403314) (xy 311.26557 -400.41068) (xy 311.26049 -400.42846) (xy 311.267348 -400.513804)
			(xy 311.275222 -400.530568) (xy 311.281826 -400.536918) (xy 311.29982 -400.554945) (xy 311.331363 -400.594937)
			(xy 311.357305 -400.63877) (xy 311.377186 -400.685664) (xy 311.390652 -400.734786) (xy 311.397463 -400.785263)
			(xy 311.397904 -400.81073) (xy 311.397904 -401.675346) (xy 311.397325 -401.705083) (xy 311.388044 -401.763831)
			(xy 311.369763 -401.820427) (xy 311.342922 -401.873502) (xy 311.308172 -401.92177) (xy 311.287668 -401.943316)
			(xy 311.281342 -401.950275) (xy 311.273785 -401.967478) (xy 311.272936 -401.976844) (xy 311.271666 -402.008086)
			(xy 311.271659 -402.017336) (xy 311.277383 -402.03491) (xy 311.282842 -402.042376) (xy 311.300859 -402.065522)
			(xy 311.329596 -402.11665) (xy 311.349234 -402.171916) (xy 311.359203 -402.229713) (xy 311.359804 -402.259038)
			(xy 311.359324 -402.284737) (xy 311.351663 -402.335561) (xy 311.336514 -402.384675) (xy 311.314213 -402.430983)
			(xy 311.28526 -402.47345) (xy 311.2503 -402.511127) (xy 311.210116 -402.543173) (xy 311.165604 -402.568872)
			(xy 311.117759 -402.587649) (xy 311.06765 -402.599087) (xy 311.016396 -402.602928) (xy 310.965142 -402.599087)
			(xy 310.915033 -402.587649) (xy 310.867188 -402.568872) (xy 310.822676 -402.543173) (xy 310.782492 -402.511127)
			(xy 310.747532 -402.47345) (xy 310.718579 -402.430983) (xy 310.696278 -402.384675) (xy 310.681129 -402.335561)
			(xy 310.673468 -402.284737) (xy 310.672988 -402.259038) (xy 310.673574 -402.22971) (xy 310.683533 -402.171907)
			(xy 310.703168 -402.116636) (xy 310.731908 -402.065505) (xy 310.74995 -402.042376) (xy 310.755454 -402.03493)
			(xy 310.761191 -402.017344) (xy 310.761126 -402.008086) (xy 310.759856 -401.976844) (xy 310.758978 -401.967484)
			(xy 310.751432 -401.950285) (xy 310.745124 -401.943316) (xy 310.724618 -401.921771) (xy 310.689864 -401.873506)
			(xy 310.663024 -401.820431) (xy 310.644747 -401.763833) (xy 310.635477 -401.705084) (xy 310.634888 -401.675346)
			(xy 310.198 -401.675346) (xy 310.197616 -401.700177) (xy 310.190902 -401.750409) (xy 310.177596 -401.79931)
			(xy 310.157934 -401.846019) (xy 310.132262 -401.889714) (xy 310.10103 -401.929625) (xy 310.0832 -401.947634)
			(xy 310.076342 -401.954492) (xy 310.068214 -401.972018) (xy 310.064404 -402.060664) (xy 310.070754 -402.078952)
			(xy 310.077104 -402.086318) (xy 310.09262 -402.10505) (xy 310.118732 -402.146089) (xy 310.138785 -402.190404)
			(xy 310.152377 -402.237108) (xy 310.159236 -402.285263) (xy 310.159654 -402.309584) (xy 310.159654 -402.309838)
			(xy 310.159174 -402.335537) (xy 310.151513 -402.386361) (xy 310.136364 -402.435475) (xy 310.114063 -402.481783)
			(xy 310.08511 -402.52425) (xy 310.05015 -402.561927) (xy 310.009966 -402.593973) (xy 309.965454 -402.619672)
			(xy 309.917609 -402.638449) (xy 309.8675 -402.649887) (xy 309.816246 -402.653728) (xy 309.764992 -402.649887)
			(xy 309.714883 -402.638449) (xy 309.667038 -402.619672) (xy 309.622526 -402.593973) (xy 309.582342 -402.561927)
			(xy 309.547382 -402.52425) (xy 309.518429 -402.481783) (xy 309.496128 -402.435475) (xy 309.480979 -402.386361)
			(xy 309.473318 -402.335537) (xy 309.472838 -402.309838) (xy 309.472838 -402.309584) (xy 309.473269 -402.285266)
			(xy 309.480155 -402.23712) (xy 309.493757 -402.190425) (xy 309.513805 -402.146113) (xy 309.539899 -402.10507)
			(xy 309.555388 -402.086318) (xy 309.561738 -402.078952) (xy 309.568088 -402.060664) (xy 309.564278 -401.972018)
			(xy 309.55615 -401.954492) (xy 309.549292 -401.947634) (xy 309.531479 -401.92961) (xy 309.50025 -401.889701)
			(xy 309.474579 -401.846008) (xy 309.454919 -401.799302) (xy 309.441615 -401.750404) (xy 309.434901 -401.700176)
			(xy 309.434484 -401.674838) (xy 308.998112 -401.674838) (xy 308.997557 -401.70399) (xy 308.988685 -401.761616)
			(xy 308.971152 -401.817222) (xy 308.945367 -401.869515) (xy 308.911928 -401.917279) (xy 308.892194 -401.938744)
			(xy 308.885879 -401.945825) (xy 308.878553 -401.963312) (xy 308.87797 -401.97278) (xy 308.875938 -402.050504)
			(xy 308.882034 -402.06803) (xy 308.884066 -402.070316) (xy 308.901224 -402.090164) (xy 308.930153 -402.133932)
			(xy 308.952398 -402.181447) (xy 308.967485 -402.231695) (xy 308.975092 -402.283605) (xy 308.975506 -402.309838)
			(xy 308.975161 -402.333352) (xy 308.969062 -402.379983) (xy 308.956923 -402.425417) (xy 308.93895 -402.468875)
			(xy 308.9275 -402.489416) (xy 308.925468 -402.493226) (xy 308.918356 -402.519134) (xy 308.918928 -402.529057)
			(xy 308.92664 -402.547354) (xy 308.933342 -402.554694) (xy 309.20817 -402.829522) (xy 309.215526 -402.836173)
			(xy 309.233826 -402.843761) (xy 309.24373 -402.844254) (xy 315.797692 -402.844254)
		)
		(stroke
			(width 0)
			(type solid)
		)
		(fill yes)
		(layer "B.Cu")
		(net "P0V9_CPU0_RT_2D")
	)
	(gr_poly
		(pts
			(xy 382.907286 -402.843238) (xy 382.914527 -402.841605) (xy 382.927687 -402.834754) (xy 382.933194 -402.829776)
			(xy 383.011426 -402.751544) (xy 383.01785 -402.744542) (xy 383.02545 -402.727141) (xy 383.026221 -402.708168)
			(xy 383.020059 -402.690206) (xy 383.01422 -402.68271) (xy 383.010918 -402.679408) (xy 383.006633 -402.675386)
			(xy 382.996629 -402.669223) (xy 382.991106 -402.667216) (xy 382.980438 -402.66366) (xy 382.974342 -402.664676)
			(xy 382.968246 -402.665438) (xy 382.955365 -402.667205) (xy 382.929431 -402.669113) (xy 382.91643 -402.669248)
			(xy 382.916176 -402.669248) (xy 382.890544 -402.668776) (xy 382.839804 -402.661454) (xy 382.79062 -402.646992)
			(xy 382.743993 -402.625683) (xy 382.70087 -402.597961) (xy 382.662128 -402.564388) (xy 382.628552 -402.525647)
			(xy 382.600827 -402.482526) (xy 382.579515 -402.4359) (xy 382.56505 -402.386718) (xy 382.557726 -402.335978)
			(xy 382.557274 -402.310346) (xy 382.557274 -402.309838) (xy 382.557821 -402.281288) (xy 382.566845 -402.224905)
			(xy 382.584673 -402.170659) (xy 382.610856 -402.119916) (xy 382.644734 -402.073951) (xy 382.664716 -402.053552)
			(xy 382.671828 -402.04644) (xy 382.675638 -402.037296) (xy 382.677555 -402.032695) (xy 382.679738 -402.022971)
			(xy 382.679956 -402.017992) (xy 382.68021 -401.998688) (xy 382.679865 -401.987738) (xy 382.671056 -401.967705)
			(xy 382.663192 -401.96008) (xy 382.643432 -401.941888) (xy 382.608704 -401.900916) (xy 382.580063 -401.855479)
			(xy 382.558075 -401.806476) (xy 382.543173 -401.754874) (xy 382.535652 -401.701693) (xy 382.535176 -401.674838)
			(xy 382.535176 -400.810984) (xy 382.535667 -400.782942) (xy 382.543871 -400.727461) (xy 382.560116 -400.673781)
			(xy 382.584051 -400.623061) (xy 382.615158 -400.576394) (xy 382.652767 -400.534789) (xy 382.674114 -400.516598)
			(xy 382.68275 -400.50974) (xy 382.692148 -400.490182) (xy 382.692656 -400.476212) (xy 382.693164 -400.461226)
			(xy 382.693189 -400.45637) (xy 382.691649 -400.446784) (xy 382.690116 -400.442176) (xy 382.686814 -400.433286)
			(xy 382.679956 -400.425666) (xy 382.664627 -400.408066) (xy 382.638765 -400.369215) (xy 382.618868 -400.326997)
			(xy 382.605364 -400.282321) (xy 382.598546 -400.23615) (xy 382.598168 -400.212814) (xy 382.598657 -400.187823)
			(xy 382.606474 -400.138457) (xy 382.621916 -400.090922) (xy 382.644605 -400.046387) (xy 382.673981 -400.00595)
			(xy 382.709321 -399.970606) (xy 382.749754 -399.941225) (xy 382.794286 -399.918531) (xy 382.84182 -399.903083)
			(xy 382.891185 -399.89526) (xy 382.916176 -399.894806) (xy 382.91643 -399.894806) (xy 382.938263 -399.895182)
			(xy 382.981516 -399.901183) (xy 383.023543 -399.91304) (xy 383.043684 -399.921476) (xy 383.043938 -399.921476)
			(xy 383.049864 -399.92385) (xy 383.062458 -399.925914) (xy 383.06883 -399.92554) (xy 383.080768 -399.924524)
			(xy 383.164842 -399.86966) (xy 383.168398 -399.866866) (xy 383.171954 -399.863564) (xy 383.177063 -399.857853)
			(xy 383.183915 -399.844154) (xy 383.185416 -399.83664) (xy 383.186178 -399.828258) (xy 383.186178 -398.248632)
			(xy 383.186418 -398.241448) (xy 383.190402 -398.227645) (xy 383.194052 -398.221454) (xy 383.198116 -398.215358)
			(xy 383.20218 -398.201388) (xy 383.20218 -398.19072) (xy 383.201742 -398.180657) (xy 383.194005 -398.162075)
			(xy 383.187194 -398.154652) (xy 383.180082 -398.14754) (xy 383.170684 -398.14373) (xy 383.148134 -398.134016)
			(xy 383.106085 -398.108665) (xy 383.068435 -398.07715) (xy 383.036078 -398.040221) (xy 383.009784 -397.998756)
			(xy 382.990178 -397.953741) (xy 382.983486 -397.930116) (xy 382.981708 -397.923512) (xy 382.666494 -397.378174)
			(xy 382.66243 -397.373856) (xy 382.64624 -397.356148) (xy 382.618862 -397.316746) (xy 382.597771 -397.27365)
			(xy 382.583452 -397.227857) (xy 382.576238 -397.180422) (xy 382.575816 -397.156432) (xy 382.575991 -397.142384)
			(xy 382.578532 -397.114401) (xy 382.580896 -397.100552) (xy 382.582108 -397.091276) (xy 382.578579 -397.072919)
			(xy 382.574038 -397.064738) (xy 382.557274 -397.037814) (xy 382.552065 -397.030116) (xy 382.537342 -397.018798)
			(xy 382.528572 -397.015716) (xy 382.506942 -397.008924) (xy 382.465717 -396.990059) (xy 382.427594 -396.965523)
			(xy 382.393348 -396.935814) (xy 382.378204 -396.918942) (xy 382.375723 -396.916188) (xy 382.370118 -396.911338)
			(xy 382.367028 -396.90929) (xy 382.354964 -396.901234) (xy 382.335009 -396.880188) (xy 382.320937 -396.85483)
			(xy 382.313636 -396.826762) (xy 382.31318 -396.812262) (xy 382.31318 -396.800324) (xy 382.311656 -396.79372)
			(xy 382.306462 -396.773348) (xy 382.300862 -396.731682) (xy 382.30048 -396.710662) (xy 382.300854 -396.689642)
			(xy 382.306464 -396.647976) (xy 382.311656 -396.627604) (xy 382.31318 -396.621) (xy 382.31318 -396.507462)
			(xy 382.313672 -396.492471) (xy 382.321431 -396.463511) (xy 382.336411 -396.437539) (xy 382.357594 -396.416322)
			(xy 382.383542 -396.401301) (xy 382.41249 -396.393496) (xy 382.42748 -396.392908) (xy 382.609598 -396.392908)
			(xy 382.610106 -396.392654) (xy 382.62687 -396.392654) (xy 382.627378 -396.392908) (xy 382.78816 -396.392908)
			(xy 382.798187 -396.392495) (xy 382.816719 -396.384833) (xy 382.830906 -396.37066) (xy 382.838586 -396.352135)
			(xy 382.83896 -396.342108) (xy 382.83896 -395.350492) (xy 382.838534 -395.340423) (xy 382.830813 -395.321825)
			(xy 382.823974 -395.314424) (xy 382.787906 -395.278356) (xy 382.780511 -395.271503) (xy 382.761912 -395.263757)
			(xy 382.751838 -395.26337) (xy 382.139952 -395.26337) (xy 382.133942 -395.263537) (xy 382.122259 -395.266359)
			(xy 382.116838 -395.268958) (xy 382.113363 -395.270796) (xy 382.106983 -395.275388) (xy 382.104138 -395.278102)
			(xy 381.83058 -395.55166) (xy 381.827875 -395.554511) (xy 381.823282 -395.56089) (xy 381.821436 -395.56436)
			(xy 381.818853 -395.569787) (xy 381.816031 -395.581467) (xy 381.815848 -395.587474) (xy 381.815848 -396.832328)
			(xy 381.81607 -396.839136) (xy 381.819681 -396.852265) (xy 381.82296 -396.858236) (xy 381.826262 -396.863824)
			(xy 381.836168 -396.873222) (xy 381.842518 -396.876778) (xy 381.86501 -396.889581) (xy 381.905887 -396.921322)
			(xy 381.9411 -396.959246) (xy 381.969727 -397.00236) (xy 381.991015 -397.049531) (xy 381.99822 -397.07439)
			(xy 381.999998 -397.080994) (xy 382.315974 -397.627602) (xy 382.320038 -397.63192) (xy 382.336195 -397.64959)
			(xy 382.363524 -397.688901) (xy 382.384597 -397.731892) (xy 382.39893 -397.777574) (xy 382.406192 -397.824897)
			(xy 382.406652 -397.848836) (xy 382.406652 -397.849344) (xy 382.406162 -397.874131) (xy 382.398401 -397.923093)
			(xy 382.383076 -397.970239) (xy 382.360565 -398.014407) (xy 382.331422 -398.05451) (xy 382.296365 -398.089561)
			(xy 382.256256 -398.118696) (xy 382.212084 -398.141199) (xy 382.164935 -398.156515) (xy 382.115971 -398.164267)
			(xy 382.091184 -398.164812) (xy 382.065791 -398.164303) (xy 382.01566 -398.156171) (xy 381.967478 -398.140118)
			(xy 381.922487 -398.116559) (xy 381.881847 -398.086102) (xy 381.846607 -398.049532) (xy 381.817676 -398.007792)
			(xy 381.7958 -397.961959) (xy 381.788162 -397.937736) (xy 381.786638 -397.931894) (xy 381.581406 -397.57731)
			(xy 381.575088 -397.567528) (xy 381.555767 -397.554572) (xy 381.544322 -397.552418) (xy 381.532892 -397.550894)
			(xy 381.510286 -397.558514) (xy 381.22225 -397.84655) (xy 381.21925 -397.849641) (xy 381.214274 -397.856669)
			(xy 381.212344 -397.86052) (xy 381.208534 -397.868648) (xy 381.207772 -397.877792) (xy 381.204892 -397.904017)
			(xy 381.191561 -397.95506) (xy 381.169991 -398.003204) (xy 381.140772 -398.047129) (xy 381.104706 -398.08563)
			(xy 381.084074 -398.102074) (xy 381.08382 -398.102328) (xy 381.079278 -398.105987) (xy 381.071835 -398.114963)
			(xy 381.069088 -398.120108) (xy 381.066548 -398.125188) (xy 381.064008 -398.136364) (xy 381.064008 -398.149064)
			(xy 381.10414 -398.185386) (xy 381.111422 -398.191505) (xy 381.129177 -398.198288) (xy 381.138684 -398.198594)
			(xy 381.141478 -398.198594) (xy 381.141732 -398.198848) (xy 381.440944 -398.198848) (xy 381.441198 -398.198594)
			(xy 381.458247 -398.198828) (xy 381.491936 -398.204065) (xy 381.508254 -398.209008) (xy 381.515874 -398.211548)
			(xy 381.545084 -398.211548) (xy 381.558442 -398.211943) (xy 381.58425 -398.218854) (xy 381.607388 -398.23221)
			(xy 381.626281 -398.2511) (xy 381.639641 -398.274237) (xy 381.646556 -398.300044) (xy 381.646938 -398.313402)
			(xy 381.646938 -398.350486) (xy 381.648716 -398.356836) (xy 381.652064 -398.370368) (xy 381.655632 -398.398015)
			(xy 381.655828 -398.411954) (xy 381.655828 -398.666716) (xy 381.646938 -398.666716) (xy 381.646938 -398.770856)
			(xy 381.646368 -398.785491) (xy 381.638032 -398.813553) (xy 381.622136 -398.838135) (xy 381.611378 -398.848072)
			(xy 381.61087 -398.84858) (xy 381.604774 -398.853914) (xy 381.595884 -398.873726) (xy 381.595884 -398.881092)
			(xy 381.595466 -398.891113) (xy 381.587797 -398.90963) (xy 381.573623 -398.923801) (xy 381.555105 -398.931467)
			(xy 381.545084 -398.931892) (xy 381.114808 -398.931892) (xy 381.104799 -398.932379) (xy 381.086303 -398.940037)
			(xy 381.072146 -398.954189) (xy 381.064482 -398.972683) (xy 381.064008 -398.982692) (xy 381.064008 -399.024602)
			(xy 382.10998 -399.024602) (xy 382.10998 -398.542002) (xy 382.110466 -398.514769) (xy 382.118217 -398.460857)
			(xy 382.133562 -398.408597) (xy 382.156188 -398.359053) (xy 382.185635 -398.313233) (xy 382.221302 -398.27207)
			(xy 382.262465 -398.236403) (xy 382.308285 -398.206956) (xy 382.357829 -398.18433) (xy 382.410089 -398.168985)
			(xy 382.464001 -398.161234) (xy 382.518467 -398.161234) (xy 382.572379 -398.168985) (xy 382.624639 -398.18433)
			(xy 382.674183 -398.206956) (xy 382.720003 -398.236403) (xy 382.761166 -398.27207) (xy 382.796833 -398.313233)
			(xy 382.82628 -398.359053) (xy 382.848906 -398.408597) (xy 382.864251 -398.460857) (xy 382.872002 -398.514769)
			(xy 382.872488 -398.542002) (xy 382.872488 -399.024602) (xy 382.872002 -399.051835) (xy 382.864251 -399.105747)
			(xy 382.848906 -399.158007) (xy 382.82628 -399.207551) (xy 382.796833 -399.253371) (xy 382.761166 -399.294534)
			(xy 382.720003 -399.330201) (xy 382.674183 -399.359648) (xy 382.624639 -399.382274) (xy 382.572379 -399.397619)
			(xy 382.518467 -399.40537) (xy 382.464001 -399.40537) (xy 382.410089 -399.397619) (xy 382.357829 -399.382274)
			(xy 382.308285 -399.359648) (xy 382.262465 -399.330201) (xy 382.221302 -399.294534) (xy 382.185635 -399.253371)
			(xy 382.156188 -399.207551) (xy 382.133562 -399.158007) (xy 382.118217 -399.105747) (xy 382.110466 -399.051835)
			(xy 382.10998 -399.024602) (xy 381.064008 -399.024602) (xy 381.064008 -399.827496) (xy 381.063586 -399.837567)
			(xy 381.055874 -399.856173) (xy 381.049022 -399.863564) (xy 380.931674 -399.980912) (xy 380.926853 -399.985469)
			(xy 380.915406 -399.992164) (xy 380.909068 -399.99412) (xy 380.901046 -399.996638) (xy 380.887169 -400.006116)
			(xy 380.88189 -400.012662) (xy 380.836932 -400.072098) (xy 380.830074 -400.081242) (xy 380.826658 -400.08597)
			(xy 380.821906 -400.096622) (xy 380.820676 -400.102324) (xy 380.818644 -400.113246) (xy 380.8222 -400.125184)
			(xy 380.827911 -400.14664) (xy 380.834032 -400.190614) (xy 380.834392 -400.212814) (xy 380.834392 -400.213068)
			(xy 380.833983 -400.236402) (xy 380.827161 -400.282567) (xy 380.813658 -400.327238) (xy 380.793765 -400.369453)
			(xy 380.767911 -400.408304) (xy 380.752604 -400.42592) (xy 380.745492 -400.433794) (xy 380.742444 -400.441668)
			(xy 380.740843 -400.446325) (xy 380.739299 -400.456049) (xy 380.739396 -400.460972) (xy 380.740158 -400.481038)
			(xy 380.740158 -400.481546) (xy 380.740412 -400.48942) (xy 380.74981 -400.508978) (xy 380.758446 -400.51609)
			(xy 380.779903 -400.534305) (xy 380.817746 -400.575965) (xy 380.849063 -400.62273) (xy 380.873175 -400.673586)
			(xy 380.889559 -400.727431) (xy 380.89786 -400.783097) (xy 380.8984 -400.811238) (xy 380.8984 -401.674838)
			(xy 381.334772 -401.674838) (xy 381.334772 -400.811238) (xy 381.335188 -400.785717) (xy 381.341978 -400.73513)
			(xy 381.355456 -400.685901) (xy 381.375381 -400.63891) (xy 381.401397 -400.594997) (xy 381.433037 -400.554947)
			(xy 381.451104 -400.536918) (xy 381.457708 -400.530568) (xy 381.465582 -400.513804) (xy 381.47244 -400.42846)
			(xy 381.46736 -400.41068) (xy 381.461772 -400.403314) (xy 381.446927 -400.382562) (xy 381.423289 -400.33735)
			(xy 381.407186 -400.28894) (xy 381.399032 -400.238577) (xy 381.398526 -400.213068) (xy 381.398526 -400.212814)
			(xy 381.399016 -400.187825) (xy 381.406835 -400.138462) (xy 381.422279 -400.09093) (xy 381.444969 -400.046398)
			(xy 381.474345 -400.005965) (xy 381.509685 -399.970625) (xy 381.550118 -399.941249) (xy 381.59465 -399.918559)
			(xy 381.642182 -399.903115) (xy 381.691545 -399.895296) (xy 381.741523 -399.895296) (xy 381.790886 -399.903115)
			(xy 381.838418 -399.918559) (xy 381.88295 -399.941249) (xy 381.923383 -399.970625) (xy 381.958723 -400.005965)
			(xy 381.988099 -400.046398) (xy 382.010789 -400.09093) (xy 382.026233 -400.138462) (xy 382.034052 -400.187825)
			(xy 382.034542 -400.212814) (xy 382.034542 -400.213068) (xy 382.034041 -400.238577) (xy 382.025865 -400.288935)
			(xy 382.009765 -400.337346) (xy 381.986153 -400.382572) (xy 381.971296 -400.403314) (xy 381.965708 -400.41068)
			(xy 381.960628 -400.42846) (xy 381.967486 -400.513804) (xy 381.97536 -400.530568) (xy 381.981964 -400.536918)
			(xy 382 -400.554975) (xy 382.03163 -400.595027) (xy 382.057641 -400.638936) (xy 382.077568 -400.685921)
			(xy 382.091057 -400.735141) (xy 382.097866 -400.78572) (xy 382.098296 -400.811238) (xy 382.098296 -401.674838)
			(xy 382.097724 -401.704001) (xy 382.088804 -401.761642) (xy 382.071223 -401.817256) (xy 382.045389 -401.869549)
			(xy 382.011904 -401.917307) (xy 381.992124 -401.938744) (xy 381.985958 -401.945821) (xy 381.978807 -401.963161)
			(xy 381.978154 -401.972526) (xy 381.976376 -402.041106) (xy 381.976525 -402.050362) (xy 381.982656 -402.067815)
			(xy 381.988314 -402.075142) (xy 381.988822 -402.07565) (xy 382.005175 -402.095264) (xy 382.032707 -402.138273)
			(xy 382.053865 -402.18475) (xy 382.06822 -402.233757) (xy 382.075483 -402.284305) (xy 382.075944 -402.309838)
			(xy 382.075442 -402.336734) (xy 382.067424 -402.389926) (xy 382.051568 -402.441329) (xy 382.028229 -402.489795)
			(xy 381.997926 -402.534241) (xy 381.961338 -402.573674) (xy 381.919281 -402.607213) (xy 381.872695 -402.634109)
			(xy 381.822621 -402.653762) (xy 381.770176 -402.665732) (xy 381.716534 -402.669752) (xy 381.662892 -402.665732)
			(xy 381.610447 -402.653762) (xy 381.560373 -402.634109) (xy 381.513787 -402.607213) (xy 381.47173 -402.573674)
			(xy 381.435142 -402.534241) (xy 381.404839 -402.489795) (xy 381.3815 -402.441329) (xy 381.365644 -402.389926)
			(xy 381.357626 -402.336734) (xy 381.357124 -402.309838) (xy 381.357607 -402.284271) (xy 381.364883 -402.233656)
			(xy 381.379277 -402.184589) (xy 381.400499 -402.138065) (xy 381.428117 -402.09503) (xy 381.4445 -402.075396)
			(xy 381.444754 -402.075142) (xy 381.450416 -402.06782) (xy 381.456528 -402.050362) (xy 381.456692 -402.041106)
			(xy 381.45466 -401.962874) (xy 381.447548 -401.945856) (xy 381.440944 -401.938744) (xy 381.421165 -401.917304)
			(xy 381.387671 -401.869552) (xy 381.361834 -401.81726) (xy 381.344255 -401.761644) (xy 381.335343 -401.704001)
			(xy 381.334772 -401.674838) (xy 380.8984 -401.674838) (xy 380.897829 -401.704001) (xy 380.888917 -401.761644)
			(xy 380.871336 -401.817258) (xy 380.845498 -401.86955) (xy 380.812002 -401.9173) (xy 380.792228 -401.938744)
			(xy 380.785624 -401.945856) (xy 380.778512 -401.962874) (xy 380.77648 -402.041106) (xy 380.776643 -402.050362)
			(xy 380.782753 -402.067822) (xy 380.788418 -402.075142) (xy 380.788672 -402.075396) (xy 380.805057 -402.095029)
			(xy 380.832676 -402.138064) (xy 380.8539 -402.184588) (xy 380.868296 -402.233655) (xy 380.875572 -402.28427)
			(xy 380.876048 -402.309838) (xy 380.875546 -402.336734) (xy 380.867528 -402.389926) (xy 380.851672 -402.441329)
			(xy 380.828333 -402.489795) (xy 380.79803 -402.534241) (xy 380.761442 -402.573674) (xy 380.719385 -402.607213)
			(xy 380.672799 -402.634109) (xy 380.622725 -402.653762) (xy 380.57028 -402.665732) (xy 380.516638 -402.669752)
			(xy 380.462996 -402.665732) (xy 380.410551 -402.653762) (xy 380.360477 -402.634109) (xy 380.313891 -402.607213)
			(xy 380.271834 -402.573674) (xy 380.235246 -402.534241) (xy 380.204943 -402.489795) (xy 380.181604 -402.441329)
			(xy 380.165748 -402.389926) (xy 380.15773 -402.336734) (xy 380.157228 -402.309838) (xy 380.157689 -402.284305)
			(xy 380.164951 -402.233757) (xy 380.179305 -402.184749) (xy 380.200462 -402.138271) (xy 380.227993 -402.095261)
			(xy 380.24435 -402.07565) (xy 380.244858 -402.075142) (xy 380.250519 -402.067816) (xy 380.256653 -402.050363)
			(xy 380.256796 -402.041106) (xy 380.255018 -401.972526) (xy 380.254365 -401.963162) (xy 380.24721 -401.945824)
			(xy 380.241048 -401.938744) (xy 380.221264 -401.917309) (xy 380.187773 -401.869553) (xy 380.161935 -401.817259)
			(xy 380.14435 -401.761644) (xy 380.135428 -401.704002) (xy 380.134876 -401.674838) (xy 380.134876 -400.811238)
			(xy 380.135371 -400.783166) (xy 380.143596 -400.727627) (xy 380.159874 -400.673894) (xy 380.183853 -400.623127)
			(xy 380.215014 -400.576424) (xy 380.252686 -400.534794) (xy 380.274068 -400.516598) (xy 380.282704 -400.50974)
			(xy 380.292102 -400.490182) (xy 380.29261 -400.476212) (xy 380.293118 -400.461226) (xy 380.293143 -400.45637)
			(xy 380.291606 -400.446783) (xy 380.29007 -400.442176) (xy 380.286768 -400.433286) (xy 380.27991 -400.425666)
			(xy 380.264583 -400.408065) (xy 380.238724 -400.369213) (xy 380.21883 -400.326995) (xy 380.205329 -400.28232)
			(xy 380.198511 -400.236149) (xy 380.198122 -400.212814) (xy 380.198122 -400.21256) (xy 380.1985 -400.190487)
			(xy 380.204621 -400.146768) (xy 380.210314 -400.125438) (xy 380.213616 -400.113754) (xy 380.211584 -400.102324)
			(xy 380.210336 -400.096568) (xy 380.2056 -400.085787) (xy 380.202186 -400.080988) (xy 380.153164 -400.016218)
			(xy 380.145612 -400.00715) (xy 380.12456 -399.996549) (xy 380.112778 -399.995898) (xy 379.719586 -399.995898)
			(xy 379.707801 -399.996553) (xy 379.686735 -400.007135) (xy 379.6792 -400.016218) (xy 379.630178 -400.081242)
			(xy 379.626761 -400.08597) (xy 379.62201 -400.096622) (xy 379.62078 -400.102324) (xy 379.618748 -400.1135)
			(xy 379.622304 -400.125438) (xy 379.627792 -400.145902) (xy 379.633915 -400.187825) (xy 379.634496 -400.209004)
			(xy 379.634496 -400.212814) (xy 379.634104 -400.236173) (xy 379.627304 -400.282394) (xy 379.613808 -400.32712)
			(xy 379.593907 -400.369387) (xy 379.568031 -400.408284) (xy 379.552708 -400.42592) (xy 379.545596 -400.43354)
			(xy 379.542548 -400.441922) (xy 379.540977 -400.44652) (xy 379.539449 -400.456113) (xy 379.5395 -400.460972)
			(xy 379.540262 -400.481038) (xy 379.540262 -400.481546) (xy 379.540516 -400.489674) (xy 379.549914 -400.509232)
			(xy 379.55855 -400.516344) (xy 379.579953 -400.534561) (xy 379.617692 -400.57621) (xy 379.648911 -400.622945)
			(xy 379.672935 -400.673755) (xy 379.689244 -400.72754) (xy 379.697484 -400.783136) (xy 379.697996 -400.811238)
			(xy 379.697996 -401.675346) (xy 379.697468 -401.703158) (xy 379.689347 -401.758185) (xy 379.673326 -401.811452)
			(xy 379.649746 -401.861831) (xy 379.619104 -401.908254) (xy 379.600968 -401.929346) (xy 379.595126 -401.93595)
			(xy 379.588268 -401.952714) (xy 379.586236 -402.027136) (xy 379.586302 -402.03605) (xy 379.591885 -402.052969)
			(xy 379.597158 -402.060156) (xy 379.597412 -402.06041) (xy 379.612149 -402.079538) (xy 379.636905 -402.120996)
			(xy 379.655883 -402.165397) (xy 379.668741 -402.21194) (xy 379.675246 -402.259787) (xy 379.675644 -402.28393)
			(xy 379.675644 -402.284438) (xy 379.675142 -402.311315) (xy 379.66713 -402.36447) (xy 379.651286 -402.415836)
			(xy 379.627962 -402.464268) (xy 379.597681 -402.508682) (xy 379.561119 -402.548087) (xy 379.519091 -402.581603)
			(xy 379.472538 -402.60848) (xy 379.422499 -402.628119) (xy 379.370092 -402.64008) (xy 379.316488 -402.644098)
			(xy 379.262884 -402.64008) (xy 379.210477 -402.628119) (xy 379.160438 -402.60848) (xy 379.113885 -402.581603)
			(xy 379.071857 -402.548087) (xy 379.035295 -402.508682) (xy 379.005014 -402.464268) (xy 378.98169 -402.415836)
			(xy 378.965846 -402.36447) (xy 378.957834 -402.311315) (xy 378.957332 -402.284438) (xy 378.957332 -402.28393)
			(xy 378.957742 -402.259788) (xy 378.964247 -402.211942) (xy 378.977104 -402.1654) (xy 378.99608 -402.121)
			(xy 379.020834 -402.079542) (xy 379.035564 -402.06041) (xy 379.035818 -402.060156) (xy 379.041034 -402.052936)
			(xy 379.046634 -402.036042) (xy 379.04674 -402.027136) (xy 379.044708 -401.952714) (xy 379.03785 -401.93595)
			(xy 379.032008 -401.929346) (xy 379.013846 -401.908273) (xy 378.98319 -401.861853) (xy 378.959605 -401.811471)
			(xy 378.94359 -401.758196) (xy 378.935486 -401.703161) (xy 378.93498 -401.675346) (xy 378.93498 -400.810984)
			(xy 378.935471 -400.782942) (xy 378.943676 -400.727461) (xy 378.959921 -400.673781) (xy 378.983855 -400.623061)
			(xy 379.014963 -400.576395) (xy 379.052572 -400.53479) (xy 379.073918 -400.516598) (xy 379.082554 -400.50974)
			(xy 379.091952 -400.490182) (xy 379.09246 -400.477736) (xy 379.092968 -400.460718) (xy 379.093013 -400.455922)
			(xy 379.09148 -400.446457) (xy 379.08992 -400.441922) (xy 379.086618 -400.433032) (xy 379.080014 -400.425666)
			(xy 379.064686 -400.408065) (xy 379.038828 -400.369213) (xy 379.018933 -400.326995) (xy 379.005432 -400.28232)
			(xy 378.998614 -400.23615) (xy 378.998226 -400.212814) (xy 378.998226 -400.21256) (xy 378.998604 -400.190487)
			(xy 379.004725 -400.146768) (xy 379.010418 -400.125438) (xy 379.01372 -400.113754) (xy 379.011688 -400.102324)
			(xy 379.010441 -400.096568) (xy 379.005704 -400.085787) (xy 379.00229 -400.080988) (xy 378.953268 -400.016218)
			(xy 378.945716 -400.00715) (xy 378.924664 -399.996547) (xy 378.912882 -399.995898) (xy 378.601224 -399.995898)
			(xy 378.59116 -399.995461) (xy 378.572576 -399.987727) (xy 378.565156 -399.980912) (xy 378.413264 -399.82902)
			(xy 378.406423 -399.82162) (xy 378.398708 -399.803021) (xy 378.398278 -399.792952) (xy 378.398278 -398.188942)
			(xy 378.398028 -398.181529) (xy 378.393772 -398.167326) (xy 378.389896 -398.161002) (xy 378.385832 -398.154652)
			(xy 378.374402 -398.145254) (xy 378.36729 -398.142206) (xy 378.345127 -398.132372) (xy 378.303824 -398.106977)
			(xy 378.266862 -398.075599) (xy 378.235098 -398.038967) (xy 378.20927 -397.997934) (xy 378.189978 -397.953452)
			(xy 378.183394 -397.930116) (xy 378.181616 -397.923512) (xy 377.875038 -397.392652) (xy 377.86691 -397.381984)
			(xy 377.849427 -397.363973) (xy 377.819792 -397.323464) (xy 377.796891 -397.2788) (xy 377.781292 -397.231093)
			(xy 377.773385 -397.181528) (xy 377.77293 -397.156432) (xy 377.773184 -397.144748) (xy 377.773438 -397.13408)
			(xy 377.769628 -397.124428) (xy 377.767599 -397.119558) (xy 377.761838 -397.110721) (xy 377.758198 -397.106902)
			(xy 377.22556 -396.574264) (xy 377.218713 -396.566866) (xy 377.210982 -396.548268) (xy 377.210574 -396.538196)
			(xy 377.210574 -395.581632) (xy 377.210404 -395.575623) (xy 377.207576 -395.563943) (xy 377.204986 -395.558518)
			(xy 377.203148 -395.555043) (xy 377.198557 -395.548661) (xy 377.195842 -395.545818) (xy 376.946668 -395.296644)
			(xy 376.943816 -395.293939) (xy 376.937436 -395.289349) (xy 376.933968 -395.2875) (xy 376.928541 -395.284916)
			(xy 376.916862 -395.282089) (xy 376.910854 -395.281912) (xy 375.689368 -395.281912) (xy 375.682002 -395.28242)
			(xy 375.67338 -395.284094) (xy 375.657921 -395.292402) (xy 375.651776 -395.298676) (xy 375.600468 -395.361414)
			(xy 375.596945 -395.36587) (xy 375.59181 -395.376002) (xy 375.590308 -395.38148) (xy 375.587768 -395.391894)
			(xy 375.590054 -395.403324) (xy 375.593003 -395.418841) (xy 375.59618 -395.450269) (xy 375.596404 -395.466062)
			(xy 375.596035 -395.487083) (xy 375.590434 -395.528751) (xy 375.585228 -395.54912) (xy 375.583704 -395.555724)
			(xy 375.583704 -395.567662) (xy 375.583277 -395.582145) (xy 375.576036 -395.610193) (xy 375.562027 -395.635548)
			(xy 375.542135 -395.656606) (xy 375.53011 -395.66469) (xy 375.529348 -395.669262) (xy 375.528438 -395.674436)
			(xy 375.528563 -395.68494) (xy 375.529602 -395.69009) (xy 375.54662 -395.764258) (xy 375.547984 -395.76947)
			(xy 375.552587 -395.77921) (xy 375.555764 -395.783562) (xy 375.56186 -395.79169) (xy 375.571766 -395.797024)
			(xy 375.596006 -395.811017) (xy 375.639571 -395.846147) (xy 375.65838 -395.866874) (xy 375.660861 -395.869628)
			(xy 375.666466 -395.874478) (xy 375.669556 -395.876526) (xy 375.681693 -395.884615) (xy 375.701769 -395.905763)
			(xy 375.715919 -395.931259) (xy 375.723244 -395.959483) (xy 375.723658 -395.974062) (xy 375.723658 -395.986508)
			(xy 375.725436 -395.992858) (xy 375.728752 -396.005812) (xy 375.733458 -396.032136) (xy 375.734834 -396.045436)
			(xy 375.734834 -396.045944) (xy 375.736358 -396.061184) (xy 375.736358 -396.075662) (xy 375.736042 -396.096612)
			(xy 375.730564 -396.138151) (xy 375.725436 -396.158466) (xy 375.723658 -396.16507) (xy 375.723658 -396.621254)
			(xy 375.725436 -396.627858) (xy 375.730521 -396.648116) (xy 375.735995 -396.689524) (xy 375.736358 -396.710408)
			(xy 375.736358 -396.710662) (xy 376.300492 -396.710662) (xy 376.300859 -396.689641) (xy 376.306469 -396.647975)
			(xy 376.311668 -396.627604) (xy 376.313192 -396.621) (xy 376.313192 -396.507462) (xy 376.3136 -396.492461)
			(xy 376.321365 -396.46348) (xy 376.336356 -396.437491) (xy 376.357556 -396.41626) (xy 376.383522 -396.40123)
			(xy 376.412491 -396.393423) (xy 376.427492 -396.392908) (xy 376.60961 -396.392908) (xy 376.610118 -396.392654)
			(xy 376.626882 -396.392654) (xy 376.62739 -396.392908) (xy 376.809 -396.392908) (xy 376.82403 -396.39338)
			(xy 376.85307 -396.40115) (xy 376.879113 -396.416163) (xy 376.900392 -396.437397) (xy 376.915458 -396.46341)
			(xy 376.923289 -396.492433) (xy 376.923808 -396.507462) (xy 376.923808 -396.621) (xy 376.925332 -396.627604)
			(xy 376.930524 -396.647976) (xy 376.936134 -396.689642) (xy 376.936508 -396.710662) (xy 376.936508 -396.71117)
			(xy 376.936337 -396.725795) (xy 376.933671 -396.754924) (xy 376.931174 -396.769336) (xy 376.929814 -396.77851)
			(xy 376.933085 -396.796752) (xy 376.937524 -396.804896) (xy 376.954034 -396.83182) (xy 376.959207 -396.839595)
			(xy 376.973931 -396.851059) (xy 376.982736 -396.854172) (xy 377.007623 -396.862219) (xy 377.054502 -396.885412)
			(xy 377.096913 -396.91602) (xy 377.133696 -396.953203) (xy 377.163841 -396.995944) (xy 377.186525 -397.043072)
			(xy 377.194318 -397.06804) (xy 377.195842 -397.073882) (xy 377.516136 -397.627602) (xy 377.5202 -397.63192)
			(xy 377.536392 -397.649639) (xy 377.563818 -397.689027) (xy 377.584963 -397.732113) (xy 377.599339 -397.777905)
			(xy 377.606616 -397.825346) (xy 377.607068 -397.849344) (xy 377.606603 -397.874808) (xy 377.598402 -397.925071)
			(xy 377.582238 -397.973365) (xy 377.558529 -398.018437) (xy 377.52789 -398.059117) (xy 377.491117 -398.09435)
			(xy 377.470416 -398.109186) (xy 377.46191 -398.115629) (xy 377.450716 -398.13377) (xy 377.447846 -398.154892)
			(xy 377.453794 -398.175362) (xy 377.467535 -398.191659) (xy 377.486707 -398.200977) (xy 377.49734 -398.201896)
			(xy 377.507246 -398.201388) (xy 377.515696 -398.200099) (xy 377.532735 -398.198702) (xy 377.541282 -398.198594)
			(xy 377.541536 -398.198848) (xy 377.840748 -398.198848) (xy 377.841002 -398.198594) (xy 377.862047 -398.199032)
			(xy 377.903366 -398.207021) (xy 377.942321 -398.222946) (xy 377.977403 -398.246191) (xy 378.007255 -398.275855)
			(xy 378.03072 -398.31079) (xy 378.04689 -398.349644) (xy 378.05514 -398.390912) (xy 378.055632 -398.411954)
			(xy 378.055632 -398.666716) (xy 378.046488 -398.666716) (xy 378.036464 -398.66711) (xy 378.017944 -398.674787)
			(xy 378.003771 -398.688967) (xy 377.996105 -398.707492) (xy 377.995688 -398.717516) (xy 377.995688 -398.881092)
			(xy 377.995274 -398.891114) (xy 377.987604 -398.909633) (xy 377.97343 -398.923806) (xy 377.95491 -398.931475)
			(xy 377.944888 -398.931892) (xy 377.437396 -398.931892) (xy 377.427373 -398.931484) (xy 377.408855 -398.923811)
			(xy 377.394683 -398.909635) (xy 377.387014 -398.891115) (xy 377.386596 -398.881092) (xy 377.386596 -398.717516)
			(xy 377.386167 -398.707495) (xy 377.378502 -398.688978) (xy 377.364332 -398.674805) (xy 377.345817 -398.667135)
			(xy 377.335796 -398.666716) (xy 377.326652 -398.666716) (xy 377.326652 -398.411446) (xy 377.327433 -398.385723)
			(xy 377.339768 -398.335777) (xy 377.351036 -398.31264) (xy 377.356878 -398.30121) (xy 377.356624 -398.27581)
			(xy 377.309126 -398.190212) (xy 377.302426 -398.179417) (xy 377.281086 -398.165686) (xy 377.268486 -398.16405)
			(xy 377.244609 -398.161895) (xy 377.197865 -398.15126) (xy 377.153268 -398.133673) (xy 377.111847 -398.109538)
			(xy 377.074555 -398.079413) (xy 377.042253 -398.043991) (xy 377.015683 -398.004088) (xy 376.995459 -397.960623)
			(xy 376.988324 -397.937736) (xy 376.9868 -397.931894) (xy 376.666506 -397.378174) (xy 376.662442 -397.373856)
			(xy 376.646281 -397.356124) (xy 376.618913 -397.316721) (xy 376.597823 -397.273631) (xy 376.583496 -397.227846)
			(xy 376.576262 -397.18042) (xy 376.575828 -397.156432) (xy 376.57601 -397.142384) (xy 376.57855 -397.114402)
			(xy 376.580908 -397.100552) (xy 376.582229 -397.091272) (xy 376.578702 -397.072876) (xy 376.57405 -397.064738)
			(xy 376.557286 -397.037814) (xy 376.552095 -397.030102) (xy 376.537362 -397.018783) (xy 376.528584 -397.015716)
			(xy 376.506962 -397.008903) (xy 376.465747 -396.990025) (xy 376.427626 -396.965493) (xy 376.393369 -396.935804)
			(xy 376.378216 -396.918942) (xy 376.375755 -396.916168) (xy 376.370142 -396.911323) (xy 376.36704 -396.90929)
			(xy 376.354976 -396.901233) (xy 376.33502 -396.880188) (xy 376.320946 -396.85483) (xy 376.313645 -396.826762)
			(xy 376.313192 -396.812262) (xy 376.313192 -396.800324) (xy 376.311668 -396.79372) (xy 376.306462 -396.773351)
			(xy 376.300861 -396.731683) (xy 376.300492 -396.710662) (xy 375.736358 -396.710662) (xy 375.736358 -396.710916)
			(xy 375.736104 -396.726664) (xy 375.735596 -396.731998) (xy 375.731278 -396.767558) (xy 375.730262 -396.772638)
			(xy 375.729969 -396.780105) (xy 375.733207 -396.794687) (xy 375.736612 -396.80134) (xy 375.749312 -396.821914)
			(xy 375.751817 -396.825735) (xy 375.757949 -396.832506) (xy 375.761504 -396.835376) (xy 375.782586 -396.851632)
			(xy 375.788174 -396.85341) (xy 375.813634 -396.862198) (xy 375.861387 -396.887099) (xy 375.88317 -396.90294)
			(xy 375.903782 -396.919282) (xy 375.939863 -396.957553) (xy 375.969169 -397.00123) (xy 375.990902 -397.049127)
			(xy 375.998232 -397.07439) (xy 376.00001 -397.080994) (xy 376.315986 -397.627602) (xy 376.32005 -397.63192)
			(xy 376.336211 -397.649588) (xy 376.363548 -397.688897) (xy 376.384627 -397.731887) (xy 376.398963 -397.77757)
			(xy 376.406228 -397.824896) (xy 376.406664 -397.848836) (xy 376.406664 -397.849344) (xy 376.406183 -397.874796)
			(xy 376.398024 -397.925042) (xy 376.381908 -397.973328) (xy 376.358253 -398.018402) (xy 376.327671 -398.059096)
			(xy 376.290956 -398.094356) (xy 376.270266 -398.109186) (xy 376.261778 -398.115675) (xy 376.250597 -398.133851)
			(xy 376.247763 -398.155002) (xy 376.253767 -398.17548) (xy 376.267571 -398.191753) (xy 376.286796 -398.201015)
			(xy 376.297444 -398.201896) (xy 376.307096 -398.201388) (xy 376.315607 -398.200075) (xy 376.332774 -398.198681)
			(xy 376.341386 -398.198594) (xy 376.34164 -398.198848) (xy 376.640852 -398.198848) (xy 376.641106 -398.198594)
			(xy 376.662155 -398.198954) (xy 376.703481 -398.206948) (xy 376.74244 -398.222881) (xy 376.777525 -398.246137)
			(xy 376.807375 -398.275814) (xy 376.830834 -398.310763) (xy 376.846993 -398.349629) (xy 376.855227 -398.390908)
			(xy 376.855736 -398.411954) (xy 376.855736 -398.615916) (xy 376.855246 -398.625924) (xy 376.847585 -398.644417)
			(xy 376.833434 -398.658573) (xy 376.814944 -398.666242) (xy 376.804936 -398.666716) (xy 376.795792 -398.666716)
			(xy 376.795792 -398.881092) (xy 376.795374 -398.891114) (xy 376.787705 -398.909632) (xy 376.773532 -398.923805)
			(xy 376.755014 -398.931474) (xy 376.744992 -398.931892) (xy 376.2375 -398.931892) (xy 376.227479 -398.931472)
			(xy 376.208964 -398.923802) (xy 376.194793 -398.90963) (xy 376.187126 -398.891113) (xy 376.1867 -398.881092)
			(xy 376.1867 -398.717516) (xy 376.186283 -398.707493) (xy 376.178616 -398.68897) (xy 376.164443 -398.674793)
			(xy 376.145923 -398.66712) (xy 376.1359 -398.666716) (xy 376.126756 -398.666716) (xy 376.126756 -398.411446)
			(xy 376.127552 -398.385725) (xy 376.139876 -398.335778) (xy 376.15114 -398.31264) (xy 376.156982 -398.30121)
			(xy 376.156728 -398.27581) (xy 376.10923 -398.190212) (xy 376.102521 -398.179424) (xy 376.081187 -398.165695)
			(xy 376.06859 -398.16405) (xy 376.044704 -398.161882) (xy 375.99794 -398.151242) (xy 375.953321 -398.133654)
			(xy 375.911874 -398.109524) (xy 375.874552 -398.079405) (xy 375.842211 -398.04399) (xy 375.815596 -398.004093)
			(xy 375.795319 -397.960631) (xy 375.788174 -397.937736) (xy 375.78665 -397.931894) (xy 375.471944 -397.387572)
			(xy 375.469912 -397.385794) (xy 375.455688 -397.383508) (xy 375.448368 -397.382648) (xy 375.433783 -397.384721)
			(xy 375.426986 -397.387572) (xy 375.341642 -397.42618) (xy 375.333216 -397.430669) (xy 375.32021 -397.44463)
			(xy 375.31317 -397.462363) (xy 375.312686 -397.4719) (xy 375.312686 -398.160748) (xy 375.3132 -398.171582)
			(xy 375.322154 -398.191314) (xy 375.329958 -398.198848) (xy 375.440956 -398.198848) (xy 375.44121 -398.198594)
			(xy 375.462258 -398.198955) (xy 375.503584 -398.206949) (xy 375.542543 -398.222883) (xy 375.577626 -398.246138)
			(xy 375.607476 -398.275815) (xy 375.630934 -398.310764) (xy 375.647093 -398.34963) (xy 375.655327 -398.390908)
			(xy 375.65584 -398.411954) (xy 375.65584 -398.666716) (xy 375.653046 -398.666716) (xy 375.628154 -398.726406)
			(xy 375.62917 -398.728438) (xy 375.631045 -398.731832) (xy 375.635639 -398.738078) (xy 375.638314 -398.740884)
			(xy 375.921778 -399.024348) (xy 375.928619 -399.031748) (xy 375.93634 -399.050346) (xy 375.936764 -399.060416)
			(xy 375.936764 -399.963132) (xy 375.936764 -399.963386) (xy 375.937119 -399.971837) (xy 375.942701 -399.987795)
			(xy 375.947686 -399.994628) (xy 375.963907 -400.012414) (xy 375.991336 -400.05197) (xy 376.012473 -400.095217)
			(xy 376.026835 -400.14116) (xy 376.03409 -400.188746) (xy 376.034554 -400.212814) (xy 376.034121 -400.236527)
			(xy 376.027085 -400.283427) (xy 376.013157 -400.32876) (xy 375.992645 -400.37152) (xy 375.966007 -400.410756)
			(xy 375.950226 -400.42846) (xy 375.943368 -400.43608) (xy 375.94032 -400.444208) (xy 375.93868 -400.448602)
			(xy 375.936897 -400.457808) (xy 375.936764 -400.462496) (xy 375.936764 -400.485864) (xy 375.94667 -400.506438)
			(xy 375.955814 -400.513804) (xy 375.977635 -400.532036) (xy 376.016158 -400.57386) (xy 376.048052 -400.620934)
			(xy 376.072614 -400.672218) (xy 376.089299 -400.726576) (xy 376.09774 -400.782807) (xy 376.098308 -400.811238)
			(xy 376.098308 -401.674838) (xy 376.53468 -401.674838) (xy 376.53468 -400.811238) (xy 376.535093 -400.785717)
			(xy 376.541884 -400.73513) (xy 376.555362 -400.685901) (xy 376.575288 -400.63891) (xy 376.601304 -400.594997)
			(xy 376.632945 -400.554947) (xy 376.651012 -400.536918) (xy 376.657616 -400.530568) (xy 376.66549 -400.513804)
			(xy 376.672348 -400.42846) (xy 376.667268 -400.41068) (xy 376.66168 -400.403314) (xy 376.646823 -400.38257)
			(xy 376.623191 -400.337354) (xy 376.607091 -400.288942) (xy 376.598939 -400.238578) (xy 376.598434 -400.213068)
			(xy 376.598434 -400.212814) (xy 376.598924 -400.187825) (xy 376.606743 -400.138462) (xy 376.622187 -400.09093)
			(xy 376.644877 -400.046398) (xy 376.674253 -400.005965) (xy 376.709593 -399.970625) (xy 376.750026 -399.941249)
			(xy 376.794558 -399.918559) (xy 376.84209 -399.903115) (xy 376.891453 -399.895296) (xy 376.941431 -399.895296)
			(xy 376.990794 -399.903115) (xy 377.038326 -399.918559) (xy 377.082858 -399.941249) (xy 377.123291 -399.970625)
			(xy 377.158631 -400.005965) (xy 377.188007 -400.046398) (xy 377.210697 -400.09093) (xy 377.226141 -400.138462)
			(xy 377.23396 -400.187825) (xy 377.23445 -400.212814) (xy 377.23445 -400.213068) (xy 377.233947 -400.238577)
			(xy 377.225771 -400.288935) (xy 377.209672 -400.337346) (xy 377.18606 -400.382571) (xy 377.171204 -400.403314)
			(xy 377.165616 -400.41068) (xy 377.160536 -400.42846) (xy 377.167394 -400.513804) (xy 377.175268 -400.530568)
			(xy 377.181872 -400.536918) (xy 377.199909 -400.554974) (xy 377.231539 -400.595026) (xy 377.257549 -400.638936)
			(xy 377.277476 -400.68592) (xy 377.290965 -400.735141) (xy 377.297774 -400.78572) (xy 377.298204 -400.811238)
			(xy 377.298204 -401.674838) (xy 377.298194 -401.675346) (xy 377.735084 -401.675346) (xy 377.735084 -400.81073)
			(xy 377.735529 -400.785262) (xy 377.742331 -400.734783) (xy 377.755791 -400.685658) (xy 377.77567 -400.638762)
			(xy 377.801614 -400.594929) (xy 377.833162 -400.55494) (xy 377.851162 -400.536918) (xy 377.857766 -400.530568)
			(xy 377.86564 -400.513804) (xy 377.872498 -400.42846) (xy 377.867418 -400.41068) (xy 377.86183 -400.403314)
			(xy 377.846979 -400.382566) (xy 377.823344 -400.337352) (xy 377.807243 -400.288941) (xy 377.79909 -400.238577)
			(xy 377.798584 -400.213068) (xy 377.798584 -400.212814) (xy 377.799074 -400.187825) (xy 377.806893 -400.138462)
			(xy 377.822337 -400.09093) (xy 377.845027 -400.046398) (xy 377.874403 -400.005965) (xy 377.909743 -399.970625)
			(xy 377.950176 -399.941249) (xy 377.994708 -399.918559) (xy 378.04224 -399.903115) (xy 378.091603 -399.895296)
			(xy 378.141581 -399.895296) (xy 378.190944 -399.903115) (xy 378.238476 -399.918559) (xy 378.283008 -399.941249)
			(xy 378.323441 -399.970625) (xy 378.358781 -400.005965) (xy 378.388157 -400.046398) (xy 378.410847 -400.09093)
			(xy 378.426291 -400.138462) (xy 378.43411 -400.187825) (xy 378.4346 -400.212814) (xy 378.4346 -400.213068)
			(xy 378.434107 -400.238577) (xy 378.42593 -400.288936) (xy 378.409828 -400.337348) (xy 378.386212 -400.382572)
			(xy 378.371354 -400.403314) (xy 378.365766 -400.41068) (xy 378.360686 -400.42846) (xy 378.367544 -400.513804)
			(xy 378.375418 -400.530568) (xy 378.382022 -400.536918) (xy 378.400015 -400.554946) (xy 378.431558 -400.594938)
			(xy 378.457501 -400.63877) (xy 378.477382 -400.685664) (xy 378.490848 -400.734786) (xy 378.497659 -400.785263)
			(xy 378.4981 -400.81073) (xy 378.4981 -401.675346) (xy 378.497611 -401.703743) (xy 378.489199 -401.759911)
			(xy 378.472539 -401.814206) (xy 378.448 -401.865425) (xy 378.416127 -401.912432) (xy 378.397262 -401.933664)
			(xy 378.391395 -401.940595) (xy 378.384493 -401.957377) (xy 378.3838 -401.96643) (xy 378.382784 -401.997418)
			(xy 378.382841 -402.006569) (xy 378.388708 -402.02389) (xy 378.394214 -402.0312) (xy 378.40955 -402.050553)
			(xy 378.435326 -402.092671) (xy 378.455107 -402.137916) (xy 378.468521 -402.185439) (xy 378.475316 -402.234349)
			(xy 378.475748 -402.259038) (xy 378.475246 -402.285915) (xy 378.467234 -402.33907) (xy 378.45139 -402.390436)
			(xy 378.428066 -402.438868) (xy 378.397785 -402.483282) (xy 378.361223 -402.522687) (xy 378.319195 -402.556203)
			(xy 378.272642 -402.58308) (xy 378.222603 -402.602719) (xy 378.170196 -402.61468) (xy 378.116592 -402.618698)
			(xy 378.062988 -402.61468) (xy 378.010581 -402.602719) (xy 377.960542 -402.58308) (xy 377.913989 -402.556203)
			(xy 377.871961 -402.522687) (xy 377.835399 -402.483282) (xy 377.805118 -402.438868) (xy 377.781794 -402.390436)
			(xy 377.76595 -402.33907) (xy 377.757938 -402.285915) (xy 377.757436 -402.259038) (xy 377.757849 -402.234345)
			(xy 377.764605 -402.185423) (xy 377.778006 -402.13789) (xy 377.797801 -402.092645) (xy 377.823616 -402.050543)
			(xy 377.83897 -402.0312) (xy 377.844454 -402.023882) (xy 377.850298 -402.006564) (xy 377.8504 -401.997418)
			(xy 377.849384 -401.96643) (xy 377.848733 -401.957367) (xy 377.841822 -401.940575) (xy 377.835922 -401.933664)
			(xy 377.817112 -401.912393) (xy 377.78529 -401.865369) (xy 377.760772 -401.814156) (xy 377.744098 -401.75988)
			(xy 377.735635 -401.703735) (xy 377.735084 -401.675346) (xy 377.298194 -401.675346) (xy 377.29763 -401.704001)
			(xy 377.28871 -401.761641) (xy 377.271129 -401.817255) (xy 377.245296 -401.869549) (xy 377.211812 -401.917307)
			(xy 377.192032 -401.938744) (xy 377.185867 -401.945822) (xy 377.178715 -401.963161) (xy 377.178062 -401.972526)
			(xy 377.176284 -402.041106) (xy 377.176431 -402.050362) (xy 377.182563 -402.067815) (xy 377.188222 -402.075142)
			(xy 377.18873 -402.07565) (xy 377.205084 -402.095263) (xy 377.232616 -402.138272) (xy 377.253774 -402.18475)
			(xy 377.268128 -402.233757) (xy 377.275391 -402.284305) (xy 377.275852 -402.309838) (xy 377.27535 -402.336734)
			(xy 377.267332 -402.389926) (xy 377.251476 -402.441329) (xy 377.228137 -402.489795) (xy 377.197834 -402.534241)
			(xy 377.161246 -402.573674) (xy 377.119189 -402.607213) (xy 377.072603 -402.634109) (xy 377.022529 -402.653762)
			(xy 376.970084 -402.665732) (xy 376.916442 -402.669752) (xy 376.8628 -402.665732) (xy 376.810355 -402.653762)
			(xy 376.760281 -402.634109) (xy 376.713695 -402.607213) (xy 376.671638 -402.573674) (xy 376.63505 -402.534241)
			(xy 376.604747 -402.489795) (xy 376.581408 -402.441329) (xy 376.565552 -402.389926) (xy 376.557534 -402.336734)
			(xy 376.557032 -402.309838) (xy 376.557513 -402.28427) (xy 376.564789 -402.233656) (xy 376.579184 -402.184588)
			(xy 376.600406 -402.138065) (xy 376.628024 -402.09503) (xy 376.644408 -402.075396) (xy 376.644662 -402.075142)
			(xy 376.650325 -402.06782) (xy 376.656437 -402.050362) (xy 376.6566 -402.041106) (xy 376.654568 -401.962874)
			(xy 376.647456 -401.945856) (xy 376.640852 -401.938744) (xy 376.621075 -401.917303) (xy 376.58758 -401.869552)
			(xy 376.561742 -401.817259) (xy 376.544163 -401.761644) (xy 376.535251 -401.704001) (xy 376.53468 -401.674838)
			(xy 376.098308 -401.674838) (xy 376.097737 -401.704001) (xy 376.088825 -401.761644) (xy 376.071245 -401.817259)
			(xy 376.045406 -401.869551) (xy 376.011911 -401.917301) (xy 375.992136 -401.938744) (xy 375.985532 -401.945856)
			(xy 375.97842 -401.962874) (xy 375.976134 -402.050504) (xy 375.98223 -402.06803) (xy 375.985278 -402.071586)
			(xy 376.002217 -402.091398) (xy 376.030791 -402.134992) (xy 376.052765 -402.182257) (xy 376.06768 -402.232201)
			(xy 376.07522 -402.283776) (xy 376.075702 -402.309838) (xy 376.075702 -402.31695) (xy 376.074529 -402.346959)
			(xy 376.063415 -402.405973) (xy 376.042628 -402.462313) (xy 376.028204 -402.488654) (xy 376.025156 -402.494242)
			(xy 376.018298 -402.519134) (xy 376.018869 -402.529058) (xy 376.026574 -402.547361) (xy 376.033284 -402.554694)
			(xy 376.308112 -402.829522) (xy 376.31547 -402.836166) (xy 376.333771 -402.843739) (xy 376.343672 -402.844254)
			(xy 382.897634 -402.844254)
		)
		(stroke
			(width 0)
			(type solid)
		)
		(fill yes)
		(layer "B.Cu")
		(net "P0V9_CPU0_RT_2D")
	)
	(gr_poly
		(pts
			(xy 59.807602 -394.461238) (xy 59.814842 -394.459603) (xy 59.827999 -394.452749) (xy 59.83351 -394.447776)
			(xy 59.911742 -394.369544) (xy 59.918165 -394.362542) (xy 59.925762 -394.34514) (xy 59.926533 -394.326168)
			(xy 59.920373 -394.308207) (xy 59.914536 -394.30071) (xy 59.911234 -394.297408) (xy 59.906946 -394.293392)
			(xy 59.896936 -394.287245) (xy 59.891422 -394.285216) (xy 59.880754 -394.28166) (xy 59.874658 -394.282676)
			(xy 59.868562 -394.283438) (xy 59.855681 -394.285205) (xy 59.829747 -394.287114) (xy 59.816746 -394.287248)
			(xy 59.816492 -394.287248) (xy 59.790828 -394.286776) (xy 59.740026 -394.279445) (xy 59.690783 -394.264962)
			(xy 59.644101 -394.243621) (xy 59.60093 -394.215856) (xy 59.562147 -394.182233) (xy 59.528542 -394.143434)
			(xy 59.500798 -394.10025) (xy 59.479479 -394.053558) (xy 59.465019 -394.004308) (xy 59.457712 -393.953502)
			(xy 59.457336 -393.927838) (xy 59.457336 -393.926568) (xy 59.457997 -393.898137) (xy 59.467193 -393.84202)
			(xy 59.485111 -393.78805) (xy 59.511305 -393.737576) (xy 59.545122 -393.691858) (xy 59.565032 -393.671552)
			(xy 59.572144 -393.66444) (xy 59.575954 -393.655804) (xy 59.577889 -393.651142) (xy 59.580065 -393.641289)
			(xy 59.580272 -393.636246) (xy 59.580526 -393.616942) (xy 59.580172 -393.605996) (xy 59.571353 -393.585975)
			(xy 59.563508 -393.578334) (xy 59.543683 -393.560152) (xy 59.508832 -393.519177) (xy 59.480082 -393.473712)
			(xy 59.458004 -393.42466) (xy 59.443036 -393.372992) (xy 59.435474 -393.319734) (xy 59.434984 -393.292838)
			(xy 59.434984 -392.429238) (xy 59.435488 -392.401138) (xy 59.443742 -392.345548) (xy 59.460062 -392.29177)
			(xy 59.484094 -392.240968) (xy 59.515319 -392.194241) (xy 59.553061 -392.1526) (xy 59.57443 -392.134344)
			(xy 59.583066 -392.127486) (xy 59.592718 -392.107928) (xy 59.592972 -392.096752) (xy 59.59348 -392.079226)
			(xy 59.593467 -392.074357) (xy 59.591805 -392.064765) (xy 59.590178 -392.060176) (xy 59.58713 -392.05154)
			(xy 59.580272 -392.04392) (xy 59.564957 -392.026311) (xy 59.539118 -391.987451) (xy 59.519231 -391.945233)
			(xy 59.505723 -391.900564) (xy 59.498883 -391.854401) (xy 59.498484 -391.831068) (xy 59.498484 -391.830814)
			(xy 59.498947 -391.805822) (xy 59.506765 -391.756453) (xy 59.522209 -391.708914) (xy 59.544899 -391.664377)
			(xy 59.574278 -391.623938) (xy 59.609621 -391.588592) (xy 59.650058 -391.559211) (xy 59.694594 -391.536517)
			(xy 59.742131 -391.52107) (xy 59.7915 -391.513249) (xy 59.816492 -391.512806) (xy 59.816492 -391.512552)
			(xy 59.838377 -391.512946) (xy 59.881724 -391.519015) (xy 59.923827 -391.530984) (xy 59.944 -391.539476)
			(xy 59.944254 -391.539476) (xy 59.95018 -391.541848) (xy 59.962774 -391.543908) (xy 59.969146 -391.54354)
			(xy 59.981084 -391.542524) (xy 60.065158 -391.48766) (xy 60.074541 -391.480049) (xy 60.085538 -391.458574)
			(xy 60.08624 -391.446512) (xy 60.08624 -389.866886) (xy 60.086543 -389.859628) (xy 60.090674 -389.845709)
			(xy 60.094368 -389.839454) (xy 60.098432 -389.833358) (xy 60.102496 -389.819388) (xy 60.102496 -389.80872)
			(xy 60.102058 -389.798656) (xy 60.094323 -389.780073) (xy 60.08751 -389.772652) (xy 60.080398 -389.76554)
			(xy 60.071 -389.76173) (xy 60.048131 -389.751865) (xy 60.005529 -389.72607) (xy 59.967472 -389.693946)
			(xy 59.934891 -389.656279) (xy 59.908583 -389.613992) (xy 59.889194 -389.568119) (xy 59.882786 -389.544052)
			(xy 59.882278 -389.542274) (xy 59.566556 -388.996174) (xy 59.562492 -388.991856) (xy 59.546277 -388.974157)
			(xy 59.518848 -388.934767) (xy 59.497705 -388.891676) (xy 59.483335 -388.845878) (xy 59.476072 -388.798432)
			(xy 59.475624 -388.774432) (xy 59.475799 -388.760384) (xy 59.478342 -388.732401) (xy 59.480704 -388.718552)
			(xy 59.482074 -388.709295) (xy 59.478665 -388.690909) (xy 59.4741 -388.682738) (xy 59.457336 -388.655814)
			(xy 59.452131 -388.64811) (xy 59.437413 -388.636775) (xy 59.428634 -388.633716) (xy 59.407001 -388.626927)
			(xy 59.365771 -388.608069) (xy 59.327643 -388.583537) (xy 59.293391 -388.553832) (xy 59.278266 -388.536942)
			(xy 59.275784 -388.534189) (xy 59.270176 -388.529343) (xy 59.26709 -388.52729) (xy 59.255044 -388.51923)
			(xy 59.235137 -388.498177) (xy 59.22113 -388.472812) (xy 59.213914 -388.44475) (xy 59.213496 -388.430262)
			(xy 59.213496 -388.418324) (xy 59.211718 -388.41172) (xy 59.206525 -388.391348) (xy 59.200925 -388.349682)
			(xy 59.200542 -388.328662) (xy 59.200916 -388.307642) (xy 59.206525 -388.265976) (xy 59.211718 -388.245604)
			(xy 59.213496 -388.239) (xy 59.213496 -388.125462) (xy 59.213947 -388.110445) (xy 59.22173 -388.081437)
			(xy 59.236757 -388.055432) (xy 59.258002 -388.034203) (xy 59.284019 -388.019197) (xy 59.313033 -388.011435)
			(xy 59.32805 -388.010908) (xy 59.50966 -388.010908) (xy 59.510168 -388.010654) (xy 59.526932 -388.010654)
			(xy 59.52744 -388.010908) (xy 59.70016 -388.010908) (xy 59.710187 -388.010495) (xy 59.728719 -388.002833)
			(xy 59.742906 -387.98866) (xy 59.750586 -387.970135) (xy 59.75096 -387.960108) (xy 59.75096 -387.011672)
			(xy 59.75053 -387.001605) (xy 59.742804 -386.983012) (xy 59.735974 -386.975604) (xy 59.656726 -386.896356)
			(xy 59.649326 -386.889515) (xy 59.630727 -386.881799) (xy 59.620658 -386.88137) (xy 59.040268 -386.88137)
			(xy 59.034258 -386.881535) (xy 59.022573 -386.884354) (xy 59.017154 -386.886958) (xy 59.013682 -386.888801)
			(xy 59.00731 -386.893401) (xy 59.004454 -386.896102) (xy 58.730896 -387.16966) (xy 58.72819 -387.172511)
			(xy 58.723596 -387.178889) (xy 58.721752 -387.18236) (xy 58.719168 -387.187787) (xy 58.716346 -387.199466)
			(xy 58.716164 -387.205474) (xy 58.716164 -388.450328) (xy 58.716386 -388.457136) (xy 58.719998 -388.470265)
			(xy 58.723276 -388.476236) (xy 58.726578 -388.481824) (xy 58.736484 -388.491222) (xy 58.742834 -388.494778)
			(xy 58.765419 -388.507635) (xy 58.806449 -388.539524) (xy 58.841763 -388.577646) (xy 58.870429 -388.62099)
			(xy 58.891685 -388.668409) (xy 58.89879 -388.693406) (xy 58.90387 -388.705852) (xy 59.216036 -389.245602)
			(xy 59.2201 -389.24992) (xy 59.236317 -389.267618) (xy 59.26375 -389.307007) (xy 59.284897 -389.350098)
			(xy 59.29927 -389.395896) (xy 59.306537 -389.443344) (xy 59.306968 -389.467344) (xy 59.306479 -389.492119)
			(xy 59.298726 -389.541058) (xy 59.283417 -389.588183) (xy 59.260928 -389.632335) (xy 59.231813 -389.672428)
			(xy 59.196788 -389.707476) (xy 59.156714 -389.736618) (xy 59.112577 -389.759136) (xy 59.065462 -389.774477)
			(xy 59.016528 -389.782263) (xy 58.991754 -389.782812) (xy 58.991246 -389.782812) (xy 58.96585 -389.782308)
			(xy 58.915712 -389.774183) (xy 58.867522 -389.758137) (xy 58.822523 -389.734582) (xy 58.781875 -389.704126)
			(xy 58.746627 -389.667556) (xy 58.717689 -389.625814) (xy 58.695807 -389.579978) (xy 58.688224 -389.555736)
			(xy 58.6867 -389.549894) (xy 58.481976 -389.195564) (xy 58.47558 -389.185651) (xy 58.455986 -389.172563)
			(xy 58.444384 -389.170418) (xy 58.4327 -389.168894) (xy 58.410602 -389.176514) (xy 58.122566 -389.46455)
			(xy 58.119566 -389.46764) (xy 58.114588 -389.474668) (xy 58.11266 -389.47852) (xy 58.10885 -389.486648)
			(xy 58.108088 -389.495792) (xy 58.105209 -389.522017) (xy 58.091878 -389.573061) (xy 58.070308 -389.621206)
			(xy 58.04109 -389.665131) (xy 58.005025 -389.703634) (xy 57.98439 -389.720074) (xy 57.984136 -389.720328)
			(xy 57.979593 -389.723986) (xy 57.972148 -389.732961) (xy 57.969404 -389.738108) (xy 57.966864 -389.743188)
			(xy 57.964324 -389.754364) (xy 57.964324 -389.767064) (xy 58.004202 -389.803386) (xy 58.011536 -389.809545)
			(xy 58.029426 -389.816341) (xy 58.039 -389.816594) (xy 58.04154 -389.816594) (xy 58.041794 -389.816848)
			(xy 58.341006 -389.816848) (xy 58.34126 -389.816594) (xy 58.358309 -389.816825) (xy 58.392 -389.822056)
			(xy 58.408316 -389.827008) (xy 58.415936 -389.829548) (xy 58.4454 -389.829548) (xy 58.458766 -389.829982)
			(xy 58.484591 -389.836888) (xy 58.507755 -389.850232) (xy 58.526686 -389.869107) (xy 58.540097 -389.892232)
			(xy 58.547079 -389.918037) (xy 58.547508 -389.931402) (xy 58.547508 -389.97001) (xy 58.549032 -389.97636)
			(xy 58.552301 -389.989519) (xy 58.555874 -390.016398) (xy 58.556144 -390.029954) (xy 58.556144 -390.284716)
			(xy 58.547508 -390.284716) (xy 58.547508 -390.388602) (xy 58.546992 -390.403126) (xy 58.538814 -390.430998)
			(xy 58.523121 -390.45544) (xy 58.512456 -390.46531) (xy 58.511694 -390.465818) (xy 58.504836 -390.472168)
			(xy 58.4962 -390.491726) (xy 58.4962 -390.499092) (xy 58.495782 -390.509114) (xy 58.488113 -390.527634)
			(xy 58.473941 -390.541809) (xy 58.455422 -390.54948) (xy 58.4454 -390.549892) (xy 58.015124 -390.549892)
			(xy 58.005099 -390.550307) (xy 57.986572 -390.557973) (xy 57.972391 -390.572146) (xy 57.964714 -390.590667)
			(xy 57.964324 -390.600692) (xy 57.964324 -390.642602) (xy 59.009788 -390.642602) (xy 59.009788 -390.160002)
			(xy 59.010274 -390.132751) (xy 59.01803 -390.078803) (xy 59.033385 -390.026508) (xy 59.056027 -389.976931)
			(xy 59.085493 -389.931081) (xy 59.121184 -389.88989) (xy 59.162375 -389.854199) (xy 59.208225 -389.824733)
			(xy 59.257802 -389.802091) (xy 59.310097 -389.786736) (xy 59.364045 -389.77898) (xy 59.418547 -389.77898)
			(xy 59.472495 -389.786736) (xy 59.52479 -389.802091) (xy 59.574367 -389.824733) (xy 59.620217 -389.854199)
			(xy 59.661408 -389.88989) (xy 59.697099 -389.931081) (xy 59.726565 -389.976931) (xy 59.749207 -390.026508)
			(xy 59.764562 -390.078803) (xy 59.772318 -390.132751) (xy 59.772804 -390.160002) (xy 59.772804 -390.642602)
			(xy 59.772318 -390.669853) (xy 59.764562 -390.723801) (xy 59.749207 -390.776096) (xy 59.726565 -390.825673)
			(xy 59.697099 -390.871523) (xy 59.661408 -390.912714) (xy 59.620217 -390.948405) (xy 59.574367 -390.977871)
			(xy 59.52479 -391.000513) (xy 59.472495 -391.015868) (xy 59.418547 -391.023624) (xy 59.364045 -391.023624)
			(xy 59.310097 -391.015868) (xy 59.257802 -391.000513) (xy 59.208225 -390.977871) (xy 59.162375 -390.948405)
			(xy 59.121184 -390.912714) (xy 59.085493 -390.871523) (xy 59.056027 -390.825673) (xy 59.033385 -390.776096)
			(xy 59.01803 -390.723801) (xy 59.010274 -390.669853) (xy 59.009788 -390.642602) (xy 57.964324 -390.642602)
			(xy 57.964324 -391.445496) (xy 57.963902 -391.455567) (xy 57.956192 -391.474175) (xy 57.949338 -391.481564)
			(xy 57.83199 -391.598912) (xy 57.82717 -391.60347) (xy 57.815724 -391.610169) (xy 57.809384 -391.61212)
			(xy 57.801397 -391.614616) (xy 57.787519 -391.623944) (xy 57.782206 -391.630408) (xy 57.734708 -391.6934)
			(xy 57.73039 -391.699242) (xy 57.726973 -391.70397) (xy 57.72222 -391.714621) (xy 57.720992 -391.720324)
			(xy 57.71896 -391.731754) (xy 57.721246 -391.740136) (xy 57.727999 -391.764641) (xy 57.73451 -391.815049)
			(xy 57.7342 -391.840466) (xy 57.732787 -391.868383) (xy 57.721402 -391.923104) (xy 57.700644 -391.974999)
			(xy 57.671149 -392.022475) (xy 57.65292 -392.043666) (xy 57.646062 -392.051032) (xy 57.64276 -392.059922)
			(xy 57.641243 -392.064468) (xy 57.63971 -392.073926) (xy 57.639712 -392.078718) (xy 57.64022 -392.097514)
			(xy 57.64022 -392.098022) (xy 57.640474 -392.107928) (xy 57.649872 -392.126978) (xy 57.658762 -392.134344)
			(xy 57.680165 -392.152561) (xy 57.717902 -392.194211) (xy 57.74912 -392.240946) (xy 57.773143 -392.291756)
			(xy 57.789452 -392.345541) (xy 57.797692 -392.401136) (xy 57.798208 -392.429238) (xy 57.798208 -393.292838)
			(xy 58.235088 -393.292838) (xy 58.235088 -392.42873) (xy 58.235532 -392.403262) (xy 58.242334 -392.352783)
			(xy 58.255794 -392.303658) (xy 58.275674 -392.256762) (xy 58.301618 -392.212929) (xy 58.333166 -392.172939)
			(xy 58.351166 -392.154918) (xy 58.35777 -392.148568) (xy 58.365644 -392.131804) (xy 58.372502 -392.04646)
			(xy 58.367422 -392.02868) (xy 58.361834 -392.021314) (xy 58.346984 -392.000566) (xy 58.323348 -391.955352)
			(xy 58.307247 -391.906941) (xy 58.299094 -391.856577) (xy 58.298588 -391.831068) (xy 58.298588 -391.830814)
			(xy 58.299078 -391.805825) (xy 58.306897 -391.756462) (xy 58.322341 -391.70893) (xy 58.345031 -391.664398)
			(xy 58.374407 -391.623965) (xy 58.409747 -391.588625) (xy 58.45018 -391.559249) (xy 58.494712 -391.536559)
			(xy 58.542244 -391.521115) (xy 58.591607 -391.513296) (xy 58.641585 -391.513296) (xy 58.690948 -391.521115)
			(xy 58.73848 -391.536559) (xy 58.783012 -391.559249) (xy 58.823445 -391.588625) (xy 58.858785 -391.623965)
			(xy 58.888161 -391.664398) (xy 58.910851 -391.70893) (xy 58.926295 -391.756462) (xy 58.934114 -391.805825)
			(xy 58.934604 -391.830814) (xy 58.934604 -391.831068) (xy 58.93411 -391.856577) (xy 58.925933 -391.906936)
			(xy 58.909831 -391.955348) (xy 58.886216 -392.000572) (xy 58.871358 -392.021314) (xy 58.86577 -392.02868)
			(xy 58.86069 -392.04646) (xy 58.867548 -392.131804) (xy 58.875422 -392.148568) (xy 58.882026 -392.154918)
			(xy 58.90002 -392.172945) (xy 58.931563 -392.212937) (xy 58.957505 -392.25677) (xy 58.977386 -392.303664)
			(xy 58.990852 -392.352786) (xy 58.997663 -392.403263) (xy 58.998104 -392.42873) (xy 58.998104 -393.292838)
			(xy 58.997557 -393.321992) (xy 58.988686 -393.37962) (xy 58.971156 -393.43523) (xy 58.945375 -393.487528)
			(xy 58.911942 -393.535297) (xy 58.892186 -393.556744) (xy 58.886029 -393.563828) (xy 58.878871 -393.581162)
			(xy 58.878216 -393.590526) (xy 58.876438 -393.659106) (xy 58.876574 -393.668363) (xy 58.882712 -393.685817)
			(xy 58.888376 -393.693142) (xy 58.888884 -393.69365) (xy 58.905197 -393.713284) (xy 58.932671 -393.756305)
			(xy 58.953774 -393.802784) (xy 58.968082 -393.851783) (xy 58.975306 -393.902315) (xy 58.975752 -393.927838)
			(xy 58.97525 -393.954715) (xy 58.967238 -394.00787) (xy 58.951394 -394.059236) (xy 58.92807 -394.107668)
			(xy 58.897789 -394.152082) (xy 58.861227 -394.191487) (xy 58.819199 -394.225003) (xy 58.772646 -394.25188)
			(xy 58.722607 -394.271519) (xy 58.6702 -394.28348) (xy 58.616596 -394.287498) (xy 58.562992 -394.28348)
			(xy 58.510585 -394.271519) (xy 58.460546 -394.25188) (xy 58.413993 -394.225003) (xy 58.371965 -394.191487)
			(xy 58.335403 -394.152082) (xy 58.305122 -394.107668) (xy 58.281798 -394.059236) (xy 58.265954 -394.00787)
			(xy 58.257942 -393.954715) (xy 58.25744 -393.927838) (xy 58.257915 -393.902281) (xy 58.265151 -393.851682)
			(xy 58.279496 -393.802622) (xy 58.300659 -393.756095) (xy 58.328212 -393.713044) (xy 58.344562 -393.693396)
			(xy 58.344816 -393.693142) (xy 58.350485 -393.685825) (xy 58.356592 -393.668363) (xy 58.356754 -393.659106)
			(xy 58.354722 -393.580874) (xy 58.34761 -393.563856) (xy 58.341006 -393.556744) (xy 58.321272 -393.535279)
			(xy 58.287833 -393.487515) (xy 58.262048 -393.435222) (xy 58.244515 -393.379616) (xy 58.235643 -393.32199)
			(xy 58.235088 -393.292838) (xy 57.798208 -393.292838) (xy 57.797653 -393.32199) (xy 57.788781 -393.379616)
			(xy 57.771248 -393.435222) (xy 57.745462 -393.487515) (xy 57.712024 -393.535278) (xy 57.69229 -393.556744)
			(xy 57.685686 -393.563856) (xy 57.678574 -393.580874) (xy 57.676542 -393.659106) (xy 57.676704 -393.668363)
			(xy 57.68281 -393.685825) (xy 57.68848 -393.693142) (xy 57.688734 -393.693396) (xy 57.705084 -393.713044)
			(xy 57.732638 -393.756095) (xy 57.753801 -393.802622) (xy 57.768146 -393.851682) (xy 57.775382 -393.902281)
			(xy 57.775856 -393.927838) (xy 57.775354 -393.954715) (xy 57.767342 -394.00787) (xy 57.751498 -394.059236)
			(xy 57.728174 -394.107668) (xy 57.697893 -394.152082) (xy 57.661331 -394.191487) (xy 57.619303 -394.225003)
			(xy 57.57275 -394.25188) (xy 57.522711 -394.271519) (xy 57.470304 -394.28348) (xy 57.4167 -394.287498)
			(xy 57.363096 -394.28348) (xy 57.310689 -394.271519) (xy 57.26065 -394.25188) (xy 57.214097 -394.225003)
			(xy 57.172069 -394.191487) (xy 57.135507 -394.152082) (xy 57.105226 -394.107668) (xy 57.081902 -394.059236)
			(xy 57.066058 -394.00787) (xy 57.058046 -393.954715) (xy 57.057544 -393.927838) (xy 57.05799 -393.902315)
			(xy 57.065214 -393.851783) (xy 57.079522 -393.802784) (xy 57.100625 -393.756305) (xy 57.128098 -393.713283)
			(xy 57.144412 -393.69365) (xy 57.14492 -393.693142) (xy 57.150584 -393.685817) (xy 57.156723 -393.668363)
			(xy 57.156858 -393.659106) (xy 57.15508 -393.590526) (xy 57.154425 -393.581162) (xy 57.147267 -393.563828)
			(xy 57.14111 -393.556744) (xy 57.121355 -393.535297) (xy 57.087922 -393.487527) (xy 57.062141 -393.43523)
			(xy 57.044611 -393.37962) (xy 57.03574 -393.321992) (xy 57.035192 -393.292838) (xy 57.035192 -392.428984)
			(xy 57.035692 -392.400914) (xy 57.043924 -392.345379) (xy 57.060208 -392.291652) (xy 57.084192 -392.240892)
			(xy 57.115357 -392.194196) (xy 57.153032 -392.152573) (xy 57.174384 -392.134344) (xy 57.18302 -392.127486)
			(xy 57.192672 -392.107928) (xy 57.192926 -392.096752) (xy 57.193434 -392.079226) (xy 57.193422 -392.074357)
			(xy 57.191761 -392.064764) (xy 57.190132 -392.060176) (xy 57.187084 -392.05154) (xy 57.180226 -392.04392)
			(xy 57.164882 -392.02627) (xy 57.139003 -391.987316) (xy 57.119103 -391.944994) (xy 57.10561 -391.900215)
			(xy 57.098816 -391.853944) (xy 57.098438 -391.83056) (xy 57.098438 -391.82675) (xy 57.099454 -391.80516)
			(xy 57.10092 -391.789518) (xy 57.106521 -391.758602) (xy 57.11063 -391.743438) (xy 57.113932 -391.731754)
			(xy 57.1119 -391.720324) (xy 57.110653 -391.714568) (xy 57.105918 -391.703786) (xy 57.102502 -391.698988)
			(xy 57.05348 -391.634218) (xy 57.045929 -391.625148) (xy 57.024877 -391.61454) (xy 57.013094 -391.613898)
			(xy 56.619902 -391.613898) (xy 56.608127 -391.614571) (xy 56.587089 -391.625173) (xy 56.579516 -391.634218)
			(xy 56.530494 -391.698988) (xy 56.527066 -391.703779) (xy 56.522327 -391.714562) (xy 56.521096 -391.720324)
			(xy 56.519064 -391.731754) (xy 56.522366 -391.743438) (xy 56.52797 -391.764462) (xy 56.534094 -391.807538)
			(xy 56.534558 -391.82929) (xy 56.534558 -391.833862) (xy 56.533934 -391.856887) (xy 56.526857 -391.9024)
			(xy 56.513282 -391.946413) (xy 56.493493 -391.988005) (xy 56.467904 -392.026303) (xy 56.45277 -392.043666)
			(xy 56.446166 -392.051032) (xy 56.442864 -392.059668) (xy 56.441262 -392.064325) (xy 56.439718 -392.074049)
			(xy 56.439816 -392.078972) (xy 56.440578 -392.097768) (xy 56.440578 -392.098276) (xy 56.440832 -392.107674)
			(xy 56.450484 -392.127486) (xy 56.458866 -392.134344) (xy 56.480268 -392.152561) (xy 56.518005 -392.194211)
			(xy 56.549223 -392.240946) (xy 56.573246 -392.291756) (xy 56.589554 -392.345541) (xy 56.597795 -392.401137)
			(xy 56.598312 -392.429238) (xy 56.598312 -393.292838) (xy 56.597802 -393.320711) (xy 56.589685 -393.375864)
			(xy 56.57363 -393.429249) (xy 56.549979 -393.47973) (xy 56.519234 -393.526232) (xy 56.50103 -393.547346)
			(xy 56.495188 -393.55395) (xy 56.48833 -393.570714) (xy 56.486298 -393.645136) (xy 56.486365 -393.65405)
			(xy 56.491954 -393.670965) (xy 56.49722 -393.678156) (xy 56.497474 -393.67841) (xy 56.512267 -393.697569)
			(xy 56.537116 -393.739109) (xy 56.556157 -393.783611) (xy 56.569045 -393.830269) (xy 56.575545 -393.878236)
			(xy 56.57596 -393.902438) (xy 56.575458 -393.929334) (xy 56.56744 -393.982526) (xy 56.551584 -394.033929)
			(xy 56.528245 -394.082395) (xy 56.497942 -394.126841) (xy 56.461354 -394.166274) (xy 56.419297 -394.199813)
			(xy 56.372711 -394.226709) (xy 56.322637 -394.246362) (xy 56.270192 -394.258332) (xy 56.21655 -394.262352)
			(xy 56.162908 -394.258332) (xy 56.110463 -394.246362) (xy 56.060389 -394.226709) (xy 56.013803 -394.199813)
			(xy 55.971746 -394.166274) (xy 55.935158 -394.126841) (xy 55.904855 -394.082395) (xy 55.881516 -394.033929)
			(xy 55.86566 -393.982526) (xy 55.857642 -393.929334) (xy 55.85714 -393.902438) (xy 55.857557 -393.878238)
			(xy 55.864091 -393.830281) (xy 55.876992 -393.783632) (xy 55.896028 -393.739132) (xy 55.920856 -393.697584)
			(xy 55.935626 -393.67841) (xy 55.93588 -393.678156) (xy 55.941091 -393.670934) (xy 55.946684 -393.654041)
			(xy 55.946802 -393.645136) (xy 55.94477 -393.570714) (xy 55.937912 -393.55395) (xy 55.93207 -393.547346)
			(xy 55.913853 -393.526242) (xy 55.883104 -393.47974) (xy 55.859453 -393.429257) (xy 55.843402 -393.375869)
			(xy 55.835295 -393.320712) (xy 55.834788 -393.292838) (xy 55.834788 -392.429238) (xy 55.835292 -392.401137)
			(xy 55.843544 -392.345545) (xy 55.859861 -392.291764) (xy 55.883889 -392.240958) (xy 55.915109 -392.194225)
			(xy 55.952846 -392.152577) (xy 55.974234 -392.134344) (xy 55.982616 -392.127486) (xy 55.992268 -392.107674)
			(xy 55.992522 -392.098022) (xy 55.993284 -392.078972) (xy 55.993327 -392.074053) (xy 55.991785 -392.064338)
			(xy 55.990236 -392.059668) (xy 55.986934 -392.051032) (xy 55.98033 -392.043666) (xy 55.965222 -392.026284)
			(xy 55.939654 -391.987979) (xy 55.919871 -391.946391) (xy 55.906287 -391.902386) (xy 55.899185 -391.856884)
			(xy 55.898542 -391.833862) (xy 55.898542 -391.83056) (xy 55.89892 -391.808487) (xy 55.905042 -391.764768)
			(xy 55.910734 -391.743438) (xy 55.914036 -391.731754) (xy 55.912004 -391.720324) (xy 55.910757 -391.714567)
			(xy 55.906022 -391.703786) (xy 55.902606 -391.698988) (xy 55.853584 -391.634218) (xy 55.846033 -391.625147)
			(xy 55.824981 -391.614537) (xy 55.813198 -391.613898) (xy 55.50154 -391.613898) (xy 55.491475 -391.613464)
			(xy 55.472886 -391.605734) (xy 55.465472 -391.598912) (xy 55.31358 -391.44702) (xy 55.306738 -391.439621)
			(xy 55.29902 -391.421022) (xy 55.298594 -391.410952) (xy 55.298594 -389.806942) (xy 55.298345 -389.799528)
			(xy 55.29409 -389.785325) (xy 55.290212 -389.779002) (xy 55.286148 -389.772652) (xy 55.274718 -389.763254)
			(xy 55.267606 -389.760206) (xy 55.245137 -389.750243) (xy 55.203319 -389.724416) (xy 55.165976 -389.69246)
			(xy 55.133998 -389.655136) (xy 55.108146 -389.613335) (xy 55.089037 -389.568052) (xy 55.082694 -389.544306)
			(xy 55.082186 -389.542274) (xy 54.771036 -389.004048) (xy 54.76875 -389.001508) (xy 54.751008 -388.983451)
			(xy 54.720907 -388.942752) (xy 54.697638 -388.897797) (xy 54.681789 -388.849722) (xy 54.673761 -388.799742)
			(xy 54.673246 -388.774432) (xy 54.6735 -388.762748) (xy 54.673754 -388.75208) (xy 54.669944 -388.742428)
			(xy 54.667916 -388.737557) (xy 54.662156 -388.728719) (xy 54.658514 -388.724902) (xy 54.125876 -388.192264)
			(xy 54.119027 -388.184867) (xy 54.111294 -388.166268) (xy 54.11089 -388.156196) (xy 54.11089 -387.199632)
			(xy 54.110721 -387.193623) (xy 54.107893 -387.181943) (xy 54.105302 -387.176518) (xy 54.103464 -387.173042)
			(xy 54.098874 -387.16666) (xy 54.096158 -387.163818) (xy 53.846984 -386.914644) (xy 53.844133 -386.911938)
			(xy 53.837754 -386.907347) (xy 53.834284 -386.9055) (xy 53.828858 -386.902914) (xy 53.817178 -386.900084)
			(xy 53.81117 -386.899912) (xy 52.589684 -386.899912) (xy 52.584604 -386.900166) (xy 52.575229 -386.901482)
			(xy 52.558382 -386.91009) (xy 52.551838 -386.91693) (xy 52.500784 -386.979414) (xy 52.49726 -386.98387)
			(xy 52.492124 -386.994001) (xy 52.490624 -386.99948) (xy 52.488084 -387.010148) (xy 52.49037 -387.021578)
			(xy 52.493245 -387.037038) (xy 52.496294 -387.068338) (xy 52.496466 -387.084062) (xy 52.496049 -387.106859)
			(xy 52.489541 -387.151988) (xy 52.483512 -387.173978) (xy 52.483512 -387.185662) (xy 52.483093 -387.20006)
			(xy 52.476002 -387.227968) (xy 52.462205 -387.253241) (xy 52.442565 -387.274297) (xy 52.43068 -387.282436)
			(xy 52.429664 -387.287008) (xy 52.428809 -387.292321) (xy 52.429061 -387.303078) (xy 52.430172 -387.308344)
			(xy 52.446936 -387.382258) (xy 52.448301 -387.38747) (xy 52.452905 -387.397209) (xy 52.45608 -387.401562)
			(xy 52.46243 -387.409944) (xy 52.472082 -387.415278) (xy 52.496233 -387.42924) (xy 52.539666 -387.464242)
			(xy 52.558442 -387.484874) (xy 52.560925 -387.487626) (xy 52.566534 -387.49247) (xy 52.569618 -387.494526)
			(xy 52.58175 -387.502619) (xy 52.601815 -387.52377) (xy 52.615957 -387.549265) (xy 52.623277 -387.577485)
			(xy 52.62372 -387.592062) (xy 52.62372 -387.604508) (xy 52.625498 -387.610858) (xy 52.630609 -387.631176)
			(xy 52.636082 -387.672714) (xy 52.63642 -387.693662) (xy 52.63642 -387.69798) (xy 52.636149 -387.709591)
			(xy 52.634113 -387.732728) (xy 52.632356 -387.744208) (xy 52.63084 -387.753255) (xy 52.626901 -387.771173)
			(xy 52.624482 -387.780022) (xy 52.62372 -387.78307) (xy 52.62372 -388.239254) (xy 52.624482 -388.242302)
			(xy 52.629603 -388.26154) (xy 52.635587 -388.300898) (xy 52.63642 -388.320788) (xy 52.63642 -388.328662)
			(xy 53.200554 -388.328662) (xy 53.200922 -388.307641) (xy 53.206532 -388.265975) (xy 53.21173 -388.245604)
			(xy 53.213508 -388.239) (xy 53.213508 -388.125462) (xy 53.214002 -388.110447) (xy 53.221781 -388.081441)
			(xy 53.2368 -388.055435) (xy 53.258035 -388.0342) (xy 53.284041 -388.019181) (xy 53.313047 -388.011402)
			(xy 53.328062 -388.010908) (xy 53.509672 -388.010908) (xy 53.51018 -388.010654) (xy 53.526944 -388.010654)
			(xy 53.527452 -388.010908) (xy 53.709062 -388.010908) (xy 53.724074 -388.011469) (xy 53.753077 -388.01923)
			(xy 53.779083 -388.034233) (xy 53.80032 -388.055456) (xy 53.815341 -388.081452) (xy 53.823121 -388.11045)
			(xy 53.823616 -388.125462) (xy 53.823616 -388.239) (xy 53.825394 -388.245604) (xy 53.830585 -388.265977)
			(xy 53.836196 -388.307642) (xy 53.83657 -388.328662) (xy 53.83657 -388.32917) (xy 53.8364 -388.343795)
			(xy 53.833733 -388.372924) (xy 53.831236 -388.387336) (xy 53.829868 -388.39651) (xy 53.833143 -388.414753)
			(xy 53.837586 -388.422896) (xy 53.854096 -388.44982) (xy 53.859247 -388.457613) (xy 53.873986 -388.469067)
			(xy 53.882798 -388.472172) (xy 53.907678 -388.48024) (xy 53.954557 -388.503428) (xy 53.99697 -388.534031)
			(xy 54.033753 -388.571211) (xy 54.063901 -388.613948) (xy 54.086586 -388.661073) (xy 54.09438 -388.68604)
			(xy 54.095904 -388.691882) (xy 54.416198 -389.245602) (xy 54.420262 -389.24992) (xy 54.436428 -389.26758)
			(xy 54.463745 -389.3069) (xy 54.484811 -389.349894) (xy 54.499143 -389.395575) (xy 54.506413 -389.442898)
			(xy 54.506876 -389.466836) (xy 54.506876 -389.467344) (xy 54.506365 -389.492792) (xy 54.498195 -389.543028)
			(xy 54.482073 -389.591303) (xy 54.458416 -389.636367) (xy 54.427839 -389.677054) (xy 54.391131 -389.712309)
			(xy 54.370478 -389.727186) (xy 54.361991 -389.733646) (xy 54.35081 -389.751782) (xy 54.347944 -389.772895)
			(xy 54.353888 -389.793355) (xy 54.367618 -389.809647) (xy 54.386775 -389.818971) (xy 54.397402 -389.819896)
			(xy 54.407308 -389.819388) (xy 54.415759 -389.818103) (xy 54.432797 -389.816703) (xy 54.441344 -389.816594)
			(xy 54.441598 -389.816848) (xy 54.74081 -389.816848) (xy 54.741064 -389.816594) (xy 54.762126 -389.816995)
			(xy 54.803485 -389.82495) (xy 54.842483 -389.840855) (xy 54.877609 -389.864094) (xy 54.907501 -389.893765)
			(xy 54.930999 -389.928717) (xy 54.947193 -389.967597) (xy 54.955454 -390.008896) (xy 54.955948 -390.029954)
			(xy 54.955948 -390.284716) (xy 54.946804 -390.284716) (xy 54.936781 -390.285123) (xy 54.918261 -390.292795)
			(xy 54.904088 -390.306971) (xy 54.896421 -390.325493) (xy 54.896004 -390.335516) (xy 54.896004 -390.499092)
			(xy 54.895574 -390.509112) (xy 54.887908 -390.527628) (xy 54.873738 -390.541801) (xy 54.855224 -390.549472)
			(xy 54.845204 -390.549892) (xy 54.337204 -390.549892) (xy 54.327182 -390.549477) (xy 54.308664 -390.541807)
			(xy 54.294491 -390.527633) (xy 54.286822 -390.509114) (xy 54.286404 -390.499092) (xy 54.286404 -390.284716)
			(xy 54.27726 -390.284716) (xy 54.267252 -390.284245) (xy 54.248762 -390.276575) (xy 54.234611 -390.262418)
			(xy 54.22695 -390.243924) (xy 54.22646 -390.233916) (xy 54.22646 -390.029954) (xy 54.2268 -390.012721)
			(xy 54.232372 -389.978708) (xy 54.243346 -389.946035) (xy 54.251098 -389.93064) (xy 54.25694 -389.91921)
			(xy 54.256686 -389.89381) (xy 54.209188 -389.808212) (xy 54.202455 -389.797442) (xy 54.18114 -389.783699)
			(xy 54.168548 -389.78205) (xy 54.144677 -389.779844) (xy 54.097933 -389.769219) (xy 54.053337 -389.75164)
			(xy 54.011915 -389.727513) (xy 53.974623 -389.697395) (xy 53.942319 -389.661979) (xy 53.915748 -389.622081)
			(xy 53.895522 -389.578621) (xy 53.888386 -389.555736) (xy 53.886862 -389.549894) (xy 53.566568 -388.996174)
			(xy 53.562504 -388.991856) (xy 53.546302 -388.974147) (xy 53.518877 -388.934756) (xy 53.497734 -388.891667)
			(xy 53.48336 -388.845873) (xy 53.476086 -388.79843) (xy 53.475636 -388.774432) (xy 53.475814 -388.760384)
			(xy 53.478358 -388.732402) (xy 53.480716 -388.718552) (xy 53.482003 -388.709296) (xy 53.478607 -388.690932)
			(xy 53.474112 -388.682738) (xy 53.457348 -388.655814) (xy 53.452135 -388.648119) (xy 53.437417 -388.636791)
			(xy 53.428646 -388.633716) (xy 53.407019 -388.626918) (xy 53.365805 -388.608035) (xy 53.327685 -388.583499)
			(xy 53.293429 -388.553806) (xy 53.278278 -388.536942) (xy 53.275809 -388.534176) (xy 53.270201 -388.529325)
			(xy 53.267102 -388.52729) (xy 53.255079 -388.519202) (xy 53.235187 -388.498146) (xy 53.221177 -388.472792)
			(xy 53.213935 -388.444745) (xy 53.213508 -388.430262) (xy 53.213508 -388.418324) (xy 53.21173 -388.41172)
			(xy 53.206523 -388.391351) (xy 53.200923 -388.349683) (xy 53.200554 -388.328662) (xy 52.63642 -388.328662)
			(xy 52.63642 -388.33298) (xy 52.636166 -388.343648) (xy 52.636166 -388.344156) (xy 52.635541 -388.354503)
			(xy 52.633124 -388.375093) (xy 52.63134 -388.385304) (xy 52.630578 -388.39394) (xy 52.63074 -388.401023)
			(xy 52.634477 -388.414685) (xy 52.637944 -388.420864) (xy 52.649628 -388.43966) (xy 52.652101 -388.443616)
			(xy 52.658237 -388.450642) (xy 52.66182 -388.45363) (xy 52.682902 -388.469632) (xy 52.68849 -388.47141)
			(xy 52.713647 -388.480067) (xy 52.760875 -388.504555) (xy 52.803374 -388.536553) (xy 52.839962 -388.575172)
			(xy 52.86962 -388.619336) (xy 52.891523 -388.667817) (xy 52.898802 -388.693406) (xy 52.903882 -388.705852)
			(xy 53.216048 -389.245602) (xy 53.220112 -389.24992) (xy 53.236328 -389.267618) (xy 53.26376 -389.307008)
			(xy 53.284906 -389.350099) (xy 53.299279 -389.395897) (xy 53.306546 -389.443344) (xy 53.30698 -389.467344)
			(xy 53.306497 -389.492809) (xy 53.298319 -389.543078) (xy 53.282168 -389.591379) (xy 53.258464 -389.636456)
			(xy 53.227822 -389.677136) (xy 53.191039 -389.712362) (xy 53.170328 -389.727186) (xy 53.161844 -389.733678)
			(xy 53.150671 -389.751857) (xy 53.147842 -389.773006) (xy 53.153843 -389.793482) (xy 53.167641 -389.809757)
			(xy 53.186859 -389.819028) (xy 53.197506 -389.819896) (xy 53.207158 -389.819388) (xy 53.215669 -389.818074)
			(xy 53.232836 -389.816676) (xy 53.241448 -389.816594) (xy 53.241702 -389.816848) (xy 53.540914 -389.816848)
			(xy 53.541168 -389.816594) (xy 53.562232 -389.816932) (xy 53.603595 -389.824891) (xy 53.642596 -389.840803)
			(xy 53.677722 -389.864051) (xy 53.707609 -389.893732) (xy 53.7311 -389.928696) (xy 53.747282 -389.967586)
			(xy 53.755527 -390.008893) (xy 53.756052 -390.029954) (xy 53.756052 -390.233916) (xy 53.755629 -390.243932)
			(xy 53.747954 -390.262435) (xy 53.733781 -390.27659) (xy 53.715268 -390.284242) (xy 53.705252 -390.284716)
			(xy 53.696108 -390.284716) (xy 53.696108 -390.499092) (xy 53.695621 -390.509101) (xy 53.687963 -390.527597)
			(xy 53.673811 -390.541754) (xy 53.655317 -390.549418) (xy 53.645308 -390.549892) (xy 53.137308 -390.549892)
			(xy 53.127286 -390.549474) (xy 53.108768 -390.541805) (xy 53.094595 -390.527632) (xy 53.086926 -390.509114)
			(xy 53.086508 -390.499092) (xy 53.086508 -390.335516) (xy 53.086091 -390.325492) (xy 53.078424 -390.306968)
			(xy 53.064252 -390.292789) (xy 53.045732 -390.285113) (xy 53.035708 -390.284716) (xy 53.026564 -390.284716)
			(xy 53.026564 -390.029954) (xy 53.027311 -390.004082) (xy 53.039762 -389.953857) (xy 53.051202 -389.93064)
			(xy 53.057044 -389.91921) (xy 53.05679 -389.89381) (xy 53.009292 -389.808212) (xy 53.00258 -389.79743)
			(xy 52.981245 -389.783717) (xy 52.968652 -389.78205) (xy 52.944768 -389.779879) (xy 52.898008 -389.769235)
			(xy 52.853394 -389.751644) (xy 52.811951 -389.727511) (xy 52.774633 -389.697391) (xy 52.742297 -389.661976)
			(xy 52.715686 -389.62208) (xy 52.695412 -389.57862) (xy 52.688236 -389.555736) (xy 52.686712 -389.549894)
			(xy 52.371752 -389.005064) (xy 52.370228 -389.003794) (xy 52.35575 -389.001508) (xy 52.348429 -389.000639)
			(xy 52.333836 -389.002696) (xy 52.327048 -389.005572) (xy 52.24272 -389.043672) (xy 52.236878 -389.046974)
			(xy 52.229769 -389.051781) (xy 52.219023 -389.065148) (xy 52.213327 -389.081325) (xy 52.213002 -389.0899)
			(xy 52.213002 -389.778748) (xy 52.213513 -389.789584) (xy 52.222457 -389.809326) (xy 52.230274 -389.816848)
			(xy 52.341018 -389.816848) (xy 52.341272 -389.816594) (xy 52.362336 -389.816933) (xy 52.403698 -389.824892)
			(xy 52.442698 -389.840805) (xy 52.477823 -389.864052) (xy 52.507711 -389.893734) (xy 52.5312 -389.928697)
			(xy 52.547382 -389.967587) (xy 52.555627 -390.008893) (xy 52.556156 -390.029954) (xy 52.556156 -390.284716)
			(xy 52.553362 -390.284716) (xy 52.52847 -390.344406) (xy 52.529486 -390.346438) (xy 52.531361 -390.349831)
			(xy 52.535956 -390.356076) (xy 52.53863 -390.358884) (xy 52.822094 -390.642348) (xy 52.828934 -390.649749)
			(xy 52.836652 -390.668347) (xy 52.83708 -390.678416) (xy 52.83708 -391.580878) (xy 52.837129 -391.584749)
			(xy 52.838278 -391.592403) (xy 52.839366 -391.596118) (xy 52.841192 -391.601445) (xy 52.846822 -391.611195)
			(xy 52.850542 -391.615422) (xy 52.867984 -391.635125) (xy 52.896765 -391.679175) (xy 52.917902 -391.727362)
			(xy 52.930819 -391.778371) (xy 52.935163 -391.83081) (xy 52.930816 -391.883249) (xy 52.917896 -391.934257)
			(xy 52.896755 -391.982443) (xy 52.867971 -392.026491) (xy 52.850542 -392.046206) (xy 52.843938 -392.053572)
			(xy 52.840636 -392.062208) (xy 52.839012 -392.066672) (xy 52.837229 -392.076002) (xy 52.83708 -392.08075)
			(xy 52.83708 -392.104118) (xy 52.846986 -392.124692) (xy 52.85613 -392.132058) (xy 52.877881 -392.150279)
			(xy 52.916273 -392.192057) (xy 52.948055 -392.23906) (xy 52.972526 -392.290251) (xy 52.989147 -392.344501)
			(xy 52.997551 -392.400614) (xy 52.998116 -392.428984) (xy 52.998116 -393.292838) (xy 53.434996 -393.292838)
			(xy 53.434996 -392.42873) (xy 53.435437 -392.403262) (xy 53.442239 -392.352783) (xy 53.4557 -392.303658)
			(xy 53.47558 -392.256762) (xy 53.501525 -392.212929) (xy 53.533073 -392.172939) (xy 53.551074 -392.154918)
			(xy 53.557678 -392.148568) (xy 53.565552 -392.131804) (xy 53.57241 -392.04646) (xy 53.56733 -392.02868)
			(xy 53.561742 -392.021314) (xy 53.546893 -392.000565) (xy 53.523257 -391.955352) (xy 53.507155 -391.90694)
			(xy 53.499002 -391.856577) (xy 53.498496 -391.831068) (xy 53.498496 -391.830814) (xy 53.498986 -391.805825)
			(xy 53.506805 -391.756462) (xy 53.522249 -391.70893) (xy 53.544939 -391.664398) (xy 53.574315 -391.623965)
			(xy 53.609655 -391.588625) (xy 53.650088 -391.559249) (xy 53.69462 -391.536559) (xy 53.742152 -391.521115)
			(xy 53.791515 -391.513296) (xy 53.841493 -391.513296) (xy 53.890856 -391.521115) (xy 53.938388 -391.536559)
			(xy 53.98292 -391.559249) (xy 54.023353 -391.588625) (xy 54.058693 -391.623965) (xy 54.088069 -391.664398)
			(xy 54.110759 -391.70893) (xy 54.126203 -391.756462) (xy 54.134022 -391.805825) (xy 54.134512 -391.830814)
			(xy 54.134512 -391.831068) (xy 54.134017 -391.856577) (xy 54.12584 -391.906936) (xy 54.109738 -391.955347)
			(xy 54.086124 -392.000572) (xy 54.071266 -392.021314) (xy 54.065678 -392.02868) (xy 54.060598 -392.04646)
			(xy 54.067456 -392.131804) (xy 54.07533 -392.148568) (xy 54.081934 -392.154918) (xy 54.09993 -392.172944)
			(xy 54.131472 -392.212936) (xy 54.157414 -392.256769) (xy 54.177294 -392.303664) (xy 54.19076 -392.352786)
			(xy 54.197571 -392.403263) (xy 54.198012 -392.42873) (xy 54.198012 -393.292838) (xy 54.634892 -393.292838)
			(xy 54.634892 -392.429238) (xy 54.635332 -392.403719) (xy 54.642121 -392.353133) (xy 54.655596 -392.303906)
			(xy 54.675516 -392.256915) (xy 54.701526 -392.213002) (xy 54.733161 -392.172949) (xy 54.751224 -392.154918)
			(xy 54.757828 -392.148568) (xy 54.765702 -392.131804) (xy 54.77256 -392.04646) (xy 54.76748 -392.02868)
			(xy 54.761892 -392.021314) (xy 54.747037 -392.000569) (xy 54.723403 -391.955354) (xy 54.707304 -391.906941)
			(xy 54.699152 -391.856578) (xy 54.698646 -391.831068) (xy 54.698646 -391.830814) (xy 54.699136 -391.805825)
			(xy 54.706955 -391.756462) (xy 54.722399 -391.70893) (xy 54.745089 -391.664398) (xy 54.774465 -391.623965)
			(xy 54.809805 -391.588625) (xy 54.850238 -391.559249) (xy 54.89477 -391.536559) (xy 54.942302 -391.521115)
			(xy 54.991665 -391.513296) (xy 55.041643 -391.513296) (xy 55.091006 -391.521115) (xy 55.138538 -391.536559)
			(xy 55.18307 -391.559249) (xy 55.223503 -391.588625) (xy 55.258843 -391.623965) (xy 55.288219 -391.664398)
			(xy 55.310909 -391.70893) (xy 55.326353 -391.756462) (xy 55.334172 -391.805825) (xy 55.334662 -391.830814)
			(xy 55.334662 -391.831068) (xy 55.334157 -391.856576) (xy 55.325981 -391.906935) (xy 55.309882 -391.955346)
			(xy 55.286272 -392.000571) (xy 55.271416 -392.021314) (xy 55.265828 -392.02868) (xy 55.260748 -392.04646)
			(xy 55.267606 -392.131804) (xy 55.27548 -392.148568) (xy 55.282084 -392.154918) (xy 55.300124 -392.172971)
			(xy 55.331753 -392.213024) (xy 55.357762 -392.256935) (xy 55.377689 -392.30392) (xy 55.391177 -392.353141)
			(xy 55.397986 -392.40372) (xy 55.398416 -392.429238) (xy 55.398416 -393.292838) (xy 55.397879 -393.32129)
			(xy 55.389433 -393.377564) (xy 55.372731 -393.431962) (xy 55.348146 -393.483281) (xy 55.316219 -393.530385)
			(xy 55.297324 -393.551664) (xy 55.291426 -393.55865) (xy 55.284522 -393.575565) (xy 55.283862 -393.584684)
			(xy 55.282846 -393.615418) (xy 55.282985 -393.624588) (xy 55.288968 -393.641908) (xy 55.29453 -393.6492)
			(xy 55.309893 -393.668537) (xy 55.335708 -393.71064) (xy 55.355504 -393.755887) (xy 55.368906 -393.803421)
			(xy 55.375662 -393.852344) (xy 55.376064 -393.877038) (xy 55.375562 -393.903934) (xy 55.367544 -393.957126)
			(xy 55.351688 -394.008529) (xy 55.328349 -394.056995) (xy 55.298046 -394.101441) (xy 55.261458 -394.140874)
			(xy 55.219401 -394.174413) (xy 55.172815 -394.201309) (xy 55.122741 -394.220962) (xy 55.070296 -394.232932)
			(xy 55.016654 -394.236952) (xy 54.963012 -394.232932) (xy 54.910567 -394.220962) (xy 54.860493 -394.201309)
			(xy 54.813907 -394.174413) (xy 54.77185 -394.140874) (xy 54.735262 -394.101441) (xy 54.704959 -394.056995)
			(xy 54.68162 -394.008529) (xy 54.665764 -393.957126) (xy 54.657746 -393.903934) (xy 54.657244 -393.877038)
			(xy 54.657697 -393.852349) (xy 54.664483 -393.803439) (xy 54.67789 -393.755916) (xy 54.697669 -393.710672)
			(xy 54.723447 -393.668556) (xy 54.738778 -393.6492) (xy 54.744301 -393.641886) (xy 54.750298 -393.624581)
			(xy 54.750462 -393.615418) (xy 54.749446 -393.584684) (xy 54.748796 -393.57556) (xy 54.741907 -393.558633)
			(xy 54.735984 -393.551664) (xy 54.717057 -393.530408) (xy 54.685097 -393.483316) (xy 54.660498 -393.431994)
			(xy 54.643806 -393.377583) (xy 54.635394 -393.321295) (xy 54.634892 -393.292838) (xy 54.198012 -393.292838)
			(xy 54.197463 -393.321991) (xy 54.188592 -393.37962) (xy 54.171062 -393.435229) (xy 54.145282 -393.487527)
			(xy 54.111849 -393.535297) (xy 54.092094 -393.556744) (xy 54.085938 -393.563828) (xy 54.078779 -393.581162)
			(xy 54.078124 -393.590526) (xy 54.076346 -393.659106) (xy 54.07648 -393.668363) (xy 54.082619 -393.685817)
			(xy 54.088284 -393.693142) (xy 54.088792 -393.69365) (xy 54.105106 -393.713283) (xy 54.132579 -393.756305)
			(xy 54.153682 -393.802784) (xy 54.16799 -393.851783) (xy 54.175214 -393.902315) (xy 54.17566 -393.927838)
			(xy 54.175158 -393.954715) (xy 54.167146 -394.00787) (xy 54.151302 -394.059236) (xy 54.127978 -394.107668)
			(xy 54.097697 -394.152082) (xy 54.061135 -394.191487) (xy 54.019107 -394.225003) (xy 53.972554 -394.25188)
			(xy 53.922515 -394.271519) (xy 53.870108 -394.28348) (xy 53.816504 -394.287498) (xy 53.7629 -394.28348)
			(xy 53.710493 -394.271519) (xy 53.660454 -394.25188) (xy 53.613901 -394.225003) (xy 53.571873 -394.191487)
			(xy 53.535311 -394.152082) (xy 53.50503 -394.107668) (xy 53.481706 -394.059236) (xy 53.465862 -394.00787)
			(xy 53.45785 -393.954715) (xy 53.457348 -393.927838) (xy 53.457821 -393.902281) (xy 53.465057 -393.851682)
			(xy 53.479402 -393.802622) (xy 53.500566 -393.756095) (xy 53.52812 -393.713044) (xy 53.54447 -393.693396)
			(xy 53.544724 -393.693142) (xy 53.550394 -393.685825) (xy 53.5565 -393.668363) (xy 53.556662 -393.659106)
			(xy 53.55463 -393.580874) (xy 53.547518 -393.563856) (xy 53.540914 -393.556744) (xy 53.521181 -393.535278)
			(xy 53.487742 -393.487515) (xy 53.461957 -393.435222) (xy 53.444423 -393.379616) (xy 53.435551 -393.32199)
			(xy 53.434996 -393.292838) (xy 52.998116 -393.292838) (xy 52.998116 -393.293346) (xy 52.997544 -393.322437)
			(xy 52.988669 -393.37994) (xy 52.971176 -393.435432) (xy 52.945471 -393.48763) (xy 52.912147 -393.535326)
			(xy 52.892452 -393.556744) (xy 52.886141 -393.563827) (xy 52.878822 -393.581313) (xy 52.878228 -393.59078)
			(xy 52.876196 -393.668504) (xy 52.882292 -393.68603) (xy 52.884324 -393.688316) (xy 52.892011 -393.696981)
			(xy 52.906375 -393.715155) (xy 52.913026 -393.724638) (xy 52.91843 -393.732651) (xy 52.928468 -393.749171)
			(xy 52.933092 -393.757658) (xy 52.946547 -393.783983) (xy 52.965595 -393.839947) (xy 52.975196 -393.898279)
			(xy 52.975764 -393.927838) (xy 52.975418 -393.951352) (xy 52.969319 -393.997983) (xy 52.957179 -394.043416)
			(xy 52.939204 -394.086873) (xy 52.927758 -394.107416) (xy 52.925726 -394.111226) (xy 52.918614 -394.137134)
			(xy 52.919185 -394.147058) (xy 52.926892 -394.165359) (xy 52.9336 -394.172694) (xy 53.208428 -394.447522)
			(xy 53.215787 -394.454164) (xy 53.234087 -394.461731) (xy 53.243988 -394.462254) (xy 59.79795 -394.462254)
		)
		(stroke
			(width 0)
			(type solid)
		)
		(fill yes)
		(layer "B.Cu")
		(net "P0V9_CPU1_RT_2D")
	)
	(gr_poly
		(pts
			(xy 348.335092 -402.843238) (xy 348.342333 -402.841604) (xy 348.355492 -402.834753) (xy 348.361 -402.829776)
			(xy 348.439232 -402.751544) (xy 348.445655 -402.744542) (xy 348.453254 -402.72714) (xy 348.454025 -402.708168)
			(xy 348.447864 -402.690207) (xy 348.442026 -402.68271) (xy 348.438724 -402.679408) (xy 348.434439 -402.675385)
			(xy 348.424436 -402.669222) (xy 348.418912 -402.667216) (xy 348.408244 -402.66366) (xy 348.402148 -402.664676)
			(xy 348.396052 -402.665438) (xy 348.383171 -402.667205) (xy 348.357237 -402.669113) (xy 348.344236 -402.669248)
			(xy 348.343982 -402.669248) (xy 348.318318 -402.668775) (xy 348.267517 -402.661443) (xy 348.218275 -402.646959)
			(xy 348.171595 -402.625617) (xy 348.128425 -402.597852) (xy 348.089644 -402.564229) (xy 348.05604 -402.525431)
			(xy 348.028296 -402.482247) (xy 348.006978 -402.435556) (xy 347.992519 -402.386307) (xy 347.985212 -402.335502)
			(xy 347.984826 -402.309838) (xy 347.984826 -402.308568) (xy 347.985487 -402.280137) (xy 347.994682 -402.224019)
			(xy 348.0126 -402.17005) (xy 348.038794 -402.119575) (xy 348.07261 -402.073856) (xy 348.092522 -402.053552)
			(xy 348.099634 -402.04644) (xy 348.103444 -402.037804) (xy 348.105379 -402.033142) (xy 348.107555 -402.023289)
			(xy 348.107762 -402.018246) (xy 348.108016 -401.998942) (xy 348.107662 -401.987996) (xy 348.098842 -401.967976)
			(xy 348.090998 -401.960334) (xy 348.071192 -401.942143) (xy 348.036378 -401.901154) (xy 348.007664 -401.855684)
			(xy 347.985618 -401.806633) (xy 347.970676 -401.754973) (xy 347.963135 -401.701727) (xy 347.962728 -401.674838)
			(xy 347.962728 -400.810984) (xy 347.963228 -400.782914) (xy 347.97146 -400.72738) (xy 347.987745 -400.673654)
			(xy 348.011731 -400.622895) (xy 348.042899 -400.576202) (xy 348.080575 -400.534582) (xy 348.10192 -400.516344)
			(xy 348.110556 -400.509486) (xy 348.120208 -400.489928) (xy 348.120462 -400.478752) (xy 348.12097 -400.461226)
			(xy 348.120957 -400.456357) (xy 348.119294 -400.446765) (xy 348.117668 -400.442176) (xy 348.11462 -400.43354)
			(xy 348.107762 -400.42592) (xy 348.092448 -400.408311) (xy 348.066609 -400.36945) (xy 348.046723 -400.327233)
			(xy 348.033215 -400.282564) (xy 348.026376 -400.236401) (xy 348.025974 -400.213068) (xy 348.025974 -400.212814)
			(xy 348.026463 -400.187824) (xy 348.03428 -400.138458) (xy 348.049722 -400.090923) (xy 348.072411 -400.046388)
			(xy 348.101787 -400.005951) (xy 348.137127 -399.970608) (xy 348.177561 -399.941228) (xy 348.222093 -399.918535)
			(xy 348.269627 -399.903087) (xy 348.318992 -399.895266) (xy 348.343982 -399.894806) (xy 348.343982 -399.894552)
			(xy 348.365867 -399.894945) (xy 348.409215 -399.901013) (xy 348.451318 -399.91298) (xy 348.47149 -399.921476)
			(xy 348.471744 -399.921476) (xy 348.47767 -399.923849) (xy 348.490264 -399.925911) (xy 348.496636 -399.92554)
			(xy 348.508574 -399.924524) (xy 348.592648 -399.86966) (xy 348.602032 -399.86205) (xy 348.613032 -399.840575)
			(xy 348.61373 -399.828512) (xy 348.61373 -398.248886) (xy 348.614033 -398.241628) (xy 348.618164 -398.227709)
			(xy 348.621858 -398.221454) (xy 348.625922 -398.215358) (xy 348.629986 -398.201388) (xy 348.629986 -398.19072)
			(xy 348.629548 -398.180657) (xy 348.621812 -398.162075) (xy 348.615 -398.154652) (xy 348.607888 -398.14754)
			(xy 348.59849 -398.14373) (xy 348.575622 -398.133864) (xy 348.533021 -398.108068) (xy 348.494965 -398.075944)
			(xy 348.462385 -398.038277) (xy 348.436078 -397.99599) (xy 348.416689 -397.950117) (xy 348.410276 -397.926052)
			(xy 348.409768 -397.924274) (xy 348.094046 -397.378174) (xy 348.089982 -397.373856) (xy 348.073794 -397.356146)
			(xy 348.04642 -397.316743) (xy 348.025332 -397.273648) (xy 348.011016 -397.227855) (xy 348.003803 -397.180422)
			(xy 348.003368 -397.156432) (xy 348.003543 -397.142383) (xy 348.006083 -397.114401) (xy 348.008448 -397.100552)
			(xy 348.00966 -397.091275) (xy 348.006134 -397.072917) (xy 348.00159 -397.064738) (xy 347.984826 -397.037814)
			(xy 347.979621 -397.030111) (xy 347.964902 -397.018779) (xy 347.956124 -397.015716) (xy 347.934492 -397.008927)
			(xy 347.893262 -396.990067) (xy 347.855135 -396.965535) (xy 347.820884 -396.935829) (xy 347.805756 -396.918942)
			(xy 347.803274 -396.91619) (xy 347.797665 -396.911344) (xy 347.79458 -396.90929) (xy 347.78252 -396.901231)
			(xy 347.762573 -396.880183) (xy 347.748507 -396.854825) (xy 347.74121 -396.82676) (xy 347.740732 -396.812262)
			(xy 347.740732 -396.800324) (xy 347.739208 -396.79372) (xy 347.734013 -396.773349) (xy 347.728412 -396.731682)
			(xy 347.728032 -396.710662) (xy 347.728406 -396.689642) (xy 347.734017 -396.647977) (xy 347.739208 -396.627604)
			(xy 347.740732 -396.621) (xy 347.740732 -396.507462) (xy 347.741224 -396.492469) (xy 347.748981 -396.463503)
			(xy 347.76396 -396.437526) (xy 347.785143 -396.416301) (xy 347.81109 -396.40127) (xy 347.84004 -396.393454)
			(xy 347.855032 -396.392908) (xy 348.03715 -396.392908) (xy 348.037658 -396.392654) (xy 348.054422 -396.392654)
			(xy 348.05493 -396.392908) (xy 348.22384 -396.392908) (xy 348.233843 -396.392413) (xy 348.252322 -396.384747)
			(xy 348.266465 -396.370595) (xy 348.274119 -396.352111) (xy 348.27464 -396.342108) (xy 348.27464 -395.393672)
			(xy 348.27421 -395.383605) (xy 348.266482 -395.365014) (xy 348.259654 -395.357604) (xy 348.180406 -395.278356)
			(xy 348.173011 -395.271503) (xy 348.154412 -395.263757) (xy 348.144338 -395.26337) (xy 347.567758 -395.26337)
			(xy 347.561748 -395.263536) (xy 347.550064 -395.266357) (xy 347.544644 -395.268958) (xy 347.541173 -395.270801)
			(xy 347.534801 -395.275402) (xy 347.531944 -395.278102) (xy 347.258386 -395.55166) (xy 347.25568 -395.554511)
			(xy 347.251087 -395.560889) (xy 347.249242 -395.56436) (xy 347.246659 -395.569787) (xy 347.243837 -395.581466)
			(xy 347.243654 -395.587474) (xy 347.243654 -396.832328) (xy 347.243876 -396.839136) (xy 347.247487 -396.852265)
			(xy 347.250766 -396.858236) (xy 347.254068 -396.863824) (xy 347.263974 -396.873222) (xy 347.270324 -396.876778)
			(xy 347.292909 -396.889634) (xy 347.33394 -396.921523) (xy 347.369256 -396.959644) (xy 347.397922 -397.002988)
			(xy 347.419179 -397.050408) (xy 347.42628 -397.075406) (xy 347.43136 -397.087852) (xy 347.743526 -397.627602)
			(xy 347.74759 -397.63192) (xy 347.763749 -397.649589) (xy 347.791082 -397.688899) (xy 347.812159 -397.731889)
			(xy 347.826493 -397.777572) (xy 347.833757 -397.824897) (xy 347.834204 -397.848836) (xy 347.834204 -397.849344)
			(xy 347.833715 -397.874132) (xy 347.825954 -397.923098) (xy 347.810629 -397.970247) (xy 347.788119 -398.014419)
			(xy 347.758977 -398.054526) (xy 347.72392 -398.089582) (xy 347.683812 -398.118723) (xy 347.63964 -398.141232)
			(xy 347.59249 -398.156556) (xy 347.543524 -398.164315) (xy 347.518736 -398.164812) (xy 347.493341 -398.164307)
			(xy 347.443204 -398.156181) (xy 347.395015 -398.140134) (xy 347.350017 -398.116578) (xy 347.30937 -398.086122)
			(xy 347.274124 -398.049552) (xy 347.245187 -398.007811) (xy 347.223306 -397.961975) (xy 347.215714 -397.937736)
			(xy 347.21419 -397.931894) (xy 347.009466 -397.577564) (xy 347.003069 -397.567653) (xy 346.983475 -397.554568)
			(xy 346.971874 -397.552418) (xy 346.96019 -397.550894) (xy 346.938092 -397.558514) (xy 346.650056 -397.84655)
			(xy 346.647056 -397.84964) (xy 346.642079 -397.856669) (xy 346.64015 -397.86052) (xy 346.63634 -397.868648)
			(xy 346.635578 -397.877792) (xy 346.632698 -397.904017) (xy 346.619368 -397.955061) (xy 346.597797 -398.003205)
			(xy 346.568579 -398.04713) (xy 346.532513 -398.085632) (xy 346.51188 -398.102074) (xy 346.511626 -398.102328)
			(xy 346.507084 -398.105987) (xy 346.49964 -398.114963) (xy 346.496894 -398.120108) (xy 346.494354 -398.125188)
			(xy 346.491814 -398.136364) (xy 346.491814 -398.149064) (xy 346.531692 -398.185386) (xy 346.539026 -398.191547)
			(xy 346.556916 -398.198346) (xy 346.56649 -398.198594) (xy 346.56903 -398.198594) (xy 346.569284 -398.198848)
			(xy 346.868496 -398.198848) (xy 346.86875 -398.198594) (xy 346.885799 -398.198824) (xy 346.919491 -398.204054)
			(xy 346.935806 -398.209008) (xy 346.943426 -398.211548) (xy 346.97289 -398.211548) (xy 346.986257 -398.211981)
			(xy 347.012084 -398.218885) (xy 347.035251 -398.232228) (xy 347.054183 -398.251104) (xy 347.067596 -398.27423)
			(xy 347.074579 -398.300036) (xy 347.074998 -398.313402) (xy 347.074998 -398.35201) (xy 347.076522 -398.35836)
			(xy 347.079724 -398.371527) (xy 347.083169 -398.398405) (xy 347.08338 -398.411954) (xy 347.08338 -398.666716)
			(xy 347.074998 -398.666716) (xy 347.074998 -398.770602) (xy 347.074516 -398.785252) (xy 347.0662 -398.813346)
			(xy 347.050254 -398.837925) (xy 347.039438 -398.847818) (xy 347.03893 -398.848326) (xy 347.032326 -398.854168)
			(xy 347.023436 -398.87398) (xy 347.023436 -398.881092) (xy 347.02295 -398.891103) (xy 347.015293 -398.909604)
			(xy 347.001141 -398.923768) (xy 346.982647 -398.931441) (xy 346.972636 -398.931892) (xy 346.542614 -398.931892)
			(xy 346.53259 -398.932309) (xy 346.514067 -398.939976) (xy 346.499889 -398.954149) (xy 346.492213 -398.972668)
			(xy 346.491814 -398.982692) (xy 346.491814 -399.024602) (xy 347.537532 -399.024602) (xy 347.537532 -398.542002)
			(xy 347.538018 -398.514769) (xy 347.545769 -398.460857) (xy 347.561114 -398.408597) (xy 347.58374 -398.359053)
			(xy 347.613187 -398.313233) (xy 347.648854 -398.27207) (xy 347.690017 -398.236403) (xy 347.735837 -398.206956)
			(xy 347.785381 -398.18433) (xy 347.837641 -398.168985) (xy 347.891553 -398.161234) (xy 347.946019 -398.161234)
			(xy 347.999931 -398.168985) (xy 348.052191 -398.18433) (xy 348.101735 -398.206956) (xy 348.147555 -398.236403)
			(xy 348.188718 -398.27207) (xy 348.224385 -398.313233) (xy 348.253832 -398.359053) (xy 348.276458 -398.408597)
			(xy 348.291803 -398.460857) (xy 348.299554 -398.514769) (xy 348.30004 -398.542002) (xy 348.30004 -399.024602)
			(xy 348.299554 -399.051835) (xy 348.291803 -399.105747) (xy 348.276458 -399.158007) (xy 348.253832 -399.207551)
			(xy 348.224385 -399.253371) (xy 348.188718 -399.294534) (xy 348.147555 -399.330201) (xy 348.101735 -399.359648)
			(xy 348.052191 -399.382274) (xy 347.999931 -399.397619) (xy 347.946019 -399.40537) (xy 347.891553 -399.40537)
			(xy 347.837641 -399.397619) (xy 347.785381 -399.382274) (xy 347.735837 -399.359648) (xy 347.690017 -399.330201)
			(xy 347.648854 -399.294534) (xy 347.613187 -399.253371) (xy 347.58374 -399.207551) (xy 347.561114 -399.158007)
			(xy 347.545769 -399.105747) (xy 347.538018 -399.051835) (xy 347.537532 -399.024602) (xy 346.491814 -399.024602)
			(xy 346.491814 -399.827496) (xy 346.491392 -399.837567) (xy 346.48368 -399.856174) (xy 346.476828 -399.863564)
			(xy 346.35948 -399.980912) (xy 346.354659 -399.985469) (xy 346.343213 -399.992166) (xy 346.336874 -399.99412)
			(xy 346.328888 -399.996617) (xy 346.315012 -400.005947) (xy 346.309696 -400.012408) (xy 346.262198 -400.0754)
			(xy 346.25788 -400.081242) (xy 346.254463 -400.08597) (xy 346.249711 -400.096622) (xy 346.248482 -400.102324)
			(xy 346.24645 -400.113754) (xy 346.248736 -400.122136) (xy 346.255489 -400.146641) (xy 346.262001 -400.197049)
			(xy 346.26169 -400.222466) (xy 346.260277 -400.250383) (xy 346.248892 -400.305103) (xy 346.228133 -400.356998)
			(xy 346.198637 -400.404474) (xy 346.18041 -400.425666) (xy 346.173552 -400.433032) (xy 346.17025 -400.441922)
			(xy 346.168734 -400.446468) (xy 346.167201 -400.455926) (xy 346.167202 -400.460718) (xy 346.16771 -400.479514)
			(xy 346.16771 -400.480022) (xy 346.167964 -400.489928) (xy 346.177362 -400.508978) (xy 346.186252 -400.516344)
			(xy 346.207666 -400.534559) (xy 346.24543 -400.576204) (xy 346.276681 -400.622935) (xy 346.300744 -400.673742)
			(xy 346.3171 -400.727527) (xy 346.325393 -400.78313) (xy 346.325952 -400.811238) (xy 346.325952 -401.674838)
			(xy 346.762324 -401.674838) (xy 346.762324 -400.811238) (xy 346.762754 -400.785718) (xy 346.769544 -400.735132)
			(xy 346.78302 -400.685904) (xy 346.802942 -400.638913) (xy 346.828954 -400.595) (xy 346.860591 -400.554948)
			(xy 346.878656 -400.536918) (xy 346.88526 -400.530568) (xy 346.893134 -400.513804) (xy 346.899992 -400.42846)
			(xy 346.894912 -400.41068) (xy 346.889324 -400.403314) (xy 346.874473 -400.382567) (xy 346.850838 -400.337352)
			(xy 346.834737 -400.288941) (xy 346.826584 -400.238578) (xy 346.826078 -400.213068) (xy 346.826078 -400.212814)
			(xy 346.826568 -400.187825) (xy 346.834387 -400.138462) (xy 346.849831 -400.09093) (xy 346.872521 -400.046398)
			(xy 346.901897 -400.005965) (xy 346.937237 -399.970625) (xy 346.97767 -399.941249) (xy 347.022202 -399.918559)
			(xy 347.069734 -399.903115) (xy 347.119097 -399.895296) (xy 347.169075 -399.895296) (xy 347.218438 -399.903115)
			(xy 347.26597 -399.918559) (xy 347.310502 -399.941249) (xy 347.350935 -399.970625) (xy 347.386275 -400.005965)
			(xy 347.415651 -400.046398) (xy 347.438341 -400.09093) (xy 347.453785 -400.138462) (xy 347.461604 -400.187825)
			(xy 347.462094 -400.212814) (xy 347.462094 -400.213068) (xy 347.461602 -400.238577) (xy 347.453425 -400.288937)
			(xy 347.437322 -400.337348) (xy 347.413707 -400.382572) (xy 347.398848 -400.403314) (xy 347.39326 -400.41068)
			(xy 347.38818 -400.42846) (xy 347.395038 -400.513804) (xy 347.402912 -400.530568) (xy 347.409516 -400.536918)
			(xy 347.427543 -400.554984) (xy 347.459176 -400.595033) (xy 347.485189 -400.63894) (xy 347.505118 -400.685923)
			(xy 347.518608 -400.735142) (xy 347.525418 -400.785721) (xy 347.525848 -400.811238) (xy 347.525848 -401.674838)
			(xy 347.525289 -401.704002) (xy 347.516368 -401.761643) (xy 347.498784 -401.817258) (xy 347.472947 -401.869552)
			(xy 347.439459 -401.917308) (xy 347.419676 -401.938744) (xy 347.413517 -401.945826) (xy 347.40636 -401.963162)
			(xy 347.405706 -401.972526) (xy 347.403928 -402.041106) (xy 347.404066 -402.050363) (xy 347.410203 -402.067817)
			(xy 347.415866 -402.075142) (xy 347.416374 -402.07565) (xy 347.432735 -402.095258) (xy 347.460265 -402.138269)
			(xy 347.48142 -402.184748) (xy 347.495773 -402.233756) (xy 347.503035 -402.284305) (xy 347.503496 -402.309838)
			(xy 347.502994 -402.336734) (xy 347.494976 -402.389926) (xy 347.47912 -402.441329) (xy 347.455781 -402.489795)
			(xy 347.425478 -402.534241) (xy 347.38889 -402.573674) (xy 347.346833 -402.607213) (xy 347.300247 -402.634109)
			(xy 347.250173 -402.653762) (xy 347.197728 -402.665732) (xy 347.144086 -402.669752) (xy 347.090444 -402.665732)
			(xy 347.037999 -402.653762) (xy 346.987925 -402.634109) (xy 346.941339 -402.607213) (xy 346.899282 -402.573674)
			(xy 346.862694 -402.534241) (xy 346.832391 -402.489795) (xy 346.809052 -402.441329) (xy 346.793196 -402.389926)
			(xy 346.785178 -402.336734) (xy 346.784676 -402.309838) (xy 346.785146 -402.28427) (xy 346.792423 -402.233654)
			(xy 346.80682 -402.184586) (xy 346.828045 -402.138063) (xy 346.855666 -402.095029) (xy 346.872052 -402.075396)
			(xy 346.872306 -402.075142) (xy 346.877974 -402.067824) (xy 346.884081 -402.050362) (xy 346.884244 -402.041106)
			(xy 346.882212 -401.962874) (xy 346.8751 -401.945856) (xy 346.868496 -401.938744) (xy 346.848709 -401.917312)
			(xy 346.815218 -401.869557) (xy 346.789383 -401.817262) (xy 346.771806 -401.761645) (xy 346.762895 -401.704002)
			(xy 346.762324 -401.674838) (xy 346.325952 -401.674838) (xy 346.325381 -401.704002) (xy 346.31647 -401.761645)
			(xy 346.298891 -401.817261) (xy 346.273055 -401.869555) (xy 346.239563 -401.917308) (xy 346.21978 -401.938744)
			(xy 346.213176 -401.945856) (xy 346.206064 -401.962874) (xy 346.204032 -402.041106) (xy 346.204194 -402.050363)
			(xy 346.210299 -402.067826) (xy 346.21597 -402.075142) (xy 346.216224 -402.075396) (xy 346.232606 -402.09503)
			(xy 346.260222 -402.138066) (xy 346.281442 -402.18459) (xy 346.295836 -402.233657) (xy 346.303111 -402.284271)
			(xy 346.3036 -402.309838) (xy 346.303098 -402.336734) (xy 346.29508 -402.389926) (xy 346.279224 -402.441329)
			(xy 346.255885 -402.489795) (xy 346.225582 -402.534241) (xy 346.188994 -402.573674) (xy 346.146937 -402.607213)
			(xy 346.100351 -402.634109) (xy 346.050277 -402.653762) (xy 345.997832 -402.665732) (xy 345.94419 -402.669752)
			(xy 345.890548 -402.665732) (xy 345.838103 -402.653762) (xy 345.788029 -402.634109) (xy 345.741443 -402.607213)
			(xy 345.699386 -402.573674) (xy 345.662798 -402.534241) (xy 345.632495 -402.489795) (xy 345.609156 -402.441329)
			(xy 345.5933 -402.389926) (xy 345.585282 -402.336734) (xy 345.58478 -402.309838) (xy 345.585241 -402.284305)
			(xy 345.592504 -402.233758) (xy 345.60686 -402.184751) (xy 345.628019 -402.138275) (xy 345.655553 -402.095267)
			(xy 345.671902 -402.07565) (xy 345.67241 -402.075142) (xy 345.678075 -402.067817) (xy 345.684215 -402.050364)
			(xy 345.684348 -402.041106) (xy 345.68257 -401.972526) (xy 345.681915 -401.963163) (xy 345.674756 -401.945829)
			(xy 345.6686 -401.938744) (xy 345.648818 -401.917308) (xy 345.615332 -401.869551) (xy 345.589497 -401.817257)
			(xy 345.571914 -401.761642) (xy 345.562994 -401.704001) (xy 345.562428 -401.674838) (xy 345.562428 -400.811238)
			(xy 345.562932 -400.783138) (xy 345.571185 -400.727546) (xy 345.587503 -400.673766) (xy 345.611533 -400.622962)
			(xy 345.642755 -400.576232) (xy 345.680494 -400.534587) (xy 345.701874 -400.516344) (xy 345.71051 -400.509486)
			(xy 345.720162 -400.489928) (xy 345.720416 -400.478752) (xy 345.720924 -400.461226) (xy 345.720911 -400.456357)
			(xy 345.71925 -400.446765) (xy 345.717622 -400.442176) (xy 345.714574 -400.43354) (xy 345.707716 -400.42592)
			(xy 345.692595 -400.408516) (xy 345.667012 -400.370164) (xy 345.647227 -400.328523) (xy 345.633656 -400.284464)
			(xy 345.626582 -400.238908) (xy 345.625928 -400.215862) (xy 345.625928 -400.21256) (xy 345.626306 -400.190487)
			(xy 345.632427 -400.146768) (xy 345.63812 -400.125438) (xy 345.641422 -400.113754) (xy 345.63939 -400.102324)
			(xy 345.638143 -400.096568) (xy 345.633407 -400.085786) (xy 345.629992 -400.080988) (xy 345.58097 -400.016218)
			(xy 345.573418 -400.007149) (xy 345.552366 -399.996545) (xy 345.540584 -399.995898) (xy 345.147392 -399.995898)
			(xy 345.135607 -399.996552) (xy 345.114538 -400.007132) (xy 345.107006 -400.016218) (xy 345.057984 -400.080988)
			(xy 345.054556 -400.085779) (xy 345.049818 -400.096562) (xy 345.048586 -400.102324) (xy 345.046554 -400.113754)
			(xy 345.049856 -400.125438) (xy 345.05546 -400.146462) (xy 345.061584 -400.189538) (xy 345.062048 -400.21129)
			(xy 345.062048 -400.215862) (xy 345.061423 -400.238887) (xy 345.054347 -400.284399) (xy 345.040771 -400.328413)
			(xy 345.020982 -400.370004) (xy 344.995393 -400.408302) (xy 344.98026 -400.425666) (xy 344.973656 -400.433032)
			(xy 344.970354 -400.441668) (xy 344.968752 -400.446325) (xy 344.967209 -400.456049) (xy 344.967306 -400.460972)
			(xy 344.968068 -400.479768) (xy 344.968068 -400.480276) (xy 344.968322 -400.489674) (xy 344.977974 -400.509486)
			(xy 344.986356 -400.516344) (xy 345.007719 -400.53456) (xy 345.045384 -400.576192) (xy 345.076545 -400.622892)
			(xy 345.100527 -400.673653) (xy 345.116815 -400.72738) (xy 345.125056 -400.782913) (xy 345.125548 -400.810984)
			(xy 345.125548 -401.675346) (xy 345.12502 -401.703157) (xy 345.116898 -401.758184) (xy 345.100876 -401.81145)
			(xy 345.077293 -401.861827) (xy 345.046648 -401.908248) (xy 345.02852 -401.929346) (xy 345.022678 -401.93595)
			(xy 345.01582 -401.952714) (xy 345.013788 -402.027136) (xy 345.013855 -402.03605) (xy 345.019443 -402.052965)
			(xy 345.02471 -402.060156) (xy 345.024964 -402.06041) (xy 345.039699 -402.079539) (xy 345.064452 -402.120998)
			(xy 345.083427 -402.165399) (xy 345.096283 -402.211942) (xy 345.102787 -402.259787) (xy 345.103196 -402.28393)
			(xy 345.103196 -402.284438) (xy 345.102694 -402.311315) (xy 345.094682 -402.36447) (xy 345.078838 -402.415836)
			(xy 345.055514 -402.464268) (xy 345.025233 -402.508682) (xy 344.988671 -402.548087) (xy 344.946643 -402.581603)
			(xy 344.90009 -402.60848) (xy 344.850051 -402.628119) (xy 344.797644 -402.64008) (xy 344.74404 -402.644098)
			(xy 344.690436 -402.64008) (xy 344.638029 -402.628119) (xy 344.58799 -402.60848) (xy 344.541437 -402.581603)
			(xy 344.499409 -402.548087) (xy 344.462847 -402.508682) (xy 344.432566 -402.464268) (xy 344.409242 -402.415836)
			(xy 344.393398 -402.36447) (xy 344.385386 -402.311315) (xy 344.384884 -402.284438) (xy 344.384884 -402.28393)
			(xy 344.385294 -402.259788) (xy 344.3918 -402.211943) (xy 344.404658 -402.165402) (xy 344.423637 -402.121003)
			(xy 344.448393 -402.079548) (xy 344.463116 -402.06041) (xy 344.46337 -402.060156) (xy 344.468582 -402.052934)
			(xy 344.474176 -402.036041) (xy 344.474292 -402.027136) (xy 344.47226 -401.952714) (xy 344.465402 -401.93595)
			(xy 344.45956 -401.929346) (xy 344.441396 -401.908274) (xy 344.410736 -401.861855) (xy 344.387147 -401.811473)
			(xy 344.37113 -401.758198) (xy 344.363025 -401.703161) (xy 344.362532 -401.675346) (xy 344.362532 -400.810984)
			(xy 344.363032 -400.782914) (xy 344.371264 -400.727381) (xy 344.38755 -400.673654) (xy 344.411535 -400.622896)
			(xy 344.442703 -400.576202) (xy 344.48038 -400.534583) (xy 344.501724 -400.516344) (xy 344.510106 -400.509486)
			(xy 344.519758 -400.489674) (xy 344.520012 -400.480022) (xy 344.520774 -400.460972) (xy 344.520817 -400.456053)
			(xy 344.519275 -400.446338) (xy 344.517726 -400.441668) (xy 344.514424 -400.433032) (xy 344.50782 -400.425666)
			(xy 344.492712 -400.408283) (xy 344.467145 -400.369979) (xy 344.447363 -400.328391) (xy 344.433779 -400.284386)
			(xy 344.426677 -400.238883) (xy 344.426032 -400.215862) (xy 344.426032 -400.21256) (xy 344.42641 -400.190487)
			(xy 344.432531 -400.146768) (xy 344.438224 -400.125438) (xy 344.441526 -400.113754) (xy 344.439494 -400.102324)
			(xy 344.438247 -400.096568) (xy 344.433511 -400.085786) (xy 344.430096 -400.080988) (xy 344.381074 -400.016218)
			(xy 344.373523 -400.007149) (xy 344.352471 -399.996543) (xy 344.340688 -399.995898) (xy 344.02903 -399.995898)
			(xy 344.018966 -399.995462) (xy 344.00038 -399.987729) (xy 343.992962 -399.980912) (xy 343.84107 -399.82902)
			(xy 343.834229 -399.82162) (xy 343.826512 -399.803021) (xy 343.826084 -399.792952) (xy 343.826084 -398.188942)
			(xy 343.825834 -398.181528) (xy 343.821579 -398.167326) (xy 343.817702 -398.161002) (xy 343.813638 -398.154652)
			(xy 343.802208 -398.145254) (xy 343.795096 -398.142206) (xy 343.772627 -398.132242) (xy 343.730811 -398.106415)
			(xy 343.693469 -398.074458) (xy 343.661491 -398.037134) (xy 343.63564 -397.995333) (xy 343.616532 -397.95005)
			(xy 343.610184 -397.926306) (xy 343.609676 -397.924274) (xy 343.298526 -397.386048) (xy 343.29624 -397.383508)
			(xy 343.278498 -397.365451) (xy 343.248399 -397.324752) (xy 343.225131 -397.279796) (xy 343.209282 -397.231721)
			(xy 343.201254 -397.181742) (xy 343.200736 -397.156432) (xy 343.20099 -397.144748) (xy 343.201244 -397.13408)
			(xy 343.197434 -397.124428) (xy 343.195405 -397.119557) (xy 343.189645 -397.110721) (xy 343.186004 -397.106902)
			(xy 342.653366 -396.574264) (xy 342.646518 -396.566867) (xy 342.638786 -396.548268) (xy 342.63838 -396.538196)
			(xy 342.63838 -395.581632) (xy 342.638211 -395.575623) (xy 342.635382 -395.563943) (xy 342.632792 -395.558518)
			(xy 342.630954 -395.555043) (xy 342.626363 -395.548661) (xy 342.623648 -395.545818) (xy 342.374474 -395.296644)
			(xy 342.371622 -395.293939) (xy 342.365243 -395.289348) (xy 342.361774 -395.2875) (xy 342.356348 -395.284915)
			(xy 342.344668 -395.282087) (xy 342.33866 -395.281912) (xy 341.117174 -395.281912) (xy 341.112094 -395.282166)
			(xy 341.102719 -395.283483) (xy 341.085876 -395.292094) (xy 341.079328 -395.29893) (xy 341.028274 -395.361414)
			(xy 341.02475 -395.36587) (xy 341.019615 -395.376001) (xy 341.018114 -395.38148) (xy 341.015574 -395.392148)
			(xy 341.01786 -395.403578) (xy 341.020735 -395.419038) (xy 341.023785 -395.450338) (xy 341.023956 -395.466062)
			(xy 341.023575 -395.487871) (xy 341.01758 -395.531076) (xy 341.012018 -395.552168) (xy 341.011256 -395.555724)
			(xy 341.011256 -395.567662) (xy 341.01081 -395.582075) (xy 341.003658 -395.61) (xy 340.989791 -395.635272)
			(xy 340.970081 -395.656307) (xy 340.95817 -395.664436) (xy 340.957154 -395.669008) (xy 340.956299 -395.674321)
			(xy 340.956551 -395.685078) (xy 340.957662 -395.690344) (xy 340.974426 -395.764258) (xy 340.975791 -395.76947)
			(xy 340.980394 -395.77921) (xy 340.98357 -395.783562) (xy 340.98992 -395.791944) (xy 340.999572 -395.797278)
			(xy 341.023724 -395.811239) (xy 341.067157 -395.846241) (xy 341.085932 -395.866874) (xy 341.088414 -395.869626)
			(xy 341.094023 -395.874472) (xy 341.097108 -395.876526) (xy 341.109241 -395.884618) (xy 341.129308 -395.905769)
			(xy 341.143451 -395.931264) (xy 341.150772 -395.959485) (xy 341.15121 -395.974062) (xy 341.15121 -395.986508)
			(xy 341.152988 -395.992858) (xy 341.158099 -396.013176) (xy 341.163572 -396.054714) (xy 341.16391 -396.075662)
			(xy 341.16391 -396.07998) (xy 341.163639 -396.091591) (xy 341.161603 -396.114728) (xy 341.159846 -396.126208)
			(xy 341.15833 -396.135255) (xy 341.154391 -396.153173) (xy 341.151972 -396.162022) (xy 341.15121 -396.16507)
			(xy 341.15121 -396.621254) (xy 341.151972 -396.624302) (xy 341.157093 -396.64354) (xy 341.163077 -396.682898)
			(xy 341.16391 -396.702788) (xy 341.16391 -396.710662) (xy 341.728044 -396.710662) (xy 341.728412 -396.689641)
			(xy 341.734022 -396.647975) (xy 341.73922 -396.627604) (xy 341.740744 -396.621) (xy 341.740744 -396.507462)
			(xy 341.7412 -396.492465) (xy 341.74896 -396.463491) (xy 341.763944 -396.437507) (xy 341.785133 -396.416277)
			(xy 341.811089 -396.401244) (xy 341.840048 -396.393428) (xy 341.855044 -396.392908) (xy 342.037162 -396.392908)
			(xy 342.03767 -396.392654) (xy 342.054434 -396.392654) (xy 342.054942 -396.392908) (xy 342.236552 -396.392908)
			(xy 342.25158 -396.393422) (xy 342.280618 -396.401181) (xy 342.306662 -396.416184) (xy 342.327941 -396.437411)
			(xy 342.343009 -396.463417) (xy 342.35084 -396.492435) (xy 342.35136 -396.507462) (xy 342.35136 -396.621)
			(xy 342.352884 -396.627604) (xy 342.358077 -396.647976) (xy 342.363686 -396.689642) (xy 342.36406 -396.710662)
			(xy 342.36406 -396.71117) (xy 342.36389 -396.725795) (xy 342.361223 -396.754924) (xy 342.358726 -396.769336)
			(xy 342.357359 -396.77851) (xy 342.360633 -396.796753) (xy 342.365076 -396.804896) (xy 342.381586 -396.83182)
			(xy 342.38674 -396.83961) (xy 342.401477 -396.851066) (xy 342.410288 -396.854172) (xy 342.435166 -396.862246)
			(xy 342.482046 -396.885433) (xy 342.524458 -396.916034) (xy 342.561242 -396.953213) (xy 342.59139 -396.995949)
			(xy 342.614076 -397.043073) (xy 342.62187 -397.06804) (xy 342.623394 -397.073882) (xy 342.943688 -397.627602)
			(xy 342.947752 -397.63192) (xy 342.963952 -397.649631) (xy 342.991375 -397.689022) (xy 343.012518 -397.732111)
			(xy 343.026892 -397.777904) (xy 343.034168 -397.825346) (xy 343.03462 -397.849344) (xy 343.034132 -397.874806)
			(xy 343.025934 -397.925067) (xy 343.009772 -397.97336) (xy 342.986067 -398.018431) (xy 342.955433 -398.059113)
			(xy 342.918666 -398.094348) (xy 342.897968 -398.109186) (xy 342.889486 -398.115651) (xy 342.878308 -398.133786)
			(xy 342.875444 -398.154896) (xy 342.881386 -398.175353) (xy 342.895113 -398.191644) (xy 342.914267 -398.20097)
			(xy 342.924892 -398.201896) (xy 342.934798 -398.201388) (xy 342.943249 -398.200104) (xy 342.960287 -398.198704)
			(xy 342.968834 -398.198594) (xy 342.969088 -398.198848) (xy 343.2683 -398.198848) (xy 343.268554 -398.198594)
			(xy 343.289601 -398.198984) (xy 343.330922 -398.206983) (xy 343.369877 -398.222917) (xy 343.404959 -398.246169)
			(xy 343.434809 -398.27584) (xy 343.458274 -398.31078) (xy 343.474443 -398.349638) (xy 343.482692 -398.39091)
			(xy 343.483184 -398.411954) (xy 343.483184 -398.666716) (xy 343.47404 -398.666716) (xy 343.464019 -398.667153)
			(xy 343.4455 -398.674812) (xy 343.431326 -398.68898) (xy 343.423657 -398.707496) (xy 343.42324 -398.717516)
			(xy 343.42324 -398.881092) (xy 343.422706 -398.891094) (xy 343.415057 -398.909578) (xy 343.400918 -398.92373)
			(xy 343.382442 -398.931397) (xy 343.37244 -398.931892) (xy 342.864948 -398.931892) (xy 342.854929 -398.931441)
			(xy 342.836411 -398.923785) (xy 342.822237 -398.909622) (xy 342.814567 -398.891111) (xy 342.814148 -398.881092)
			(xy 342.814148 -398.717516) (xy 342.8136 -398.707515) (xy 342.805955 -398.689033) (xy 342.791821 -398.674881)
			(xy 342.773348 -398.667213) (xy 342.763348 -398.666716) (xy 342.754204 -398.666716) (xy 342.754204 -398.411446)
			(xy 342.754989 -398.385724) (xy 342.767322 -398.335778) (xy 342.778588 -398.31264) (xy 342.78443 -398.30121)
			(xy 342.784176 -398.27581) (xy 342.736678 -398.190212) (xy 342.72995 -398.179438) (xy 342.708631 -398.165697)
			(xy 342.696038 -398.16405) (xy 342.672166 -398.161853) (xy 342.625422 -398.151225) (xy 342.580826 -398.133645)
			(xy 342.539404 -398.109518) (xy 342.502112 -398.079398) (xy 342.469808 -398.043981) (xy 342.443237 -398.004082)
			(xy 342.423012 -397.960622) (xy 342.415876 -397.937736) (xy 342.414352 -397.931894) (xy 342.094058 -397.378174)
			(xy 342.089994 -397.373856) (xy 342.073841 -397.356116) (xy 342.046471 -397.316716) (xy 342.025378 -397.273628)
			(xy 342.011049 -397.227844) (xy 342.003814 -397.180419) (xy 342.00338 -397.156432) (xy 342.003561 -397.142384)
			(xy 342.006102 -397.114402) (xy 342.00846 -397.100552) (xy 342.009788 -397.091273) (xy 342.006258 -397.072875)
			(xy 342.001602 -397.064738) (xy 341.984838 -397.037814) (xy 341.979629 -397.030116) (xy 341.964908 -397.01879)
			(xy 341.956136 -397.015716) (xy 341.934508 -397.008921) (xy 341.893294 -396.990038) (xy 341.855174 -396.965501)
			(xy 341.820919 -396.935806) (xy 341.805768 -396.918942) (xy 341.8033 -396.916174) (xy 341.797692 -396.911325)
			(xy 341.794592 -396.90929) (xy 341.782539 -396.901217) (xy 341.762579 -396.88018) (xy 341.748501 -396.854826)
			(xy 341.741198 -396.826761) (xy 341.740744 -396.812262) (xy 341.740744 -396.800324) (xy 341.73922 -396.79372)
			(xy 341.734013 -396.773351) (xy 341.728413 -396.731683) (xy 341.728044 -396.710662) (xy 341.16391 -396.710662)
			(xy 341.16391 -396.71498) (xy 341.163656 -396.725648) (xy 341.163656 -396.726156) (xy 341.163031 -396.736503)
			(xy 341.160614 -396.757093) (xy 341.15883 -396.767304) (xy 341.158068 -396.77594) (xy 341.15823 -396.783024)
			(xy 341.161966 -396.796685) (xy 341.165434 -396.802864) (xy 341.177118 -396.82166) (xy 341.17959 -396.825616)
			(xy 341.185726 -396.832643) (xy 341.18931 -396.83563) (xy 341.210392 -396.851632) (xy 341.21598 -396.85341)
			(xy 341.241132 -396.862073) (xy 341.288349 -396.886569) (xy 341.330837 -396.918572) (xy 341.367414 -396.957193)
			(xy 341.397063 -397.001356) (xy 341.418958 -397.049834) (xy 341.426292 -397.075406) (xy 341.431372 -397.087852)
			(xy 341.743538 -397.627602) (xy 341.747602 -397.63192) (xy 341.76376 -397.649589) (xy 341.791093 -397.688899)
			(xy 341.812168 -397.73189) (xy 341.826502 -397.777572) (xy 341.833765 -397.824897) (xy 341.834216 -397.848836)
			(xy 341.834216 -397.849344) (xy 341.833736 -397.874797) (xy 341.825577 -397.925044) (xy 341.809463 -397.973332)
			(xy 341.78581 -398.018409) (xy 341.755231 -398.059106) (xy 341.718519 -398.094371) (xy 341.697818 -398.109186)
			(xy 341.689324 -398.115669) (xy 341.678131 -398.133842) (xy 341.675292 -398.154996) (xy 341.681298 -398.175477)
			(xy 341.695112 -398.191747) (xy 341.714346 -398.200997) (xy 341.724996 -398.201896) (xy 341.734648 -398.201388)
			(xy 341.743159 -398.200074) (xy 341.760326 -398.198675) (xy 341.768938 -398.198594) (xy 341.769192 -398.198848)
			(xy 342.068404 -398.198848) (xy 342.068658 -398.198594) (xy 342.089703 -398.198959) (xy 342.131021 -398.206961)
			(xy 342.169972 -398.222899) (xy 342.205047 -398.246156) (xy 342.234889 -398.275832) (xy 342.258341 -398.310777)
			(xy 342.274496 -398.349639) (xy 342.282727 -398.390911) (xy 342.283288 -398.411954) (xy 342.283288 -398.615916)
			(xy 342.282797 -398.625921) (xy 342.275134 -398.644405) (xy 342.260981 -398.65855) (xy 342.242493 -398.666203)
			(xy 342.232488 -398.666716) (xy 342.223344 -398.666716) (xy 342.223344 -398.881092) (xy 342.222858 -398.891104)
			(xy 342.215201 -398.909606) (xy 342.20105 -398.923772) (xy 342.182555 -398.931448) (xy 342.172544 -398.931892)
			(xy 341.665052 -398.931892) (xy 341.655051 -398.931396) (xy 341.636577 -398.923727) (xy 341.622441 -398.909576)
			(xy 341.614793 -398.891093) (xy 341.614252 -398.881092) (xy 341.614252 -398.717516) (xy 341.613835 -398.707496)
			(xy 341.606166 -398.688982) (xy 341.591991 -398.674816) (xy 341.573472 -398.667159) (xy 341.563452 -398.666716)
			(xy 341.554308 -398.666716) (xy 341.554308 -398.411446) (xy 341.555104 -398.385724) (xy 341.567426 -398.335776)
			(xy 341.578692 -398.31264) (xy 341.584534 -398.30121) (xy 341.58428 -398.27581) (xy 341.536782 -398.190212)
			(xy 341.530069 -398.179432) (xy 341.508733 -398.165723) (xy 341.496142 -398.16405) (xy 341.472258 -398.161879)
			(xy 341.425499 -398.151233) (xy 341.380886 -398.133641) (xy 341.339445 -398.109508) (xy 341.302129 -398.079388)
			(xy 341.269794 -398.043973) (xy 341.243184 -398.004077) (xy 341.22291 -397.960617) (xy 341.215726 -397.937736)
			(xy 341.214202 -397.931894) (xy 340.899242 -397.387064) (xy 340.897718 -397.385794) (xy 340.88324 -397.383508)
			(xy 340.875919 -397.38264) (xy 340.861328 -397.3847) (xy 340.854538 -397.387572) (xy 340.77021 -397.425672)
			(xy 340.764368 -397.428974) (xy 340.75726 -397.433782) (xy 340.746516 -397.447149) (xy 340.740821 -397.463325)
			(xy 340.740492 -397.4719) (xy 340.740492 -398.160748) (xy 340.741003 -398.171585) (xy 340.749945 -398.191328)
			(xy 340.757764 -398.198848) (xy 340.868508 -398.198848) (xy 340.868762 -398.198594) (xy 340.889807 -398.19896)
			(xy 340.931124 -398.206962) (xy 340.970074 -398.2229) (xy 341.005149 -398.246157) (xy 341.03499 -398.275833)
			(xy 341.058442 -398.310778) (xy 341.074596 -398.349639) (xy 341.082827 -398.390911) (xy 341.083392 -398.411954)
			(xy 341.083392 -398.666716) (xy 341.080852 -398.666716) (xy 341.05596 -398.726406) (xy 341.056976 -398.728438)
			(xy 341.058851 -398.731832) (xy 341.063445 -398.738077) (xy 341.06612 -398.740884) (xy 341.349584 -399.024348)
			(xy 341.356425 -399.031748) (xy 341.364144 -399.050347) (xy 341.36457 -399.060416) (xy 341.36457 -399.962878)
			(xy 341.364619 -399.966749) (xy 341.365768 -399.974403) (xy 341.366856 -399.978118) (xy 341.368681 -399.983445)
			(xy 341.374311 -399.993196) (xy 341.378032 -399.997422) (xy 341.395475 -400.017125) (xy 341.424257 -400.061175)
			(xy 341.445395 -400.109362) (xy 341.458312 -400.160371) (xy 341.462656 -400.21281) (xy 341.458308 -400.26525)
			(xy 341.445388 -400.316258) (xy 341.424247 -400.364443) (xy 341.395462 -400.408491) (xy 341.378032 -400.428206)
			(xy 341.371428 -400.435572) (xy 341.368126 -400.444208) (xy 341.366502 -400.448672) (xy 341.364719 -400.458002)
			(xy 341.36457 -400.46275) (xy 341.36457 -400.486118) (xy 341.374476 -400.506692) (xy 341.38362 -400.514058)
			(xy 341.405417 -400.532277) (xy 341.443894 -400.574069) (xy 341.475748 -400.621105) (xy 341.500275 -400.672344)
			(xy 341.516932 -400.726654) (xy 341.525351 -400.782834) (xy 341.52586 -400.811238) (xy 341.52586 -401.674838)
			(xy 341.962232 -401.674838) (xy 341.962232 -400.811238) (xy 341.96266 -400.785718) (xy 341.969449 -400.735132)
			(xy 341.982926 -400.685904) (xy 342.002849 -400.638913) (xy 342.028861 -400.594999) (xy 342.060499 -400.554948)
			(xy 342.078564 -400.536918) (xy 342.085168 -400.530568) (xy 342.093042 -400.513804) (xy 342.0999 -400.42846)
			(xy 342.09482 -400.41068) (xy 342.089232 -400.403314) (xy 342.074382 -400.382566) (xy 342.050746 -400.337352)
			(xy 342.034645 -400.288941) (xy 342.026492 -400.238577) (xy 342.025986 -400.213068) (xy 342.025986 -400.212814)
			(xy 342.026476 -400.187825) (xy 342.034295 -400.138462) (xy 342.049739 -400.09093) (xy 342.072429 -400.046398)
			(xy 342.101805 -400.005965) (xy 342.137145 -399.970625) (xy 342.177578 -399.941249) (xy 342.22211 -399.918559)
			(xy 342.269642 -399.903115) (xy 342.319005 -399.895296) (xy 342.368983 -399.895296) (xy 342.418346 -399.903115)
			(xy 342.465878 -399.918559) (xy 342.51041 -399.941249) (xy 342.550843 -399.970625) (xy 342.586183 -400.005965)
			(xy 342.615559 -400.046398) (xy 342.638249 -400.09093) (xy 342.653693 -400.138462) (xy 342.661512 -400.187825)
			(xy 342.662002 -400.212814) (xy 342.662002 -400.213068) (xy 342.661509 -400.238577) (xy 342.653331 -400.288936)
			(xy 342.637229 -400.337348) (xy 342.613614 -400.382572) (xy 342.598756 -400.403314) (xy 342.593168 -400.41068)
			(xy 342.588088 -400.42846) (xy 342.594946 -400.513804) (xy 342.60282 -400.530568) (xy 342.609424 -400.536918)
			(xy 342.627453 -400.554982) (xy 342.659085 -400.595032) (xy 342.685097 -400.638939) (xy 342.705026 -400.685922)
			(xy 342.718516 -400.735142) (xy 342.725326 -400.785721) (xy 342.725756 -400.811238) (xy 342.725756 -401.674838)
			(xy 342.725746 -401.675346) (xy 343.162636 -401.675346) (xy 343.162636 -400.81073) (xy 343.163065 -400.785262)
			(xy 343.169868 -400.734781) (xy 343.18333 -400.685656) (xy 343.203212 -400.638759) (xy 343.22916 -400.594927)
			(xy 343.260712 -400.554938) (xy 343.278714 -400.536918) (xy 343.285318 -400.530568) (xy 343.293192 -400.513804)
			(xy 343.30005 -400.42846) (xy 343.29497 -400.41068) (xy 343.289382 -400.403314) (xy 343.274525 -400.38257)
			(xy 343.250893 -400.337354) (xy 343.234793 -400.288942) (xy 343.226642 -400.238578) (xy 343.226136 -400.213068)
			(xy 343.226136 -400.212814) (xy 343.226626 -400.187825) (xy 343.234445 -400.138462) (xy 343.249889 -400.09093)
			(xy 343.272579 -400.046398) (xy 343.301955 -400.005965) (xy 343.337295 -399.970625) (xy 343.377728 -399.941249)
			(xy 343.42226 -399.918559) (xy 343.469792 -399.903115) (xy 343.519155 -399.895296) (xy 343.569133 -399.895296)
			(xy 343.618496 -399.903115) (xy 343.666028 -399.918559) (xy 343.71056 -399.941249) (xy 343.750993 -399.970625)
			(xy 343.786333 -400.005965) (xy 343.815709 -400.046398) (xy 343.838399 -400.09093) (xy 343.853843 -400.138462)
			(xy 343.861662 -400.187825) (xy 343.862152 -400.212814) (xy 343.862152 -400.213068) (xy 343.861649 -400.238577)
			(xy 343.853473 -400.288935) (xy 343.837374 -400.337346) (xy 343.813762 -400.382571) (xy 343.798906 -400.403314)
			(xy 343.793318 -400.41068) (xy 343.788238 -400.42846) (xy 343.795096 -400.513804) (xy 343.80297 -400.530568)
			(xy 343.809574 -400.536918) (xy 343.827577 -400.554936) (xy 343.859117 -400.594931) (xy 343.885057 -400.638766)
			(xy 343.904936 -400.685662) (xy 343.9184 -400.734785) (xy 343.925211 -400.785263) (xy 343.925652 -400.81073)
			(xy 343.925652 -401.675346) (xy 343.925176 -401.703744) (xy 343.916763 -401.759913) (xy 343.9001 -401.814209)
			(xy 343.875558 -401.865428) (xy 343.843681 -401.912433) (xy 343.824814 -401.933664) (xy 343.818954 -401.9406)
			(xy 343.812046 -401.957378) (xy 343.811352 -401.96643) (xy 343.810336 -401.997418) (xy 343.810382 -402.00657)
			(xy 343.816255 -402.023892) (xy 343.821766 -402.0312) (xy 343.83711 -402.050547) (xy 343.862884 -402.092668)
			(xy 343.882662 -402.137914) (xy 343.896074 -402.185438) (xy 343.902869 -402.234348) (xy 343.9033 -402.259038)
			(xy 343.902798 -402.285915) (xy 343.894786 -402.33907) (xy 343.878942 -402.390436) (xy 343.855618 -402.438868)
			(xy 343.825337 -402.483282) (xy 343.788775 -402.522687) (xy 343.746747 -402.556203) (xy 343.700194 -402.58308)
			(xy 343.650155 -402.602719) (xy 343.597748 -402.61468) (xy 343.544144 -402.618698) (xy 343.49054 -402.61468)
			(xy 343.438133 -402.602719) (xy 343.388094 -402.58308) (xy 343.341541 -402.556203) (xy 343.299513 -402.522687)
			(xy 343.262951 -402.483282) (xy 343.23267 -402.438868) (xy 343.209346 -402.390436) (xy 343.193502 -402.33907)
			(xy 343.18549 -402.285915) (xy 343.184988 -402.259038) (xy 343.18539 -402.234344) (xy 343.192146 -402.185422)
			(xy 343.20555 -402.137888) (xy 343.225348 -402.092643) (xy 343.251166 -402.050542) (xy 343.266522 -402.0312)
			(xy 343.272001 -402.023878) (xy 343.277849 -402.006563) (xy 343.277952 -401.997418) (xy 343.276936 -401.96643)
			(xy 343.276296 -401.957366) (xy 343.269378 -401.940573) (xy 343.263474 -401.933664) (xy 343.244656 -401.9124)
			(xy 343.212837 -401.865373) (xy 343.188321 -401.814158) (xy 343.171649 -401.759881) (xy 343.163187 -401.703735)
			(xy 343.162636 -401.675346) (xy 342.725746 -401.675346) (xy 342.725195 -401.704001) (xy 342.716274 -401.761643)
			(xy 342.698691 -401.817258) (xy 342.672854 -401.869551) (xy 342.639366 -401.917308) (xy 342.619584 -401.938744)
			(xy 342.613426 -401.945827) (xy 342.606268 -401.963162) (xy 342.605614 -401.972526) (xy 342.603836 -402.041106)
			(xy 342.603972 -402.050363) (xy 342.61011 -402.067817) (xy 342.615774 -402.075142) (xy 342.616282 -402.07565)
			(xy 342.632628 -402.095269) (xy 342.660164 -402.138276) (xy 342.681323 -402.184752) (xy 342.695679 -402.233758)
			(xy 342.702942 -402.284305) (xy 342.703404 -402.309838) (xy 342.702902 -402.336734) (xy 342.694884 -402.389926)
			(xy 342.679028 -402.441329) (xy 342.655689 -402.489795) (xy 342.625386 -402.534241) (xy 342.588798 -402.573674)
			(xy 342.546741 -402.607213) (xy 342.500155 -402.634109) (xy 342.450081 -402.653762) (xy 342.397636 -402.665732)
			(xy 342.343994 -402.669752) (xy 342.290352 -402.665732) (xy 342.237907 -402.653762) (xy 342.187833 -402.634109)
			(xy 342.141247 -402.607213) (xy 342.09919 -402.573674) (xy 342.062602 -402.534241) (xy 342.032299 -402.489795)
			(xy 342.00896 -402.441329) (xy 341.993104 -402.389926) (xy 341.985086 -402.336734) (xy 341.984584 -402.309838)
			(xy 341.985052 -402.28427) (xy 341.992329 -402.233654) (xy 342.006727 -402.184586) (xy 342.027952 -402.138063)
			(xy 342.055574 -402.095029) (xy 342.07196 -402.075396) (xy 342.072214 -402.075142) (xy 342.077883 -402.067825)
			(xy 342.08399 -402.050363) (xy 342.084152 -402.041106) (xy 342.08212 -401.962874) (xy 342.075008 -401.945856)
			(xy 342.068404 -401.938744) (xy 342.048619 -401.917311) (xy 342.015127 -401.869556) (xy 341.989292 -401.817262)
			(xy 341.971714 -401.761645) (xy 341.962803 -401.704002) (xy 341.962232 -401.674838) (xy 341.52586 -401.674838)
			(xy 341.525305 -401.70399) (xy 341.516432 -401.761615) (xy 341.498897 -401.81722) (xy 341.473109 -401.869511)
			(xy 341.439668 -401.917271) (xy 341.419942 -401.938744) (xy 341.413632 -401.945827) (xy 341.406314 -401.963314)
			(xy 341.405718 -401.97278) (xy 341.403686 -402.050504) (xy 341.409782 -402.06803) (xy 341.411814 -402.070316)
			(xy 341.419501 -402.07898) (xy 341.433866 -402.097154) (xy 341.440516 -402.106638) (xy 341.44592 -402.114651)
			(xy 341.455958 -402.13117) (xy 341.460582 -402.139658) (xy 341.474075 -402.165975) (xy 341.493206 -402.221932)
			(xy 341.5029 -402.280269) (xy 341.503508 -402.309838) (xy 341.502938 -402.336564) (xy 341.494876 -402.389408)
			(xy 341.479096 -402.440482) (xy 341.467948 -402.464778) (xy 341.467948 -402.465286) (xy 341.455248 -402.489416)
			(xy 341.453216 -402.493226) (xy 341.446104 -402.519134) (xy 341.446675 -402.529058) (xy 341.454381 -402.54736)
			(xy 341.46109 -402.554694) (xy 341.735918 -402.829522) (xy 341.743276 -402.836166) (xy 341.761577 -402.843736)
			(xy 341.771478 -402.844254) (xy 348.32544 -402.844254)
		)
		(stroke
			(width 0)
			(type solid)
		)
		(fill yes)
		(layer "B.Cu")
		(net "P0V9_CPU0_RT_2D")
	)
	(gr_poly
		(pts
			(xy 92.33535 -394.461238) (xy 92.342593 -394.45961) (xy 92.35576 -394.452766) (xy 92.361258 -394.447776)
			(xy 92.43949 -394.369544) (xy 92.445918 -394.362544) (xy 92.453523 -394.345142) (xy 92.454295 -394.326166)
			(xy 92.448128 -394.308204) (xy 92.442284 -394.30071) (xy 92.438982 -394.297408) (xy 92.434696 -394.293388)
			(xy 92.424689 -394.287233) (xy 92.41917 -394.285216) (xy 92.408502 -394.28166) (xy 92.402406 -394.282676)
			(xy 92.39631 -394.283438) (xy 92.383428 -394.285204) (xy 92.357495 -394.287109) (xy 92.344494 -394.287248)
			(xy 92.34424 -394.287248) (xy 92.318578 -394.286772) (xy 92.267782 -394.279435) (xy 92.218545 -394.264948)
			(xy 92.17187 -394.243604) (xy 92.128705 -394.215838) (xy 92.089929 -394.182214) (xy 92.056329 -394.143417)
			(xy 92.02859 -394.100235) (xy 92.007275 -394.053547) (xy 91.992817 -394.004301) (xy 91.985512 -393.9535)
			(xy 91.985084 -393.927838) (xy 91.985084 -393.926568) (xy 91.985746 -393.898138) (xy 91.994942 -393.842021)
			(xy 92.012862 -393.788053) (xy 92.039059 -393.737581) (xy 92.072878 -393.691866) (xy 92.09278 -393.671552)
			(xy 92.099892 -393.66444) (xy 92.103702 -393.655804) (xy 92.105635 -393.651142) (xy 92.107809 -393.641288)
			(xy 92.10802 -393.636246) (xy 92.108274 -393.616942) (xy 92.107919 -393.605997) (xy 92.099093 -393.585982)
			(xy 92.091256 -393.578334) (xy 92.071429 -393.560154) (xy 92.036573 -393.51918) (xy 92.00782 -393.473716)
			(xy 91.985739 -393.424663) (xy 91.970769 -393.372994) (xy 91.963206 -393.319735) (xy 91.962732 -393.292838)
			(xy 91.962732 -392.429238) (xy 91.963236 -392.401138) (xy 91.971489 -392.345546) (xy 91.987807 -392.291767)
			(xy 92.011837 -392.240962) (xy 92.043059 -392.194232) (xy 92.080798 -392.152588) (xy 92.102178 -392.134344)
			(xy 92.110814 -392.127486) (xy 92.120466 -392.107928) (xy 92.12072 -392.096752) (xy 92.121228 -392.079226)
			(xy 92.121215 -392.074357) (xy 92.119554 -392.064765) (xy 92.117926 -392.060176) (xy 92.114878 -392.05154)
			(xy 92.10802 -392.04392) (xy 92.092708 -392.02631) (xy 92.066872 -391.987448) (xy 92.046989 -391.945231)
			(xy 92.033483 -391.900562) (xy 92.026644 -391.854401) (xy 92.026232 -391.831068) (xy 92.026232 -391.830814)
			(xy 92.026696 -391.805823) (xy 92.034513 -391.756457) (xy 92.049958 -391.708922) (xy 92.072649 -391.664388)
			(xy 92.102029 -391.623953) (xy 92.137372 -391.588612) (xy 92.17781 -391.559236) (xy 92.222346 -391.536548)
			(xy 92.269882 -391.521107) (xy 92.319249 -391.513294) (xy 92.34424 -391.512806) (xy 92.34424 -391.512552)
			(xy 92.366124 -391.512949) (xy 92.409469 -391.519024) (xy 92.451569 -391.530999) (xy 92.471748 -391.539476)
			(xy 92.472002 -391.539476) (xy 92.477929 -391.541842) (xy 92.490521 -391.54389) (xy 92.496894 -391.54354)
			(xy 92.508832 -391.542524) (xy 92.592906 -391.48766) (xy 92.602282 -391.480045) (xy 92.613268 -391.458571)
			(xy 92.613988 -391.446512) (xy 92.613988 -389.866886) (xy 92.614291 -389.859629) (xy 92.618426 -389.845711)
			(xy 92.622116 -389.839454) (xy 92.62618 -389.833358) (xy 92.630244 -389.819388) (xy 92.630244 -389.80872)
			(xy 92.629805 -389.798658) (xy 92.622064 -389.780079) (xy 92.615258 -389.772652) (xy 92.608146 -389.76554)
			(xy 92.598748 -389.76173) (xy 92.575882 -389.751862) (xy 92.533286 -389.726063) (xy 92.495234 -389.693936)
			(xy 92.462659 -389.656269) (xy 92.436356 -389.613982) (xy 92.41697 -389.56811) (xy 92.410534 -389.544052)
			(xy 92.410026 -389.542274) (xy 92.094304 -388.996174) (xy 92.09024 -388.991856) (xy 92.074023 -388.974158)
			(xy 92.04659 -388.93477) (xy 92.025443 -388.891678) (xy 92.011071 -388.84588) (xy 92.003807 -388.798432)
			(xy 92.003372 -388.774432) (xy 92.003547 -388.760384) (xy 92.006089 -388.732401) (xy 92.008452 -388.718552)
			(xy 92.009821 -388.709295) (xy 92.006415 -388.690907) (xy 92.001848 -388.682738) (xy 91.985084 -388.655814)
			(xy 91.979876 -388.648115) (xy 91.965153 -388.636795) (xy 91.956382 -388.633716) (xy 91.934751 -388.626924)
			(xy 91.893526 -388.60806) (xy 91.855402 -388.583525) (xy 91.821155 -388.553817) (xy 91.806014 -388.536942)
			(xy 91.803534 -388.534187) (xy 91.797928 -388.529337) (xy 91.794838 -388.52729) (xy 91.782797 -388.519227)
			(xy 91.762898 -388.498171) (xy 91.748898 -388.472807) (xy 91.741686 -388.444748) (xy 91.741244 -388.430262)
			(xy 91.741244 -388.418324) (xy 91.739466 -388.41172) (xy 91.734272 -388.391348) (xy 91.728672 -388.349682)
			(xy 91.72829 -388.328662) (xy 91.728664 -388.307642) (xy 91.734274 -388.265976) (xy 91.739466 -388.245604)
			(xy 91.741244 -388.239) (xy 91.741244 -388.125462) (xy 91.741739 -388.110448) (xy 91.749518 -388.081446)
			(xy 91.764538 -388.055445) (xy 91.785774 -388.034216) (xy 91.81178 -388.019205) (xy 91.840784 -388.011434)
			(xy 91.855798 -388.010908) (xy 92.037408 -388.010908) (xy 92.037916 -388.010654) (xy 92.05468 -388.010654)
			(xy 92.055188 -388.010908) (xy 92.2274 -388.010908) (xy 92.237408 -388.01042) (xy 92.255901 -388.002761)
			(xy 92.270056 -387.988608) (xy 92.277718 -387.970116) (xy 92.2782 -387.960108) (xy 92.2782 -387.520942)
			(xy 92.277766 -387.510877) (xy 92.270037 -387.492287) (xy 92.263214 -387.484874) (xy 92.222066 -387.443726)
			(xy 92.215224 -387.436327) (xy 92.207506 -387.417728) (xy 92.20708 -387.407658) (xy 92.20708 -387.037072)
			(xy 92.206651 -387.027004) (xy 92.198927 -387.008409) (xy 92.192094 -387.001004) (xy 92.087446 -386.896356)
			(xy 92.080047 -386.889512) (xy 92.061448 -386.881788) (xy 92.051378 -386.88137) (xy 91.568016 -386.88137)
			(xy 91.562007 -386.881541) (xy 91.550328 -386.88437) (xy 91.544902 -386.886958) (xy 91.541428 -386.888798)
			(xy 91.535051 -386.893394) (xy 91.532202 -386.896102) (xy 91.258644 -387.16966) (xy 91.255936 -387.172509)
			(xy 91.251338 -387.178885) (xy 91.2495 -387.18236) (xy 91.246919 -387.187787) (xy 91.244099 -387.199467)
			(xy 91.243912 -387.205474) (xy 91.243912 -388.450328) (xy 91.244134 -388.457136) (xy 91.247749 -388.470263)
			(xy 91.251024 -388.476236) (xy 91.254326 -388.481824) (xy 91.264232 -388.491222) (xy 91.270582 -388.494778)
			(xy 91.293164 -388.507637) (xy 91.334189 -388.53953) (xy 91.369498 -388.577653) (xy 91.398159 -388.620998)
			(xy 91.419411 -388.668416) (xy 91.426538 -388.693406) (xy 91.431618 -388.705852) (xy 91.743784 -389.245602)
			(xy 91.747848 -389.24992) (xy 91.764067 -389.267617) (xy 91.791504 -389.307005) (xy 91.812655 -389.350096)
			(xy 91.827031 -389.395894) (xy 91.834299 -389.443343) (xy 91.834716 -389.467344) (xy 91.834228 -389.49212)
			(xy 91.826475 -389.541062) (xy 91.811166 -389.58819) (xy 91.788678 -389.632346) (xy 91.759564 -389.672443)
			(xy 91.72454 -389.707496) (xy 91.684466 -389.736643) (xy 91.640329 -389.759167) (xy 91.593213 -389.774514)
			(xy 91.544278 -389.782307) (xy 91.519502 -389.782812) (xy 91.518994 -389.782812) (xy 91.493601 -389.782304)
			(xy 91.443469 -389.774173) (xy 91.395285 -389.758121) (xy 91.350292 -389.734563) (xy 91.309651 -389.704106)
			(xy 91.27441 -389.667536) (xy 91.245478 -389.625796) (xy 91.223601 -389.579962) (xy 91.215972 -389.555736)
			(xy 91.214448 -389.549894) (xy 91.009724 -389.195564) (xy 91.003332 -389.185645) (xy 90.98374 -389.172538)
			(xy 90.972132 -389.170418) (xy 90.960448 -389.168894) (xy 90.93835 -389.176514) (xy 90.650314 -389.46455)
			(xy 90.647316 -389.467642) (xy 90.642343 -389.474672) (xy 90.640408 -389.47852) (xy 90.636598 -389.486648)
			(xy 90.635836 -389.495792) (xy 90.632956 -389.522017) (xy 90.619624 -389.573059) (xy 90.598052 -389.621201)
			(xy 90.568831 -389.665123) (xy 90.532763 -389.703621) (xy 90.512138 -389.720074) (xy 90.511884 -389.720328)
			(xy 90.507338 -389.723984) (xy 90.499886 -389.732956) (xy 90.497152 -389.738108) (xy 90.494612 -389.743188)
			(xy 90.492072 -389.754364) (xy 90.492072 -389.767064) (xy 90.53195 -389.803386) (xy 90.539287 -389.809538)
			(xy 90.557177 -389.816316) (xy 90.566748 -389.816594) (xy 90.569288 -389.816594) (xy 90.569542 -389.816848)
			(xy 90.868754 -389.816848) (xy 90.869008 -389.816594) (xy 90.886057 -389.816829) (xy 90.919745 -389.822067)
			(xy 90.936064 -389.827008) (xy 90.943684 -389.829548) (xy 90.973148 -389.829548) (xy 90.98651 -389.829988)
			(xy 91.012325 -389.836902) (xy 91.035478 -389.850249) (xy 91.054398 -389.869123) (xy 91.067802 -389.892243)
			(xy 91.074779 -389.918041) (xy 91.075256 -389.931402) (xy 91.075256 -389.97001) (xy 91.07678 -389.97636)
			(xy 91.080048 -389.989519) (xy 91.083621 -390.016398) (xy 91.083892 -390.029954) (xy 91.083892 -390.284716)
			(xy 91.075256 -390.284716) (xy 91.075256 -390.388602) (xy 91.074739 -390.403125) (xy 91.066558 -390.430994)
			(xy 91.050859 -390.455431) (xy 91.040204 -390.46531) (xy 91.039442 -390.465818) (xy 91.032584 -390.472168)
			(xy 91.023948 -390.491726) (xy 91.023948 -390.499092) (xy 91.023462 -390.509104) (xy 91.015806 -390.527607)
			(xy 91.001654 -390.541774) (xy 90.98316 -390.549451) (xy 90.973148 -390.549892) (xy 90.542872 -390.549892)
			(xy 90.532868 -390.550385) (xy 90.514384 -390.558049) (xy 90.500238 -390.572201) (xy 90.492581 -390.590687)
			(xy 90.492072 -390.600692) (xy 90.492072 -390.642602) (xy 91.537536 -390.642602) (xy 91.537536 -390.160002)
			(xy 91.538022 -390.132751) (xy 91.545778 -390.078803) (xy 91.561133 -390.026508) (xy 91.583775 -389.976931)
			(xy 91.613241 -389.931081) (xy 91.648932 -389.88989) (xy 91.690123 -389.854199) (xy 91.735973 -389.824733)
			(xy 91.78555 -389.802091) (xy 91.837845 -389.786736) (xy 91.891793 -389.77898) (xy 91.946295 -389.77898)
			(xy 92.000243 -389.786736) (xy 92.052538 -389.802091) (xy 92.102115 -389.824733) (xy 92.147965 -389.854199)
			(xy 92.189156 -389.88989) (xy 92.224847 -389.931081) (xy 92.254313 -389.976931) (xy 92.276955 -390.026508)
			(xy 92.29231 -390.078803) (xy 92.300066 -390.132751) (xy 92.300552 -390.160002) (xy 92.300552 -390.642602)
			(xy 92.300066 -390.669853) (xy 92.29231 -390.723801) (xy 92.276955 -390.776096) (xy 92.254313 -390.825673)
			(xy 92.224847 -390.871523) (xy 92.189156 -390.912714) (xy 92.147965 -390.948405) (xy 92.102115 -390.977871)
			(xy 92.052538 -391.000513) (xy 92.000243 -391.015868) (xy 91.946295 -391.023624) (xy 91.891793 -391.023624)
			(xy 91.837845 -391.015868) (xy 91.78555 -391.000513) (xy 91.735973 -390.977871) (xy 91.690123 -390.948405)
			(xy 91.648932 -390.912714) (xy 91.613241 -390.871523) (xy 91.583775 -390.825673) (xy 91.561133 -390.776096)
			(xy 91.545778 -390.723801) (xy 91.538022 -390.669853) (xy 91.537536 -390.642602) (xy 90.492072 -390.642602)
			(xy 90.492072 -391.445496) (xy 90.491649 -391.455566) (xy 90.483932 -391.474169) (xy 90.477086 -391.481564)
			(xy 90.359738 -391.598912) (xy 90.354915 -391.603465) (xy 90.343467 -391.610153) (xy 90.337132 -391.61212)
			(xy 90.32915 -391.614622) (xy 90.315283 -391.623959) (xy 90.309954 -391.630408) (xy 90.262456 -391.6934)
			(xy 90.258138 -391.699242) (xy 90.254724 -391.703971) (xy 90.249976 -391.714623) (xy 90.24874 -391.720324)
			(xy 90.246708 -391.731754) (xy 90.248994 -391.740136) (xy 90.255746 -391.764641) (xy 90.262257 -391.815049)
			(xy 90.261948 -391.840466) (xy 90.260535 -391.868382) (xy 90.249148 -391.923102) (xy 90.228388 -391.974995)
			(xy 90.198889 -392.022469) (xy 90.180668 -392.043666) (xy 90.17381 -392.051032) (xy 90.170508 -392.059922)
			(xy 90.168993 -392.064468) (xy 90.167461 -392.073926) (xy 90.16746 -392.078718) (xy 90.167968 -392.097514)
			(xy 90.167968 -392.098022) (xy 90.168222 -392.107928) (xy 90.17762 -392.126978) (xy 90.18651 -392.134344)
			(xy 90.207915 -392.15256) (xy 90.245657 -392.194207) (xy 90.27688 -392.240942) (xy 90.300906 -392.291752)
			(xy 90.317217 -392.345538) (xy 90.325459 -392.401136) (xy 90.325956 -392.429238) (xy 90.325956 -393.292838)
			(xy 90.762836 -393.292838) (xy 90.762836 -392.42873) (xy 90.763265 -392.403262) (xy 90.770068 -392.352781)
			(xy 90.78353 -392.303656) (xy 90.803412 -392.256759) (xy 90.82936 -392.212927) (xy 90.860912 -392.172938)
			(xy 90.878914 -392.154918) (xy 90.885518 -392.148568) (xy 90.893392 -392.131804) (xy 90.90025 -392.04646)
			(xy 90.89517 -392.02868) (xy 90.889582 -392.021314) (xy 90.874725 -392.00057) (xy 90.851093 -391.955354)
			(xy 90.834993 -391.906942) (xy 90.826842 -391.856578) (xy 90.826336 -391.831068) (xy 90.826336 -391.830814)
			(xy 90.826826 -391.805825) (xy 90.834645 -391.756462) (xy 90.850089 -391.70893) (xy 90.872779 -391.664398)
			(xy 90.902155 -391.623965) (xy 90.937495 -391.588625) (xy 90.977928 -391.559249) (xy 91.02246 -391.536559)
			(xy 91.069992 -391.521115) (xy 91.119355 -391.513296) (xy 91.169333 -391.513296) (xy 91.218696 -391.521115)
			(xy 91.266228 -391.536559) (xy 91.31076 -391.559249) (xy 91.351193 -391.588625) (xy 91.386533 -391.623965)
			(xy 91.415909 -391.664398) (xy 91.438599 -391.70893) (xy 91.454043 -391.756462) (xy 91.461862 -391.805825)
			(xy 91.462352 -391.830814) (xy 91.462352 -391.831068) (xy 91.461849 -391.856577) (xy 91.453673 -391.906935)
			(xy 91.437574 -391.955346) (xy 91.413962 -392.000571) (xy 91.399106 -392.021314) (xy 91.393518 -392.02868)
			(xy 91.388438 -392.04646) (xy 91.395296 -392.131804) (xy 91.40317 -392.148568) (xy 91.409774 -392.154918)
			(xy 91.427777 -392.172936) (xy 91.459317 -392.212931) (xy 91.485257 -392.256766) (xy 91.505136 -392.303662)
			(xy 91.5186 -392.352785) (xy 91.525411 -392.403263) (xy 91.525852 -392.42873) (xy 91.525852 -393.292838)
			(xy 91.525292 -393.321991) (xy 91.516422 -393.379618) (xy 91.498894 -393.435227) (xy 91.473116 -393.487525)
			(xy 91.439687 -393.535296) (xy 91.419934 -393.556744) (xy 91.41377 -393.563822) (xy 91.406617 -393.581161)
			(xy 91.405964 -393.590526) (xy 91.404186 -393.659106) (xy 91.404333 -393.668362) (xy 91.410465 -393.685815)
			(xy 91.416124 -393.693142) (xy 91.416632 -393.69365) (xy 91.432952 -393.713278) (xy 91.460423 -393.756302)
			(xy 91.481524 -393.802782) (xy 91.495831 -393.851783) (xy 91.503054 -393.902315) (xy 91.5035 -393.927838)
			(xy 91.502998 -393.954715) (xy 91.494986 -394.00787) (xy 91.479142 -394.059236) (xy 91.455818 -394.107668)
			(xy 91.425537 -394.152082) (xy 91.388975 -394.191487) (xy 91.346947 -394.225003) (xy 91.300394 -394.25188)
			(xy 91.250355 -394.271519) (xy 91.197948 -394.28348) (xy 91.144344 -394.287498) (xy 91.09074 -394.28348)
			(xy 91.038333 -394.271519) (xy 90.988294 -394.25188) (xy 90.941741 -394.225003) (xy 90.899713 -394.191487)
			(xy 90.863151 -394.152082) (xy 90.83287 -394.107668) (xy 90.809546 -394.059236) (xy 90.793702 -394.00787)
			(xy 90.78569 -393.954715) (xy 90.785188 -393.927838) (xy 90.785651 -393.90228) (xy 90.792888 -393.85168)
			(xy 90.807235 -393.80262) (xy 90.828401 -393.756094) (xy 90.855958 -393.713043) (xy 90.87231 -393.693396)
			(xy 90.872564 -393.693142) (xy 90.878227 -393.68582) (xy 90.884339 -393.668362) (xy 90.884502 -393.659106)
			(xy 90.88247 -393.580874) (xy 90.875358 -393.563856) (xy 90.868754 -393.556744) (xy 90.849028 -393.535271)
			(xy 90.815587 -393.487511) (xy 90.789799 -393.43522) (xy 90.772264 -393.379615) (xy 90.763391 -393.32199)
			(xy 90.762836 -393.292838) (xy 90.325956 -393.292838) (xy 90.325401 -393.321991) (xy 90.31653 -393.379617)
			(xy 90.298998 -393.435225) (xy 90.273215 -393.487519) (xy 90.23978 -393.535286) (xy 90.220038 -393.556744)
			(xy 90.213434 -393.563856) (xy 90.206322 -393.580874) (xy 90.20429 -393.659106) (xy 90.204453 -393.668362)
			(xy 90.210564 -393.685821) (xy 90.216228 -393.693142) (xy 90.216482 -393.693396) (xy 90.232834 -393.713043)
			(xy 90.260392 -393.756093) (xy 90.281558 -393.80262) (xy 90.295906 -393.85168) (xy 90.303143 -393.90228)
			(xy 90.303604 -393.927838) (xy 90.303102 -393.954715) (xy 90.29509 -394.00787) (xy 90.279246 -394.059236)
			(xy 90.255922 -394.107668) (xy 90.225641 -394.152082) (xy 90.189079 -394.191487) (xy 90.147051 -394.225003)
			(xy 90.100498 -394.25188) (xy 90.050459 -394.271519) (xy 89.998052 -394.28348) (xy 89.944448 -394.287498)
			(xy 89.890844 -394.28348) (xy 89.838437 -394.271519) (xy 89.788398 -394.25188) (xy 89.741845 -394.225003)
			(xy 89.699817 -394.191487) (xy 89.663255 -394.152082) (xy 89.632974 -394.107668) (xy 89.60965 -394.059236)
			(xy 89.593806 -394.00787) (xy 89.585794 -393.954715) (xy 89.585292 -393.927838) (xy 89.585738 -393.902315)
			(xy 89.592961 -393.851782) (xy 89.607267 -393.802782) (xy 89.628368 -393.756301) (xy 89.655838 -393.713277)
			(xy 89.67216 -393.69365) (xy 89.672668 -393.693142) (xy 89.678328 -393.685815) (xy 89.684461 -393.668362)
			(xy 89.684606 -393.659106) (xy 89.682828 -393.590526) (xy 89.682175 -393.581161) (xy 89.675021 -393.563823)
			(xy 89.668858 -393.556744) (xy 89.6491 -393.535299) (xy 89.615664 -393.48753) (xy 89.589879 -393.435232)
			(xy 89.572347 -393.379622) (xy 89.563475 -393.321992) (xy 89.56294 -393.292838) (xy 89.56294 -392.428984)
			(xy 89.56344 -392.400914) (xy 89.571673 -392.345381) (xy 89.587958 -392.291655) (xy 89.611944 -392.240897)
			(xy 89.643112 -392.194204) (xy 89.680789 -392.152584) (xy 89.702132 -392.134344) (xy 89.710768 -392.127486)
			(xy 89.72042 -392.107928) (xy 89.720674 -392.096752) (xy 89.721182 -392.079226) (xy 89.721169 -392.074357)
			(xy 89.719507 -392.064765) (xy 89.71788 -392.060176) (xy 89.714832 -392.05154) (xy 89.707974 -392.04392)
			(xy 89.692628 -392.026271) (xy 89.666745 -391.987318) (xy 89.646842 -391.944996) (xy 89.633347 -391.900217)
			(xy 89.626551 -391.853945) (xy 89.626186 -391.83056) (xy 89.626186 -391.82675) (xy 89.627202 -391.80516)
			(xy 89.628668 -391.789518) (xy 89.634271 -391.758602) (xy 89.638378 -391.743438) (xy 89.64168 -391.731754)
			(xy 89.639648 -391.720324) (xy 89.6384 -391.714568) (xy 89.63366 -391.703789) (xy 89.63025 -391.698988)
			(xy 89.581228 -391.634218) (xy 89.573674 -391.625156) (xy 89.552621 -391.61457) (xy 89.540842 -391.613898)
			(xy 89.14765 -391.613898) (xy 89.135869 -391.614561) (xy 89.114815 -391.625151) (xy 89.107264 -391.634218)
			(xy 89.058242 -391.698988) (xy 89.054817 -391.703781) (xy 89.050083 -391.714564) (xy 89.048844 -391.720324)
			(xy 89.046812 -391.731754) (xy 89.050114 -391.743438) (xy 89.055717 -391.764462) (xy 89.06184 -391.807538)
			(xy 89.062306 -391.82929) (xy 89.062306 -391.833862) (xy 89.061681 -391.856887) (xy 89.054604 -391.902399)
			(xy 89.041027 -391.946411) (xy 89.021235 -391.988001) (xy 88.995644 -392.026296) (xy 88.980518 -392.043666)
			(xy 88.973914 -392.051032) (xy 88.970612 -392.059668) (xy 88.969011 -392.064325) (xy 88.967469 -392.074049)
			(xy 88.967564 -392.078972) (xy 88.968326 -392.097768) (xy 88.968326 -392.098276) (xy 88.96858 -392.107674)
			(xy 88.978232 -392.127486) (xy 88.986614 -392.134344) (xy 89.008019 -392.15256) (xy 89.045761 -392.194207)
			(xy 89.076983 -392.240942) (xy 89.101009 -392.291753) (xy 89.11732 -392.345539) (xy 89.125562 -392.401136)
			(xy 89.12606 -392.429238) (xy 89.12606 -393.292838) (xy 89.12555 -393.320711) (xy 89.117432 -393.375863)
			(xy 89.101376 -393.429247) (xy 89.077722 -393.479726) (xy 89.046974 -393.526225) (xy 89.028778 -393.547346)
			(xy 89.022936 -393.55395) (xy 89.016078 -393.570714) (xy 89.014046 -393.645136) (xy 89.014112 -393.65405)
			(xy 89.019696 -393.670968) (xy 89.024968 -393.678156) (xy 89.025222 -393.67841) (xy 89.040017 -393.697568)
			(xy 89.06487 -393.739107) (xy 89.083914 -393.783609) (xy 89.096803 -393.830268) (xy 89.103304 -393.878235)
			(xy 89.103708 -393.902438) (xy 89.103206 -393.929334) (xy 89.095188 -393.982526) (xy 89.079332 -394.033929)
			(xy 89.055993 -394.082395) (xy 89.02569 -394.126841) (xy 88.989102 -394.166274) (xy 88.947045 -394.199813)
			(xy 88.900459 -394.226709) (xy 88.850385 -394.246362) (xy 88.79794 -394.258332) (xy 88.744298 -394.262352)
			(xy 88.690656 -394.258332) (xy 88.638211 -394.246362) (xy 88.588137 -394.226709) (xy 88.541551 -394.199813)
			(xy 88.499494 -394.166274) (xy 88.462906 -394.126841) (xy 88.432603 -394.082395) (xy 88.409264 -394.033929)
			(xy 88.393408 -393.982526) (xy 88.38539 -393.929334) (xy 88.384888 -393.902438) (xy 88.385305 -393.878238)
			(xy 88.39184 -393.830282) (xy 88.404743 -393.783633) (xy 88.423781 -393.739135) (xy 88.44861 -393.697589)
			(xy 88.463374 -393.67841) (xy 88.463628 -393.678156) (xy 88.468843 -393.670935) (xy 88.474442 -393.654042)
			(xy 88.47455 -393.645136) (xy 88.472518 -393.570714) (xy 88.46566 -393.55395) (xy 88.459818 -393.547346)
			(xy 88.441599 -393.526243) (xy 88.410846 -393.479742) (xy 88.387192 -393.429259) (xy 88.371139 -393.37587)
			(xy 88.363031 -393.320713) (xy 88.362536 -393.292838) (xy 88.362536 -392.429238) (xy 88.36304 -392.401138)
			(xy 88.371293 -392.345546) (xy 88.387611 -392.291767) (xy 88.411641 -392.240963) (xy 88.442864 -392.194233)
			(xy 88.480603 -392.152589) (xy 88.501982 -392.134344) (xy 88.510364 -392.127486) (xy 88.520016 -392.107674)
			(xy 88.52027 -392.098022) (xy 88.521032 -392.078972) (xy 88.521075 -392.074053) (xy 88.519531 -392.064338)
			(xy 88.517984 -392.059668) (xy 88.514682 -392.051032) (xy 88.508078 -392.043666) (xy 88.492968 -392.026285)
			(xy 88.467396 -391.987982) (xy 88.44761 -391.946393) (xy 88.434024 -391.902388) (xy 88.42692 -391.856884)
			(xy 88.42629 -391.833862) (xy 88.42629 -391.83056) (xy 88.426668 -391.808487) (xy 88.432789 -391.764768)
			(xy 88.438482 -391.743438) (xy 88.441784 -391.731754) (xy 88.439752 -391.720324) (xy 88.438504 -391.714568)
			(xy 88.433765 -391.703789) (xy 88.430354 -391.698988) (xy 88.381332 -391.634218) (xy 88.373778 -391.625156)
			(xy 88.352725 -391.614567) (xy 88.340946 -391.613898) (xy 88.029288 -391.613898) (xy 88.019219 -391.613472)
			(xy 88.000618 -391.605755) (xy 87.99322 -391.598912) (xy 87.841328 -391.44702) (xy 87.834491 -391.439619)
			(xy 87.826781 -391.42102) (xy 87.826342 -391.410952) (xy 87.826342 -389.806942) (xy 87.826093 -389.799528)
			(xy 87.821842 -389.785323) (xy 87.81796 -389.779002) (xy 87.813896 -389.772652) (xy 87.802466 -389.763254)
			(xy 87.795354 -389.760206) (xy 87.772887 -389.75024) (xy 87.731076 -389.724409) (xy 87.693739 -389.692451)
			(xy 87.661765 -389.655126) (xy 87.635918 -389.613325) (xy 87.616813 -389.568043) (xy 87.610442 -389.544306)
			(xy 87.609934 -389.542274) (xy 87.298784 -389.004048) (xy 87.296498 -389.001508) (xy 87.278753 -388.983452)
			(xy 87.248649 -388.942755) (xy 87.225376 -388.8978) (xy 87.209524 -388.849724) (xy 87.201494 -388.799743)
			(xy 87.200994 -388.774432) (xy 87.201248 -388.762748) (xy 87.201502 -388.75208) (xy 87.197692 -388.742428)
			(xy 87.195662 -388.737558) (xy 87.189898 -388.728725) (xy 87.186262 -388.724902) (xy 86.653624 -388.192264)
			(xy 86.646781 -388.184865) (xy 86.639055 -388.166266) (xy 86.638638 -388.156196) (xy 86.638638 -387.93928)
			(xy 86.638384 -387.931406) (xy 86.638384 -387.194552) (xy 86.637335 -387.186979) (xy 86.631397 -387.172898)
			(xy 86.6267 -387.166866) (xy 86.374986 -386.914898) (xy 86.374732 -386.914644) (xy 86.371882 -386.911936)
			(xy 86.365506 -386.907339) (xy 86.362032 -386.9055) (xy 86.356605 -386.90292) (xy 86.344925 -386.900101)
			(xy 86.338918 -386.899912) (xy 85.117432 -386.899912) (xy 85.112352 -386.900166) (xy 85.102981 -386.90149)
			(xy 85.086148 -386.91011) (xy 85.079586 -386.91693) (xy 85.028532 -386.979414) (xy 85.025011 -386.983872)
			(xy 85.01988 -386.994003) (xy 85.018372 -386.99948) (xy 85.015832 -387.010148) (xy 85.018118 -387.021578)
			(xy 85.020994 -387.037038) (xy 85.024043 -387.068338) (xy 85.024214 -387.084062) (xy 85.023797 -387.106859)
			(xy 85.017288 -387.151988) (xy 85.01126 -387.173978) (xy 85.01126 -387.185662) (xy 85.010841 -387.200059)
			(xy 85.003748 -387.227964) (xy 84.989947 -387.253233) (xy 84.970302 -387.274282) (xy 84.958428 -387.282436)
			(xy 84.957412 -387.287008) (xy 84.956558 -387.292322) (xy 84.956809 -387.303078) (xy 84.95792 -387.308344)
			(xy 84.974684 -387.382258) (xy 84.97605 -387.38747) (xy 84.980658 -387.397206) (xy 84.983828 -387.401562)
			(xy 84.990178 -387.409944) (xy 84.99983 -387.415278) (xy 85.023984 -387.429237) (xy 85.067422 -387.464234)
			(xy 85.08619 -387.484874) (xy 85.088671 -387.487628) (xy 85.094277 -387.492477) (xy 85.097366 -387.494526)
			(xy 85.109503 -387.502615) (xy 85.129577 -387.523764) (xy 85.143725 -387.54926) (xy 85.151049 -387.577483)
			(xy 85.151468 -387.592062) (xy 85.151468 -387.604508) (xy 85.153246 -387.610858) (xy 85.158358 -387.631176)
			(xy 85.163832 -387.672714) (xy 85.164168 -387.693662) (xy 85.164168 -387.69798) (xy 85.163897 -387.709591)
			(xy 85.16186 -387.732728) (xy 85.160104 -387.744208) (xy 85.158587 -387.753255) (xy 85.154648 -387.771173)
			(xy 85.15223 -387.780022) (xy 85.151468 -387.78307) (xy 85.151468 -388.239254) (xy 85.15223 -388.242302)
			(xy 85.157352 -388.26154) (xy 85.163336 -388.300898) (xy 85.164168 -388.320788) (xy 85.164168 -388.328662)
			(xy 85.728302 -388.328662) (xy 85.728668 -388.307641) (xy 85.734279 -388.265975) (xy 85.739478 -388.245604)
			(xy 85.741256 -388.239) (xy 85.741256 -388.125462) (xy 85.741703 -388.110443) (xy 85.749486 -388.08143)
			(xy 85.764512 -388.055419) (xy 85.785757 -388.034182) (xy 85.811774 -388.019167) (xy 85.84079 -388.011396)
			(xy 85.85581 -388.010908) (xy 86.03742 -388.010908) (xy 86.037928 -388.010654) (xy 86.054692 -388.010654)
			(xy 86.0552 -388.010908) (xy 86.23681 -388.010908) (xy 86.251824 -388.011427) (xy 86.280829 -388.019199)
			(xy 86.306835 -388.034212) (xy 86.328071 -388.055442) (xy 86.34309 -388.081445) (xy 86.35087 -388.110448)
			(xy 86.351364 -388.125462) (xy 86.351364 -388.239) (xy 86.353142 -388.245604) (xy 86.358334 -388.265976)
			(xy 86.363944 -388.307642) (xy 86.364318 -388.328662) (xy 86.364318 -388.32917) (xy 86.364147 -388.343795)
			(xy 86.36148 -388.372924) (xy 86.358984 -388.387336) (xy 86.357623 -388.39651) (xy 86.360894 -388.414752)
			(xy 86.365334 -388.422896) (xy 86.381844 -388.44982) (xy 86.387014 -388.457598) (xy 86.40174 -388.46906)
			(xy 86.410546 -388.472172) (xy 86.435435 -388.480213) (xy 86.482314 -388.503408) (xy 86.524725 -388.534017)
			(xy 86.561506 -388.571202) (xy 86.591652 -388.613943) (xy 86.614335 -388.661071) (xy 86.622128 -388.68604)
			(xy 86.623652 -388.691882) (xy 86.943946 -389.245602) (xy 86.94801 -389.24992) (xy 86.964167 -389.267588)
			(xy 86.991488 -389.306905) (xy 87.012556 -389.349896) (xy 87.02689 -389.395577) (xy 87.034161 -389.442898)
			(xy 87.034624 -389.466836) (xy 87.034624 -389.467344) (xy 87.034163 -389.492795) (xy 87.02599 -389.543038)
			(xy 87.009864 -389.591319) (xy 86.986201 -389.636387) (xy 86.955616 -389.677076) (xy 86.918899 -389.712332)
			(xy 86.898226 -389.727186) (xy 86.889715 -389.733624) (xy 86.878518 -389.751766) (xy 86.875646 -389.772892)
			(xy 86.881595 -389.793364) (xy 86.89534 -389.809662) (xy 86.914515 -389.818979) (xy 86.92515 -389.819896)
			(xy 86.935056 -389.819388) (xy 86.943506 -389.818097) (xy 86.960545 -389.816701) (xy 86.969092 -389.816594)
			(xy 86.969346 -389.816848) (xy 87.268558 -389.816848) (xy 87.268812 -389.816594) (xy 87.289875 -389.816951)
			(xy 87.331236 -389.824915) (xy 87.370235 -389.840828) (xy 87.405361 -389.864073) (xy 87.435252 -389.89375)
			(xy 87.458749 -389.928708) (xy 87.474942 -389.967591) (xy 87.483203 -390.008894) (xy 87.483696 -390.029954)
			(xy 87.483696 -390.284716) (xy 87.474552 -390.284716) (xy 87.464539 -390.285149) (xy 87.446043 -390.292828)
			(xy 87.431892 -390.306997) (xy 87.424237 -390.325503) (xy 87.423752 -390.335516) (xy 87.423752 -390.499092)
			(xy 87.423373 -390.509119) (xy 87.415697 -390.527645) (xy 87.401511 -390.541819) (xy 87.382979 -390.549481)
			(xy 87.372952 -390.549892) (xy 86.864952 -390.549892) (xy 86.85494 -390.549451) (xy 86.836446 -390.541774)
			(xy 86.822294 -390.527607) (xy 86.814638 -390.509104) (xy 86.814152 -390.499092) (xy 86.814152 -390.284716)
			(xy 86.805008 -390.284716) (xy 86.795003 -390.284206) (xy 86.776514 -390.276552) (xy 86.762362 -390.262406)
			(xy 86.754699 -390.243921) (xy 86.754208 -390.233916) (xy 86.754208 -390.029954) (xy 86.754554 -390.012721)
			(xy 86.760124 -389.978708) (xy 86.771096 -389.946035) (xy 86.778846 -389.93064) (xy 86.784688 -389.91921)
			(xy 86.784434 -389.89381) (xy 86.736936 -389.808212) (xy 86.73023 -389.797421) (xy 86.708895 -389.783688)
			(xy 86.696296 -389.78205) (xy 86.67242 -389.779887) (xy 86.625676 -389.769253) (xy 86.581079 -389.751667)
			(xy 86.539658 -389.727534) (xy 86.502366 -389.69741) (xy 86.470063 -389.661989) (xy 86.443494 -389.622087)
			(xy 86.42327 -389.578623) (xy 86.416134 -389.555736) (xy 86.41461 -389.549894) (xy 86.094316 -388.996174)
			(xy 86.090252 -388.991856) (xy 86.074041 -388.974155) (xy 86.046619 -388.934761) (xy 86.025479 -388.89167)
			(xy 86.011107 -388.845874) (xy 86.003834 -388.798431) (xy 86.003384 -388.774432) (xy 86.003563 -388.760384)
			(xy 86.006106 -388.732402) (xy 86.008464 -388.718552) (xy 86.009759 -388.709296) (xy 86.006359 -388.690931)
			(xy 86.00186 -388.682738) (xy 85.985096 -388.655814) (xy 85.979901 -388.648105) (xy 85.965171 -388.636784)
			(xy 85.956394 -388.633716) (xy 85.934773 -388.626899) (xy 85.893558 -388.608022) (xy 85.855437 -388.583492)
			(xy 85.821179 -388.553803) (xy 85.806026 -388.536942) (xy 85.803563 -388.53417) (xy 85.797951 -388.529323)
			(xy 85.79485 -388.52729) (xy 85.782816 -388.519218) (xy 85.762929 -388.498154) (xy 85.748922 -388.472796)
			(xy 85.741683 -388.444746) (xy 85.741256 -388.430262) (xy 85.741256 -388.418324) (xy 85.739478 -388.41172)
			(xy 85.734272 -388.391351) (xy 85.728671 -388.349683) (xy 85.728302 -388.328662) (xy 85.164168 -388.328662)
			(xy 85.164168 -388.33298) (xy 85.163914 -388.343648) (xy 85.163914 -388.344156) (xy 85.163289 -388.354503)
			(xy 85.160871 -388.375093) (xy 85.159088 -388.385304) (xy 85.158326 -388.39394) (xy 85.158488 -388.401024)
			(xy 85.162221 -388.414687) (xy 85.165692 -388.420864) (xy 85.177376 -388.43966) (xy 85.17985 -388.443614)
			(xy 85.18599 -388.450636) (xy 85.189568 -388.45363) (xy 85.21065 -388.469632) (xy 85.216238 -388.47141)
			(xy 85.241392 -388.48007) (xy 85.288614 -388.504562) (xy 85.331107 -388.536563) (xy 85.36769 -388.575183)
			(xy 85.397343 -388.619347) (xy 85.419242 -388.667826) (xy 85.42655 -388.693406) (xy 85.43163 -388.705852)
			(xy 85.743796 -389.245602) (xy 85.74786 -389.24992) (xy 85.764079 -389.267617) (xy 85.791515 -389.307005)
			(xy 85.812665 -389.350096) (xy 85.82704 -389.395895) (xy 85.834308 -389.443343) (xy 85.834728 -389.467344)
			(xy 85.834245 -389.49281) (xy 85.826068 -389.54308) (xy 85.809919 -389.591382) (xy 85.786216 -389.636462)
			(xy 85.755577 -389.677146) (xy 85.718798 -389.712377) (xy 85.698076 -389.727186) (xy 85.689587 -389.733674)
			(xy 85.678403 -389.751849) (xy 85.675569 -389.773) (xy 85.681573 -389.793479) (xy 85.695379 -389.809752)
			(xy 85.714606 -389.819011) (xy 85.725254 -389.819896) (xy 85.734906 -389.819388) (xy 85.743417 -389.818072)
			(xy 85.760584 -389.81667) (xy 85.769196 -389.816594) (xy 85.76945 -389.816848) (xy 86.068662 -389.816848)
			(xy 86.068916 -389.816594) (xy 86.089977 -389.816937) (xy 86.131333 -389.824903) (xy 86.170325 -389.840819)
			(xy 86.205442 -389.864068) (xy 86.235323 -389.893749) (xy 86.258807 -389.92871) (xy 86.274984 -389.967595)
			(xy 86.283227 -390.008896) (xy 86.2838 -390.029954) (xy 86.2838 -390.233916) (xy 86.283309 -390.243922)
			(xy 86.275647 -390.262408) (xy 86.261494 -390.276556) (xy 86.243006 -390.284212) (xy 86.233 -390.284716)
			(xy 86.223856 -390.284716) (xy 86.223856 -390.499092) (xy 86.223437 -390.509111) (xy 86.215767 -390.527623)
			(xy 86.201593 -390.541787) (xy 86.183075 -390.549444) (xy 86.173056 -390.549892) (xy 85.665056 -390.549892)
			(xy 85.655055 -390.549396) (xy 85.636579 -390.541729) (xy 85.622442 -390.527577) (xy 85.614794 -390.509094)
			(xy 85.614256 -390.499092) (xy 85.614256 -390.335516) (xy 85.613839 -390.325496) (xy 85.60617 -390.306981)
			(xy 85.591995 -390.292814) (xy 85.573476 -390.285156) (xy 85.563456 -390.284716) (xy 85.554312 -390.284716)
			(xy 85.554312 -390.029954) (xy 85.555059 -390.004082) (xy 85.567512 -389.953858) (xy 85.57895 -389.93064)
			(xy 85.584792 -389.91921) (xy 85.584538 -389.89381) (xy 85.53704 -389.808212) (xy 85.530332 -389.797423)
			(xy 85.508998 -389.78369) (xy 85.4964 -389.78205) (xy 85.472518 -389.779876) (xy 85.425764 -389.769225)
			(xy 85.381156 -389.75163) (xy 85.33972 -389.727494) (xy 85.302408 -389.697373) (xy 85.270078 -389.661958)
			(xy 85.243472 -389.622063) (xy 85.223202 -389.578605) (xy 85.215984 -389.555736) (xy 85.21446 -389.549894)
			(xy 84.8995 -389.005064) (xy 84.897976 -389.003794) (xy 84.883498 -389.001508) (xy 84.876178 -389.000647)
			(xy 84.861592 -389.002717) (xy 84.854796 -389.005572) (xy 84.770468 -389.043672) (xy 84.764626 -389.046974)
			(xy 84.757522 -389.051785) (xy 84.746788 -389.065154) (xy 84.741098 -389.081327) (xy 84.74075 -389.0899)
			(xy 84.74075 -389.778748) (xy 84.741263 -389.789583) (xy 84.750212 -389.80932) (xy 84.758022 -389.816848)
			(xy 84.868766 -389.816848) (xy 84.86902 -389.816594) (xy 84.890081 -389.816937) (xy 84.931436 -389.824904)
			(xy 84.970428 -389.84082) (xy 85.005544 -389.86407) (xy 85.035424 -389.89375) (xy 85.058907 -389.928711)
			(xy 85.075084 -389.967595) (xy 85.083327 -390.008896) (xy 85.083904 -390.029954) (xy 85.083904 -390.284716)
			(xy 85.08111 -390.284716) (xy 85.056218 -390.344406) (xy 85.057234 -390.346438) (xy 85.059108 -390.349833)
			(xy 85.063699 -390.356081) (xy 85.066378 -390.358884) (xy 85.349842 -390.642348) (xy 85.356687 -390.649746)
			(xy 85.364413 -390.668345) (xy 85.364828 -390.678416) (xy 85.364828 -391.580878) (xy 85.364877 -391.584748)
			(xy 85.366028 -391.592403) (xy 85.367114 -391.596118) (xy 85.368941 -391.601444) (xy 85.374575 -391.611191)
			(xy 85.37829 -391.615422) (xy 85.395735 -391.635124) (xy 85.42452 -391.679173) (xy 85.445661 -391.72736)
			(xy 85.45858 -391.77837) (xy 85.462925 -391.83081) (xy 85.458577 -391.883251) (xy 85.445654 -391.93426)
			(xy 85.424511 -391.982445) (xy 85.395722 -392.026492) (xy 85.37829 -392.046206) (xy 85.371686 -392.053572)
			(xy 85.368384 -392.062208) (xy 85.366761 -392.066672) (xy 85.36498 -392.076002) (xy 85.364828 -392.08075)
			(xy 85.364828 -392.104118) (xy 85.374734 -392.124692) (xy 85.383878 -392.132058) (xy 85.405632 -392.150277)
			(xy 85.444028 -392.192053) (xy 85.475814 -392.239056) (xy 85.500289 -392.290247) (xy 85.516913 -392.344498)
			(xy 85.525318 -392.400613) (xy 85.525864 -392.428984) (xy 85.525864 -393.292838) (xy 85.962744 -393.292838)
			(xy 85.962744 -392.42873) (xy 85.963171 -392.403262) (xy 85.969974 -392.352781) (xy 85.983437 -392.303655)
			(xy 86.003319 -392.256759) (xy 86.029267 -392.212926) (xy 86.060819 -392.172938) (xy 86.078822 -392.154918)
			(xy 86.085426 -392.148568) (xy 86.0933 -392.131804) (xy 86.100158 -392.04646) (xy 86.095078 -392.02868)
			(xy 86.08949 -392.021314) (xy 86.074634 -392.00057) (xy 86.051001 -391.955354) (xy 86.034902 -391.906941)
			(xy 86.02675 -391.856578) (xy 86.026244 -391.831068) (xy 86.026244 -391.830814) (xy 86.026734 -391.805825)
			(xy 86.034553 -391.756462) (xy 86.049997 -391.70893) (xy 86.072687 -391.664398) (xy 86.102063 -391.623965)
			(xy 86.137403 -391.588625) (xy 86.177836 -391.559249) (xy 86.222368 -391.536559) (xy 86.2699 -391.521115)
			(xy 86.319263 -391.513296) (xy 86.369241 -391.513296) (xy 86.418604 -391.521115) (xy 86.466136 -391.536559)
			(xy 86.510668 -391.559249) (xy 86.551101 -391.588625) (xy 86.586441 -391.623965) (xy 86.615817 -391.664398)
			(xy 86.638507 -391.70893) (xy 86.653951 -391.756462) (xy 86.66177 -391.805825) (xy 86.66226 -391.830814)
			(xy 86.66226 -391.831068) (xy 86.661755 -391.856576) (xy 86.65358 -391.906935) (xy 86.637481 -391.955346)
			(xy 86.61387 -392.000571) (xy 86.599014 -392.021314) (xy 86.593426 -392.02868) (xy 86.588346 -392.04646)
			(xy 86.595204 -392.131804) (xy 86.603078 -392.148568) (xy 86.609682 -392.154918) (xy 86.627686 -392.172935)
			(xy 86.659226 -392.21293) (xy 86.685166 -392.256766) (xy 86.705044 -392.303662) (xy 86.718509 -392.352785)
			(xy 86.725319 -392.403263) (xy 86.72576 -392.42873) (xy 86.72576 -393.292838) (xy 87.16264 -393.292838)
			(xy 87.16264 -392.429238) (xy 87.163065 -392.403718) (xy 87.169855 -392.353132) (xy 87.183332 -392.303903)
			(xy 87.203255 -392.256912) (xy 87.229268 -392.212999) (xy 87.260907 -392.172948) (xy 87.278972 -392.154918)
			(xy 87.285576 -392.148568) (xy 87.29345 -392.131804) (xy 87.300308 -392.04646) (xy 87.295228 -392.02868)
			(xy 87.28964 -392.021314) (xy 87.274791 -392.000565) (xy 87.251155 -391.955352) (xy 87.235053 -391.90694)
			(xy 87.2269 -391.856577) (xy 87.226394 -391.831068) (xy 87.226394 -391.830814) (xy 87.226884 -391.805825)
			(xy 87.234703 -391.756462) (xy 87.250147 -391.70893) (xy 87.272837 -391.664398) (xy 87.302213 -391.623965)
			(xy 87.337553 -391.588625) (xy 87.377986 -391.559249) (xy 87.422518 -391.536559) (xy 87.47005 -391.521115)
			(xy 87.519413 -391.513296) (xy 87.569391 -391.513296) (xy 87.618754 -391.521115) (xy 87.666286 -391.536559)
			(xy 87.710818 -391.559249) (xy 87.751251 -391.588625) (xy 87.786591 -391.623965) (xy 87.815967 -391.664398)
			(xy 87.838657 -391.70893) (xy 87.854101 -391.756462) (xy 87.86192 -391.805825) (xy 87.86241 -391.830814)
			(xy 87.86241 -391.831068) (xy 87.861915 -391.856577) (xy 87.853738 -391.906936) (xy 87.837636 -391.955347)
			(xy 87.814022 -392.000572) (xy 87.799164 -392.021314) (xy 87.793576 -392.02868) (xy 87.788496 -392.04646)
			(xy 87.795354 -392.131804) (xy 87.803228 -392.148568) (xy 87.809832 -392.154918) (xy 87.827862 -392.172981)
			(xy 87.859494 -392.213031) (xy 87.885506 -392.256939) (xy 87.905435 -392.303922) (xy 87.918924 -392.353142)
			(xy 87.925734 -392.403721) (xy 87.926164 -392.429238) (xy 87.926164 -393.292838) (xy 87.925641 -393.321291)
			(xy 87.917193 -393.377566) (xy 87.900489 -393.431965) (xy 87.8759 -393.483284) (xy 87.843969 -393.530387)
			(xy 87.825072 -393.551664) (xy 87.819167 -393.558645) (xy 87.812269 -393.575564) (xy 87.81161 -393.584684)
			(xy 87.810594 -393.615418) (xy 87.810744 -393.624587) (xy 87.816721 -393.641906) (xy 87.822278 -393.6492)
			(xy 87.837648 -393.668531) (xy 87.863461 -393.710637) (xy 87.883254 -393.755885) (xy 87.896655 -393.80342)
			(xy 87.90341 -393.852344) (xy 87.903812 -393.877038) (xy 87.90331 -393.903934) (xy 87.895292 -393.957126)
			(xy 87.879436 -394.008529) (xy 87.856097 -394.056995) (xy 87.825794 -394.101441) (xy 87.789206 -394.140874)
			(xy 87.747149 -394.174413) (xy 87.700563 -394.201309) (xy 87.650489 -394.220962) (xy 87.598044 -394.232932)
			(xy 87.544402 -394.236952) (xy 87.49076 -394.232932) (xy 87.438315 -394.220962) (xy 87.388241 -394.201309)
			(xy 87.341655 -394.174413) (xy 87.299598 -394.140874) (xy 87.26301 -394.101441) (xy 87.232707 -394.056995)
			(xy 87.209368 -394.008529) (xy 87.193512 -393.957126) (xy 87.185494 -393.903934) (xy 87.184992 -393.877038)
			(xy 87.185434 -393.852349) (xy 87.192221 -393.803438) (xy 87.205631 -393.755914) (xy 87.225412 -393.71067)
			(xy 87.251193 -393.668556) (xy 87.266526 -393.6492) (xy 87.272055 -393.641889) (xy 87.278047 -393.624582)
			(xy 87.27821 -393.615418) (xy 87.277194 -393.584684) (xy 87.276557 -393.575558) (xy 87.269661 -393.55863)
			(xy 87.263732 -393.551664) (xy 87.244813 -393.530401) (xy 87.21285 -393.483312) (xy 87.188248 -393.431991)
			(xy 87.171555 -393.377582) (xy 87.163142 -393.321295) (xy 87.16264 -393.292838) (xy 86.72576 -393.292838)
			(xy 86.725225 -393.321992) (xy 86.716353 -393.379622) (xy 86.698821 -393.435232) (xy 86.673036 -393.48753)
			(xy 86.6396 -393.535299) (xy 86.619842 -393.556744) (xy 86.613679 -393.563823) (xy 86.606525 -393.581161)
			(xy 86.605872 -393.590526) (xy 86.604094 -393.659106) (xy 86.604239 -393.668362) (xy 86.610372 -393.685815)
			(xy 86.616032 -393.693142) (xy 86.61654 -393.69365) (xy 86.632862 -393.713277) (xy 86.660332 -393.756301)
			(xy 86.681433 -393.802782) (xy 86.695739 -393.851782) (xy 86.702962 -393.902315) (xy 86.703408 -393.927838)
			(xy 86.702906 -393.954715) (xy 86.694894 -394.00787) (xy 86.67905 -394.059236) (xy 86.655726 -394.107668)
			(xy 86.625445 -394.152082) (xy 86.588883 -394.191487) (xy 86.546855 -394.225003) (xy 86.500302 -394.25188)
			(xy 86.450263 -394.271519) (xy 86.397856 -394.28348) (xy 86.344252 -394.287498) (xy 86.290648 -394.28348)
			(xy 86.238241 -394.271519) (xy 86.188202 -394.25188) (xy 86.141649 -394.225003) (xy 86.099621 -394.191487)
			(xy 86.063059 -394.152082) (xy 86.032778 -394.107668) (xy 86.009454 -394.059236) (xy 85.99361 -394.00787)
			(xy 85.985598 -393.954715) (xy 85.985096 -393.927838) (xy 85.985557 -393.90228) (xy 85.992794 -393.85168)
			(xy 86.007142 -393.80262) (xy 86.028308 -393.756093) (xy 86.055866 -393.713043) (xy 86.072218 -393.693396)
			(xy 86.072472 -393.693142) (xy 86.078136 -393.685821) (xy 86.084247 -393.668362) (xy 86.08441 -393.659106)
			(xy 86.082378 -393.580874) (xy 86.075266 -393.563856) (xy 86.068662 -393.556744) (xy 86.04892 -393.535286)
			(xy 86.015485 -393.487519) (xy 85.989702 -393.435225) (xy 85.97217 -393.379617) (xy 85.963299 -393.321991)
			(xy 85.962744 -393.292838) (xy 85.525864 -393.292838) (xy 85.525864 -393.293346) (xy 85.525292 -393.322437)
			(xy 85.516416 -393.379939) (xy 85.498921 -393.43543) (xy 85.473213 -393.487625) (xy 85.439887 -393.535318)
			(xy 85.4202 -393.556744) (xy 85.413884 -393.563824) (xy 85.406557 -393.581311) (xy 85.405976 -393.59078)
			(xy 85.403944 -393.668504) (xy 85.41004 -393.68603) (xy 85.412072 -393.688316) (xy 85.419758 -393.696981)
			(xy 85.434121 -393.715156) (xy 85.440774 -393.724638) (xy 85.446177 -393.732652) (xy 85.456214 -393.749172)
			(xy 85.46084 -393.757658) (xy 85.474297 -393.783983) (xy 85.493347 -393.839946) (xy 85.50295 -393.898278)
			(xy 85.503512 -393.927838) (xy 85.503167 -393.951352) (xy 85.497068 -393.997983) (xy 85.484929 -394.043417)
			(xy 85.466956 -394.086875) (xy 85.455506 -394.107416) (xy 85.453474 -394.111226) (xy 85.446362 -394.137134)
			(xy 85.446934 -394.147057) (xy 85.454647 -394.165353) (xy 85.461348 -394.172694) (xy 85.736176 -394.447522)
			(xy 85.743532 -394.454172) (xy 85.761832 -394.461758) (xy 85.771736 -394.462254) (xy 92.325698 -394.462254)
		)
		(stroke
			(width 0)
			(type solid)
		)
		(fill yes)
		(layer "B.Cu")
		(net "P0V9_CPU1_RT_2D")
	)
	(gr_poly
		(pts
			(xy 415.435034 -402.843238) (xy 415.442278 -402.841611) (xy 415.455448 -402.83477) (xy 415.460942 -402.829776)
			(xy 415.539174 -402.751544) (xy 415.545604 -402.744545) (xy 415.553211 -402.727143) (xy 415.553983 -402.708166)
			(xy 415.547814 -402.690203) (xy 415.541968 -402.68271) (xy 415.538666 -402.679408) (xy 415.534379 -402.67539)
			(xy 415.524372 -402.669237) (xy 415.518854 -402.667216) (xy 415.508186 -402.66366) (xy 415.50209 -402.664676)
			(xy 415.495994 -402.665438) (xy 415.483112 -402.667203) (xy 415.457179 -402.669107) (xy 415.444178 -402.669248)
			(xy 415.443924 -402.669248) (xy 415.418294 -402.668772) (xy 415.36756 -402.661445) (xy 415.318383 -402.646978)
			(xy 415.271762 -402.625666) (xy 415.228646 -402.597942) (xy 415.189909 -402.56437) (xy 415.15634 -402.52563)
			(xy 415.128619 -402.482511) (xy 415.107311 -402.435889) (xy 415.092849 -402.386711) (xy 415.085526 -402.335976)
			(xy 415.085022 -402.310346) (xy 415.085022 -402.309838) (xy 415.085569 -402.281287) (xy 415.094592 -402.224904)
			(xy 415.112418 -402.170656) (xy 415.138598 -402.11991) (xy 415.172473 -402.073943) (xy 415.192464 -402.053552)
			(xy 415.199576 -402.04644) (xy 415.203386 -402.037296) (xy 415.205305 -402.032696) (xy 415.20749 -402.022972)
			(xy 415.207704 -402.017992) (xy 415.207958 -401.998688) (xy 415.207611 -401.987739) (xy 415.198796 -401.967712)
			(xy 415.19094 -401.96008) (xy 415.171177 -401.94189) (xy 415.136446 -401.900918) (xy 415.107801 -401.855482)
			(xy 415.08581 -401.806479) (xy 415.070906 -401.754876) (xy 415.063384 -401.701694) (xy 415.062924 -401.674838)
			(xy 415.062924 -400.810984) (xy 415.063415 -400.782942) (xy 415.07162 -400.727462) (xy 415.087867 -400.673784)
			(xy 415.111803 -400.623065) (xy 415.142913 -400.576402) (xy 415.180525 -400.5348) (xy 415.201862 -400.516598)
			(xy 415.210498 -400.50974) (xy 415.219896 -400.490182) (xy 415.220404 -400.476212) (xy 415.220912 -400.461226)
			(xy 415.220937 -400.45637) (xy 415.219399 -400.446783) (xy 415.217864 -400.442176) (xy 415.214562 -400.433286)
			(xy 415.207704 -400.425666) (xy 415.192377 -400.408065) (xy 415.166519 -400.369213) (xy 415.146625 -400.326995)
			(xy 415.133124 -400.282319) (xy 415.126306 -400.236149) (xy 415.125916 -400.212814) (xy 415.12638 -400.187823)
			(xy 415.134197 -400.138456) (xy 415.149642 -400.090919) (xy 415.172333 -400.046384) (xy 415.201712 -400.005948)
			(xy 415.237055 -399.970605) (xy 415.277493 -399.941228) (xy 415.322028 -399.918538) (xy 415.369565 -399.903095)
			(xy 415.418933 -399.895279) (xy 415.443924 -399.894806) (xy 415.444178 -399.894806) (xy 415.472792 -399.895406)
			(xy 415.529097 -399.905645) (xy 415.582653 -399.925815) (xy 415.6075 -399.940018) (xy 415.607754 -399.940018)
			(xy 415.613585 -399.943325) (xy 415.626458 -399.947051) (xy 415.633154 -399.947384) (xy 415.646108 -399.947384)
			(xy 415.735262 -399.897346) (xy 415.74593 -399.889218) (xy 415.752522 -399.88217) (xy 415.760339 -399.864544)
			(xy 415.76117 -399.854928) (xy 415.76117 -398.289018) (xy 415.761676 -398.278968) (xy 415.769397 -398.260407)
			(xy 415.776156 -398.25295) (xy 415.782252 -398.246854) (xy 415.788685 -398.239856) (xy 415.7963 -398.222452)
			(xy 415.797075 -398.203471) (xy 415.790905 -398.185505) (xy 415.785046 -398.17802) (xy 415.781998 -398.174972)
			(xy 415.779321 -398.172363) (xy 415.773325 -398.167901) (xy 415.77006 -398.166082) (xy 415.763964 -398.16278)
			(xy 415.756344 -398.161256) (xy 415.731557 -398.155791) (xy 415.684003 -398.13805) (xy 415.639874 -398.112978)
			(xy 415.600289 -398.081211) (xy 415.566257 -398.043556) (xy 415.538641 -398.000972) (xy 415.518143 -397.95454)
			(xy 415.511234 -397.930116) (xy 415.509456 -397.923512) (xy 415.194242 -397.378174) (xy 415.190178 -397.373856)
			(xy 415.17399 -397.356146) (xy 415.146617 -397.316743) (xy 415.125529 -397.273647) (xy 415.111213 -397.227855)
			(xy 415.104 -397.180422) (xy 415.103564 -397.156432) (xy 415.103739 -397.142383) (xy 415.106279 -397.114401)
			(xy 415.108644 -397.100552) (xy 415.109856 -397.091275) (xy 415.106329 -397.072917) (xy 415.101786 -397.064738)
			(xy 415.085022 -397.037814) (xy 415.079816 -397.030112) (xy 415.065097 -397.018781) (xy 415.05632 -397.015716)
			(xy 415.034688 -397.008927) (xy 414.993459 -396.990066) (xy 414.955332 -396.965534) (xy 414.921081 -396.935828)
			(xy 414.905952 -396.918942) (xy 414.90347 -396.91619) (xy 414.897861 -396.911344) (xy 414.894776 -396.90929)
			(xy 414.882716 -396.901231) (xy 414.86277 -396.880182) (xy 414.848705 -396.854824) (xy 414.841408 -396.82676)
			(xy 414.840928 -396.812262) (xy 414.840928 -396.800324) (xy 414.839404 -396.79372) (xy 414.834209 -396.773349)
			(xy 414.828608 -396.731682) (xy 414.828228 -396.710662) (xy 414.828602 -396.689642) (xy 414.834213 -396.647977)
			(xy 414.839404 -396.627604) (xy 414.840928 -396.621) (xy 414.840928 -396.507462) (xy 414.841419 -396.492469)
			(xy 414.849177 -396.463503) (xy 414.864156 -396.437525) (xy 414.885338 -396.416299) (xy 414.911286 -396.401267)
			(xy 414.940236 -396.39345) (xy 414.955228 -396.392908) (xy 415.137346 -396.392908) (xy 415.137854 -396.392654)
			(xy 415.154618 -396.392654) (xy 415.155126 -396.392908) (xy 415.3281 -396.392908) (xy 415.338108 -396.39242)
			(xy 415.356601 -396.384761) (xy 415.370756 -396.370608) (xy 415.378418 -396.352116) (xy 415.3789 -396.342108)
			(xy 415.3789 -395.370812) (xy 415.378479 -395.360741) (xy 415.370768 -395.342133) (xy 415.363914 -395.334744)
			(xy 415.307526 -395.278356) (xy 415.300126 -395.271515) (xy 415.281527 -395.263799) (xy 415.271458 -395.26337)
			(xy 414.6677 -395.26337) (xy 414.661692 -395.263543) (xy 414.650014 -395.266375) (xy 414.644586 -395.268958)
			(xy 414.641113 -395.270799) (xy 414.634737 -395.275396) (xy 414.631886 -395.278102) (xy 414.358328 -395.55166)
			(xy 414.355621 -395.55451) (xy 414.351024 -395.560886) (xy 414.349184 -395.56436) (xy 414.346603 -395.569787)
			(xy 414.343784 -395.581467) (xy 414.343596 -395.587474) (xy 414.343596 -396.832328) (xy 414.343818 -396.839136)
			(xy 414.347432 -396.852263) (xy 414.350708 -396.858236) (xy 414.35401 -396.863824) (xy 414.363916 -396.873222)
			(xy 414.370266 -396.876778) (xy 414.392756 -396.889584) (xy 414.433627 -396.921327) (xy 414.468835 -396.959254)
			(xy 414.497458 -397.002368) (xy 414.518742 -397.049538) (xy 414.525968 -397.07439) (xy 414.527746 -397.080994)
			(xy 414.843722 -397.627602) (xy 414.847786 -397.63192) (xy 414.863945 -397.649589) (xy 414.891279 -397.688899)
			(xy 414.912356 -397.731889) (xy 414.92669 -397.777572) (xy 414.933954 -397.824897) (xy 414.9344 -397.848836)
			(xy 414.9344 -397.849344) (xy 414.933911 -397.874132) (xy 414.92615 -397.923098) (xy 414.910825 -397.970247)
			(xy 414.888315 -398.014418) (xy 414.859173 -398.054525) (xy 414.824116 -398.089581) (xy 414.784008 -398.118721)
			(xy 414.739835 -398.14123) (xy 414.692686 -398.156552) (xy 414.64372 -398.164312) (xy 414.618932 -398.164812)
			(xy 414.593537 -398.164307) (xy 414.543401 -398.15618) (xy 414.495212 -398.140132) (xy 414.450215 -398.116577)
			(xy 414.409568 -398.086121) (xy 414.374323 -398.049551) (xy 414.345386 -398.007809) (xy 414.323505 -397.961974)
			(xy 414.31591 -397.937736) (xy 414.314386 -397.931894) (xy 414.109154 -397.57731) (xy 414.10284 -397.567521)
			(xy 414.083522 -397.554548) (xy 414.07207 -397.552418) (xy 414.06064 -397.550894) (xy 414.038034 -397.558514)
			(xy 413.749998 -397.84655) (xy 413.746996 -397.849639) (xy 413.742015 -397.856666) (xy 413.740092 -397.86052)
			(xy 413.736282 -397.868648) (xy 413.73552 -397.877792) (xy 413.732641 -397.904018) (xy 413.719311 -397.955062)
			(xy 413.697743 -398.003209) (xy 413.668527 -398.047137) (xy 413.632464 -398.085643) (xy 413.611822 -398.102074)
			(xy 413.611568 -398.102328) (xy 413.607023 -398.105985) (xy 413.599574 -398.114958) (xy 413.596836 -398.120108)
			(xy 413.594296 -398.125188) (xy 413.591756 -398.136364) (xy 413.591756 -398.149064) (xy 413.631888 -398.185386)
			(xy 413.639167 -398.191514) (xy 413.656922 -398.198314) (xy 413.666432 -398.198594) (xy 413.669226 -398.198594)
			(xy 413.66948 -398.198848) (xy 413.968692 -398.198848) (xy 413.968946 -398.198594) (xy 413.985995 -398.198824)
			(xy 414.019687 -398.204053) (xy 414.036002 -398.209008) (xy 414.043622 -398.211548) (xy 414.072832 -398.211548)
			(xy 414.086181 -398.211987) (xy 414.111968 -398.218904) (xy 414.135087 -398.232259) (xy 414.153962 -398.25114)
			(xy 414.167309 -398.274264) (xy 414.174217 -398.300053) (xy 414.174686 -398.313402) (xy 414.174686 -398.350486)
			(xy 414.176464 -398.356836) (xy 414.179812 -398.370368) (xy 414.183378 -398.398015) (xy 414.183576 -398.411954)
			(xy 414.183576 -398.666716) (xy 414.174686 -398.666716) (xy 414.174686 -398.770856) (xy 414.174117 -398.785492)
			(xy 414.165784 -398.813556) (xy 414.149893 -398.838143) (xy 414.139126 -398.848072) (xy 414.138618 -398.84858)
			(xy 414.132522 -398.853914) (xy 414.123632 -398.873726) (xy 414.123632 -398.881092) (xy 414.123146 -398.891103)
			(xy 414.115489 -398.909603) (xy 414.101337 -398.923766) (xy 414.082843 -398.931438) (xy 414.072832 -398.931892)
			(xy 413.642556 -398.931892) (xy 413.632554 -398.932388) (xy 413.614076 -398.940055) (xy 413.599935 -398.954206)
			(xy 413.592281 -398.972689) (xy 413.591756 -398.982692) (xy 413.591756 -399.024602) (xy 414.637728 -399.024602)
			(xy 414.637728 -398.542002) (xy 414.638214 -398.514769) (xy 414.645965 -398.460857) (xy 414.66131 -398.408597)
			(xy 414.683936 -398.359053) (xy 414.713383 -398.313233) (xy 414.74905 -398.27207) (xy 414.790213 -398.236403)
			(xy 414.836033 -398.206956) (xy 414.885577 -398.18433) (xy 414.937837 -398.168985) (xy 414.991749 -398.161234)
			(xy 415.046215 -398.161234) (xy 415.100127 -398.168985) (xy 415.152387 -398.18433) (xy 415.201931 -398.206956)
			(xy 415.247751 -398.236403) (xy 415.288914 -398.27207) (xy 415.324581 -398.313233) (xy 415.354028 -398.359053)
			(xy 415.376654 -398.408597) (xy 415.391999 -398.460857) (xy 415.39975 -398.514769) (xy 415.400236 -398.542002)
			(xy 415.400236 -399.024602) (xy 415.39975 -399.051835) (xy 415.391999 -399.105747) (xy 415.376654 -399.158007)
			(xy 415.354028 -399.207551) (xy 415.324581 -399.253371) (xy 415.288914 -399.294534) (xy 415.247751 -399.330201)
			(xy 415.201931 -399.359648) (xy 415.152387 -399.382274) (xy 415.100127 -399.397619) (xy 415.046215 -399.40537)
			(xy 414.991749 -399.40537) (xy 414.937837 -399.397619) (xy 414.885577 -399.382274) (xy 414.836033 -399.359648)
			(xy 414.790213 -399.330201) (xy 414.74905 -399.294534) (xy 414.713383 -399.253371) (xy 414.683936 -399.207551)
			(xy 414.66131 -399.158007) (xy 414.645965 -399.105747) (xy 414.638214 -399.051835) (xy 414.637728 -399.024602)
			(xy 413.591756 -399.024602) (xy 413.591756 -399.827496) (xy 413.591332 -399.837566) (xy 413.583614 -399.856167)
			(xy 413.57677 -399.863564) (xy 413.459422 -399.980912) (xy 413.454598 -399.985464) (xy 413.443149 -399.992148)
			(xy 413.436816 -399.99412) (xy 413.428789 -399.996632) (xy 413.414902 -400.006103) (xy 413.409638 -400.012662)
			(xy 413.36468 -400.072098) (xy 413.357822 -400.081242) (xy 413.354408 -400.085972) (xy 413.349662 -400.096624)
			(xy 413.348424 -400.102324) (xy 413.346392 -400.113246) (xy 413.349948 -400.125184) (xy 413.355659 -400.14664)
			(xy 413.361782 -400.190614) (xy 413.36214 -400.212814) (xy 413.36214 -400.213068) (xy 413.361731 -400.236402)
			(xy 413.35491 -400.282568) (xy 413.341408 -400.32724) (xy 413.321518 -400.369457) (xy 413.295667 -400.40831)
			(xy 413.280352 -400.42592) (xy 413.27324 -400.433794) (xy 413.270192 -400.441668) (xy 413.26859 -400.446325)
			(xy 413.267045 -400.456049) (xy 413.267144 -400.460972) (xy 413.267906 -400.481038) (xy 413.267906 -400.481546)
			(xy 413.26816 -400.48942) (xy 413.277558 -400.508978) (xy 413.286194 -400.51609) (xy 413.307649 -400.534306)
			(xy 413.345487 -400.575968) (xy 413.3768 -400.622734) (xy 413.400908 -400.673589) (xy 413.41729 -400.727433)
			(xy 413.42559 -400.783098) (xy 413.426148 -400.811238) (xy 413.426148 -401.674838) (xy 413.86252 -401.674838)
			(xy 413.86252 -400.811238) (xy 413.862951 -400.785718) (xy 413.869741 -400.735132) (xy 413.883217 -400.685904)
			(xy 413.903139 -400.638914) (xy 413.929151 -400.595) (xy 413.960788 -400.554949) (xy 413.978852 -400.536918)
			(xy 413.985456 -400.530568) (xy 413.99333 -400.513804) (xy 414.000188 -400.42846) (xy 413.995108 -400.41068)
			(xy 413.98952 -400.403314) (xy 413.974668 -400.382567) (xy 413.951033 -400.337353) (xy 413.934932 -400.288941)
			(xy 413.92678 -400.238578) (xy 413.926274 -400.213068) (xy 413.926274 -400.212814) (xy 413.926764 -400.187825)
			(xy 413.934583 -400.138462) (xy 413.950027 -400.09093) (xy 413.972717 -400.046398) (xy 414.002093 -400.005965)
			(xy 414.037433 -399.970625) (xy 414.077866 -399.941249) (xy 414.122398 -399.918559) (xy 414.16993 -399.903115)
			(xy 414.219293 -399.895296) (xy 414.269271 -399.895296) (xy 414.318634 -399.903115) (xy 414.366166 -399.918559)
			(xy 414.410698 -399.941249) (xy 414.451131 -399.970625) (xy 414.486471 -400.005965) (xy 414.515847 -400.046398)
			(xy 414.538537 -400.09093) (xy 414.553981 -400.138462) (xy 414.5618 -400.187825) (xy 414.56229 -400.212814)
			(xy 414.56229 -400.213068) (xy 414.561779 -400.238576) (xy 414.553605 -400.288934) (xy 414.537507 -400.337345)
			(xy 414.513899 -400.382571) (xy 414.499044 -400.403314) (xy 414.493456 -400.41068) (xy 414.488376 -400.42846)
			(xy 414.495234 -400.513804) (xy 414.503108 -400.530568) (xy 414.509712 -400.536918) (xy 414.527738 -400.554984)
			(xy 414.559371 -400.595033) (xy 414.585384 -400.63894) (xy 414.605314 -400.685923) (xy 414.618804 -400.735142)
			(xy 414.625614 -400.785721) (xy 414.626044 -400.811238) (xy 414.626044 -401.674838) (xy 414.625486 -401.704002)
			(xy 414.616565 -401.761644) (xy 414.598981 -401.817258) (xy 414.573144 -401.869552) (xy 414.539655 -401.917308)
			(xy 414.519872 -401.938744) (xy 414.513712 -401.945826) (xy 414.506556 -401.963162) (xy 414.505902 -401.972526)
			(xy 414.504124 -402.041106) (xy 414.504262 -402.050363) (xy 414.510399 -402.067816) (xy 414.516062 -402.075142)
			(xy 414.51657 -402.07565) (xy 414.53293 -402.095258) (xy 414.56046 -402.138269) (xy 414.581616 -402.184748)
			(xy 414.595969 -402.233757) (xy 414.603231 -402.284305) (xy 414.603692 -402.309838) (xy 414.60319 -402.336734)
			(xy 414.595172 -402.389926) (xy 414.579316 -402.441329) (xy 414.555977 -402.489795) (xy 414.525674 -402.534241)
			(xy 414.489086 -402.573674) (xy 414.447029 -402.607213) (xy 414.400443 -402.634109) (xy 414.350369 -402.653762)
			(xy 414.297924 -402.665732) (xy 414.244282 -402.669752) (xy 414.19064 -402.665732) (xy 414.138195 -402.653762)
			(xy 414.088121 -402.634109) (xy 414.041535 -402.607213) (xy 413.999478 -402.573674) (xy 413.96289 -402.534241)
			(xy 413.932587 -402.489795) (xy 413.909248 -402.441329) (xy 413.893392 -402.389926) (xy 413.885374 -402.336734)
			(xy 413.884872 -402.309838) (xy 413.885343 -402.28427) (xy 413.89262 -402.233654) (xy 413.907017 -402.184587)
			(xy 413.928241 -402.138063) (xy 413.955863 -402.095029) (xy 413.972248 -402.075396) (xy 413.972502 -402.075142)
			(xy 413.97817 -402.067824) (xy 413.984277 -402.050362) (xy 413.98444 -402.041106) (xy 413.982408 -401.962874)
			(xy 413.975296 -401.945856) (xy 413.968692 -401.938744) (xy 413.948905 -401.917312) (xy 413.915414 -401.869557)
			(xy 413.889579 -401.817262) (xy 413.872002 -401.761646) (xy 413.863091 -401.704002) (xy 413.86252 -401.674838)
			(xy 413.426148 -401.674838) (xy 413.425577 -401.704002) (xy 413.416666 -401.761645) (xy 413.399087 -401.817261)
			(xy 413.373251 -401.869554) (xy 413.339758 -401.917308) (xy 413.319976 -401.938744) (xy 413.313372 -401.945856)
			(xy 413.30626 -401.962874) (xy 413.304228 -402.041106) (xy 413.304392 -402.050361) (xy 413.310506 -402.067818)
			(xy 413.316166 -402.075142) (xy 413.31642 -402.075396) (xy 413.332803 -402.09503) (xy 413.360419 -402.138066)
			(xy 413.381639 -402.18459) (xy 413.396033 -402.233656) (xy 413.403308 -402.284271) (xy 413.403796 -402.309838)
			(xy 413.403294 -402.336734) (xy 413.395276 -402.389926) (xy 413.37942 -402.441329) (xy 413.356081 -402.489795)
			(xy 413.325778 -402.534241) (xy 413.28919 -402.573674) (xy 413.247133 -402.607213) (xy 413.200547 -402.634109)
			(xy 413.150473 -402.653762) (xy 413.098028 -402.665732) (xy 413.044386 -402.669752) (xy 412.990744 -402.665732)
			(xy 412.938299 -402.653762) (xy 412.888225 -402.634109) (xy 412.841639 -402.607213) (xy 412.799582 -402.573674)
			(xy 412.762994 -402.534241) (xy 412.732691 -402.489795) (xy 412.709352 -402.441329) (xy 412.693496 -402.389926)
			(xy 412.685478 -402.336734) (xy 412.684976 -402.309838) (xy 412.685437 -402.284305) (xy 412.6927 -402.233758)
			(xy 412.707056 -402.184751) (xy 412.728214 -402.138274) (xy 412.755749 -402.095267) (xy 412.772098 -402.07565)
			(xy 412.772606 -402.075142) (xy 412.778272 -402.067817) (xy 412.784412 -402.050364) (xy 412.784544 -402.041106)
			(xy 412.782766 -401.972526) (xy 412.782111 -401.963163) (xy 412.774951 -401.94583) (xy 412.768796 -401.938744)
			(xy 412.749015 -401.917308) (xy 412.715528 -401.86955) (xy 412.689693 -401.817257) (xy 412.672111 -401.761642)
			(xy 412.663191 -401.704001) (xy 412.662624 -401.674838) (xy 412.662624 -400.811238) (xy 412.66312 -400.783166)
			(xy 412.671345 -400.727628) (xy 412.687625 -400.673897) (xy 412.711606 -400.623132) (xy 412.74277 -400.576432)
			(xy 412.780444 -400.534806) (xy 412.801816 -400.516598) (xy 412.810452 -400.50974) (xy 412.81985 -400.490182)
			(xy 412.820358 -400.476212) (xy 412.820866 -400.461226) (xy 412.820891 -400.45637) (xy 412.819352 -400.446784)
			(xy 412.817818 -400.442176) (xy 412.814516 -400.433286) (xy 412.807658 -400.425666) (xy 412.792329 -400.408066)
			(xy 412.766467 -400.369215) (xy 412.746569 -400.326997) (xy 412.733066 -400.282321) (xy 412.726247 -400.23615)
			(xy 412.72587 -400.212814) (xy 412.72587 -400.21256) (xy 412.726248 -400.190487) (xy 412.732371 -400.146768)
			(xy 412.738062 -400.125438) (xy 412.741364 -400.113754) (xy 412.739332 -400.102324) (xy 412.738083 -400.096569)
			(xy 412.733342 -400.08579) (xy 412.729934 -400.080988) (xy 412.680912 -400.016218) (xy 412.673357 -400.007159)
			(xy 412.652304 -399.996579) (xy 412.640526 -399.995898) (xy 412.247334 -399.995898) (xy 412.235555 -399.996564)
			(xy 412.214506 -400.007159) (xy 412.206948 -400.016218) (xy 412.157926 -400.081242) (xy 412.154512 -400.085972)
			(xy 412.149766 -400.096624) (xy 412.148528 -400.102324) (xy 412.146496 -400.1135) (xy 412.150052 -400.125438)
			(xy 412.155539 -400.145902) (xy 412.161661 -400.187825) (xy 412.162244 -400.209004) (xy 412.162244 -400.212814)
			(xy 412.161852 -400.236174) (xy 412.155053 -400.282395) (xy 412.141558 -400.327122) (xy 412.12166 -400.369391)
			(xy 412.095787 -400.408291) (xy 412.080456 -400.42592) (xy 412.073344 -400.43354) (xy 412.070296 -400.441922)
			(xy 412.068726 -400.44652) (xy 412.067201 -400.456113) (xy 412.067248 -400.460972) (xy 412.06801 -400.481038)
			(xy 412.06801 -400.481546) (xy 412.068264 -400.489674) (xy 412.077662 -400.509232) (xy 412.086298 -400.516344)
			(xy 412.107704 -400.534559) (xy 412.145447 -400.576206) (xy 412.17667 -400.622941) (xy 412.200698 -400.673751)
			(xy 412.217009 -400.727538) (xy 412.225251 -400.783135) (xy 412.225744 -400.811238) (xy 412.225744 -401.675346)
			(xy 412.225216 -401.703157) (xy 412.217094 -401.758184) (xy 412.201071 -401.81145) (xy 412.177488 -401.861827)
			(xy 412.146844 -401.908247) (xy 412.128716 -401.929346) (xy 412.122874 -401.93595) (xy 412.116016 -401.952714)
			(xy 412.113984 -402.027136) (xy 412.114051 -402.03605) (xy 412.119639 -402.052966) (xy 412.124906 -402.060156)
			(xy 412.12516 -402.06041) (xy 412.139895 -402.079539) (xy 412.164648 -402.120997) (xy 412.183623 -402.165399)
			(xy 412.196479 -402.211942) (xy 412.202984 -402.259787) (xy 412.203392 -402.28393) (xy 412.203392 -402.284438)
			(xy 412.20289 -402.311315) (xy 412.194878 -402.36447) (xy 412.179034 -402.415836) (xy 412.15571 -402.464268)
			(xy 412.125429 -402.508682) (xy 412.088867 -402.548087) (xy 412.046839 -402.581603) (xy 412.000286 -402.60848)
			(xy 411.950247 -402.628119) (xy 411.89784 -402.64008) (xy 411.844236 -402.644098) (xy 411.790632 -402.64008)
			(xy 411.738225 -402.628119) (xy 411.688186 -402.60848) (xy 411.641633 -402.581603) (xy 411.599605 -402.548087)
			(xy 411.563043 -402.508682) (xy 411.532762 -402.464268) (xy 411.509438 -402.415836) (xy 411.493594 -402.36447)
			(xy 411.485582 -402.311315) (xy 411.48508 -402.284438) (xy 411.48508 -402.28393) (xy 411.48549 -402.259788)
			(xy 411.491996 -402.211943) (xy 411.504854 -402.165402) (xy 411.523832 -402.121003) (xy 411.548589 -402.079548)
			(xy 411.563312 -402.06041) (xy 411.563566 -402.060156) (xy 411.568778 -402.052934) (xy 411.574373 -402.036041)
			(xy 411.574488 -402.027136) (xy 411.572456 -401.952714) (xy 411.565598 -401.93595) (xy 411.559756 -401.929346)
			(xy 411.541592 -401.908274) (xy 411.510933 -401.861855) (xy 411.487344 -401.811473) (xy 411.471327 -401.758198)
			(xy 411.463222 -401.703161) (xy 411.462728 -401.675346) (xy 411.462728 -400.810984) (xy 411.463219 -400.782942)
			(xy 411.471424 -400.727463) (xy 411.487671 -400.673784) (xy 411.511608 -400.623066) (xy 411.542718 -400.576402)
			(xy 411.58033 -400.534801) (xy 411.601666 -400.516598) (xy 411.610302 -400.50974) (xy 411.6197 -400.490182)
			(xy 411.620208 -400.477736) (xy 411.620716 -400.460718) (xy 411.620761 -400.455922) (xy 411.619229 -400.446456)
			(xy 411.617668 -400.441922) (xy 411.614366 -400.433032) (xy 411.607762 -400.425666) (xy 411.592433 -400.408066)
			(xy 411.56657 -400.369215) (xy 411.546673 -400.326997) (xy 411.533169 -400.282321) (xy 411.52635 -400.23615)
			(xy 411.525974 -400.212814) (xy 411.525974 -400.21256) (xy 411.526352 -400.190487) (xy 411.532475 -400.146768)
			(xy 411.538166 -400.125438) (xy 411.541468 -400.113754) (xy 411.539436 -400.102324) (xy 411.538187 -400.096569)
			(xy 411.533447 -400.08579) (xy 411.530038 -400.080988) (xy 411.481016 -400.016218) (xy 411.473461 -400.007158)
			(xy 411.452408 -399.996576) (xy 411.44063 -399.995898) (xy 411.128972 -399.995898) (xy 411.118904 -399.99547)
			(xy 411.100307 -399.987748) (xy 411.092904 -399.980912) (xy 410.941012 -399.82902) (xy 410.934177 -399.821618)
			(xy 410.92647 -399.803019) (xy 410.926026 -399.792952) (xy 410.926026 -398.188942) (xy 410.925777 -398.181528)
			(xy 410.921525 -398.167323) (xy 410.917644 -398.161002) (xy 410.91358 -398.154652) (xy 410.90215 -398.145254)
			(xy 410.895038 -398.142206) (xy 410.872877 -398.13237) (xy 410.831581 -398.10697) (xy 410.794624 -398.075589)
			(xy 410.762865 -398.038957) (xy 410.737042 -397.997924) (xy 410.717754 -397.953443) (xy 410.711142 -397.930116)
			(xy 410.709364 -397.923512) (xy 410.402786 -397.392652) (xy 410.394658 -397.381984) (xy 410.377178 -397.363972)
			(xy 410.347547 -397.323461) (xy 410.32465 -397.278797) (xy 410.309054 -397.231091) (xy 410.301148 -397.181527)
			(xy 410.300678 -397.156432) (xy 410.300932 -397.144748) (xy 410.301186 -397.13408) (xy 410.297376 -397.124428)
			(xy 410.295345 -397.119559) (xy 410.28958 -397.110727) (xy 410.285946 -397.106902) (xy 409.753308 -396.574264)
			(xy 409.746466 -396.566864) (xy 409.738744 -396.548266) (xy 409.738322 -396.538196) (xy 409.738322 -395.581632)
			(xy 409.738153 -395.575623) (xy 409.735326 -395.563942) (xy 409.732734 -395.558518) (xy 409.730897 -395.555042)
			(xy 409.726309 -395.548657) (xy 409.72359 -395.545818) (xy 409.474416 -395.296644) (xy 409.471566 -395.293937)
			(xy 409.465189 -395.289342) (xy 409.461716 -395.2875) (xy 409.456288 -395.284921) (xy 409.444609 -395.282107)
			(xy 409.438602 -395.281912) (xy 408.217116 -395.281912) (xy 408.20975 -395.28242) (xy 408.201133 -395.284102)
			(xy 408.185685 -395.29242) (xy 408.179524 -395.298676) (xy 408.128216 -395.361414) (xy 408.124696 -395.365872)
			(xy 408.119567 -395.376004) (xy 408.118056 -395.38148) (xy 408.115516 -395.391894) (xy 408.117802 -395.403324)
			(xy 408.120751 -395.418841) (xy 408.123929 -395.450269) (xy 408.124152 -395.466062) (xy 408.123783 -395.487083)
			(xy 408.118183 -395.528751) (xy 408.112976 -395.54912) (xy 408.111452 -395.555724) (xy 408.111452 -395.567662)
			(xy 408.111024 -395.582144) (xy 408.103781 -395.610189) (xy 408.089768 -395.635539) (xy 408.069872 -395.65659)
			(xy 408.057858 -395.66469) (xy 408.057096 -395.669262) (xy 408.056187 -395.674437) (xy 408.056311 -395.68494)
			(xy 408.05735 -395.69009) (xy 408.074368 -395.764258) (xy 408.075734 -395.76947) (xy 408.08034 -395.779207)
			(xy 408.083512 -395.783562) (xy 408.089608 -395.79169) (xy 408.099514 -395.797024) (xy 408.123752 -395.811019)
			(xy 408.167312 -395.846154) (xy 408.186128 -395.866874) (xy 408.18861 -395.869626) (xy 408.194219 -395.874472)
			(xy 408.197304 -395.876526) (xy 408.209437 -395.884618) (xy 408.229505 -395.905768) (xy 408.243648 -395.931263)
			(xy 408.25097 -395.959485) (xy 408.251406 -395.974062) (xy 408.251406 -395.986508) (xy 408.253184 -395.992858)
			(xy 408.256499 -396.005812) (xy 408.261204 -396.032136) (xy 408.262582 -396.045436) (xy 408.262582 -396.045944)
			(xy 408.264106 -396.061184) (xy 408.264106 -396.075662) (xy 408.26379 -396.096612) (xy 408.258313 -396.138151)
			(xy 408.253184 -396.158466) (xy 408.251406 -396.16507) (xy 408.251406 -396.621254) (xy 408.253184 -396.627858)
			(xy 408.25827 -396.648116) (xy 408.263745 -396.689524) (xy 408.264106 -396.710408) (xy 408.264106 -396.710662)
			(xy 408.82824 -396.710662) (xy 408.828608 -396.689641) (xy 408.834218 -396.647975) (xy 408.839416 -396.627604)
			(xy 408.84094 -396.621) (xy 408.84094 -396.507462) (xy 408.8414 -396.492465) (xy 408.84916 -396.463492)
			(xy 408.864143 -396.437508) (xy 408.885331 -396.416279) (xy 408.911286 -396.401245) (xy 408.940244 -396.393429)
			(xy 408.95524 -396.392908) (xy 409.137358 -396.392908) (xy 409.137866 -396.392654) (xy 409.15463 -396.392654)
			(xy 409.155138 -396.392908) (xy 409.336748 -396.392908) (xy 409.351781 -396.393338) (xy 409.380821 -396.40112)
			(xy 409.406865 -396.416142) (xy 409.428142 -396.437384) (xy 409.443207 -396.463402) (xy 409.451037 -396.49243)
			(xy 409.451556 -396.507462) (xy 409.451556 -396.621) (xy 409.45308 -396.627604) (xy 409.458273 -396.647976)
			(xy 409.463882 -396.689642) (xy 409.464256 -396.710662) (xy 409.464256 -396.71117) (xy 409.464086 -396.725795)
			(xy 409.461419 -396.754924) (xy 409.458922 -396.769336) (xy 409.457556 -396.77851) (xy 409.46083 -396.796752)
			(xy 409.465272 -396.804896) (xy 409.481782 -396.83182) (xy 409.486938 -396.839609) (xy 409.501674 -396.851065)
			(xy 409.510484 -396.854172) (xy 409.535361 -396.862248) (xy 409.582241 -396.885434) (xy 409.624654 -396.916035)
			(xy 409.661438 -396.953213) (xy 409.691586 -396.99595) (xy 409.714272 -397.043073) (xy 409.722066 -397.06804)
			(xy 409.72359 -397.073882) (xy 410.043884 -397.627602) (xy 410.047948 -397.63192) (xy 410.064148 -397.649631)
			(xy 410.091571 -397.689022) (xy 410.112713 -397.732111) (xy 410.127088 -397.777904) (xy 410.134364 -397.825346)
			(xy 410.134816 -397.849344) (xy 410.13433 -397.874806) (xy 410.126131 -397.925067) (xy 410.109969 -397.97336)
			(xy 410.086264 -398.018432) (xy 410.05563 -398.059113) (xy 410.018862 -398.094348) (xy 409.998164 -398.109186)
			(xy 409.989634 -398.115606) (xy 409.978424 -398.133753) (xy 409.975548 -398.154889) (xy 409.9815 -398.175372)
			(xy 409.995257 -398.191674) (xy 410.014447 -398.200986) (xy 410.025088 -398.201896) (xy 410.034994 -398.201388)
			(xy 410.043445 -398.200105) (xy 410.060483 -398.198704) (xy 410.06903 -398.198594) (xy 410.069284 -398.198848)
			(xy 410.368496 -398.198848) (xy 410.36875 -398.198594) (xy 410.389797 -398.198988) (xy 410.431117 -398.206986)
			(xy 410.470073 -398.222919) (xy 410.505155 -398.246171) (xy 410.535005 -398.275841) (xy 410.55847 -398.310781)
			(xy 410.574639 -398.349639) (xy 410.582888 -398.39091) (xy 410.58338 -398.411954) (xy 410.58338 -398.666716)
			(xy 410.574236 -398.666716) (xy 410.564215 -398.667149) (xy 410.545696 -398.674811) (xy 410.531522 -398.688979)
			(xy 410.523853 -398.707495) (xy 410.523436 -398.717516) (xy 410.523436 -398.881092) (xy 410.522906 -398.891095)
			(xy 410.515256 -398.909579) (xy 410.501116 -398.923731) (xy 410.482638 -398.931398) (xy 410.472636 -398.931892)
			(xy 409.965144 -398.931892) (xy 409.955125 -398.931444) (xy 409.936607 -398.923787) (xy 409.922433 -398.909623)
			(xy 409.914763 -398.891111) (xy 409.914344 -398.881092) (xy 409.914344 -398.717516) (xy 409.9138 -398.707515)
			(xy 409.906154 -398.689032) (xy 409.892019 -398.67488) (xy 409.873545 -398.667212) (xy 409.863544 -398.666716)
			(xy 409.8544 -398.666716) (xy 409.8544 -398.411446) (xy 409.855186 -398.385724) (xy 409.867518 -398.335778)
			(xy 409.878784 -398.31264) (xy 409.884626 -398.30121) (xy 409.884372 -398.27581) (xy 409.836874 -398.190212)
			(xy 409.830148 -398.179436) (xy 409.808828 -398.165696) (xy 409.796234 -398.16405) (xy 409.772361 -398.161856)
			(xy 409.725618 -398.151228) (xy 409.681021 -398.133647) (xy 409.6396 -398.109519) (xy 409.602307 -398.079399)
			(xy 409.570004 -398.043982) (xy 409.543433 -398.004083) (xy 409.523208 -397.960622) (xy 409.516072 -397.937736)
			(xy 409.514548 -397.931894) (xy 409.194254 -397.378174) (xy 409.19019 -397.373856) (xy 409.174037 -397.356117)
			(xy 409.146666 -397.316717) (xy 409.125574 -397.273628) (xy 409.111245 -397.227844) (xy 409.10401 -397.180419)
			(xy 409.103576 -397.156432) (xy 409.103757 -397.142384) (xy 409.106298 -397.114402) (xy 409.108656 -397.100552)
			(xy 409.109985 -397.091273) (xy 409.106454 -397.072875) (xy 409.101798 -397.064738) (xy 409.085034 -397.037814)
			(xy 409.079826 -397.030115) (xy 409.065105 -397.018789) (xy 409.056332 -397.015716) (xy 409.034703 -397.008923)
			(xy 408.99349 -396.990039) (xy 408.95537 -396.965501) (xy 408.921115 -396.935806) (xy 408.905964 -396.918942)
			(xy 408.903496 -396.916174) (xy 408.897888 -396.911325) (xy 408.894788 -396.90929) (xy 408.882734 -396.901218)
			(xy 408.862774 -396.88018) (xy 408.848697 -396.854826) (xy 408.841394 -396.826761) (xy 408.84094 -396.812262)
			(xy 408.84094 -396.800324) (xy 408.839416 -396.79372) (xy 408.834209 -396.773351) (xy 408.828609 -396.731683)
			(xy 408.82824 -396.710662) (xy 408.264106 -396.710662) (xy 408.264106 -396.710916) (xy 408.263852 -396.726664)
			(xy 408.263344 -396.731998) (xy 408.259026 -396.767558) (xy 408.25801 -396.772638) (xy 408.257718 -396.780105)
			(xy 408.260959 -396.794685) (xy 408.26436 -396.80134) (xy 408.27706 -396.821914) (xy 408.279567 -396.825733)
			(xy 408.285702 -396.8325) (xy 408.289252 -396.835376) (xy 408.310334 -396.851632) (xy 408.315922 -396.85341)
			(xy 408.341384 -396.862194) (xy 408.389142 -396.887089) (xy 408.410918 -396.90294) (xy 408.431533 -396.91928)
			(xy 408.467619 -396.957548) (xy 408.496929 -397.001224) (xy 408.518667 -397.049122) (xy 408.52598 -397.07439)
			(xy 408.527758 -397.080994) (xy 408.843734 -397.627602) (xy 408.847798 -397.63192) (xy 408.863956 -397.649589)
			(xy 408.891289 -397.688899) (xy 408.912365 -397.73189) (xy 408.926699 -397.777572) (xy 408.933962 -397.824897)
			(xy 408.934412 -397.848836) (xy 408.934412 -397.849344) (xy 408.933932 -397.874797) (xy 408.925773 -397.925044)
			(xy 408.909659 -397.973332) (xy 408.886006 -398.018408) (xy 408.855427 -398.059106) (xy 408.818714 -398.09437)
			(xy 408.798014 -398.109186) (xy 408.78952 -398.11567) (xy 408.778328 -398.133843) (xy 408.77549 -398.154996)
			(xy 408.781496 -398.175477) (xy 408.795309 -398.191747) (xy 408.814542 -398.200998) (xy 408.825192 -398.201896)
			(xy 408.834844 -398.201388) (xy 408.843355 -398.200073) (xy 408.860522 -398.198674) (xy 408.869134 -398.198594)
			(xy 408.869388 -398.198848) (xy 409.1686 -398.198848) (xy 409.168854 -398.198594) (xy 409.189899 -398.198959)
			(xy 409.231218 -398.20696) (xy 409.270169 -398.222897) (xy 409.305246 -398.246154) (xy 409.335088 -398.27583)
			(xy 409.358541 -398.310776) (xy 409.374696 -398.349638) (xy 409.382927 -398.390911) (xy 409.383484 -398.411954)
			(xy 409.383484 -398.615916) (xy 409.382993 -398.62592) (xy 409.37533 -398.644404) (xy 409.361177 -398.658548)
			(xy 409.342689 -398.666199) (xy 409.332684 -398.666716) (xy 409.32354 -398.666716) (xy 409.32354 -398.881092)
			(xy 409.323054 -398.891104) (xy 409.315397 -398.909605) (xy 409.301245 -398.92377) (xy 409.282751 -398.931444)
			(xy 409.27274 -398.931892) (xy 408.765248 -398.931892) (xy 408.755221 -398.931481) (xy 408.736689 -398.923819)
			(xy 408.722503 -398.909645) (xy 408.714827 -398.891119) (xy 408.714448 -398.881092) (xy 408.714448 -398.717516)
			(xy 408.713963 -398.707503) (xy 408.706308 -398.688997) (xy 408.692157 -398.674828) (xy 408.673661 -398.667149)
			(xy 408.663648 -398.666716) (xy 408.654504 -398.666716) (xy 408.654504 -398.411446) (xy 408.6553 -398.385724)
			(xy 408.667621 -398.335776) (xy 408.678888 -398.31264) (xy 408.68473 -398.30121) (xy 408.684476 -398.27581)
			(xy 408.636978 -398.190212) (xy 408.630265 -398.179432) (xy 408.608929 -398.165725) (xy 408.596338 -398.16405)
			(xy 408.572455 -398.161878) (xy 408.525696 -398.151232) (xy 408.481083 -398.13364) (xy 408.439643 -398.109507)
			(xy 408.402327 -398.079386) (xy 408.369992 -398.043971) (xy 408.343383 -398.004076) (xy 408.323109 -397.960616)
			(xy 408.315922 -397.937736) (xy 408.314398 -397.931894) (xy 407.999692 -397.387572) (xy 407.99766 -397.385794)
			(xy 407.983436 -397.383508) (xy 407.976115 -397.382641) (xy 407.961524 -397.384702) (xy 407.954734 -397.387572)
			(xy 407.86939 -397.42618) (xy 407.860958 -397.430665) (xy 407.84794 -397.444623) (xy 407.840892 -397.46236)
			(xy 407.840434 -397.4719) (xy 407.840434 -398.160748) (xy 407.840946 -398.171584) (xy 407.849894 -398.191322)
			(xy 407.857706 -398.198848) (xy 407.968704 -398.198848) (xy 407.968958 -398.198594) (xy 407.990003 -398.198959)
			(xy 408.031321 -398.206961) (xy 408.070272 -398.222899) (xy 408.105347 -398.246156) (xy 408.135189 -398.275832)
			(xy 408.158641 -398.310777) (xy 408.174796 -398.349639) (xy 408.183027 -398.390911) (xy 408.183588 -398.411954)
			(xy 408.183588 -398.666716) (xy 408.180794 -398.666716) (xy 408.155902 -398.726406) (xy 408.156918 -398.728438)
			(xy 408.158794 -398.731831) (xy 408.163391 -398.738074) (xy 408.166062 -398.740884) (xy 408.449526 -399.024348)
			(xy 408.456373 -399.031745) (xy 408.464102 -399.050345) (xy 408.464512 -399.060416) (xy 408.464512 -399.963132)
			(xy 408.464512 -399.963386) (xy 408.464906 -399.971831) (xy 408.470479 -399.987779) (xy 408.475434 -399.994628)
			(xy 408.491657 -400.012413) (xy 408.51909 -400.051968) (xy 408.540231 -400.095214) (xy 408.554595 -400.141158)
			(xy 408.561851 -400.188745) (xy 408.562302 -400.212814) (xy 408.561869 -400.236527) (xy 408.554834 -400.283428)
			(xy 408.540908 -400.328762) (xy 408.520398 -400.371524) (xy 408.493762 -400.410763) (xy 408.477974 -400.42846)
			(xy 408.471116 -400.43608) (xy 408.468068 -400.444208) (xy 408.46643 -400.448602) (xy 408.464649 -400.457808)
			(xy 408.464512 -400.462496) (xy 408.464512 -400.485864) (xy 408.474418 -400.506438) (xy 408.483562 -400.513804)
			(xy 408.505386 -400.532035) (xy 408.543913 -400.573857) (xy 408.575812 -400.62093) (xy 408.600377 -400.672214)
			(xy 408.617065 -400.726573) (xy 408.625507 -400.782806) (xy 408.626056 -400.811238) (xy 408.626056 -401.674838)
			(xy 409.062428 -401.674838) (xy 409.062428 -400.811238) (xy 409.062857 -400.785718) (xy 409.069647 -400.735132)
			(xy 409.083123 -400.685904) (xy 409.103046 -400.638913) (xy 409.129058 -400.595) (xy 409.160695 -400.554948)
			(xy 409.17876 -400.536918) (xy 409.185364 -400.530568) (xy 409.193238 -400.513804) (xy 409.200096 -400.42846)
			(xy 409.195016 -400.41068) (xy 409.189428 -400.403314) (xy 409.174577 -400.382566) (xy 409.150942 -400.337352)
			(xy 409.134841 -400.288941) (xy 409.126688 -400.238577) (xy 409.126182 -400.213068) (xy 409.126182 -400.212814)
			(xy 409.126672 -400.187825) (xy 409.134491 -400.138462) (xy 409.149935 -400.09093) (xy 409.172625 -400.046398)
			(xy 409.202001 -400.005965) (xy 409.237341 -399.970625) (xy 409.277774 -399.941249) (xy 409.322306 -399.918559)
			(xy 409.369838 -399.903115) (xy 409.419201 -399.895296) (xy 409.469179 -399.895296) (xy 409.518542 -399.903115)
			(xy 409.566074 -399.918559) (xy 409.610606 -399.941249) (xy 409.651039 -399.970625) (xy 409.686379 -400.005965)
			(xy 409.715755 -400.046398) (xy 409.738445 -400.09093) (xy 409.753889 -400.138462) (xy 409.761708 -400.187825)
			(xy 409.762198 -400.212814) (xy 409.762198 -400.213068) (xy 409.761705 -400.238577) (xy 409.753528 -400.288937)
			(xy 409.737426 -400.337348) (xy 409.71381 -400.382572) (xy 409.698952 -400.403314) (xy 409.693364 -400.41068)
			(xy 409.688284 -400.42846) (xy 409.695142 -400.513804) (xy 409.703016 -400.530568) (xy 409.70962 -400.536918)
			(xy 409.727648 -400.554983) (xy 409.75928 -400.595032) (xy 409.785293 -400.63894) (xy 409.805222 -400.685923)
			(xy 409.818712 -400.735142) (xy 409.825522 -400.785721) (xy 409.825952 -400.811238) (xy 409.825952 -401.674838)
			(xy 409.825942 -401.675346) (xy 410.262832 -401.675346) (xy 410.262832 -400.81073) (xy 410.263262 -400.785262)
			(xy 410.270065 -400.734781) (xy 410.283527 -400.685656) (xy 410.303409 -400.638759) (xy 410.329357 -400.594927)
			(xy 410.360908 -400.554938) (xy 410.37891 -400.536918) (xy 410.385514 -400.530568) (xy 410.393388 -400.513804)
			(xy 410.400246 -400.42846) (xy 410.395166 -400.41068) (xy 410.389578 -400.403314) (xy 410.374733 -400.382562)
			(xy 410.351095 -400.33735) (xy 410.334992 -400.28894) (xy 410.326838 -400.238577) (xy 410.326332 -400.213068)
			(xy 410.326332 -400.212814) (xy 410.326822 -400.187825) (xy 410.334641 -400.138462) (xy 410.350085 -400.09093)
			(xy 410.372775 -400.046398) (xy 410.402151 -400.005965) (xy 410.437491 -399.970625) (xy 410.477924 -399.941249)
			(xy 410.522456 -399.918559) (xy 410.569988 -399.903115) (xy 410.619351 -399.895296) (xy 410.669329 -399.895296)
			(xy 410.718692 -399.903115) (xy 410.766224 -399.918559) (xy 410.810756 -399.941249) (xy 410.851189 -399.970625)
			(xy 410.886529 -400.005965) (xy 410.915905 -400.046398) (xy 410.938595 -400.09093) (xy 410.954039 -400.138462)
			(xy 410.961858 -400.187825) (xy 410.962348 -400.212814) (xy 410.962348 -400.213068) (xy 410.961846 -400.238577)
			(xy 410.95367 -400.288935) (xy 410.93757 -400.337346) (xy 410.913958 -400.382571) (xy 410.899102 -400.403314)
			(xy 410.893514 -400.41068) (xy 410.888434 -400.42846) (xy 410.895292 -400.513804) (xy 410.903166 -400.530568)
			(xy 410.90977 -400.536918) (xy 410.927772 -400.554937) (xy 410.959313 -400.594932) (xy 410.985253 -400.638766)
			(xy 411.005132 -400.685662) (xy 411.018596 -400.734785) (xy 411.025407 -400.785263) (xy 411.025848 -400.81073)
			(xy 411.025848 -401.675346) (xy 411.025373 -401.703744) (xy 411.01696 -401.759913) (xy 411.000297 -401.814209)
			(xy 410.975755 -401.865428) (xy 410.943877 -401.912433) (xy 410.92501 -401.933664) (xy 410.91915 -401.9406)
			(xy 410.912242 -401.957377) (xy 410.911548 -401.96643) (xy 410.910532 -401.997418) (xy 410.910579 -402.00657)
			(xy 410.916451 -402.023891) (xy 410.921962 -402.0312) (xy 410.937305 -402.050548) (xy 410.963079 -402.092668)
			(xy 410.982858 -402.137914) (xy 410.99627 -402.185438) (xy 411.003065 -402.234348) (xy 411.003496 -402.259038)
			(xy 411.002994 -402.285915) (xy 410.994982 -402.33907) (xy 410.979138 -402.390436) (xy 410.955814 -402.438868)
			(xy 410.925533 -402.483282) (xy 410.888971 -402.522687) (xy 410.846943 -402.556203) (xy 410.80039 -402.58308)
			(xy 410.750351 -402.602719) (xy 410.697944 -402.61468) (xy 410.64434 -402.618698) (xy 410.590736 -402.61468)
			(xy 410.538329 -402.602719) (xy 410.48829 -402.58308) (xy 410.441737 -402.556203) (xy 410.399709 -402.522687)
			(xy 410.363147 -402.483282) (xy 410.332866 -402.438868) (xy 410.309542 -402.390436) (xy 410.293698 -402.33907)
			(xy 410.285686 -402.285915) (xy 410.285184 -402.259038) (xy 410.285586 -402.234344) (xy 410.292343 -402.185422)
			(xy 410.305746 -402.137889) (xy 410.325544 -402.092644) (xy 410.351362 -402.050542) (xy 410.366718 -402.0312)
			(xy 410.372196 -402.023878) (xy 410.378045 -402.006563) (xy 410.378148 -401.997418) (xy 410.377132 -401.96643)
			(xy 410.376493 -401.957365) (xy 410.369575 -401.940573) (xy 410.36367 -401.933664) (xy 410.344851 -401.9124)
			(xy 410.313032 -401.865374) (xy 410.288517 -401.814159) (xy 410.271845 -401.759881) (xy 410.263383 -401.703735)
			(xy 410.262832 -401.675346) (xy 409.825942 -401.675346) (xy 409.825392 -401.704002) (xy 409.816471 -401.761643)
			(xy 409.798887 -401.817258) (xy 409.773051 -401.869552) (xy 409.739563 -401.917308) (xy 409.71978 -401.938744)
			(xy 409.713621 -401.945827) (xy 409.706464 -401.963162) (xy 409.70581 -401.972526) (xy 409.704032 -402.041106)
			(xy 409.704169 -402.050363) (xy 409.710307 -402.067817) (xy 409.71597 -402.075142) (xy 409.716478 -402.07565)
			(xy 409.732839 -402.095257) (xy 409.760369 -402.138269) (xy 409.781524 -402.184748) (xy 409.795877 -402.233756)
			(xy 409.803139 -402.284305) (xy 409.8036 -402.309838) (xy 409.803098 -402.336734) (xy 409.79508 -402.389926)
			(xy 409.779224 -402.441329) (xy 409.755885 -402.489795) (xy 409.725582 -402.534241) (xy 409.688994 -402.573674)
			(xy 409.646937 -402.607213) (xy 409.600351 -402.634109) (xy 409.550277 -402.653762) (xy 409.497832 -402.665732)
			(xy 409.44419 -402.669752) (xy 409.390548 -402.665732) (xy 409.338103 -402.653762) (xy 409.288029 -402.634109)
			(xy 409.241443 -402.607213) (xy 409.199386 -402.573674) (xy 409.162798 -402.534241) (xy 409.132495 -402.489795)
			(xy 409.109156 -402.441329) (xy 409.0933 -402.389926) (xy 409.085282 -402.336734) (xy 409.08478 -402.309838)
			(xy 409.085249 -402.28427) (xy 409.092526 -402.233654) (xy 409.106923 -402.184586) (xy 409.128148 -402.138063)
			(xy 409.15577 -402.095029) (xy 409.172156 -402.075396) (xy 409.17241 -402.075142) (xy 409.178079 -402.067824)
			(xy 409.184186 -402.050363) (xy 409.184348 -402.041106) (xy 409.182316 -401.962874) (xy 409.175204 -401.945856)
			(xy 409.1686 -401.938744) (xy 409.148814 -401.917311) (xy 409.115323 -401.869556) (xy 409.089487 -401.817262)
			(xy 409.07191 -401.761645) (xy 409.062999 -401.704002) (xy 409.062428 -401.674838) (xy 408.626056 -401.674838)
			(xy 408.625485 -401.704002) (xy 408.616574 -401.761645) (xy 408.598996 -401.817261) (xy 408.57316 -401.869555)
			(xy 408.539667 -401.917309) (xy 408.519884 -401.938744) (xy 408.51328 -401.945856) (xy 408.506168 -401.962874)
			(xy 408.503882 -402.050504) (xy 408.509978 -402.06803) (xy 408.513026 -402.071586) (xy 408.522693 -402.082745)
			(xy 408.540372 -402.106396) (xy 408.548332 -402.11883) (xy 408.561411 -402.140374) (xy 408.58207 -402.186344)
			(xy 408.596109 -402.234749) (xy 408.603251 -402.284639) (xy 408.603704 -402.309838) (xy 408.60314 -402.338255)
			(xy 408.594146 -402.394375) (xy 408.576438 -402.448381) (xy 408.550454 -402.498929) (xy 408.534108 -402.522182)
			(xy 408.529536 -402.528278) (xy 408.522424 -402.549868) (xy 408.521001 -402.554235) (xy 408.519594 -402.563309)
			(xy 408.51963 -402.567902) (xy 408.520392 -402.58492) (xy 408.520646 -402.590508) (xy 408.521404 -402.599953)
			(xy 408.528967 -402.617313) (xy 408.535378 -402.62429) (xy 408.740864 -402.829776) (xy 408.746364 -402.834762)
			(xy 408.759532 -402.841599) (xy 408.766772 -402.843238) (xy 408.776424 -402.844254) (xy 415.425382 -402.844254)
		)
		(stroke
			(width 0)
			(type solid)
		)
		(fill yes)
		(layer "B.Cu")
		(net "P0V9_CPU0_RT_2D")
	)
	(gr_poly
		(pts
			(xy 126.907544 -394.461238) (xy 126.914788 -394.45961) (xy 126.927956 -394.452767) (xy 126.933452 -394.447776)
			(xy 127.011684 -394.369544) (xy 127.018113 -394.362544) (xy 127.025719 -394.345142) (xy 127.02649 -394.326166)
			(xy 127.020323 -394.308204) (xy 127.014478 -394.30071) (xy 127.011176 -394.297408) (xy 127.006889 -394.293389)
			(xy 126.996883 -394.287234) (xy 126.991364 -394.285216) (xy 126.980696 -394.28166) (xy 126.9746 -394.282676)
			(xy 126.968504 -394.283438) (xy 126.955622 -394.285203) (xy 126.929689 -394.287108) (xy 126.916688 -394.287248)
			(xy 126.8984 -394.287248) (xy 126.892304 -394.286994) (xy 126.878842 -394.285216) (xy 126.878334 -394.285216)
			(xy 126.851909 -394.281873) (xy 126.800378 -394.268398) (xy 126.751399 -394.247469) (xy 126.728474 -394.233908)
			(xy 126.704011 -394.218207) (xy 126.660045 -394.180188) (xy 126.622768 -394.13559) (xy 126.593151 -394.085576)
			(xy 126.571967 -394.031448) (xy 126.559768 -393.974618) (xy 126.557786 -393.945618) (xy 126.557532 -393.936982)
			(xy 126.557278 -393.928346) (xy 126.557278 -393.92733) (xy 126.557861 -393.898831) (xy 126.566933 -393.842559)
			(xy 126.584776 -393.788425) (xy 126.610941 -393.737786) (xy 126.644772 -393.691913) (xy 126.66472 -393.671552)
			(xy 126.672086 -393.66444) (xy 126.675896 -393.655804) (xy 126.677829 -393.651142) (xy 126.680003 -393.641288)
			(xy 126.680214 -393.636246) (xy 126.680468 -393.616942) (xy 126.680112 -393.605998) (xy 126.671286 -393.585983)
			(xy 126.66345 -393.578334) (xy 126.643646 -393.560141) (xy 126.608837 -393.519151) (xy 126.580126 -393.473681)
			(xy 126.558082 -393.42463) (xy 126.543143 -393.372971) (xy 126.535603 -393.319726) (xy 126.53518 -393.292838)
			(xy 126.53518 -392.428984) (xy 126.535679 -392.400913) (xy 126.543911 -392.345379) (xy 126.560195 -392.291651)
			(xy 126.584178 -392.24089) (xy 126.615343 -392.194194) (xy 126.653017 -392.15257) (xy 126.674372 -392.134344)
			(xy 126.683008 -392.127486) (xy 126.69266 -392.107928) (xy 126.692914 -392.096752) (xy 126.693422 -392.079226)
			(xy 126.693409 -392.074357) (xy 126.691748 -392.064765) (xy 126.69012 -392.060176) (xy 126.687072 -392.05154)
			(xy 126.680214 -392.04392) (xy 126.664902 -392.02631) (xy 126.639067 -391.987448) (xy 126.619184 -391.945231)
			(xy 126.605678 -391.900562) (xy 126.59884 -391.8544) (xy 126.598426 -391.831068) (xy 126.598426 -391.830814)
			(xy 126.59889 -391.805823) (xy 126.606707 -391.756456) (xy 126.622152 -391.708921) (xy 126.644843 -391.664387)
			(xy 126.674222 -391.623951) (xy 126.709566 -391.588609) (xy 126.750004 -391.559233) (xy 126.794539 -391.536544)
			(xy 126.842076 -391.521103) (xy 126.891443 -391.513288) (xy 126.916434 -391.512806) (xy 126.916434 -391.512552)
			(xy 126.938318 -391.512949) (xy 126.981664 -391.519023) (xy 127.023763 -391.530997) (xy 127.043942 -391.539476)
			(xy 127.044196 -391.539476) (xy 127.050123 -391.541843) (xy 127.062715 -391.543893) (xy 127.069088 -391.54354)
			(xy 127.081026 -391.542524) (xy 127.1651 -391.48766) (xy 127.168656 -391.484866) (xy 127.172212 -391.481564)
			(xy 127.177316 -391.475851) (xy 127.184161 -391.462151) (xy 127.185674 -391.45464) (xy 127.186436 -391.446258)
			(xy 127.186436 -389.866632) (xy 127.186677 -389.859449) (xy 127.190665 -389.845648) (xy 127.19431 -389.839454)
			(xy 127.198374 -389.833358) (xy 127.202438 -389.819388) (xy 127.202438 -389.80872) (xy 127.201999 -389.798658)
			(xy 127.194257 -389.78008) (xy 127.187452 -389.772652) (xy 127.18034 -389.76554) (xy 127.170942 -389.76173)
			(xy 127.148076 -389.751862) (xy 127.105481 -389.726062) (xy 127.06743 -389.693935) (xy 127.034855 -389.656268)
			(xy 127.008553 -389.613981) (xy 126.989167 -389.568109) (xy 126.982728 -389.544052) (xy 126.98222 -389.542274)
			(xy 126.666498 -388.996174) (xy 126.662434 -388.991856) (xy 126.646243 -388.974148) (xy 126.618866 -388.934746)
			(xy 126.597774 -388.89165) (xy 126.583455 -388.845857) (xy 126.576241 -388.798422) (xy 126.57582 -388.774432)
			(xy 126.575995 -388.760383) (xy 126.578535 -388.732401) (xy 126.5809 -388.718552) (xy 126.582112 -388.709276)
			(xy 126.578583 -388.690919) (xy 126.574042 -388.682738) (xy 126.557278 -388.655814) (xy 126.55207 -388.648116)
			(xy 126.537346 -388.636797) (xy 126.528576 -388.633716) (xy 126.506945 -388.626924) (xy 126.46572 -388.60806)
			(xy 126.427597 -388.583524) (xy 126.393351 -388.553815) (xy 126.378208 -388.536942) (xy 126.375727 -388.534188)
			(xy 126.370122 -388.529337) (xy 126.367032 -388.52729) (xy 126.354967 -388.519234) (xy 126.335012 -388.498189)
			(xy 126.320939 -388.47283) (xy 126.313639 -388.444762) (xy 126.313184 -388.430262) (xy 126.313184 -388.418324)
			(xy 126.31166 -388.41172) (xy 126.306466 -388.391348) (xy 126.300866 -388.349682) (xy 126.300484 -388.328662)
			(xy 126.300858 -388.307642) (xy 126.306468 -388.265976) (xy 126.31166 -388.245604) (xy 126.313184 -388.239)
			(xy 126.313184 -388.125462) (xy 126.313676 -388.110471) (xy 126.321435 -388.081511) (xy 126.336415 -388.05554)
			(xy 126.357599 -388.034324) (xy 126.383546 -388.019303) (xy 126.412494 -388.0115) (xy 126.427484 -388.010908)
			(xy 126.609602 -388.010908) (xy 126.61011 -388.010654) (xy 126.626874 -388.010654) (xy 126.627382 -388.010908)
			(xy 126.808738 -388.010908) (xy 126.809246 -388.010908) (xy 126.82347 -388.01167) (xy 126.826518 -388.012178)
			(xy 126.82982 -388.012178) (xy 126.839837 -388.011754) (xy 126.858343 -388.00408) (xy 126.872504 -387.989908)
			(xy 126.880163 -387.971395) (xy 126.88062 -387.961378) (xy 126.88062 -386.963412) (xy 126.8802 -386.95334)
			(xy 126.872491 -386.934731) (xy 126.865634 -386.927344) (xy 126.834646 -386.896356) (xy 126.827247 -386.889512)
			(xy 126.808648 -386.881788) (xy 126.798578 -386.88137) (xy 126.14021 -386.88137) (xy 126.134202 -386.881542)
			(xy 126.122523 -386.884372) (xy 126.117096 -386.886958) (xy 126.113623 -386.888799) (xy 126.107246 -386.893395)
			(xy 126.104396 -386.896102) (xy 125.830838 -387.16966) (xy 125.82813 -387.17251) (xy 125.823532 -387.178886)
			(xy 125.821694 -387.18236) (xy 125.819113 -387.187787) (xy 125.816293 -387.199467) (xy 125.816106 -387.205474)
			(xy 125.816106 -388.450328) (xy 125.816328 -388.457136) (xy 125.819943 -388.470263) (xy 125.823218 -388.476236)
			(xy 125.82652 -388.481824) (xy 125.836426 -388.491222) (xy 125.842776 -388.494778) (xy 125.865358 -388.507637)
			(xy 125.906384 -388.539529) (xy 125.941694 -388.577652) (xy 125.970355 -388.620997) (xy 125.991608 -388.668415)
			(xy 125.998732 -388.693406) (xy 126.003812 -388.705852) (xy 126.315978 -389.245602) (xy 126.320042 -389.24992)
			(xy 126.336198 -389.26759) (xy 126.363528 -389.306901) (xy 126.3846 -389.349892) (xy 126.398933 -389.395574)
			(xy 126.406195 -389.442897) (xy 126.406656 -389.466836) (xy 126.406656 -389.467344) (xy 126.406166 -389.492131)
			(xy 126.398405 -389.541094) (xy 126.38308 -389.58824) (xy 126.360569 -389.632408) (xy 126.331426 -389.672511)
			(xy 126.296369 -389.707562) (xy 126.25626 -389.736698) (xy 126.212088 -389.759201) (xy 126.164939 -389.774518)
			(xy 126.115975 -389.782271) (xy 126.091188 -389.782812) (xy 126.065795 -389.782303) (xy 126.015664 -389.774171)
			(xy 125.967481 -389.758119) (xy 125.922489 -389.734561) (xy 125.881849 -389.704103) (xy 125.846608 -389.667533)
			(xy 125.817677 -389.625793) (xy 125.7958 -389.57996) (xy 125.788166 -389.555736) (xy 125.786642 -389.549894)
			(xy 125.581918 -389.195564) (xy 125.575525 -389.185645) (xy 125.555934 -389.172541) (xy 125.544326 -389.170418)
			(xy 125.532642 -389.168894) (xy 125.510544 -389.176514) (xy 125.222508 -389.46455) (xy 125.21951 -389.467642)
			(xy 125.214538 -389.474673) (xy 125.212602 -389.47852) (xy 125.208792 -389.486648) (xy 125.20803 -389.495792)
			(xy 125.205151 -389.522018) (xy 125.191822 -389.573063) (xy 125.170254 -389.62121) (xy 125.141038 -389.665138)
			(xy 125.104976 -389.703645) (xy 125.084332 -389.720074) (xy 125.084078 -389.720328) (xy 125.079533 -389.723984)
			(xy 125.072082 -389.732957) (xy 125.069346 -389.738108) (xy 125.06452 -389.748014) (xy 125.06452 -389.75538)
			(xy 125.073156 -389.774938) (xy 125.104144 -389.803386) (xy 125.111481 -389.809538) (xy 125.12937 -389.816319)
			(xy 125.138942 -389.816594) (xy 125.141482 -389.816594) (xy 125.141736 -389.816848) (xy 125.440948 -389.816848)
			(xy 125.441202 -389.816594) (xy 125.458251 -389.816828) (xy 125.49194 -389.822066) (xy 125.508258 -389.827008)
			(xy 125.515878 -389.829548) (xy 125.545342 -389.829548) (xy 125.55869 -389.829989) (xy 125.584475 -389.836907)
			(xy 125.607591 -389.850262) (xy 125.626465 -389.869144) (xy 125.63981 -389.892266) (xy 125.646717 -389.918054)
			(xy 125.647196 -389.931402) (xy 125.647196 -389.969248) (xy 125.648974 -389.975598) (xy 125.652209 -389.988953)
			(xy 125.655648 -390.016214) (xy 125.655832 -390.029954) (xy 125.655832 -390.284716) (xy 125.647196 -390.284716)
			(xy 125.647196 -390.388856) (xy 125.646718 -390.403174) (xy 125.638787 -390.430689) (xy 125.623535 -390.454924)
			(xy 125.61316 -390.464802) (xy 125.605032 -390.471914) (xy 125.595888 -390.491726) (xy 125.595888 -390.499092)
			(xy 125.59547 -390.509114) (xy 125.587801 -390.527631) (xy 125.573628 -390.541803) (xy 125.55511 -390.549471)
			(xy 125.545088 -390.549892) (xy 125.11532 -390.549892) (xy 125.105295 -390.550308) (xy 125.08677 -390.557974)
			(xy 125.07259 -390.572147) (xy 125.064914 -390.590668) (xy 125.06452 -390.600692) (xy 125.06452 -390.642602)
			(xy 126.109984 -390.642602) (xy 126.109984 -390.160002) (xy 126.11047 -390.132769) (xy 126.118221 -390.078857)
			(xy 126.133566 -390.026597) (xy 126.156192 -389.977053) (xy 126.185639 -389.931233) (xy 126.221306 -389.89007)
			(xy 126.262469 -389.854403) (xy 126.308289 -389.824956) (xy 126.357833 -389.80233) (xy 126.410093 -389.786985)
			(xy 126.464005 -389.779234) (xy 126.518471 -389.779234) (xy 126.572383 -389.786985) (xy 126.624643 -389.80233)
			(xy 126.674187 -389.824956) (xy 126.720007 -389.854403) (xy 126.76117 -389.89007) (xy 126.796837 -389.931233)
			(xy 126.826284 -389.977053) (xy 126.84891 -390.026597) (xy 126.864255 -390.078857) (xy 126.872006 -390.132769)
			(xy 126.872492 -390.160002) (xy 126.872492 -390.642602) (xy 126.872006 -390.669835) (xy 126.864255 -390.723747)
			(xy 126.84891 -390.776007) (xy 126.826284 -390.825551) (xy 126.796837 -390.871371) (xy 126.76117 -390.912534)
			(xy 126.720007 -390.948201) (xy 126.674187 -390.977648) (xy 126.624643 -391.000274) (xy 126.572383 -391.015619)
			(xy 126.518471 -391.02337) (xy 126.464005 -391.02337) (xy 126.410093 -391.015619) (xy 126.357833 -391.000274)
			(xy 126.308289 -390.977648) (xy 126.262469 -390.948201) (xy 126.221306 -390.912534) (xy 126.185639 -390.871371)
			(xy 126.156192 -390.825551) (xy 126.133566 -390.776007) (xy 126.118221 -390.723747) (xy 126.11047 -390.669835)
			(xy 126.109984 -390.642602) (xy 125.06452 -390.642602) (xy 125.06452 -391.158222) (xy 125.064266 -391.165842)
			(xy 125.064266 -391.445496) (xy 125.063843 -391.455566) (xy 125.056126 -391.474168) (xy 125.04928 -391.481564)
			(xy 124.931932 -391.598912) (xy 124.927109 -391.603465) (xy 124.91566 -391.610151) (xy 124.909326 -391.61212)
			(xy 124.901344 -391.614623) (xy 124.887479 -391.623961) (xy 124.882148 -391.630408) (xy 124.83465 -391.6934)
			(xy 124.830332 -391.699242) (xy 124.826918 -391.703972) (xy 124.822171 -391.714624) (xy 124.820934 -391.720324)
			(xy 124.818902 -391.731754) (xy 124.821188 -391.740136) (xy 124.82794 -391.764641) (xy 124.834451 -391.815049)
			(xy 124.834142 -391.840466) (xy 124.832729 -391.868382) (xy 124.821342 -391.923102) (xy 124.800581 -391.974995)
			(xy 124.771082 -392.022468) (xy 124.752862 -392.043666) (xy 124.746004 -392.051032) (xy 124.742702 -392.059922)
			(xy 124.741187 -392.064468) (xy 124.739655 -392.073926) (xy 124.739654 -392.078718) (xy 124.740162 -392.097514)
			(xy 124.740162 -392.098022) (xy 124.740416 -392.107928) (xy 124.749814 -392.126978) (xy 124.758704 -392.134344)
			(xy 124.780116 -392.152561) (xy 124.817875 -392.194207) (xy 124.849122 -392.240939) (xy 124.873181 -392.291745)
			(xy 124.889534 -392.34553) (xy 124.897827 -392.401131) (xy 124.898404 -392.429238) (xy 124.898404 -393.292838)
			(xy 125.334776 -393.292838) (xy 125.334776 -392.429238) (xy 125.33519 -392.403717) (xy 125.341981 -392.35313)
			(xy 125.355459 -392.303901) (xy 125.375384 -392.25691) (xy 125.4014 -392.212997) (xy 125.433041 -392.172947)
			(xy 125.451108 -392.154918) (xy 125.457712 -392.148568) (xy 125.465586 -392.131804) (xy 125.472444 -392.04646)
			(xy 125.467364 -392.02868) (xy 125.461776 -392.021314) (xy 125.446931 -392.000562) (xy 125.423293 -391.95535)
			(xy 125.40719 -391.90694) (xy 125.399036 -391.856577) (xy 125.39853 -391.831068) (xy 125.39853 -391.830814)
			(xy 125.39902 -391.805825) (xy 125.406839 -391.756462) (xy 125.422283 -391.70893) (xy 125.444973 -391.664398)
			(xy 125.474349 -391.623965) (xy 125.509689 -391.588625) (xy 125.550122 -391.559249) (xy 125.594654 -391.536559)
			(xy 125.642186 -391.521115) (xy 125.691549 -391.513296) (xy 125.741527 -391.513296) (xy 125.79089 -391.521115)
			(xy 125.838422 -391.536559) (xy 125.882954 -391.559249) (xy 125.923387 -391.588625) (xy 125.958727 -391.623965)
			(xy 125.988103 -391.664398) (xy 126.010793 -391.70893) (xy 126.026237 -391.756462) (xy 126.034056 -391.805825)
			(xy 126.034546 -391.830814) (xy 126.034546 -391.831068) (xy 126.034044 -391.856577) (xy 126.025868 -391.906935)
			(xy 126.009768 -391.955346) (xy 125.986156 -392.000572) (xy 125.9713 -392.021314) (xy 125.965712 -392.02868)
			(xy 125.960632 -392.04646) (xy 125.96749 -392.131804) (xy 125.975364 -392.148568) (xy 125.981968 -392.154918)
			(xy 126.000005 -392.172974) (xy 126.031635 -392.213026) (xy 126.057645 -392.256936) (xy 126.077572 -392.30392)
			(xy 126.091061 -392.353141) (xy 126.09787 -392.40372) (xy 126.0983 -392.429238) (xy 126.0983 -393.292838)
			(xy 126.097727 -393.322001) (xy 126.088807 -393.379641) (xy 126.071226 -393.435255) (xy 126.045393 -393.487549)
			(xy 126.011908 -393.535307) (xy 125.992128 -393.556744) (xy 125.985963 -393.563822) (xy 125.978811 -393.581161)
			(xy 125.978158 -393.590526) (xy 125.97638 -393.659106) (xy 125.976528 -393.668362) (xy 125.982659 -393.685815)
			(xy 125.988318 -393.693142) (xy 125.988826 -393.69365) (xy 126.005179 -393.713264) (xy 126.032712 -393.756273)
			(xy 126.053869 -393.80275) (xy 126.068224 -393.851757) (xy 126.075487 -393.902305) (xy 126.075948 -393.927838)
			(xy 126.075446 -393.954734) (xy 126.067428 -394.007926) (xy 126.051572 -394.059329) (xy 126.028233 -394.107795)
			(xy 125.99793 -394.152241) (xy 125.961342 -394.191674) (xy 125.919285 -394.225213) (xy 125.872699 -394.252109)
			(xy 125.822625 -394.271762) (xy 125.77018 -394.283732) (xy 125.716538 -394.287752) (xy 125.662896 -394.283732)
			(xy 125.610451 -394.271762) (xy 125.560377 -394.252109) (xy 125.513791 -394.225213) (xy 125.471734 -394.191674)
			(xy 125.435146 -394.152241) (xy 125.404843 -394.107795) (xy 125.381504 -394.059329) (xy 125.365648 -394.007926)
			(xy 125.35763 -393.954734) (xy 125.357128 -393.927838) (xy 125.35761 -393.902271) (xy 125.364886 -393.851656)
			(xy 125.379281 -393.802589) (xy 125.400502 -393.756065) (xy 125.42812 -393.71303) (xy 125.444504 -393.693396)
			(xy 125.444758 -393.693142) (xy 125.450421 -393.68582) (xy 125.456533 -393.668362) (xy 125.456696 -393.659106)
			(xy 125.454664 -393.580874) (xy 125.447552 -393.563856) (xy 125.440948 -393.556744) (xy 125.42117 -393.535304)
			(xy 125.387676 -393.487552) (xy 125.361838 -393.435259) (xy 125.344259 -393.379644) (xy 125.335347 -393.322001)
			(xy 125.334776 -393.292838) (xy 124.898404 -393.292838) (xy 124.897833 -393.322001) (xy 124.888921 -393.379644)
			(xy 124.871341 -393.435258) (xy 124.845502 -393.48755) (xy 124.812006 -393.535301) (xy 124.792232 -393.556744)
			(xy 124.785628 -393.563856) (xy 124.778516 -393.580874) (xy 124.776484 -393.659106) (xy 124.776647 -393.668362)
			(xy 124.782757 -393.685822) (xy 124.788422 -393.693142) (xy 124.788676 -393.693396) (xy 124.80506 -393.713029)
			(xy 124.83268 -393.756064) (xy 124.853903 -393.802588) (xy 124.868299 -393.851655) (xy 124.875575 -393.90227)
			(xy 124.876052 -393.927838) (xy 124.87555 -393.954734) (xy 124.867532 -394.007926) (xy 124.851676 -394.059329)
			(xy 124.828337 -394.107795) (xy 124.798034 -394.152241) (xy 124.761446 -394.191674) (xy 124.719389 -394.225213)
			(xy 124.672803 -394.252109) (xy 124.622729 -394.271762) (xy 124.570284 -394.283732) (xy 124.516642 -394.287752)
			(xy 124.463 -394.283732) (xy 124.410555 -394.271762) (xy 124.360481 -394.252109) (xy 124.313895 -394.225213)
			(xy 124.271838 -394.191674) (xy 124.23525 -394.152241) (xy 124.204947 -394.107795) (xy 124.181608 -394.059329)
			(xy 124.165752 -394.007926) (xy 124.157734 -393.954734) (xy 124.157232 -393.927838) (xy 124.157693 -393.902305)
			(xy 124.164955 -393.851757) (xy 124.17931 -393.802749) (xy 124.200466 -393.756271) (xy 124.227998 -393.713261)
			(xy 124.244354 -393.69365) (xy 124.244862 -393.693142) (xy 124.250523 -393.685816) (xy 124.256656 -393.668362)
			(xy 124.2568 -393.659106) (xy 124.255022 -393.590526) (xy 124.254369 -393.581161) (xy 124.247215 -393.563824)
			(xy 124.241052 -393.556744) (xy 124.221268 -393.535309) (xy 124.187777 -393.487553) (xy 124.161938 -393.43526)
			(xy 124.144353 -393.379645) (xy 124.135431 -393.322002) (xy 124.13488 -393.292838) (xy 124.13488 -392.429238)
			(xy 124.135384 -392.401138) (xy 124.143638 -392.345548) (xy 124.159957 -392.291769) (xy 124.183989 -392.240967)
			(xy 124.215214 -392.19424) (xy 124.252956 -392.152599) (xy 124.274326 -392.134344) (xy 124.282962 -392.127486)
			(xy 124.292614 -392.107928) (xy 124.292868 -392.096752) (xy 124.293376 -392.079226) (xy 124.293363 -392.074357)
			(xy 124.2917 -392.064765) (xy 124.290074 -392.060176) (xy 124.287026 -392.05154) (xy 124.280168 -392.04392)
			(xy 124.265046 -392.026517) (xy 124.239458 -391.988166) (xy 124.21967 -391.946526) (xy 124.206097 -391.902466)
			(xy 124.199022 -391.856909) (xy 124.19838 -391.833862) (xy 124.19838 -391.83056) (xy 124.198758 -391.808487)
			(xy 124.204881 -391.764768) (xy 124.210572 -391.743438) (xy 124.213874 -391.731754) (xy 124.211842 -391.720324)
			(xy 124.210593 -391.714568) (xy 124.205854 -391.70379) (xy 124.202444 -391.698988) (xy 124.153422 -391.634218)
			(xy 124.145867 -391.625157) (xy 124.124815 -391.614573) (xy 124.113036 -391.613898) (xy 123.719844 -391.613898)
			(xy 123.708064 -391.614562) (xy 123.687012 -391.625154) (xy 123.679458 -391.634218) (xy 123.630436 -391.698988)
			(xy 123.627006 -391.703778) (xy 123.622263 -391.714561) (xy 123.621038 -391.720324) (xy 123.619006 -391.731754)
			(xy 123.622308 -391.743438) (xy 123.627911 -391.764462) (xy 123.634034 -391.807538) (xy 123.6345 -391.82929)
			(xy 123.6345 -391.833862) (xy 123.633875 -391.856887) (xy 123.626798 -391.902398) (xy 123.613221 -391.946411)
			(xy 123.593429 -391.988) (xy 123.567837 -392.026295) (xy 123.552712 -392.043666) (xy 123.546108 -392.051032)
			(xy 123.542806 -392.059668) (xy 123.541203 -392.064324) (xy 123.539658 -392.074049) (xy 123.539758 -392.078972)
			(xy 123.54052 -392.097768) (xy 123.54052 -392.098276) (xy 123.540774 -392.107674) (xy 123.550426 -392.127486)
			(xy 123.558808 -392.134344) (xy 123.580173 -392.152559) (xy 123.617843 -392.194189) (xy 123.649007 -392.240888)
			(xy 123.672993 -392.29165) (xy 123.689283 -392.345378) (xy 123.697526 -392.400913) (xy 123.698 -392.428984)
			(xy 123.698 -393.293346) (xy 123.697472 -393.321158) (xy 123.689351 -393.376186) (xy 123.67333 -393.429453)
			(xy 123.64975 -393.479831) (xy 123.619109 -393.526255) (xy 123.600972 -393.547346) (xy 123.59513 -393.55395)
			(xy 123.588272 -393.570714) (xy 123.58624 -393.645136) (xy 123.586306 -393.65405) (xy 123.59189 -393.670969)
			(xy 123.597162 -393.678156) (xy 123.597416 -393.67841) (xy 123.612153 -393.697538) (xy 123.636909 -393.738996)
			(xy 123.655886 -393.783397) (xy 123.668744 -393.82994) (xy 123.67525 -393.877787) (xy 123.675648 -393.90193)
			(xy 123.675648 -393.902438) (xy 123.675146 -393.929315) (xy 123.667134 -393.98247) (xy 123.65129 -394.033836)
			(xy 123.627966 -394.082268) (xy 123.597685 -394.126682) (xy 123.561123 -394.166087) (xy 123.519095 -394.199603)
			(xy 123.472542 -394.22648) (xy 123.422503 -394.246119) (xy 123.370096 -394.25808) (xy 123.316492 -394.262098)
			(xy 123.262888 -394.25808) (xy 123.210481 -394.246119) (xy 123.160442 -394.22648) (xy 123.113889 -394.199603)
			(xy 123.071861 -394.166087) (xy 123.035299 -394.126682) (xy 123.005018 -394.082268) (xy 122.981694 -394.033836)
			(xy 122.96585 -393.98247) (xy 122.957838 -393.929315) (xy 122.957336 -393.902438) (xy 122.957336 -393.90193)
			(xy 122.957746 -393.877788) (xy 122.964251 -393.829943) (xy 122.977108 -393.7834) (xy 122.996084 -393.739)
			(xy 123.020838 -393.697543) (xy 123.035568 -393.67841) (xy 123.035822 -393.678156) (xy 123.041038 -393.670936)
			(xy 123.046637 -393.654042) (xy 123.046744 -393.645136) (xy 123.044712 -393.570714) (xy 123.037854 -393.55395)
			(xy 123.032012 -393.547346) (xy 123.01385 -393.526273) (xy 122.983194 -393.479853) (xy 122.959608 -393.429471)
			(xy 122.943593 -393.376197) (xy 122.935489 -393.321161) (xy 122.934984 -393.293346) (xy 122.934984 -392.428984)
			(xy 122.935483 -392.400913) (xy 122.943715 -392.345379) (xy 122.959999 -392.291651) (xy 122.983982 -392.240891)
			(xy 123.015148 -392.194194) (xy 123.052822 -392.152571) (xy 123.074176 -392.134344) (xy 123.082558 -392.127486)
			(xy 123.09221 -392.107674) (xy 123.092464 -392.098022) (xy 123.093226 -392.078972) (xy 123.093269 -392.074053)
			(xy 123.091725 -392.064338) (xy 123.090178 -392.059668) (xy 123.086876 -392.051032) (xy 123.080272 -392.043666)
			(xy 123.065162 -392.026284) (xy 123.03959 -391.987981) (xy 123.019805 -391.946393) (xy 123.006219 -391.902388)
			(xy 122.999116 -391.856884) (xy 122.998484 -391.833862) (xy 122.998484 -391.83056) (xy 122.998862 -391.808487)
			(xy 123.004982 -391.764767) (xy 123.010676 -391.743438) (xy 123.013978 -391.731754) (xy 123.011946 -391.720324)
			(xy 123.010698 -391.714568) (xy 123.005958 -391.703789) (xy 123.002548 -391.698988) (xy 122.953526 -391.634218)
			(xy 122.945971 -391.625157) (xy 122.924919 -391.614571) (xy 122.91314 -391.613898) (xy 122.601482 -391.613898)
			(xy 122.591413 -391.613471) (xy 122.572814 -391.605752) (xy 122.565414 -391.598912) (xy 122.413522 -391.44702)
			(xy 122.406686 -391.439618) (xy 122.398977 -391.42102) (xy 122.398536 -391.410952) (xy 122.398536 -389.806942)
			(xy 122.398287 -389.799528) (xy 122.394036 -389.785323) (xy 122.390154 -389.779002) (xy 122.38609 -389.772652)
			(xy 122.37466 -389.763254) (xy 122.367548 -389.760206) (xy 122.345082 -389.75024) (xy 122.303271 -389.724409)
			(xy 122.265934 -389.69245) (xy 122.233961 -389.655125) (xy 122.208115 -389.613324) (xy 122.18901 -389.568042)
			(xy 122.182636 -389.544306) (xy 122.182128 -389.542274) (xy 121.870978 -389.004048) (xy 121.868692 -389.001508)
			(xy 121.850948 -388.983452) (xy 121.820843 -388.942754) (xy 121.797571 -388.897799) (xy 121.78172 -388.849724)
			(xy 121.77369 -388.799743) (xy 121.773188 -388.774432) (xy 121.773442 -388.762748) (xy 121.773696 -388.75208)
			(xy 121.769886 -388.742428) (xy 121.767855 -388.737559) (xy 121.762091 -388.728726) (xy 121.758456 -388.724902)
			(xy 121.225818 -388.192264) (xy 121.218975 -388.184864) (xy 121.211251 -388.166266) (xy 121.210832 -388.156196)
			(xy 121.210832 -387.199632) (xy 121.210663 -387.193623) (xy 121.207837 -387.181942) (xy 121.205244 -387.176518)
			(xy 121.203405 -387.173044) (xy 121.198811 -387.166665) (xy 121.1961 -387.163818) (xy 120.946926 -386.914644)
			(xy 120.944076 -386.911936) (xy 120.9377 -386.90734) (xy 120.934226 -386.9055) (xy 120.928798 -386.90292)
			(xy 120.917119 -386.900103) (xy 120.911112 -386.899912) (xy 119.689626 -386.899912) (xy 119.684546 -386.900166)
			(xy 119.675176 -386.901491) (xy 119.658344 -386.910112) (xy 119.65178 -386.91693) (xy 119.600726 -386.979414)
			(xy 119.597205 -386.983872) (xy 119.592075 -386.994004) (xy 119.590566 -386.99948) (xy 119.588026 -387.010148)
			(xy 119.590312 -387.021578) (xy 119.593188 -387.037038) (xy 119.596237 -387.068338) (xy 119.596408 -387.084062)
			(xy 119.596027 -387.105871) (xy 119.590033 -387.149077) (xy 119.58447 -387.170168) (xy 119.583708 -387.173724)
			(xy 119.583708 -387.185662) (xy 119.583263 -387.200076) (xy 119.576113 -387.228004) (xy 119.56225 -387.253281)
			(xy 119.542544 -387.274323) (xy 119.530622 -387.282436) (xy 119.529606 -387.287008) (xy 119.528751 -387.292321)
			(xy 119.529002 -387.303079) (xy 119.530114 -387.308344) (xy 119.546878 -387.382258) (xy 119.548244 -387.38747)
			(xy 119.552851 -387.397207) (xy 119.556022 -387.401562) (xy 119.562372 -387.409944) (xy 119.572024 -387.415278)
			(xy 119.596173 -387.429242) (xy 119.639602 -387.464248) (xy 119.658384 -387.484874) (xy 119.660865 -387.487628)
			(xy 119.666471 -387.492478) (xy 119.66956 -387.494526) (xy 119.681697 -387.502615) (xy 119.701772 -387.523763)
			(xy 119.715921 -387.549259) (xy 119.723246 -387.577483) (xy 119.723662 -387.592062) (xy 119.723662 -387.604508)
			(xy 119.72544 -387.610858) (xy 119.730552 -387.631176) (xy 119.736026 -387.672714) (xy 119.736362 -387.693662)
			(xy 119.736362 -387.69798) (xy 119.736091 -387.709591) (xy 119.734054 -387.732728) (xy 119.732298 -387.744208)
			(xy 119.730781 -387.753255) (xy 119.726842 -387.771173) (xy 119.724424 -387.780022) (xy 119.723662 -387.78307)
			(xy 119.723662 -388.239254) (xy 119.724424 -388.242302) (xy 119.729546 -388.26154) (xy 119.735531 -388.300898)
			(xy 119.736362 -388.320788) (xy 119.736362 -388.328662) (xy 120.300496 -388.328662) (xy 120.300863 -388.307641)
			(xy 120.306473 -388.265975) (xy 120.311672 -388.245604) (xy 120.313196 -388.239) (xy 120.313196 -388.125462)
			(xy 120.313699 -388.110469) (xy 120.321455 -388.081502) (xy 120.336432 -388.055523) (xy 120.357611 -388.034294)
			(xy 120.383555 -388.019258) (xy 120.412504 -388.011434) (xy 120.427496 -388.010908) (xy 120.609614 -388.010908)
			(xy 120.610122 -388.010654) (xy 120.626886 -388.010654) (xy 120.627394 -388.010908) (xy 120.809004 -388.010908)
			(xy 120.824035 -388.011377) (xy 120.853074 -388.019148) (xy 120.879118 -388.034161) (xy 120.900396 -388.055396)
			(xy 120.915462 -388.081409) (xy 120.923293 -388.110432) (xy 120.923812 -388.125462) (xy 120.923812 -388.239)
			(xy 120.925336 -388.245604) (xy 120.930528 -388.265976) (xy 120.936138 -388.307642) (xy 120.936512 -388.328662)
			(xy 120.936512 -388.32917) (xy 120.936341 -388.343795) (xy 120.933675 -388.372924) (xy 120.931178 -388.387336)
			(xy 120.929818 -388.39651) (xy 120.933089 -388.414752) (xy 120.937528 -388.422896) (xy 120.954038 -388.44982)
			(xy 120.95921 -388.457597) (xy 120.973934 -388.46906) (xy 120.98274 -388.472172) (xy 121.007628 -388.480216)
			(xy 121.054507 -388.503411) (xy 121.096918 -388.534019) (xy 121.1337 -388.571203) (xy 121.163846 -388.613944)
			(xy 121.186529 -388.661072) (xy 121.194322 -388.68604) (xy 121.195846 -388.691882) (xy 121.51614 -389.245602)
			(xy 121.520204 -389.24992) (xy 121.536396 -389.267638) (xy 121.563822 -389.307026) (xy 121.584967 -389.350113)
			(xy 121.599343 -389.395905) (xy 121.60662 -389.443346) (xy 121.607072 -389.467344) (xy 121.606605 -389.492807)
			(xy 121.598405 -389.54307) (xy 121.582241 -389.591364) (xy 121.558532 -389.636436) (xy 121.527893 -389.677117)
			(xy 121.491121 -389.71235) (xy 121.47042 -389.727186) (xy 121.461912 -389.733627) (xy 121.450717 -389.751768)
			(xy 121.447846 -389.772892) (xy 121.453794 -389.793363) (xy 121.467537 -389.80966) (xy 121.48671 -389.818978)
			(xy 121.497344 -389.819896) (xy 121.50725 -389.819388) (xy 121.5157 -389.818098) (xy 121.532739 -389.816701)
			(xy 121.541286 -389.816594) (xy 121.54154 -389.816848) (xy 121.840752 -389.816848) (xy 121.841006 -389.816594)
			(xy 121.862051 -389.817028) (xy 121.90337 -389.825018) (xy 121.942325 -389.840944) (xy 121.977408 -389.864189)
			(xy 122.007259 -389.893854) (xy 122.030724 -389.92879) (xy 122.046895 -389.967644) (xy 122.055144 -390.008912)
			(xy 122.055636 -390.029954) (xy 122.055636 -390.284716) (xy 122.046492 -390.284716) (xy 122.036468 -390.285113)
			(xy 122.017948 -390.292789) (xy 122.003776 -390.306968) (xy 121.996109 -390.325492) (xy 121.995692 -390.335516)
			(xy 121.995692 -390.499092) (xy 121.995274 -390.509114) (xy 121.987605 -390.527632) (xy 121.973432 -390.541805)
			(xy 121.954914 -390.549474) (xy 121.944892 -390.549892) (xy 121.4374 -390.549892) (xy 121.427378 -390.54948)
			(xy 121.408859 -390.541809) (xy 121.394687 -390.527634) (xy 121.387018 -390.509114) (xy 121.3866 -390.499092)
			(xy 121.3866 -390.335516) (xy 121.386168 -390.325496) (xy 121.378503 -390.306979) (xy 121.364334 -390.292806)
			(xy 121.34582 -390.285136) (xy 121.3358 -390.284716) (xy 121.326656 -390.284716) (xy 121.326656 -390.029446)
			(xy 121.327436 -390.003723) (xy 121.339772 -389.953777) (xy 121.35104 -389.93064) (xy 121.356882 -389.91921)
			(xy 121.356628 -389.89381) (xy 121.30913 -389.808212) (xy 121.302427 -389.797418) (xy 121.28109 -389.783687)
			(xy 121.26849 -389.78205) (xy 121.244614 -389.779891) (xy 121.197869 -389.769257) (xy 121.153272 -389.75167)
			(xy 121.111851 -389.727537) (xy 121.074559 -389.697412) (xy 121.042257 -389.66199) (xy 121.015687 -389.622088)
			(xy 120.995463 -389.578623) (xy 120.988328 -389.555736) (xy 120.986804 -389.549894) (xy 120.66651 -388.996174)
			(xy 120.662446 -388.991856) (xy 120.646285 -388.974123) (xy 120.618918 -388.934721) (xy 120.597827 -388.891631)
			(xy 120.5835 -388.845845) (xy 120.576266 -388.798419) (xy 120.575832 -388.774432) (xy 120.576014 -388.760384)
			(xy 120.578554 -388.732402) (xy 120.580912 -388.718552) (xy 120.582233 -388.709272) (xy 120.578706 -388.690876)
			(xy 120.574054 -388.682738) (xy 120.55729 -388.655814) (xy 120.552097 -388.648103) (xy 120.537365 -388.636784)
			(xy 120.528588 -388.633716) (xy 120.506967 -388.626901) (xy 120.465752 -388.608024) (xy 120.42763 -388.583493)
			(xy 120.393373 -388.553804) (xy 120.37822 -388.536942) (xy 120.375758 -388.534169) (xy 120.370145 -388.529323)
			(xy 120.367044 -388.52729) (xy 120.354981 -388.519231) (xy 120.335024 -388.498188) (xy 120.32095 -388.47283)
			(xy 120.313649 -388.444762) (xy 120.313196 -388.430262) (xy 120.313196 -388.418324) (xy 120.311672 -388.41172)
			(xy 120.306466 -388.391351) (xy 120.300865 -388.349683) (xy 120.300496 -388.328662) (xy 119.736362 -388.328662)
			(xy 119.736362 -388.33298) (xy 119.736108 -388.343648) (xy 119.736108 -388.344156) (xy 119.735483 -388.354503)
			(xy 119.733065 -388.375093) (xy 119.731282 -388.385304) (xy 119.73052 -388.39394) (xy 119.730682 -388.401024)
			(xy 119.734415 -388.414687) (xy 119.737886 -388.420864) (xy 119.74957 -388.43966) (xy 119.752044 -388.443615)
			(xy 119.758184 -388.450637) (xy 119.761762 -388.45363) (xy 119.782844 -388.469632) (xy 119.788432 -388.47141)
			(xy 119.813586 -388.48007) (xy 119.860809 -388.504561) (xy 119.903303 -388.536562) (xy 119.939886 -388.575182)
			(xy 119.96954 -388.619346) (xy 119.991439 -388.667825) (xy 119.998744 -388.693406) (xy 120.003824 -388.705852)
			(xy 120.31599 -389.245602) (xy 120.320054 -389.24992) (xy 120.336214 -389.267588) (xy 120.363551 -389.306897)
			(xy 120.38463 -389.349887) (xy 120.398966 -389.395571) (xy 120.40623 -389.442896) (xy 120.406668 -389.466836)
			(xy 120.406668 -389.467344) (xy 120.406188 -389.492796) (xy 120.398028 -389.543042) (xy 120.381912 -389.591328)
			(xy 120.358257 -389.636402) (xy 120.327676 -389.677097) (xy 120.290961 -389.712357) (xy 120.27027 -389.727186)
			(xy 120.261781 -389.733674) (xy 120.250599 -389.75185) (xy 120.247765 -389.773001) (xy 120.253769 -389.793479)
			(xy 120.267574 -389.809752) (xy 120.2868 -389.819013) (xy 120.297448 -389.819896) (xy 120.3071 -389.819388)
			(xy 120.315611 -389.818072) (xy 120.332778 -389.816669) (xy 120.34139 -389.816594) (xy 120.341644 -389.816848)
			(xy 120.640856 -389.816848) (xy 120.64111 -389.816594) (xy 120.662158 -389.816955) (xy 120.703484 -389.824949)
			(xy 120.742443 -389.840883) (xy 120.777526 -389.864138) (xy 120.807376 -389.893815) (xy 120.830834 -389.928764)
			(xy 120.846993 -389.96763) (xy 120.855227 -390.008908) (xy 120.85574 -390.029954) (xy 120.85574 -390.233916)
			(xy 120.85525 -390.243924) (xy 120.847589 -390.262418) (xy 120.833438 -390.276575) (xy 120.814948 -390.284245)
			(xy 120.80494 -390.284716) (xy 120.795796 -390.284716) (xy 120.795796 -390.499092) (xy 120.795378 -390.509114)
			(xy 120.787709 -390.527633) (xy 120.773536 -390.541807) (xy 120.755018 -390.549477) (xy 120.744996 -390.549892)
			(xy 120.237504 -390.549892) (xy 120.227483 -390.549473) (xy 120.208966 -390.541804) (xy 120.194794 -390.527631)
			(xy 120.187126 -390.509113) (xy 120.186704 -390.499092) (xy 120.186704 -390.335516) (xy 120.186287 -390.325492)
			(xy 120.17862 -390.306969) (xy 120.164448 -390.292791) (xy 120.145928 -390.285117) (xy 120.135904 -390.284716)
			(xy 120.12676 -390.284716) (xy 120.12676 -390.029446) (xy 120.127556 -390.003725) (xy 120.139881 -389.953778)
			(xy 120.151144 -389.93064) (xy 120.156986 -389.91921) (xy 120.156732 -389.89381) (xy 120.109234 -389.808212)
			(xy 120.102525 -389.797424) (xy 120.081192 -389.783693) (xy 120.068594 -389.78205) (xy 120.044708 -389.779882)
			(xy 119.997943 -389.769243) (xy 119.953324 -389.751655) (xy 119.911877 -389.727525) (xy 119.874554 -389.697406)
			(xy 119.842213 -389.661991) (xy 119.815597 -389.622094) (xy 119.79532 -389.578632) (xy 119.788178 -389.555736)
			(xy 119.786654 -389.549894) (xy 119.471694 -389.005064) (xy 119.47017 -389.003794) (xy 119.455692 -389.001508)
			(xy 119.448372 -389.000647) (xy 119.433787 -389.00272) (xy 119.42699 -389.005572) (xy 119.342662 -389.043672)
			(xy 119.33682 -389.046974) (xy 119.329717 -389.051785) (xy 119.318984 -389.065154) (xy 119.313295 -389.081328)
			(xy 119.312944 -389.0899) (xy 119.312944 -389.778748) (xy 119.313457 -389.789583) (xy 119.322406 -389.80932)
			(xy 119.330216 -389.816848) (xy 119.44096 -389.816848) (xy 119.441214 -389.816594) (xy 119.462262 -389.816955)
			(xy 119.503587 -389.82495) (xy 119.542545 -389.840884) (xy 119.577628 -389.86414) (xy 119.607477 -389.893817)
			(xy 119.630935 -389.928765) (xy 119.647094 -389.967631) (xy 119.655327 -390.008908) (xy 119.655844 -390.029954)
			(xy 119.655844 -390.284716) (xy 119.653304 -390.284716) (xy 119.628412 -390.344406) (xy 119.629428 -390.346438)
			(xy 119.631305 -390.34983) (xy 119.635902 -390.356072) (xy 119.638572 -390.358884) (xy 119.922036 -390.642348)
			(xy 119.928882 -390.649746) (xy 119.936609 -390.668345) (xy 119.937022 -390.678416) (xy 119.937022 -391.580878)
			(xy 119.937071 -391.584749) (xy 119.938222 -391.592403) (xy 119.939308 -391.596118) (xy 119.941135 -391.601444)
			(xy 119.946769 -391.611191) (xy 119.950484 -391.615422) (xy 119.967929 -391.635124) (xy 119.996715 -391.679173)
			(xy 120.017856 -391.727359) (xy 120.030776 -391.778369) (xy 120.035121 -391.83081) (xy 120.030772 -391.883251)
			(xy 120.01785 -391.93426) (xy 119.996705 -391.982446) (xy 119.967916 -392.026492) (xy 119.950484 -392.046206)
			(xy 119.94388 -392.053572) (xy 119.940578 -392.062208) (xy 119.938956 -392.066672) (xy 119.937174 -392.076002)
			(xy 119.937022 -392.08075) (xy 119.937022 -392.104118) (xy 119.946928 -392.124692) (xy 119.956072 -392.132058)
			(xy 119.977871 -392.150275) (xy 120.016353 -392.192065) (xy 120.048211 -392.239101) (xy 120.072741 -392.290341)
			(xy 120.089401 -392.344652) (xy 120.09782 -392.400833) (xy 120.098312 -392.429238) (xy 120.098312 -393.292838)
			(xy 120.534684 -393.292838) (xy 120.534684 -392.429238) (xy 120.535096 -392.403717) (xy 120.541887 -392.35313)
			(xy 120.555365 -392.303901) (xy 120.575291 -392.25691) (xy 120.601307 -392.212997) (xy 120.632949 -392.172947)
			(xy 120.651016 -392.154918) (xy 120.65762 -392.148568) (xy 120.665494 -392.131804) (xy 120.672352 -392.04646)
			(xy 120.667272 -392.02868) (xy 120.661684 -392.021314) (xy 120.646828 -392.00057) (xy 120.623195 -391.955354)
			(xy 120.607096 -391.906942) (xy 120.598944 -391.856578) (xy 120.598438 -391.831068) (xy 120.598438 -391.830814)
			(xy 120.598928 -391.805825) (xy 120.606747 -391.756462) (xy 120.622191 -391.70893) (xy 120.644881 -391.664398)
			(xy 120.674257 -391.623965) (xy 120.709597 -391.588625) (xy 120.75003 -391.559249) (xy 120.794562 -391.536559)
			(xy 120.842094 -391.521115) (xy 120.891457 -391.513296) (xy 120.941435 -391.513296) (xy 120.990798 -391.521115)
			(xy 121.03833 -391.536559) (xy 121.082862 -391.559249) (xy 121.123295 -391.588625) (xy 121.158635 -391.623965)
			(xy 121.188011 -391.664398) (xy 121.210701 -391.70893) (xy 121.226145 -391.756462) (xy 121.233964 -391.805825)
			(xy 121.234454 -391.830814) (xy 121.234454 -391.831068) (xy 121.23395 -391.856577) (xy 121.225775 -391.906935)
			(xy 121.209675 -391.955346) (xy 121.186064 -392.000571) (xy 121.171208 -392.021314) (xy 121.16562 -392.02868)
			(xy 121.16054 -392.04646) (xy 121.167398 -392.131804) (xy 121.175272 -392.148568) (xy 121.181876 -392.154918)
			(xy 121.199914 -392.172973) (xy 121.231544 -392.213025) (xy 121.257554 -392.256936) (xy 121.277481 -392.30392)
			(xy 121.290969 -392.353141) (xy 121.297778 -392.40372) (xy 121.298208 -392.429238) (xy 121.298208 -393.292838)
			(xy 121.298198 -393.293346) (xy 121.735088 -393.293346) (xy 121.735088 -392.42873) (xy 121.735532 -392.403262)
			(xy 121.742334 -392.352783) (xy 121.755794 -392.303658) (xy 121.775674 -392.256762) (xy 121.801618 -392.212929)
			(xy 121.833166 -392.172939) (xy 121.851166 -392.154918) (xy 121.85777 -392.148568) (xy 121.865644 -392.131804)
			(xy 121.872502 -392.04646) (xy 121.867422 -392.02868) (xy 121.861834 -392.021314) (xy 121.846984 -392.000566)
			(xy 121.823348 -391.955352) (xy 121.807247 -391.906941) (xy 121.799094 -391.856577) (xy 121.798588 -391.831068)
			(xy 121.798588 -391.830814) (xy 121.799078 -391.805825) (xy 121.806897 -391.756462) (xy 121.822341 -391.70893)
			(xy 121.845031 -391.664398) (xy 121.874407 -391.623965) (xy 121.909747 -391.588625) (xy 121.95018 -391.559249)
			(xy 121.994712 -391.536559) (xy 122.042244 -391.521115) (xy 122.091607 -391.513296) (xy 122.141585 -391.513296)
			(xy 122.190948 -391.521115) (xy 122.23848 -391.536559) (xy 122.283012 -391.559249) (xy 122.323445 -391.588625)
			(xy 122.358785 -391.623965) (xy 122.388161 -391.664398) (xy 122.410851 -391.70893) (xy 122.426295 -391.756462)
			(xy 122.434114 -391.805825) (xy 122.434604 -391.830814) (xy 122.434604 -391.831068) (xy 122.43411 -391.856577)
			(xy 122.425933 -391.906936) (xy 122.409831 -391.955348) (xy 122.386216 -392.000572) (xy 122.371358 -392.021314)
			(xy 122.36577 -392.02868) (xy 122.36069 -392.04646) (xy 122.367548 -392.131804) (xy 122.375422 -392.148568)
			(xy 122.382026 -392.154918) (xy 122.40002 -392.172945) (xy 122.431563 -392.212937) (xy 122.457505 -392.25677)
			(xy 122.477386 -392.303664) (xy 122.490852 -392.352786) (xy 122.497663 -392.403263) (xy 122.498104 -392.42873)
			(xy 122.498104 -393.293346) (xy 122.497614 -393.321743) (xy 122.489202 -393.377911) (xy 122.472542 -393.432206)
			(xy 122.448004 -393.483425) (xy 122.416131 -393.530432) (xy 122.397266 -393.551664) (xy 122.3914 -393.558596)
			(xy 122.384497 -393.575377) (xy 122.383804 -393.58443) (xy 122.382788 -393.615418) (xy 122.382845 -393.624569)
			(xy 122.388712 -393.64189) (xy 122.394218 -393.6492) (xy 122.409555 -393.668553) (xy 122.435331 -393.710671)
			(xy 122.455111 -393.755916) (xy 122.468525 -393.803439) (xy 122.47532 -393.852349) (xy 122.475752 -393.877038)
			(xy 122.47525 -393.903915) (xy 122.467238 -393.95707) (xy 122.451394 -394.008436) (xy 122.42807 -394.056868)
			(xy 122.397789 -394.101282) (xy 122.361227 -394.140687) (xy 122.319199 -394.174203) (xy 122.272646 -394.20108)
			(xy 122.222607 -394.220719) (xy 122.1702 -394.23268) (xy 122.116596 -394.236698) (xy 122.062992 -394.23268)
			(xy 122.010585 -394.220719) (xy 121.960546 -394.20108) (xy 121.913993 -394.174203) (xy 121.871965 -394.140687)
			(xy 121.835403 -394.101282) (xy 121.805122 -394.056868) (xy 121.781798 -394.008436) (xy 121.765954 -393.95707)
			(xy 121.757942 -393.903915) (xy 121.75744 -393.877038) (xy 121.757852 -393.852345) (xy 121.764608 -393.803423)
			(xy 121.77801 -393.75589) (xy 121.797805 -393.710645) (xy 121.823619 -393.668543) (xy 121.838974 -393.6492)
			(xy 121.844459 -393.641882) (xy 121.850302 -393.624564) (xy 121.850404 -393.615418) (xy 121.849388 -393.58443)
			(xy 121.848736 -393.575367) (xy 121.841825 -393.558576) (xy 121.835926 -393.551664) (xy 121.817117 -393.530392)
			(xy 121.785294 -393.483369) (xy 121.760776 -393.432156) (xy 121.744102 -393.37788) (xy 121.735639 -393.321735)
			(xy 121.735088 -393.293346) (xy 121.298198 -393.293346) (xy 121.29766 -393.322002) (xy 121.288738 -393.379645)
			(xy 121.271152 -393.43526) (xy 121.245313 -393.487554) (xy 121.211821 -393.535309) (xy 121.192036 -393.556744)
			(xy 121.185872 -393.563822) (xy 121.178719 -393.581161) (xy 121.178066 -393.590526) (xy 121.176288 -393.659106)
			(xy 121.176435 -393.668362) (xy 121.182566 -393.685815) (xy 121.188226 -393.693142) (xy 121.188734 -393.69365)
			(xy 121.205088 -393.713263) (xy 121.232621 -393.756272) (xy 121.253778 -393.80275) (xy 121.268132 -393.851757)
			(xy 121.275395 -393.902305) (xy 121.275856 -393.927838) (xy 121.275354 -393.954734) (xy 121.267336 -394.007926)
			(xy 121.25148 -394.059329) (xy 121.228141 -394.107795) (xy 121.197838 -394.152241) (xy 121.16125 -394.191674)
			(xy 121.119193 -394.225213) (xy 121.072607 -394.252109) (xy 121.022533 -394.271762) (xy 120.970088 -394.283732)
			(xy 120.916446 -394.287752) (xy 120.862804 -394.283732) (xy 120.810359 -394.271762) (xy 120.760285 -394.252109)
			(xy 120.713699 -394.225213) (xy 120.671642 -394.191674) (xy 120.635054 -394.152241) (xy 120.604751 -394.107795)
			(xy 120.581412 -394.059329) (xy 120.565556 -394.007926) (xy 120.557538 -393.954734) (xy 120.557036 -393.927838)
			(xy 120.557516 -393.90227) (xy 120.564792 -393.851655) (xy 120.579187 -393.802588) (xy 120.600409 -393.756065)
			(xy 120.628028 -393.71303) (xy 120.644412 -393.693396) (xy 120.644666 -393.693142) (xy 120.650329 -393.685821)
			(xy 120.656441 -393.668362) (xy 120.656604 -393.659106) (xy 120.654572 -393.580874) (xy 120.64746 -393.563856)
			(xy 120.640856 -393.556744) (xy 120.62108 -393.535303) (xy 120.587585 -393.487551) (xy 120.561747 -393.435259)
			(xy 120.544167 -393.379644) (xy 120.535255 -393.322001) (xy 120.534684 -393.292838) (xy 120.098312 -393.292838)
			(xy 120.097757 -393.32199) (xy 120.088885 -393.379616) (xy 120.071352 -393.435222) (xy 120.045567 -393.487515)
			(xy 120.012128 -393.535279) (xy 119.992394 -393.556744) (xy 119.98579 -393.563348) (xy 119.978424 -393.580874)
			(xy 119.976138 -393.66825) (xy 119.982488 -393.68603) (xy 119.988838 -393.693142) (xy 120.005189 -393.712791)
			(xy 120.032746 -393.755843) (xy 120.053917 -393.802369) (xy 120.068274 -393.851427) (xy 120.075527 -393.902026)
			(xy 120.07596 -393.927584) (xy 120.07596 -393.927838) (xy 120.075575 -393.951358) (xy 120.0694 -393.997992)
			(xy 120.057186 -394.04342) (xy 120.039143 -394.086863) (xy 120.0277 -394.107416) (xy 120.025668 -394.111226)
			(xy 120.018556 -394.137134) (xy 120.019128 -394.147057) (xy 120.02684 -394.165354) (xy 120.033542 -394.172694)
			(xy 120.30837 -394.447522) (xy 120.315726 -394.454173) (xy 120.334026 -394.461761) (xy 120.34393 -394.462254)
			(xy 126.897892 -394.462254)
		)
		(stroke
			(width 0)
			(type solid)
		)
		(fill yes)
		(layer "B.Cu")
		(net "P0V9_CPU1_RT_2D")
	)
	(gr_poly
		(pts
			(xy 159.435292 -394.461238) (xy 159.442533 -394.459604) (xy 159.455692 -394.452753) (xy 159.4612 -394.447776)
			(xy 159.539432 -394.369544) (xy 159.545855 -394.362542) (xy 159.553454 -394.34514) (xy 159.554225 -394.326168)
			(xy 159.548064 -394.308207) (xy 159.542226 -394.30071) (xy 159.538924 -394.297408) (xy 159.534639 -394.293385)
			(xy 159.524636 -394.287222) (xy 159.519112 -394.285216) (xy 159.508444 -394.28166) (xy 159.502348 -394.282676)
			(xy 159.496252 -394.283438) (xy 159.483371 -394.285205) (xy 159.457437 -394.287113) (xy 159.444436 -394.287248)
			(xy 159.426148 -394.287248) (xy 159.420052 -394.286994) (xy 159.40659 -394.285216) (xy 159.406082 -394.285216)
			(xy 159.379658 -394.281869) (xy 159.328131 -394.268387) (xy 159.279156 -394.247453) (xy 159.256222 -394.233908)
			(xy 159.231757 -394.218209) (xy 159.187785 -394.180192) (xy 159.150502 -394.135596) (xy 159.120882 -394.085581)
			(xy 159.099695 -394.031453) (xy 159.087493 -393.97462) (xy 159.085534 -393.945618) (xy 159.08528 -393.936982)
			(xy 159.085026 -393.928346) (xy 159.085026 -393.92733) (xy 159.085609 -393.898831) (xy 159.09468 -393.842558)
			(xy 159.11252 -393.788422) (xy 159.138683 -393.737781) (xy 159.172511 -393.691905) (xy 159.192468 -393.671552)
			(xy 159.199834 -393.66444) (xy 159.203644 -393.655804) (xy 159.205579 -393.651142) (xy 159.207755 -393.641289)
			(xy 159.207962 -393.636246) (xy 159.208216 -393.616942) (xy 159.207862 -393.605996) (xy 159.199042 -393.585976)
			(xy 159.191198 -393.578334) (xy 159.171392 -393.560143) (xy 159.136578 -393.519154) (xy 159.107864 -393.473684)
			(xy 159.085818 -393.424633) (xy 159.070876 -393.372973) (xy 159.063335 -393.319727) (xy 159.062928 -393.292838)
			(xy 159.062928 -392.428984) (xy 159.063428 -392.400914) (xy 159.07166 -392.34538) (xy 159.087945 -392.291654)
			(xy 159.111931 -392.240895) (xy 159.143099 -392.194202) (xy 159.180775 -392.152582) (xy 159.20212 -392.134344)
			(xy 159.210756 -392.127486) (xy 159.220408 -392.107928) (xy 159.220662 -392.096752) (xy 159.22117 -392.079226)
			(xy 159.221157 -392.074357) (xy 159.219494 -392.064765) (xy 159.217868 -392.060176) (xy 159.21482 -392.05154)
			(xy 159.207962 -392.04392) (xy 159.192648 -392.026311) (xy 159.166809 -391.98745) (xy 159.146923 -391.945233)
			(xy 159.133415 -391.900564) (xy 159.126576 -391.854401) (xy 159.126174 -391.831068) (xy 159.126174 -391.830814)
			(xy 159.126663 -391.805824) (xy 159.13448 -391.756458) (xy 159.149922 -391.708923) (xy 159.172611 -391.664388)
			(xy 159.201987 -391.623951) (xy 159.237327 -391.588608) (xy 159.277761 -391.559228) (xy 159.322293 -391.536535)
			(xy 159.369827 -391.521087) (xy 159.419192 -391.513266) (xy 159.444182 -391.512806) (xy 159.472796 -391.513406)
			(xy 159.5291 -391.523646) (xy 159.582656 -391.543816) (xy 159.607504 -391.558018) (xy 159.607758 -391.558018)
			(xy 159.613589 -391.561325) (xy 159.626462 -391.56505) (xy 159.633158 -391.565384) (xy 159.64662 -391.565384)
			(xy 159.73552 -391.515092) (xy 159.744156 -391.508996) (xy 159.751574 -391.501816) (xy 159.760472 -391.483208)
			(xy 159.761428 -391.472928) (xy 159.761428 -389.907018) (xy 159.761867 -389.896955) (xy 159.769605 -389.878375)
			(xy 159.776414 -389.87095) (xy 159.78251 -389.864854) (xy 159.788938 -389.857853) (xy 159.796543 -389.84045)
			(xy 159.797317 -389.821473) (xy 159.791155 -389.803509) (xy 159.785304 -389.79602) (xy 159.782256 -389.792972)
			(xy 159.779581 -389.790361) (xy 159.773589 -389.785892) (xy 159.770318 -389.784082) (xy 159.764222 -389.78078)
			(xy 159.756602 -389.779256) (xy 159.731534 -389.773706) (xy 159.683483 -389.755622) (xy 159.638957 -389.730063)
			(xy 159.599107 -389.697691) (xy 159.564967 -389.659346) (xy 159.537422 -389.61602) (xy 159.517184 -389.568836)
			(xy 159.510476 -389.544052) (xy 159.509968 -389.542274) (xy 159.194246 -388.996174) (xy 159.190182 -388.991856)
			(xy 159.173994 -388.974146) (xy 159.14662 -388.934743) (xy 159.125532 -388.891648) (xy 159.111216 -388.845855)
			(xy 159.104003 -388.798422) (xy 159.103568 -388.774432) (xy 159.103743 -388.760383) (xy 159.106283 -388.732401)
			(xy 159.108648 -388.718552) (xy 159.10986 -388.709275) (xy 159.106334 -388.690917) (xy 159.10179 -388.682738)
			(xy 159.085026 -388.655814) (xy 159.079821 -388.648111) (xy 159.065102 -388.636779) (xy 159.056324 -388.633716)
			(xy 159.034692 -388.626927) (xy 158.993462 -388.608067) (xy 158.955335 -388.583535) (xy 158.921084 -388.553829)
			(xy 158.905956 -388.536942) (xy 158.903474 -388.53419) (xy 158.897865 -388.529344) (xy 158.89478 -388.52729)
			(xy 158.88272 -388.519231) (xy 158.862773 -388.498183) (xy 158.848707 -388.472825) (xy 158.84141 -388.44476)
			(xy 158.840932 -388.430262) (xy 158.840932 -388.418324) (xy 158.839408 -388.41172) (xy 158.834213 -388.391349)
			(xy 158.828612 -388.349682) (xy 158.828232 -388.328662) (xy 158.828606 -388.307642) (xy 158.834217 -388.265977)
			(xy 158.839408 -388.245604) (xy 158.840932 -388.239) (xy 158.840932 -388.125462) (xy 158.841424 -388.110469)
			(xy 158.849181 -388.081503) (xy 158.86416 -388.055526) (xy 158.885343 -388.034301) (xy 158.91129 -388.01927)
			(xy 158.94024 -388.011454) (xy 158.955232 -388.010908) (xy 159.13735 -388.010908) (xy 159.137858 -388.010654)
			(xy 159.154622 -388.010654) (xy 159.15513 -388.010908) (xy 159.33166 -388.010908) (xy 159.341687 -388.010495)
			(xy 159.360219 -388.002833) (xy 159.374406 -387.98866) (xy 159.382086 -387.970135) (xy 159.38246 -387.960108)
			(xy 159.38246 -386.973572) (xy 159.38203 -386.963505) (xy 159.374304 -386.944912) (xy 159.367474 -386.937504)
			(xy 159.326326 -386.896356) (xy 159.318926 -386.889515) (xy 159.300327 -386.881799) (xy 159.290258 -386.88137)
			(xy 158.667958 -386.88137) (xy 158.661948 -386.881536) (xy 158.650264 -386.884357) (xy 158.644844 -386.886958)
			(xy 158.641373 -386.888801) (xy 158.635001 -386.893402) (xy 158.632144 -386.896102) (xy 158.358586 -387.16966)
			(xy 158.35588 -387.172511) (xy 158.351287 -387.178889) (xy 158.349442 -387.18236) (xy 158.346859 -387.187787)
			(xy 158.344037 -387.199466) (xy 158.343854 -387.205474) (xy 158.343854 -388.450328) (xy 158.344076 -388.457136)
			(xy 158.347687 -388.470265) (xy 158.350966 -388.476236) (xy 158.354268 -388.481824) (xy 158.364174 -388.491222)
			(xy 158.370524 -388.494778) (xy 158.393109 -388.507634) (xy 158.43414 -388.539523) (xy 158.469456 -388.577644)
			(xy 158.498122 -388.620988) (xy 158.519379 -388.668408) (xy 158.52648 -388.693406) (xy 158.53156 -388.705852)
			(xy 158.843726 -389.245602) (xy 158.84779 -389.24992) (xy 158.863949 -389.267589) (xy 158.891282 -389.306899)
			(xy 158.912359 -389.349889) (xy 158.926693 -389.395572) (xy 158.933957 -389.442897) (xy 158.934404 -389.466836)
			(xy 158.934404 -389.467344) (xy 158.933915 -389.492132) (xy 158.926154 -389.541098) (xy 158.910829 -389.588247)
			(xy 158.888319 -389.632419) (xy 158.859177 -389.672526) (xy 158.82412 -389.707582) (xy 158.784012 -389.736723)
			(xy 158.73984 -389.759232) (xy 158.69269 -389.774556) (xy 158.643724 -389.782315) (xy 158.618936 -389.782812)
			(xy 158.593541 -389.782307) (xy 158.543404 -389.774181) (xy 158.495215 -389.758134) (xy 158.450217 -389.734578)
			(xy 158.40957 -389.704122) (xy 158.374324 -389.667552) (xy 158.345387 -389.625811) (xy 158.323506 -389.579975)
			(xy 158.315914 -389.555736) (xy 158.31439 -389.549894) (xy 158.109666 -389.195564) (xy 158.103269 -389.185653)
			(xy 158.083675 -389.172568) (xy 158.072074 -389.170418) (xy 158.06039 -389.168894) (xy 158.038292 -389.176514)
			(xy 157.750256 -389.46455) (xy 157.747256 -389.46764) (xy 157.742279 -389.474669) (xy 157.74035 -389.47852)
			(xy 157.73654 -389.486648) (xy 157.735778 -389.495792) (xy 157.732898 -389.522017) (xy 157.719568 -389.573061)
			(xy 157.697997 -389.621205) (xy 157.668779 -389.66513) (xy 157.632713 -389.703632) (xy 157.61208 -389.720074)
			(xy 157.611826 -389.720328) (xy 157.607284 -389.723987) (xy 157.59984 -389.732963) (xy 157.597094 -389.738108)
			(xy 157.592268 -389.748014) (xy 157.592268 -389.75538) (xy 157.600904 -389.774938) (xy 157.631892 -389.803386)
			(xy 157.639226 -389.809547) (xy 157.657116 -389.816346) (xy 157.66669 -389.816594) (xy 157.66923 -389.816594)
			(xy 157.669484 -389.816848) (xy 157.968696 -389.816848) (xy 157.96895 -389.816594) (xy 157.985999 -389.816824)
			(xy 158.019691 -389.822054) (xy 158.036006 -389.827008) (xy 158.043626 -389.829548) (xy 158.07309 -389.829548)
			(xy 158.086448 -389.829943) (xy 158.112254 -389.836856) (xy 158.135391 -389.850212) (xy 158.154283 -389.869102)
			(xy 158.167641 -389.892239) (xy 158.174556 -389.918044) (xy 158.174944 -389.931402) (xy 158.174944 -389.969248)
			(xy 158.176722 -389.975598) (xy 158.179957 -389.988953) (xy 158.183398 -390.016214) (xy 158.18358 -390.029954)
			(xy 158.18358 -390.284716) (xy 158.174944 -390.284716) (xy 158.174944 -390.388856) (xy 158.174465 -390.403173)
			(xy 158.166531 -390.430685) (xy 158.151274 -390.454915) (xy 158.140908 -390.464802) (xy 158.13278 -390.471914)
			(xy 158.123636 -390.491726) (xy 158.123636 -390.499092) (xy 158.12315 -390.509103) (xy 158.115493 -390.527604)
			(xy 158.101341 -390.541768) (xy 158.082847 -390.549441) (xy 158.072836 -390.549892) (xy 157.643068 -390.549892)
			(xy 157.633064 -390.550386) (xy 157.614582 -390.558051) (xy 157.600437 -390.572202) (xy 157.592781 -390.590688)
			(xy 157.592268 -390.600692) (xy 157.592268 -390.642602) (xy 158.637732 -390.642602) (xy 158.637732 -390.160002)
			(xy 158.638218 -390.132769) (xy 158.645969 -390.078857) (xy 158.661314 -390.026597) (xy 158.68394 -389.977053)
			(xy 158.713387 -389.931233) (xy 158.749054 -389.89007) (xy 158.790217 -389.854403) (xy 158.836037 -389.824956)
			(xy 158.885581 -389.80233) (xy 158.937841 -389.786985) (xy 158.991753 -389.779234) (xy 159.046219 -389.779234)
			(xy 159.100131 -389.786985) (xy 159.152391 -389.80233) (xy 159.201935 -389.824956) (xy 159.247755 -389.854403)
			(xy 159.288918 -389.89007) (xy 159.324585 -389.931233) (xy 159.354032 -389.977053) (xy 159.376658 -390.026597)
			(xy 159.392003 -390.078857) (xy 159.399754 -390.132769) (xy 159.40024 -390.160002) (xy 159.40024 -390.642602)
			(xy 159.399754 -390.669835) (xy 159.392003 -390.723747) (xy 159.376658 -390.776007) (xy 159.354032 -390.825551)
			(xy 159.324585 -390.871371) (xy 159.288918 -390.912534) (xy 159.247755 -390.948201) (xy 159.201935 -390.977648)
			(xy 159.152391 -391.000274) (xy 159.100131 -391.015619) (xy 159.046219 -391.02337) (xy 158.991753 -391.02337)
			(xy 158.937841 -391.015619) (xy 158.885581 -391.000274) (xy 158.836037 -390.977648) (xy 158.790217 -390.948201)
			(xy 158.749054 -390.912534) (xy 158.713387 -390.871371) (xy 158.68394 -390.825551) (xy 158.661314 -390.776007)
			(xy 158.645969 -390.723747) (xy 158.638218 -390.669835) (xy 158.637732 -390.642602) (xy 157.592268 -390.642602)
			(xy 157.592268 -391.158222) (xy 157.592014 -391.165842) (xy 157.592014 -391.445496) (xy 157.591592 -391.455567)
			(xy 157.58388 -391.474174) (xy 157.577028 -391.481564) (xy 157.45968 -391.598912) (xy 157.454859 -391.603469)
			(xy 157.443413 -391.610166) (xy 157.437074 -391.61212) (xy 157.429088 -391.614617) (xy 157.415212 -391.623947)
			(xy 157.409896 -391.630408) (xy 157.362398 -391.6934) (xy 157.35808 -391.699242) (xy 157.354663 -391.70397)
			(xy 157.349911 -391.714622) (xy 157.348682 -391.720324) (xy 157.34665 -391.731754) (xy 157.348936 -391.740136)
			(xy 157.355689 -391.764641) (xy 157.362201 -391.815049) (xy 157.36189 -391.840466) (xy 157.360477 -391.868383)
			(xy 157.349092 -391.923103) (xy 157.328333 -391.974998) (xy 157.298837 -392.022474) (xy 157.28061 -392.043666)
			(xy 157.273752 -392.051032) (xy 157.27045 -392.059922) (xy 157.268934 -392.064468) (xy 157.267401 -392.073926)
			(xy 157.267402 -392.078718) (xy 157.26791 -392.097514) (xy 157.26791 -392.098022) (xy 157.268164 -392.107928)
			(xy 157.277562 -392.126978) (xy 157.286452 -392.134344) (xy 157.307866 -392.152559) (xy 157.34563 -392.194204)
			(xy 157.376881 -392.240935) (xy 157.400944 -392.291742) (xy 157.4173 -392.345527) (xy 157.425593 -392.40113)
			(xy 157.426152 -392.429238) (xy 157.426152 -393.292838) (xy 157.862524 -393.292838) (xy 157.862524 -392.429238)
			(xy 157.862954 -392.403718) (xy 157.869744 -392.353132) (xy 157.88322 -392.303904) (xy 157.903142 -392.256913)
			(xy 157.929154 -392.213) (xy 157.960791 -392.172948) (xy 157.978856 -392.154918) (xy 157.98546 -392.148568)
			(xy 157.993334 -392.131804) (xy 158.000192 -392.04646) (xy 157.995112 -392.02868) (xy 157.989524 -392.021314)
			(xy 157.974673 -392.000567) (xy 157.951038 -391.955352) (xy 157.934937 -391.906941) (xy 157.926784 -391.856578)
			(xy 157.926278 -391.831068) (xy 157.926278 -391.830814) (xy 157.926768 -391.805825) (xy 157.934587 -391.756462)
			(xy 157.950031 -391.70893) (xy 157.972721 -391.664398) (xy 158.002097 -391.623965) (xy 158.037437 -391.588625)
			(xy 158.07787 -391.559249) (xy 158.122402 -391.536559) (xy 158.169934 -391.521115) (xy 158.219297 -391.513296)
			(xy 158.269275 -391.513296) (xy 158.318638 -391.521115) (xy 158.36617 -391.536559) (xy 158.410702 -391.559249)
			(xy 158.451135 -391.588625) (xy 158.486475 -391.623965) (xy 158.515851 -391.664398) (xy 158.538541 -391.70893)
			(xy 158.553985 -391.756462) (xy 158.561804 -391.805825) (xy 158.562294 -391.830814) (xy 158.562294 -391.831068)
			(xy 158.561802 -391.856577) (xy 158.553625 -391.906937) (xy 158.537522 -391.955348) (xy 158.513907 -392.000572)
			(xy 158.499048 -392.021314) (xy 158.49346 -392.02868) (xy 158.48838 -392.04646) (xy 158.495238 -392.131804)
			(xy 158.503112 -392.148568) (xy 158.509716 -392.154918) (xy 158.527743 -392.172984) (xy 158.559376 -392.213033)
			(xy 158.585389 -392.25694) (xy 158.605318 -392.303923) (xy 158.618808 -392.353142) (xy 158.625618 -392.403721)
			(xy 158.626048 -392.429238) (xy 158.626048 -393.292838) (xy 158.625489 -393.322002) (xy 158.616568 -393.379643)
			(xy 158.598984 -393.435258) (xy 158.573147 -393.487552) (xy 158.539659 -393.535308) (xy 158.519876 -393.556744)
			(xy 158.513717 -393.563826) (xy 158.50656 -393.581162) (xy 158.505906 -393.590526) (xy 158.504128 -393.659106)
			(xy 158.504266 -393.668363) (xy 158.510403 -393.685817) (xy 158.516066 -393.693142) (xy 158.516574 -393.69365)
			(xy 158.532935 -393.713258) (xy 158.560465 -393.756269) (xy 158.58162 -393.802748) (xy 158.595973 -393.851756)
			(xy 158.603235 -393.902305) (xy 158.603696 -393.927838) (xy 158.603194 -393.954734) (xy 158.595176 -394.007926)
			(xy 158.57932 -394.059329) (xy 158.555981 -394.107795) (xy 158.525678 -394.152241) (xy 158.48909 -394.191674)
			(xy 158.447033 -394.225213) (xy 158.400447 -394.252109) (xy 158.350373 -394.271762) (xy 158.297928 -394.283732)
			(xy 158.244286 -394.287752) (xy 158.190644 -394.283732) (xy 158.138199 -394.271762) (xy 158.088125 -394.252109)
			(xy 158.041539 -394.225213) (xy 157.999482 -394.191674) (xy 157.962894 -394.152241) (xy 157.932591 -394.107795)
			(xy 157.909252 -394.059329) (xy 157.893396 -394.007926) (xy 157.885378 -393.954734) (xy 157.884876 -393.927838)
			(xy 157.885346 -393.90227) (xy 157.892623 -393.851654) (xy 157.90702 -393.802586) (xy 157.928245 -393.756063)
			(xy 157.955866 -393.713029) (xy 157.972252 -393.693396) (xy 157.972506 -393.693142) (xy 157.978174 -393.685824)
			(xy 157.984281 -393.668362) (xy 157.984444 -393.659106) (xy 157.982412 -393.580874) (xy 157.9753 -393.563856)
			(xy 157.968696 -393.556744) (xy 157.948909 -393.535312) (xy 157.915418 -393.487557) (xy 157.889583 -393.435262)
			(xy 157.872006 -393.379645) (xy 157.863095 -393.322002) (xy 157.862524 -393.292838) (xy 157.426152 -393.292838)
			(xy 157.425581 -393.322002) (xy 157.41667 -393.379645) (xy 157.399091 -393.435261) (xy 157.373255 -393.487555)
			(xy 157.339763 -393.535308) (xy 157.31998 -393.556744) (xy 157.313376 -393.563856) (xy 157.306264 -393.580874)
			(xy 157.304232 -393.659106) (xy 157.304394 -393.668363) (xy 157.310499 -393.685826) (xy 157.31617 -393.693142)
			(xy 157.316424 -393.693396) (xy 157.332806 -393.71303) (xy 157.360422 -393.756066) (xy 157.381642 -393.80259)
			(xy 157.396036 -393.851657) (xy 157.403311 -393.902271) (xy 157.4038 -393.927838) (xy 157.403298 -393.954734)
			(xy 157.39528 -394.007926) (xy 157.379424 -394.059329) (xy 157.356085 -394.107795) (xy 157.325782 -394.152241)
			(xy 157.289194 -394.191674) (xy 157.247137 -394.225213) (xy 157.200551 -394.252109) (xy 157.150477 -394.271762)
			(xy 157.098032 -394.283732) (xy 157.04439 -394.287752) (xy 156.990748 -394.283732) (xy 156.938303 -394.271762)
			(xy 156.888229 -394.252109) (xy 156.841643 -394.225213) (xy 156.799586 -394.191674) (xy 156.762998 -394.152241)
			(xy 156.732695 -394.107795) (xy 156.709356 -394.059329) (xy 156.6935 -394.007926) (xy 156.685482 -393.954734)
			(xy 156.68498 -393.927838) (xy 156.685441 -393.902305) (xy 156.692704 -393.851758) (xy 156.70706 -393.802751)
			(xy 156.728219 -393.756275) (xy 156.755753 -393.713267) (xy 156.772102 -393.69365) (xy 156.77261 -393.693142)
			(xy 156.778275 -393.685817) (xy 156.784415 -393.668364) (xy 156.784548 -393.659106) (xy 156.78277 -393.590526)
			(xy 156.782115 -393.581163) (xy 156.774956 -393.563829) (xy 156.7688 -393.556744) (xy 156.749018 -393.535308)
			(xy 156.715532 -393.487551) (xy 156.689697 -393.435257) (xy 156.672114 -393.379642) (xy 156.663194 -393.322001)
			(xy 156.662628 -393.292838) (xy 156.662628 -392.429238) (xy 156.663132 -392.401138) (xy 156.671385 -392.345546)
			(xy 156.687703 -392.291766) (xy 156.711733 -392.240962) (xy 156.742955 -392.194232) (xy 156.780694 -392.152587)
			(xy 156.802074 -392.134344) (xy 156.81071 -392.127486) (xy 156.820362 -392.107928) (xy 156.820616 -392.096752)
			(xy 156.821124 -392.079226) (xy 156.821111 -392.074357) (xy 156.81945 -392.064765) (xy 156.817822 -392.060176)
			(xy 156.814774 -392.05154) (xy 156.807916 -392.04392) (xy 156.792795 -392.026516) (xy 156.767212 -391.988164)
			(xy 156.747427 -391.946523) (xy 156.733856 -391.902464) (xy 156.726782 -391.856908) (xy 156.726128 -391.833862)
			(xy 156.726128 -391.83056) (xy 156.726506 -391.808487) (xy 156.732627 -391.764768) (xy 156.73832 -391.743438)
			(xy 156.741622 -391.731754) (xy 156.73959 -391.720324) (xy 156.738343 -391.714568) (xy 156.733607 -391.703786)
			(xy 156.730192 -391.698988) (xy 156.68117 -391.634218) (xy 156.673618 -391.625149) (xy 156.652566 -391.614545)
			(xy 156.640784 -391.613898) (xy 156.247592 -391.613898) (xy 156.235807 -391.614552) (xy 156.214738 -391.625132)
			(xy 156.207206 -391.634218) (xy 156.158184 -391.698988) (xy 156.154756 -391.703779) (xy 156.150018 -391.714562)
			(xy 156.148786 -391.720324) (xy 156.146754 -391.731754) (xy 156.150056 -391.743438) (xy 156.15566 -391.764462)
			(xy 156.161784 -391.807538) (xy 156.162248 -391.82929) (xy 156.162248 -391.833862) (xy 156.161623 -391.856887)
			(xy 156.154547 -391.902399) (xy 156.140971 -391.946413) (xy 156.121182 -391.988004) (xy 156.095593 -392.026302)
			(xy 156.08046 -392.043666) (xy 156.073856 -392.051032) (xy 156.070554 -392.059668) (xy 156.068952 -392.064325)
			(xy 156.067409 -392.074049) (xy 156.067506 -392.078972) (xy 156.068268 -392.097768) (xy 156.068268 -392.098276)
			(xy 156.068522 -392.107674) (xy 156.078174 -392.127486) (xy 156.086556 -392.134344) (xy 156.107919 -392.15256)
			(xy 156.145584 -392.194192) (xy 156.176745 -392.240892) (xy 156.200727 -392.291653) (xy 156.217015 -392.34538)
			(xy 156.225256 -392.400913) (xy 156.225748 -392.428984) (xy 156.225748 -393.293346) (xy 156.22522 -393.321157)
			(xy 156.217098 -393.376184) (xy 156.201076 -393.42945) (xy 156.177493 -393.479827) (xy 156.146848 -393.526248)
			(xy 156.12872 -393.547346) (xy 156.122878 -393.55395) (xy 156.11602 -393.570714) (xy 156.113988 -393.645136)
			(xy 156.114055 -393.65405) (xy 156.119643 -393.670965) (xy 156.12491 -393.678156) (xy 156.125164 -393.67841)
			(xy 156.139899 -393.697539) (xy 156.164652 -393.738998) (xy 156.183627 -393.783399) (xy 156.196483 -393.829942)
			(xy 156.202987 -393.877787) (xy 156.203396 -393.90193) (xy 156.203396 -393.902438) (xy 156.202894 -393.929315)
			(xy 156.194882 -393.98247) (xy 156.179038 -394.033836) (xy 156.155714 -394.082268) (xy 156.125433 -394.126682)
			(xy 156.088871 -394.166087) (xy 156.046843 -394.199603) (xy 156.00029 -394.22648) (xy 155.950251 -394.246119)
			(xy 155.897844 -394.25808) (xy 155.84424 -394.262098) (xy 155.790636 -394.25808) (xy 155.738229 -394.246119)
			(xy 155.68819 -394.22648) (xy 155.641637 -394.199603) (xy 155.599609 -394.166087) (xy 155.563047 -394.126682)
			(xy 155.532766 -394.082268) (xy 155.509442 -394.033836) (xy 155.493598 -393.98247) (xy 155.485586 -393.929315)
			(xy 155.485084 -393.902438) (xy 155.485084 -393.90193) (xy 155.485494 -393.877788) (xy 155.492 -393.829943)
			(xy 155.504858 -393.783402) (xy 155.523837 -393.739003) (xy 155.548593 -393.697548) (xy 155.563316 -393.67841)
			(xy 155.56357 -393.678156) (xy 155.568782 -393.670934) (xy 155.574376 -393.654041) (xy 155.574492 -393.645136)
			(xy 155.57246 -393.570714) (xy 155.565602 -393.55395) (xy 155.55976 -393.547346) (xy 155.541596 -393.526274)
			(xy 155.510936 -393.479855) (xy 155.487347 -393.429473) (xy 155.47133 -393.376198) (xy 155.463225 -393.321161)
			(xy 155.462732 -393.293346) (xy 155.462732 -392.428984) (xy 155.463232 -392.400914) (xy 155.471464 -392.345381)
			(xy 155.48775 -392.291654) (xy 155.511735 -392.240896) (xy 155.542903 -392.194202) (xy 155.58058 -392.152583)
			(xy 155.601924 -392.134344) (xy 155.610306 -392.127486) (xy 155.619958 -392.107674) (xy 155.620212 -392.098022)
			(xy 155.620974 -392.078972) (xy 155.621017 -392.074053) (xy 155.619475 -392.064338) (xy 155.617926 -392.059668)
			(xy 155.614624 -392.051032) (xy 155.60802 -392.043666) (xy 155.592912 -392.026283) (xy 155.567345 -391.987979)
			(xy 155.547563 -391.946391) (xy 155.533979 -391.902386) (xy 155.526877 -391.856883) (xy 155.526232 -391.833862)
			(xy 155.526232 -391.83056) (xy 155.52661 -391.808487) (xy 155.532731 -391.764768) (xy 155.538424 -391.743438)
			(xy 155.541726 -391.731754) (xy 155.539694 -391.720324) (xy 155.538447 -391.714568) (xy 155.533711 -391.703786)
			(xy 155.530296 -391.698988) (xy 155.481274 -391.634218) (xy 155.473723 -391.625149) (xy 155.452671 -391.614543)
			(xy 155.440888 -391.613898) (xy 155.12923 -391.613898) (xy 155.119166 -391.613462) (xy 155.10058 -391.605729)
			(xy 155.093162 -391.598912) (xy 154.94127 -391.44702) (xy 154.934429 -391.43962) (xy 154.926712 -391.421021)
			(xy 154.926284 -391.410952) (xy 154.926284 -389.806942) (xy 154.926034 -389.799528) (xy 154.921779 -389.785326)
			(xy 154.917902 -389.779002) (xy 154.913838 -389.772652) (xy 154.902408 -389.763254) (xy 154.895296 -389.760206)
			(xy 154.872827 -389.750242) (xy 154.831011 -389.724415) (xy 154.793669 -389.692458) (xy 154.761691 -389.655134)
			(xy 154.73584 -389.613333) (xy 154.716732 -389.56805) (xy 154.710384 -389.544306) (xy 154.709876 -389.542274)
			(xy 154.398726 -389.004048) (xy 154.39644 -389.001508) (xy 154.378698 -388.983451) (xy 154.348599 -388.942752)
			(xy 154.325331 -388.897796) (xy 154.309482 -388.849721) (xy 154.301454 -388.799742) (xy 154.300936 -388.774432)
			(xy 154.30119 -388.762748) (xy 154.301444 -388.75208) (xy 154.297634 -388.742428) (xy 154.295605 -388.737557)
			(xy 154.289845 -388.728721) (xy 154.286204 -388.724902) (xy 153.753566 -388.192264) (xy 153.746718 -388.184867)
			(xy 153.738986 -388.166268) (xy 153.73858 -388.156196) (xy 153.73858 -387.199632) (xy 153.738411 -387.193623)
			(xy 153.735582 -387.181943) (xy 153.732992 -387.176518) (xy 153.731154 -387.173043) (xy 153.726563 -387.166661)
			(xy 153.723848 -387.163818) (xy 153.474674 -386.914644) (xy 153.471822 -386.911939) (xy 153.465443 -386.907348)
			(xy 153.461974 -386.9055) (xy 153.456548 -386.902915) (xy 153.444868 -386.900087) (xy 153.43886 -386.899912)
			(xy 152.217374 -386.899912) (xy 152.212294 -386.900166) (xy 152.202919 -386.901483) (xy 152.186076 -386.910094)
			(xy 152.179528 -386.91693) (xy 152.128474 -386.979414) (xy 152.12495 -386.98387) (xy 152.119815 -386.994001)
			(xy 152.118314 -386.99948) (xy 152.115774 -387.010148) (xy 152.11806 -387.021578) (xy 152.120935 -387.037038)
			(xy 152.123985 -387.068338) (xy 152.124156 -387.084062) (xy 152.123775 -387.105871) (xy 152.11778 -387.149076)
			(xy 152.112218 -387.170168) (xy 152.111456 -387.173724) (xy 152.111456 -387.185662) (xy 152.11101 -387.200075)
			(xy 152.103858 -387.228) (xy 152.089991 -387.253272) (xy 152.070281 -387.274307) (xy 152.05837 -387.282436)
			(xy 152.057354 -387.287008) (xy 152.056499 -387.292321) (xy 152.056751 -387.303078) (xy 152.057862 -387.308344)
			(xy 152.074626 -387.382258) (xy 152.075991 -387.38747) (xy 152.080594 -387.39721) (xy 152.08377 -387.401562)
			(xy 152.09012 -387.409944) (xy 152.099772 -387.415278) (xy 152.123924 -387.429239) (xy 152.167357 -387.464241)
			(xy 152.186132 -387.484874) (xy 152.188614 -387.487626) (xy 152.194223 -387.492472) (xy 152.197308 -387.494526)
			(xy 152.209441 -387.502618) (xy 152.229508 -387.523769) (xy 152.243651 -387.549264) (xy 152.250972 -387.577485)
			(xy 152.25141 -387.592062) (xy 152.25141 -387.604508) (xy 152.253188 -387.610858) (xy 152.258299 -387.631176)
			(xy 152.263772 -387.672714) (xy 152.26411 -387.693662) (xy 152.26411 -387.69798) (xy 152.263839 -387.709591)
			(xy 152.261803 -387.732728) (xy 152.260046 -387.744208) (xy 152.25853 -387.753255) (xy 152.254591 -387.771173)
			(xy 152.252172 -387.780022) (xy 152.25141 -387.78307) (xy 152.25141 -388.239254) (xy 152.252172 -388.242302)
			(xy 152.257293 -388.26154) (xy 152.263277 -388.300898) (xy 152.26411 -388.320788) (xy 152.26411 -388.328662)
			(xy 152.828244 -388.328662) (xy 152.828612 -388.307641) (xy 152.834222 -388.265975) (xy 152.83942 -388.245604)
			(xy 152.840944 -388.239) (xy 152.840944 -388.125462) (xy 152.8414 -388.110465) (xy 152.84916 -388.081491)
			(xy 152.864144 -388.055507) (xy 152.885333 -388.034277) (xy 152.911289 -388.019244) (xy 152.940248 -388.011428)
			(xy 152.955244 -388.010908) (xy 153.137362 -388.010908) (xy 153.13787 -388.010654) (xy 153.154634 -388.010654)
			(xy 153.155142 -388.010908) (xy 153.336752 -388.010908) (xy 153.35178 -388.011422) (xy 153.380818 -388.019181)
			(xy 153.406862 -388.034184) (xy 153.428141 -388.055411) (xy 153.443209 -388.081417) (xy 153.45104 -388.110435)
			(xy 153.45156 -388.125462) (xy 153.45156 -388.239) (xy 153.453084 -388.245604) (xy 153.458277 -388.265976)
			(xy 153.463886 -388.307642) (xy 153.46426 -388.328662) (xy 153.46426 -388.32917) (xy 153.46409 -388.343795)
			(xy 153.461423 -388.372924) (xy 153.458926 -388.387336) (xy 153.457559 -388.39651) (xy 153.460833 -388.414753)
			(xy 153.465276 -388.422896) (xy 153.481786 -388.44982) (xy 153.48694 -388.45761) (xy 153.501677 -388.469066)
			(xy 153.510488 -388.472172) (xy 153.535366 -388.480246) (xy 153.582246 -388.503433) (xy 153.624658 -388.534034)
			(xy 153.661442 -388.571213) (xy 153.69159 -388.613949) (xy 153.714276 -388.661073) (xy 153.72207 -388.68604)
			(xy 153.723594 -388.691882) (xy 154.043888 -389.245602) (xy 154.047952 -389.24992) (xy 154.064152 -389.267631)
			(xy 154.091575 -389.307022) (xy 154.112718 -389.350111) (xy 154.127092 -389.395904) (xy 154.134368 -389.443346)
			(xy 154.13482 -389.467344) (xy 154.134332 -389.492806) (xy 154.126134 -389.543067) (xy 154.109972 -389.59136)
			(xy 154.086267 -389.636431) (xy 154.055633 -389.677113) (xy 154.018866 -389.712348) (xy 153.998168 -389.727186)
			(xy 153.989686 -389.733651) (xy 153.978508 -389.751786) (xy 153.975644 -389.772896) (xy 153.981586 -389.793353)
			(xy 153.995313 -389.809644) (xy 154.014467 -389.81897) (xy 154.025092 -389.819896) (xy 154.034998 -389.819388)
			(xy 154.043449 -389.818104) (xy 154.060487 -389.816704) (xy 154.069034 -389.816594) (xy 154.069288 -389.816848)
			(xy 154.3685 -389.816848) (xy 154.368754 -389.816594) (xy 154.389801 -389.816984) (xy 154.431122 -389.824983)
			(xy 154.470077 -389.840917) (xy 154.505159 -389.864169) (xy 154.535009 -389.89384) (xy 154.558474 -389.92878)
			(xy 154.574643 -389.967638) (xy 154.582892 -390.00891) (xy 154.583384 -390.029954) (xy 154.583384 -390.284716)
			(xy 154.57424 -390.284716) (xy 154.564219 -390.285153) (xy 154.5457 -390.292812) (xy 154.531526 -390.30698)
			(xy 154.523857 -390.325496) (xy 154.52344 -390.335516) (xy 154.52344 -390.499092) (xy 154.522906 -390.509094)
			(xy 154.515257 -390.527578) (xy 154.501118 -390.54173) (xy 154.482642 -390.549397) (xy 154.47264 -390.549892)
			(xy 153.965148 -390.549892) (xy 153.955129 -390.549441) (xy 153.936611 -390.541785) (xy 153.922437 -390.527622)
			(xy 153.914767 -390.509111) (xy 153.914348 -390.499092) (xy 153.914348 -390.335516) (xy 153.9138 -390.325515)
			(xy 153.906155 -390.307033) (xy 153.892021 -390.292881) (xy 153.873548 -390.285213) (xy 153.863548 -390.284716)
			(xy 153.854404 -390.284716) (xy 153.854404 -390.029446) (xy 153.855189 -390.003724) (xy 153.867522 -389.953778)
			(xy 153.878788 -389.93064) (xy 153.88463 -389.91921) (xy 153.884376 -389.89381) (xy 153.836878 -389.808212)
			(xy 153.83015 -389.797438) (xy 153.808831 -389.783697) (xy 153.796238 -389.78205) (xy 153.772366 -389.779853)
			(xy 153.725622 -389.769225) (xy 153.681026 -389.751645) (xy 153.639604 -389.727518) (xy 153.602312 -389.697398)
			(xy 153.570008 -389.661981) (xy 153.543437 -389.622082) (xy 153.523212 -389.578622) (xy 153.516076 -389.555736)
			(xy 153.514552 -389.549894) (xy 153.194258 -388.996174) (xy 153.190194 -388.991856) (xy 153.174041 -388.974116)
			(xy 153.146671 -388.934716) (xy 153.125578 -388.891628) (xy 153.111249 -388.845844) (xy 153.104014 -388.798419)
			(xy 153.10358 -388.774432) (xy 153.103761 -388.760384) (xy 153.106302 -388.732402) (xy 153.10866 -388.718552)
			(xy 153.109988 -388.709273) (xy 153.106458 -388.690875) (xy 153.101802 -388.682738) (xy 153.085038 -388.655814)
			(xy 153.079829 -388.648116) (xy 153.065108 -388.63679) (xy 153.056336 -388.633716) (xy 153.034708 -388.626921)
			(xy 152.993494 -388.608038) (xy 152.955374 -388.583501) (xy 152.921119 -388.553806) (xy 152.905968 -388.536942)
			(xy 152.9035 -388.534174) (xy 152.897892 -388.529325) (xy 152.894792 -388.52729) (xy 152.882739 -388.519217)
			(xy 152.862779 -388.49818) (xy 152.848701 -388.472826) (xy 152.841398 -388.444761) (xy 152.840944 -388.430262)
			(xy 152.840944 -388.418324) (xy 152.83942 -388.41172) (xy 152.834213 -388.391351) (xy 152.828613 -388.349683)
			(xy 152.828244 -388.328662) (xy 152.26411 -388.328662) (xy 152.26411 -388.33298) (xy 152.263856 -388.343648)
			(xy 152.263856 -388.344156) (xy 152.263231 -388.354503) (xy 152.260814 -388.375093) (xy 152.25903 -388.385304)
			(xy 152.258268 -388.39394) (xy 152.25843 -388.401024) (xy 152.262166 -388.414685) (xy 152.265634 -388.420864)
			(xy 152.277318 -388.43966) (xy 152.27979 -388.443616) (xy 152.285926 -388.450643) (xy 152.28951 -388.45363)
			(xy 152.310592 -388.469632) (xy 152.31618 -388.47141) (xy 152.341332 -388.480073) (xy 152.388549 -388.504569)
			(xy 152.431037 -388.536572) (xy 152.467614 -388.575193) (xy 152.497263 -388.619356) (xy 152.519158 -388.667834)
			(xy 152.526492 -388.693406) (xy 152.531572 -388.705852) (xy 152.843738 -389.245602) (xy 152.847802 -389.24992)
			(xy 152.86396 -389.267589) (xy 152.891293 -389.306899) (xy 152.912368 -389.34989) (xy 152.926702 -389.395572)
			(xy 152.933965 -389.442897) (xy 152.934416 -389.466836) (xy 152.934416 -389.467344) (xy 152.933936 -389.492797)
			(xy 152.925777 -389.543044) (xy 152.909663 -389.591332) (xy 152.88601 -389.636409) (xy 152.855431 -389.677106)
			(xy 152.818719 -389.712371) (xy 152.798018 -389.727186) (xy 152.789524 -389.733669) (xy 152.778331 -389.751842)
			(xy 152.775492 -389.772996) (xy 152.781498 -389.793477) (xy 152.795312 -389.809747) (xy 152.814546 -389.818997)
			(xy 152.825196 -389.819896) (xy 152.834848 -389.819388) (xy 152.843359 -389.818074) (xy 152.860526 -389.816675)
			(xy 152.869138 -389.816594) (xy 152.869392 -389.816848) (xy 153.168604 -389.816848) (xy 153.168858 -389.816594)
			(xy 153.189903 -389.816959) (xy 153.231221 -389.824961) (xy 153.270172 -389.840899) (xy 153.305247 -389.864156)
			(xy 153.335089 -389.893832) (xy 153.358541 -389.928777) (xy 153.374696 -389.967639) (xy 153.382927 -390.008911)
			(xy 153.383488 -390.029954) (xy 153.383488 -390.233916) (xy 153.382997 -390.243921) (xy 153.375334 -390.262405)
			(xy 153.361181 -390.27655) (xy 153.342693 -390.284203) (xy 153.332688 -390.284716) (xy 153.323544 -390.284716)
			(xy 153.323544 -390.499092) (xy 153.323058 -390.509104) (xy 153.315401 -390.527606) (xy 153.30125 -390.541772)
			(xy 153.282755 -390.549448) (xy 153.272744 -390.549892) (xy 152.765252 -390.549892) (xy 152.755251 -390.549396)
			(xy 152.736777 -390.541727) (xy 152.722641 -390.527576) (xy 152.714993 -390.509093) (xy 152.714452 -390.499092)
			(xy 152.714452 -390.335516) (xy 152.714035 -390.325496) (xy 152.706366 -390.306982) (xy 152.692191 -390.292816)
			(xy 152.673672 -390.285159) (xy 152.663652 -390.284716) (xy 152.654508 -390.284716) (xy 152.654508 -390.029446)
			(xy 152.655304 -390.003724) (xy 152.667626 -389.953776) (xy 152.678892 -389.93064) (xy 152.684734 -389.91921)
			(xy 152.68448 -389.89381) (xy 152.636982 -389.808212) (xy 152.630269 -389.797432) (xy 152.608933 -389.783723)
			(xy 152.596342 -389.78205) (xy 152.572458 -389.779879) (xy 152.525699 -389.769233) (xy 152.481086 -389.751641)
			(xy 152.439645 -389.727508) (xy 152.402329 -389.697388) (xy 152.369994 -389.661973) (xy 152.343384 -389.622077)
			(xy 152.32311 -389.578617) (xy 152.315926 -389.555736) (xy 152.314402 -389.549894) (xy 151.999442 -389.005064)
			(xy 151.997918 -389.003794) (xy 151.98344 -389.001508) (xy 151.976119 -389.00064) (xy 151.961528 -389.0027)
			(xy 151.954738 -389.005572) (xy 151.87041 -389.043672) (xy 151.864568 -389.046974) (xy 151.85746 -389.051782)
			(xy 151.846716 -389.065149) (xy 151.841021 -389.081325) (xy 151.840692 -389.0899) (xy 151.840692 -389.778748)
			(xy 151.841203 -389.789585) (xy 151.850145 -389.809328) (xy 151.857964 -389.816848) (xy 151.968708 -389.816848)
			(xy 151.968962 -389.816594) (xy 151.990007 -389.81696) (xy 152.031324 -389.824962) (xy 152.070274 -389.8409)
			(xy 152.105349 -389.864157) (xy 152.13519 -389.893833) (xy 152.158642 -389.928778) (xy 152.174796 -389.967639)
			(xy 152.183027 -390.008911) (xy 152.183592 -390.029954) (xy 152.183592 -390.284716) (xy 152.181052 -390.284716)
			(xy 152.15616 -390.344406) (xy 152.157176 -390.346438) (xy 152.159051 -390.349832) (xy 152.163645 -390.356077)
			(xy 152.16632 -390.358884) (xy 152.449784 -390.642348) (xy 152.456625 -390.649748) (xy 152.464344 -390.668347)
			(xy 152.46477 -390.678416) (xy 152.46477 -391.580878) (xy 152.464819 -391.584749) (xy 152.465968 -391.592403)
			(xy 152.467056 -391.596118) (xy 152.468881 -391.601445) (xy 152.474511 -391.611196) (xy 152.478232 -391.615422)
			(xy 152.495675 -391.635125) (xy 152.524457 -391.679175) (xy 152.545595 -391.727362) (xy 152.558512 -391.778371)
			(xy 152.562856 -391.83081) (xy 152.558508 -391.88325) (xy 152.545588 -391.934258) (xy 152.524447 -391.982443)
			(xy 152.495662 -392.026491) (xy 152.478232 -392.046206) (xy 152.471628 -392.053572) (xy 152.468326 -392.062208)
			(xy 152.466702 -392.066672) (xy 152.464919 -392.076002) (xy 152.46477 -392.08075) (xy 152.46477 -392.104118)
			(xy 152.474676 -392.124692) (xy 152.48382 -392.132058) (xy 152.505617 -392.150277) (xy 152.544094 -392.192069)
			(xy 152.575948 -392.239105) (xy 152.600475 -392.290344) (xy 152.617132 -392.344654) (xy 152.625551 -392.400834)
			(xy 152.62606 -392.429238) (xy 152.62606 -393.292838) (xy 153.062432 -393.292838) (xy 153.062432 -392.429238)
			(xy 153.06286 -392.403718) (xy 153.069649 -392.353132) (xy 153.083126 -392.303904) (xy 153.103049 -392.256913)
			(xy 153.129061 -392.212999) (xy 153.160699 -392.172948) (xy 153.178764 -392.154918) (xy 153.185368 -392.148568)
			(xy 153.193242 -392.131804) (xy 153.2001 -392.04646) (xy 153.19502 -392.02868) (xy 153.189432 -392.021314)
			(xy 153.174582 -392.000566) (xy 153.150946 -391.955352) (xy 153.134845 -391.906941) (xy 153.126692 -391.856577)
			(xy 153.126186 -391.831068) (xy 153.126186 -391.830814) (xy 153.126676 -391.805825) (xy 153.134495 -391.756462)
			(xy 153.149939 -391.70893) (xy 153.172629 -391.664398) (xy 153.202005 -391.623965) (xy 153.237345 -391.588625)
			(xy 153.277778 -391.559249) (xy 153.32231 -391.536559) (xy 153.369842 -391.521115) (xy 153.419205 -391.513296)
			(xy 153.469183 -391.513296) (xy 153.518546 -391.521115) (xy 153.566078 -391.536559) (xy 153.61061 -391.559249)
			(xy 153.651043 -391.588625) (xy 153.686383 -391.623965) (xy 153.715759 -391.664398) (xy 153.738449 -391.70893)
			(xy 153.753893 -391.756462) (xy 153.761712 -391.805825) (xy 153.762202 -391.830814) (xy 153.762202 -391.831068)
			(xy 153.761709 -391.856577) (xy 153.753531 -391.906936) (xy 153.737429 -391.955348) (xy 153.713814 -392.000572)
			(xy 153.698956 -392.021314) (xy 153.693368 -392.02868) (xy 153.688288 -392.04646) (xy 153.695146 -392.131804)
			(xy 153.70302 -392.148568) (xy 153.709624 -392.154918) (xy 153.727653 -392.172982) (xy 153.759285 -392.213032)
			(xy 153.785297 -392.256939) (xy 153.805226 -392.303922) (xy 153.818716 -392.353142) (xy 153.825526 -392.403721)
			(xy 153.825956 -392.429238) (xy 153.825956 -393.292838) (xy 153.825946 -393.293346) (xy 154.262836 -393.293346)
			(xy 154.262836 -392.42873) (xy 154.263265 -392.403262) (xy 154.270068 -392.352781) (xy 154.28353 -392.303656)
			(xy 154.303412 -392.256759) (xy 154.32936 -392.212927) (xy 154.360912 -392.172938) (xy 154.378914 -392.154918)
			(xy 154.385518 -392.148568) (xy 154.393392 -392.131804) (xy 154.40025 -392.04646) (xy 154.39517 -392.02868)
			(xy 154.389582 -392.021314) (xy 154.374725 -392.00057) (xy 154.351093 -391.955354) (xy 154.334993 -391.906942)
			(xy 154.326842 -391.856578) (xy 154.326336 -391.831068) (xy 154.326336 -391.830814) (xy 154.326826 -391.805825)
			(xy 154.334645 -391.756462) (xy 154.350089 -391.70893) (xy 154.372779 -391.664398) (xy 154.402155 -391.623965)
			(xy 154.437495 -391.588625) (xy 154.477928 -391.559249) (xy 154.52246 -391.536559) (xy 154.569992 -391.521115)
			(xy 154.619355 -391.513296) (xy 154.669333 -391.513296) (xy 154.718696 -391.521115) (xy 154.766228 -391.536559)
			(xy 154.81076 -391.559249) (xy 154.851193 -391.588625) (xy 154.886533 -391.623965) (xy 154.915909 -391.664398)
			(xy 154.938599 -391.70893) (xy 154.954043 -391.756462) (xy 154.961862 -391.805825) (xy 154.962352 -391.830814)
			(xy 154.962352 -391.831068) (xy 154.961849 -391.856577) (xy 154.953673 -391.906935) (xy 154.937574 -391.955346)
			(xy 154.913962 -392.000571) (xy 154.899106 -392.021314) (xy 154.893518 -392.02868) (xy 154.888438 -392.04646)
			(xy 154.895296 -392.131804) (xy 154.90317 -392.148568) (xy 154.909774 -392.154918) (xy 154.927777 -392.172936)
			(xy 154.959317 -392.212931) (xy 154.985257 -392.256766) (xy 155.005136 -392.303662) (xy 155.0186 -392.352785)
			(xy 155.025411 -392.403263) (xy 155.025852 -392.42873) (xy 155.025852 -393.293346) (xy 155.025376 -393.321744)
			(xy 155.016963 -393.377913) (xy 155.0003 -393.432209) (xy 154.975758 -393.483428) (xy 154.943881 -393.530433)
			(xy 154.925014 -393.551664) (xy 154.919154 -393.5586) (xy 154.912246 -393.575378) (xy 154.911552 -393.58443)
			(xy 154.910536 -393.615418) (xy 154.910582 -393.62457) (xy 154.916455 -393.641892) (xy 154.921966 -393.6492)
			(xy 154.93731 -393.668547) (xy 154.963084 -393.710668) (xy 154.982862 -393.755914) (xy 154.996274 -393.803438)
			(xy 155.003069 -393.852348) (xy 155.0035 -393.877038) (xy 155.002998 -393.903915) (xy 154.994986 -393.95707)
			(xy 154.979142 -394.008436) (xy 154.955818 -394.056868) (xy 154.925537 -394.101282) (xy 154.888975 -394.140687)
			(xy 154.846947 -394.174203) (xy 154.800394 -394.20108) (xy 154.750355 -394.220719) (xy 154.697948 -394.23268)
			(xy 154.644344 -394.236698) (xy 154.59074 -394.23268) (xy 154.538333 -394.220719) (xy 154.488294 -394.20108)
			(xy 154.441741 -394.174203) (xy 154.399713 -394.140687) (xy 154.363151 -394.101282) (xy 154.33287 -394.056868)
			(xy 154.309546 -394.008436) (xy 154.293702 -393.95707) (xy 154.28569 -393.903915) (xy 154.285188 -393.877038)
			(xy 154.28559 -393.852344) (xy 154.292346 -393.803422) (xy 154.30575 -393.755888) (xy 154.325548 -393.710643)
			(xy 154.351366 -393.668542) (xy 154.366722 -393.6492) (xy 154.372201 -393.641878) (xy 154.378049 -393.624563)
			(xy 154.378152 -393.615418) (xy 154.377136 -393.58443) (xy 154.376496 -393.575366) (xy 154.369578 -393.558573)
			(xy 154.363674 -393.551664) (xy 154.344856 -393.5304) (xy 154.313037 -393.483373) (xy 154.288521 -393.432158)
			(xy 154.271849 -393.377881) (xy 154.263387 -393.321735) (xy 154.262836 -393.293346) (xy 153.825946 -393.293346)
			(xy 153.825395 -393.322001) (xy 153.816474 -393.379643) (xy 153.798891 -393.435258) (xy 153.773054 -393.487551)
			(xy 153.739566 -393.535308) (xy 153.719784 -393.556744) (xy 153.713626 -393.563827) (xy 153.706468 -393.581162)
			(xy 153.705814 -393.590526) (xy 153.704036 -393.659106) (xy 153.704172 -393.668363) (xy 153.71031 -393.685817)
			(xy 153.715974 -393.693142) (xy 153.716482 -393.69365) (xy 153.732828 -393.713269) (xy 153.760364 -393.756276)
			(xy 153.781523 -393.802752) (xy 153.795879 -393.851758) (xy 153.803142 -393.902305) (xy 153.803604 -393.927838)
			(xy 153.803102 -393.954734) (xy 153.795084 -394.007926) (xy 153.779228 -394.059329) (xy 153.755889 -394.107795)
			(xy 153.725586 -394.152241) (xy 153.688998 -394.191674) (xy 153.646941 -394.225213) (xy 153.600355 -394.252109)
			(xy 153.550281 -394.271762) (xy 153.497836 -394.283732) (xy 153.444194 -394.287752) (xy 153.390552 -394.283732)
			(xy 153.338107 -394.271762) (xy 153.288033 -394.252109) (xy 153.241447 -394.225213) (xy 153.19939 -394.191674)
			(xy 153.162802 -394.152241) (xy 153.132499 -394.107795) (xy 153.10916 -394.059329) (xy 153.093304 -394.007926)
			(xy 153.085286 -393.954734) (xy 153.084784 -393.927838) (xy 153.085252 -393.90227) (xy 153.092529 -393.851654)
			(xy 153.106927 -393.802586) (xy 153.128152 -393.756063) (xy 153.155774 -393.713029) (xy 153.17216 -393.693396)
			(xy 153.172414 -393.693142) (xy 153.178083 -393.685825) (xy 153.18419 -393.668363) (xy 153.184352 -393.659106)
			(xy 153.18232 -393.580874) (xy 153.175208 -393.563856) (xy 153.168604 -393.556744) (xy 153.148819 -393.535311)
			(xy 153.115327 -393.487556) (xy 153.089492 -393.435262) (xy 153.071914 -393.379645) (xy 153.063003 -393.322002)
			(xy 153.062432 -393.292838) (xy 152.62606 -393.292838) (xy 152.625505 -393.32199) (xy 152.616632 -393.379615)
			(xy 152.599097 -393.43522) (xy 152.573309 -393.487511) (xy 152.539868 -393.535271) (xy 152.520142 -393.556744)
			(xy 152.513538 -393.563348) (xy 152.506172 -393.580874) (xy 152.503886 -393.66825) (xy 152.510236 -393.68603)
			(xy 152.516586 -393.693142) (xy 152.532939 -393.71279) (xy 152.5605 -393.755841) (xy 152.581674 -393.802366)
			(xy 152.596033 -393.851425) (xy 152.603288 -393.902025) (xy 152.603708 -393.927584) (xy 152.603708 -393.927838)
			(xy 152.60318 -393.956175) (xy 152.59429 -394.012147) (xy 152.576722 -394.066028) (xy 152.55091 -394.116482)
			(xy 152.53462 -394.139674) (xy 152.530048 -394.146024) (xy 152.522682 -394.167868) (xy 152.521241 -394.172295)
			(xy 152.519841 -394.1815) (xy 152.519888 -394.186156) (xy 152.52065 -394.20292) (xy 152.520904 -394.208508)
			(xy 152.521664 -394.217952) (xy 152.529233 -394.235307) (xy 152.535636 -394.24229) (xy 152.741122 -394.447776)
			(xy 152.74662 -394.452766) (xy 152.759786 -394.459614) (xy 152.76703 -394.461238) (xy 152.776682 -394.462254)
			(xy 159.42564 -394.462254)
		)
		(stroke
			(width 0)
			(type solid)
		)
		(fill yes)
		(layer "B.Cu")
		(net "P0V9_CPU1_RT_2D")
	)
	(gr_poly
		(pts
			(xy 458.921358 -142.66672) (xy 458.931424 -142.666287) (xy 458.950015 -142.65856) (xy 458.957426 -142.651734)
			(xy 459.524354 -142.084806) (xy 459.531206 -142.07741) (xy 459.53895 -142.058812) (xy 459.53934 -142.048738)
			(xy 459.53934 -118.052342) (xy 459.538905 -118.042278) (xy 459.531169 -118.023694) (xy 459.524354 -118.016274)
			(xy 438.828434 -97.320354) (xy 438.820598 -97.31331) (xy 438.800977 -97.305692) (xy 438.779946 -97.306541)
			(xy 438.770268 -97.310702) (xy 438.669176 -97.359724) (xy 438.653682 -97.388172) (xy 438.655714 -97.404428)
			(xy 438.657007 -97.415814) (xy 438.658402 -97.438689) (xy 438.658508 -97.450148) (xy 438.658019 -97.477398)
			(xy 438.650256 -97.531344) (xy 438.634895 -97.583635) (xy 438.612249 -97.633209) (xy 438.582778 -97.679055)
			(xy 438.547083 -97.72024) (xy 438.50589 -97.755926) (xy 438.460038 -97.785387) (xy 438.41046 -97.808023)
			(xy 438.358166 -97.823373) (xy 438.304219 -97.831125) (xy 438.249718 -97.83112) (xy 438.195772 -97.823359)
			(xy 438.14348 -97.808001) (xy 438.093905 -97.785357) (xy 438.048058 -97.755888) (xy 438.006871 -97.720195)
			(xy 437.971183 -97.679003) (xy 437.94172 -97.633152) (xy 437.919083 -97.583575) (xy 437.90373 -97.531281)
			(xy 437.895977 -97.477335) (xy 437.895979 -97.422833) (xy 437.903737 -97.368887) (xy 437.919094 -97.316595)
			(xy 437.941736 -97.267019) (xy 437.971203 -97.221171) (xy 438.006894 -97.179983) (xy 438.048084 -97.144293)
			(xy 438.093934 -97.114828) (xy 438.14351 -97.092188) (xy 438.195803 -97.076834) (xy 438.249749 -97.069078)
			(xy 438.277 -97.06864) (xy 438.288459 -97.068729) (xy 438.311335 -97.070125) (xy 438.32272 -97.071434)
			(xy 438.338976 -97.073466) (xy 438.367424 -97.057972) (xy 438.416446 -96.95688) (xy 438.420598 -96.947197)
			(xy 438.421472 -96.92617) (xy 438.413825 -96.906564) (xy 438.406794 -96.898714) (xy 437.044338 -95.536258)
			(xy 437.037494 -95.528859) (xy 437.029769 -95.51026) (xy 437.029352 -95.50019) (xy 437.029352 -95.473012)
			(xy 437.029181 -95.467003) (xy 437.026352 -95.455324) (xy 437.023764 -95.449898) (xy 437.011572 -95.425514)
			(xy 437.00446 -95.417132) (xy 437.000142 -95.413576) (xy 436.979186 -95.396528) (xy 436.941824 -95.357512)
			(xy 436.910335 -95.313618) (xy 436.885348 -95.265724) (xy 436.867361 -95.214785) (xy 436.856735 -95.16182)
			(xy 436.853682 -95.107886) (xy 436.858262 -95.05406) (xy 436.870384 -95.001417) (xy 436.889805 -94.951008)
			(xy 436.916139 -94.903841) (xy 436.948859 -94.860857) (xy 436.987312 -94.822915) (xy 437.008778 -94.806516)
			(xy 437.01843 -94.799404) (xy 437.029352 -94.777814) (xy 437.029352 -94.746064) (xy 437.028926 -94.736051)
			(xy 437.021247 -94.717555) (xy 437.007075 -94.703405) (xy 436.988566 -94.695758) (xy 436.978552 -94.695264)
			(xy 436.963566 -94.695264) (xy 436.95112 -94.703392) (xy 436.926498 -94.718685) (xy 436.874454 -94.744204)
			(xy 436.819842 -94.763632) (xy 436.763373 -94.776714) (xy 436.705782 -94.78328) (xy 436.6768 -94.783656)
			(xy 436.669942 -94.783656) (xy 436.636942 -94.782685) (xy 436.571598 -94.773258) (xy 436.508024 -94.755455)
			(xy 436.447289 -94.729573) (xy 436.390414 -94.696048) (xy 436.338357 -94.655444) (xy 436.291992 -94.608445)
			(xy 436.252099 -94.55584) (xy 436.219351 -94.498515) (xy 436.194296 -94.437434) (xy 436.177358 -94.373624)
			(xy 436.16882 -94.308158) (xy 436.168292 -94.275148) (xy 436.168826 -94.242068) (xy 436.177413 -94.176467)
			(xy 436.194436 -94.112535) (xy 436.219606 -94.051349) (xy 436.252499 -93.993945) (xy 436.292559 -93.941292)
			(xy 436.33911 -93.894279) (xy 436.391364 -93.8537) (xy 436.44844 -93.820241) (xy 436.509374 -93.794467)
			(xy 436.573135 -93.776814) (xy 436.638648 -93.767578) (xy 436.67172 -93.76664) (xy 436.677054 -93.76664)
			(xy 436.712976 -93.767256) (xy 436.784104 -93.777363) (xy 436.853102 -93.797381) (xy 436.886096 -93.811598)
			(xy 436.898034 -93.816932) (xy 436.923434 -93.815154) (xy 437.005984 -93.761814) (xy 437.01208 -93.757242)
			(xy 437.019553 -93.750019) (xy 437.028489 -93.731275) (xy 437.029352 -93.72092) (xy 437.029352 -57.859422)
			(xy 437.028913 -57.849359) (xy 437.021174 -57.83078) (xy 437.014366 -57.823354) (xy 436.630318 -57.439306)
			(xy 436.623206 -57.43194) (xy 436.60441 -57.42432) (xy 428.920402 -57.42432) (xy 428.910331 -57.423898)
			(xy 428.891724 -57.416186) (xy 428.884334 -57.409334) (xy 427.884336 -56.409336) (xy 427.876369 -56.402209)
			(xy 427.856418 -56.394602) (xy 427.845728 -56.394604) (xy 427.759368 -56.399176) (xy 427.740318 -56.408828)
			(xy 427.73346 -56.417464) (xy 427.712703 -56.442306) (xy 427.665921 -56.487054) (xy 427.61384 -56.525506)
			(xy 427.557302 -56.55704) (xy 427.49722 -56.581147) (xy 427.434566 -56.597438) (xy 427.370351 -56.605648)
			(xy 427.337982 -56.606186) (xy 427.307251 -56.605739) (xy 427.246238 -56.598329) (xy 427.186562 -56.583618)
			(xy 427.129095 -56.561821) (xy 427.074674 -56.533256) (xy 427.024094 -56.49834) (xy 426.97809 -56.457581)
			(xy 426.937335 -56.411575) (xy 426.902423 -56.360991) (xy 426.873863 -56.306568) (xy 426.85207 -56.2491)
			(xy 426.837364 -56.189423) (xy 426.829958 -56.128409) (xy 426.829474 -56.097678) (xy 426.829982 -56.065309)
			(xy 426.838198 -56.001093) (xy 426.854494 -55.938439) (xy 426.878608 -55.878359) (xy 426.910149 -55.821824)
			(xy 426.948608 -55.769747) (xy 426.993363 -55.72297) (xy 427.018196 -55.7022) (xy 427.026832 -55.695342)
			(xy 427.036484 -55.676292) (xy 427.041056 -55.589932) (xy 427.041178 -55.579222) (xy 427.033551 -55.559228)
			(xy 427.026324 -55.551324) (xy 426.887386 -55.412386) (xy 426.880532 -55.404991) (xy 426.87279 -55.386392)
			(xy 426.8724 -55.376318) (xy 426.8724 -52.935886) (xy 426.8724 -52.933346) (xy 426.87112 -52.92131)
			(xy 426.859051 -52.900367) (xy 426.849286 -52.893214) (xy 426.844714 -52.890674) (xy 426.752004 -52.842668)
			(xy 426.72381 -52.8447) (xy 426.712126 -52.853082) (xy 426.686228 -52.870905) (xy 426.630878 -52.90072)
			(xy 426.572275 -52.923485) (xy 426.511313 -52.938853) (xy 426.448921 -52.946589) (xy 426.417486 -52.947062)
			(xy 426.385528 -52.946559) (xy 426.322117 -52.938547) (xy 426.260211 -52.922651) (xy 426.200784 -52.899121)
			(xy 426.144776 -52.868328) (xy 426.093068 -52.830759) (xy 426.046476 -52.787005) (xy 426.005736 -52.737757)
			(xy 425.971489 -52.683792) (xy 425.944276 -52.625959) (xy 425.924525 -52.565172) (xy 425.912549 -52.502389)
			(xy 425.908535 -52.4386) (xy 425.912549 -52.374811) (xy 425.924525 -52.312028) (xy 425.944276 -52.251241)
			(xy 425.971489 -52.193408) (xy 426.005736 -52.139443) (xy 426.046476 -52.090195) (xy 426.093068 -52.046441)
			(xy 426.144776 -52.008872) (xy 426.200784 -51.978079) (xy 426.260211 -51.954549) (xy 426.322117 -51.938653)
			(xy 426.385528 -51.930641) (xy 426.417486 -51.930046) (xy 426.448921 -51.930513) (xy 426.511313 -51.938255)
			(xy 426.572276 -51.953623) (xy 426.630882 -51.976383) (xy 426.686238 -52.006188) (xy 426.712126 -52.024026)
			(xy 426.72381 -52.032408) (xy 426.752004 -52.03444) (xy 426.844714 -51.986434) (xy 426.849286 -51.983894)
			(xy 426.859063 -51.976751) (xy 426.871139 -51.955803) (xy 426.8724 -51.943762) (xy 426.8724 -49.322482)
			(xy 426.871973 -49.312413) (xy 426.864254 -49.293814) (xy 426.857414 -49.286414) (xy 426.279818 -48.708818)
			(xy 426.272706 -48.701452) (xy 426.25391 -48.693832) (xy 423.62247 -48.693832) (xy 423.612403 -48.694261)
			(xy 423.593809 -48.701987) (xy 423.586402 -48.708818) (xy 418.874745 -53.420475) (xy 422.233084 -53.420475)
			(xy 422.233084 -53.356553) (xy 422.241095 -53.293135) (xy 422.256992 -53.231221) (xy 422.280524 -53.171788)
			(xy 422.311318 -53.115773) (xy 422.348891 -53.064058) (xy 422.392648 -53.017461) (xy 422.441901 -52.976716)
			(xy 422.495872 -52.942465) (xy 422.553711 -52.915248) (xy 422.614504 -52.895495) (xy 422.677294 -52.883517)
			(xy 422.74109 -52.879504) (xy 422.804886 -52.883517) (xy 422.867676 -52.895495) (xy 422.928469 -52.915248)
			(xy 422.986308 -52.942465) (xy 423.040279 -52.976716) (xy 423.089532 -53.017461) (xy 423.133289 -53.064058)
			(xy 423.170862 -53.115773) (xy 423.201656 -53.171788) (xy 423.225188 -53.231221) (xy 423.241085 -53.293135)
			(xy 423.249096 -53.356553) (xy 423.249598 -53.388514) (xy 423.249096 -53.420475) (xy 423.241085 -53.483893)
			(xy 423.225188 -53.545807) (xy 423.201656 -53.60524) (xy 423.170862 -53.661255) (xy 423.133289 -53.71297)
			(xy 423.089532 -53.759567) (xy 423.040279 -53.800312) (xy 422.986308 -53.834563) (xy 422.928469 -53.86178)
			(xy 422.867676 -53.881533) (xy 422.804886 -53.893511) (xy 422.74109 -53.897525) (xy 422.677294 -53.893511)
			(xy 422.614504 -53.881533) (xy 422.553711 -53.86178) (xy 422.495872 -53.834563) (xy 422.441901 -53.800312)
			(xy 422.392648 -53.759567) (xy 422.348891 -53.71297) (xy 422.311318 -53.661255) (xy 422.280524 -53.60524)
			(xy 422.256992 -53.545807) (xy 422.241095 -53.483893) (xy 422.233084 -53.420475) (xy 418.874745 -53.420475)
			(xy 418.416486 -53.878734) (xy 418.409635 -53.88613) (xy 418.4019 -53.904729) (xy 418.4015 -53.914802)
			(xy 418.4015 -54.765913) (xy 421.972734 -54.765913) (xy 421.972734 -54.701991) (xy 421.980745 -54.638573)
			(xy 421.996642 -54.576659) (xy 422.020174 -54.517226) (xy 422.050968 -54.461211) (xy 422.088541 -54.409496)
			(xy 422.132298 -54.362899) (xy 422.181551 -54.322154) (xy 422.235522 -54.287903) (xy 422.293361 -54.260686)
			(xy 422.354154 -54.240933) (xy 422.416944 -54.228955) (xy 422.48074 -54.224942) (xy 422.544536 -54.228955)
			(xy 422.607326 -54.240933) (xy 422.668119 -54.260686) (xy 422.725958 -54.287903) (xy 422.779929 -54.322154)
			(xy 422.829182 -54.362899) (xy 422.872939 -54.409496) (xy 422.910512 -54.461211) (xy 422.941306 -54.517226)
			(xy 422.964838 -54.576659) (xy 422.980735 -54.638573) (xy 422.988746 -54.701991) (xy 422.989248 -54.733952)
			(xy 422.988746 -54.765913) (xy 422.980735 -54.829331) (xy 422.964838 -54.891245) (xy 422.941306 -54.950678)
			(xy 422.910512 -55.006693) (xy 422.872939 -55.058408) (xy 422.829182 -55.105005) (xy 422.779929 -55.14575)
			(xy 422.725958 -55.180001) (xy 422.668119 -55.207218) (xy 422.607326 -55.226971) (xy 422.544536 -55.238949)
			(xy 422.48074 -55.242963) (xy 422.416944 -55.238949) (xy 422.354154 -55.226971) (xy 422.293361 -55.207218)
			(xy 422.235522 -55.180001) (xy 422.181551 -55.14575) (xy 422.132298 -55.105005) (xy 422.088541 -55.058408)
			(xy 422.050968 -55.006693) (xy 422.020174 -54.950678) (xy 421.996642 -54.891245) (xy 421.980745 -54.829331)
			(xy 421.972734 -54.765913) (xy 418.4015 -54.765913) (xy 418.4015 -56.379829) (xy 418.597836 -56.379829)
			(xy 418.597836 -56.315907) (xy 418.605847 -56.252489) (xy 418.621744 -56.190575) (xy 418.645276 -56.131142)
			(xy 418.67607 -56.075127) (xy 418.713643 -56.023412) (xy 418.7574 -55.976815) (xy 418.806653 -55.93607)
			(xy 418.860624 -55.901819) (xy 418.918463 -55.874602) (xy 418.979256 -55.854849) (xy 419.042046 -55.842871)
			(xy 419.105842 -55.838858) (xy 419.169638 -55.842871) (xy 419.232428 -55.854849) (xy 419.293221 -55.874602)
			(xy 419.35106 -55.901819) (xy 419.405031 -55.93607) (xy 419.454284 -55.976815) (xy 419.498041 -56.023412)
			(xy 419.535614 -56.075127) (xy 419.548011 -56.097678) (xy 424.616624 -56.097678) (xy 424.620695 -56.042056)
			(xy 424.632821 -55.987619) (xy 424.652744 -55.935528) (xy 424.68004 -55.886893) (xy 424.714126 -55.84275)
			(xy 424.754275 -55.804041) (xy 424.799633 -55.77159) (xy 424.849233 -55.746089) (xy 424.902017 -55.728082)
			(xy 424.95686 -55.717952) (xy 425.012594 -55.715915) (xy 425.068031 -55.722015) (xy 425.121988 -55.736121)
			(xy 425.173317 -55.757933) (xy 425.220923 -55.786987) (xy 425.263791 -55.822662) (xy 425.301008 -55.864199)
			(xy 425.331781 -55.910712) (xy 425.355453 -55.961209) (xy 425.371521 -56.014616) (xy 425.379641 -56.069792)
			(xy 425.38015 -56.097678) (xy 425.379641 -56.125564) (xy 425.371521 -56.18074) (xy 425.355453 -56.234147)
			(xy 425.331781 -56.284644) (xy 425.301008 -56.331157) (xy 425.263791 -56.372694) (xy 425.220923 -56.408369)
			(xy 425.173317 -56.437423) (xy 425.121988 -56.459235) (xy 425.068031 -56.473341) (xy 425.012594 -56.479441)
			(xy 424.95686 -56.477404) (xy 424.902017 -56.467274) (xy 424.849233 -56.449267) (xy 424.799633 -56.423766)
			(xy 424.754275 -56.391315) (xy 424.714126 -56.352606) (xy 424.68004 -56.308463) (xy 424.652744 -56.259828)
			(xy 424.632821 -56.207737) (xy 424.620695 -56.1533) (xy 424.616624 -56.097678) (xy 419.548011 -56.097678)
			(xy 419.566408 -56.131142) (xy 419.58994 -56.190575) (xy 419.605837 -56.252489) (xy 419.613848 -56.315907)
			(xy 419.61435 -56.347868) (xy 419.613848 -56.379829) (xy 419.605837 -56.443247) (xy 419.58994 -56.505161)
			(xy 419.566408 -56.564594) (xy 419.535614 -56.620609) (xy 419.498041 -56.672324) (xy 419.454284 -56.718921)
			(xy 419.405031 -56.759666) (xy 419.35106 -56.793917) (xy 419.293221 -56.821134) (xy 419.232428 -56.840887)
			(xy 419.169638 -56.852865) (xy 419.105842 -56.856879) (xy 419.042046 -56.852865) (xy 418.979256 -56.840887)
			(xy 418.918463 -56.821134) (xy 418.860624 -56.793917) (xy 418.806653 -56.759666) (xy 418.7574 -56.718921)
			(xy 418.713643 -56.672324) (xy 418.67607 -56.620609) (xy 418.645276 -56.564594) (xy 418.621744 -56.505161)
			(xy 418.605847 -56.443247) (xy 418.597836 -56.379829) (xy 418.4015 -56.379829) (xy 418.4015 -57.079599)
			(xy 419.71442 -57.079599) (xy 419.71442 -57.015677) (xy 419.722431 -56.952259) (xy 419.738328 -56.890345)
			(xy 419.76186 -56.830912) (xy 419.792654 -56.774897) (xy 419.830227 -56.723182) (xy 419.873984 -56.676585)
			(xy 419.923237 -56.63584) (xy 419.977208 -56.601589) (xy 420.035047 -56.574372) (xy 420.09584 -56.554619)
			(xy 420.15863 -56.542641) (xy 420.222426 -56.538628) (xy 420.286222 -56.542641) (xy 420.349012 -56.554619)
			(xy 420.409805 -56.574372) (xy 420.467644 -56.601589) (xy 420.521615 -56.63584) (xy 420.570868 -56.676585)
			(xy 420.614625 -56.723182) (xy 420.652198 -56.774897) (xy 420.682992 -56.830912) (xy 420.706524 -56.890345)
			(xy 420.722421 -56.952259) (xy 420.730432 -57.015677) (xy 420.730934 -57.047638) (xy 420.730432 -57.079599)
			(xy 420.98442 -57.079599) (xy 420.98442 -57.015677) (xy 420.992431 -56.952259) (xy 421.008328 -56.890345)
			(xy 421.03186 -56.830912) (xy 421.062654 -56.774897) (xy 421.100227 -56.723182) (xy 421.143984 -56.676585)
			(xy 421.193237 -56.63584) (xy 421.247208 -56.601589) (xy 421.305047 -56.574372) (xy 421.36584 -56.554619)
			(xy 421.42863 -56.542641) (xy 421.492426 -56.538628) (xy 421.556222 -56.542641) (xy 421.619012 -56.554619)
			(xy 421.679805 -56.574372) (xy 421.737644 -56.601589) (xy 421.791615 -56.63584) (xy 421.840868 -56.676585)
			(xy 421.884625 -56.723182) (xy 421.922198 -56.774897) (xy 421.952992 -56.830912) (xy 421.976524 -56.890345)
			(xy 421.992421 -56.952259) (xy 422.000432 -57.015677) (xy 422.000934 -57.047638) (xy 422.000432 -57.079599)
			(xy 421.992421 -57.143017) (xy 421.976524 -57.204931) (xy 421.952992 -57.264364) (xy 421.922198 -57.320379)
			(xy 421.884625 -57.372094) (xy 421.840868 -57.418691) (xy 421.791615 -57.459436) (xy 421.737644 -57.493687)
			(xy 421.679805 -57.520904) (xy 421.619012 -57.540657) (xy 421.556222 -57.552635) (xy 421.492426 -57.556649)
			(xy 421.42863 -57.552635) (xy 421.36584 -57.540657) (xy 421.305047 -57.520904) (xy 421.247208 -57.493687)
			(xy 421.193237 -57.459436) (xy 421.143984 -57.418691) (xy 421.100227 -57.372094) (xy 421.062654 -57.320379)
			(xy 421.03186 -57.264364) (xy 421.008328 -57.204931) (xy 420.992431 -57.143017) (xy 420.98442 -57.079599)
			(xy 420.730432 -57.079599) (xy 420.722421 -57.143017) (xy 420.706524 -57.204931) (xy 420.682992 -57.264364)
			(xy 420.652198 -57.320379) (xy 420.614625 -57.372094) (xy 420.570868 -57.418691) (xy 420.521615 -57.459436)
			(xy 420.467644 -57.493687) (xy 420.409805 -57.520904) (xy 420.349012 -57.540657) (xy 420.286222 -57.552635)
			(xy 420.222426 -57.556649) (xy 420.15863 -57.552635) (xy 420.09584 -57.540657) (xy 420.035047 -57.520904)
			(xy 419.977208 -57.493687) (xy 419.923237 -57.459436) (xy 419.873984 -57.418691) (xy 419.830227 -57.372094)
			(xy 419.792654 -57.320379) (xy 419.76186 -57.264364) (xy 419.738328 -57.204931) (xy 419.722431 -57.143017)
			(xy 419.71442 -57.079599) (xy 418.4015 -57.079599) (xy 418.4015 -57.729839) (xy 418.597836 -57.729839)
			(xy 418.597836 -57.665917) (xy 418.605847 -57.602499) (xy 418.621744 -57.540585) (xy 418.645276 -57.481152)
			(xy 418.67607 -57.425137) (xy 418.713643 -57.373422) (xy 418.7574 -57.326825) (xy 418.806653 -57.28608)
			(xy 418.860624 -57.251829) (xy 418.918463 -57.224612) (xy 418.979256 -57.204859) (xy 419.042046 -57.192881)
			(xy 419.105842 -57.188868) (xy 419.169638 -57.192881) (xy 419.232428 -57.204859) (xy 419.293221 -57.224612)
			(xy 419.35106 -57.251829) (xy 419.405031 -57.28608) (xy 419.454284 -57.326825) (xy 419.498041 -57.373422)
			(xy 419.535614 -57.425137) (xy 419.566408 -57.481152) (xy 419.58994 -57.540585) (xy 419.605837 -57.602499)
			(xy 419.613848 -57.665917) (xy 419.61435 -57.697878) (xy 419.613848 -57.729839) (xy 419.605837 -57.793257)
			(xy 419.58994 -57.855171) (xy 419.566408 -57.914604) (xy 419.535614 -57.970619) (xy 419.498041 -58.022334)
			(xy 419.454284 -58.068931) (xy 419.405031 -58.109676) (xy 419.35106 -58.143927) (xy 419.293221 -58.171144)
			(xy 419.232428 -58.190897) (xy 419.169638 -58.202875) (xy 419.105842 -58.206889) (xy 419.042046 -58.202875)
			(xy 418.979256 -58.190897) (xy 418.918463 -58.171144) (xy 418.860624 -58.143927) (xy 418.806653 -58.109676)
			(xy 418.7574 -58.068931) (xy 418.713643 -58.022334) (xy 418.67607 -57.970619) (xy 418.645276 -57.914604)
			(xy 418.621744 -57.855171) (xy 418.605847 -57.793257) (xy 418.597836 -57.729839) (xy 418.4015 -57.729839)
			(xy 418.4015 -58.397648) (xy 419.713918 -58.397648) (xy 419.71442 -58.365687) (xy 419.722431 -58.302269)
			(xy 419.738328 -58.240355) (xy 419.76186 -58.180922) (xy 419.792654 -58.124907) (xy 419.830227 -58.073192)
			(xy 419.873984 -58.026595) (xy 419.923237 -57.98585) (xy 419.977208 -57.951599) (xy 420.035047 -57.924382)
			(xy 420.09584 -57.904629) (xy 420.15863 -57.892651) (xy 420.222426 -57.888638) (xy 420.286222 -57.892651)
			(xy 420.349012 -57.904629) (xy 420.409805 -57.924382) (xy 420.467644 -57.951599) (xy 420.521615 -57.98585)
			(xy 420.570868 -58.026595) (xy 420.614625 -58.073192) (xy 420.652198 -58.124907) (xy 420.682992 -58.180922)
			(xy 420.706524 -58.240355) (xy 420.722421 -58.302269) (xy 420.730432 -58.365687) (xy 420.730934 -58.397648)
			(xy 420.730407 -58.431206) (xy 420.721839 -58.495649) (xy 421.621706 -58.495649) (xy 421.621706 -58.431727)
			(xy 421.629717 -58.368309) (xy 421.645614 -58.306395) (xy 421.669146 -58.246962) (xy 421.69994 -58.190947)
			(xy 421.737513 -58.139232) (xy 421.78127 -58.092635) (xy 421.830523 -58.05189) (xy 421.884494 -58.017639)
			(xy 421.942333 -57.990422) (xy 422.003126 -57.970669) (xy 422.065916 -57.958691) (xy 422.129712 -57.954678)
			(xy 422.193508 -57.958691) (xy 422.256298 -57.970669) (xy 422.317091 -57.990422) (xy 422.37493 -58.017639)
			(xy 422.396968 -58.031625) (xy 426.747419 -58.031625) (xy 426.747419 -57.963571) (xy 426.755319 -57.895978)
			(xy 426.771013 -57.82976) (xy 426.794289 -57.765811) (xy 426.824831 -57.704996) (xy 426.862227 -57.648139)
			(xy 426.90597 -57.596007) (xy 426.95547 -57.549306) (xy 427.010057 -57.508668) (xy 427.068993 -57.474641)
			(xy 427.131481 -57.447687) (xy 427.196675 -57.428169) (xy 427.263694 -57.416351) (xy 427.331632 -57.412395)
			(xy 427.39957 -57.416351) (xy 427.466589 -57.428169) (xy 427.531783 -57.447687) (xy 427.594271 -57.474641)
			(xy 427.653207 -57.508668) (xy 427.707794 -57.549306) (xy 427.757294 -57.596007) (xy 427.801037 -57.648139)
			(xy 427.838433 -57.704996) (xy 427.868975 -57.765811) (xy 427.892251 -57.82976) (xy 427.907945 -57.895978)
			(xy 427.915845 -57.963571) (xy 427.91634 -57.997598) (xy 427.915845 -58.031625) (xy 427.907945 -58.099218)
			(xy 427.892251 -58.165436) (xy 427.868975 -58.229385) (xy 427.838433 -58.2902) (xy 427.801037 -58.347057)
			(xy 427.757294 -58.399189) (xy 427.707794 -58.44589) (xy 427.653207 -58.486528) (xy 427.594271 -58.520555)
			(xy 427.531783 -58.547509) (xy 427.466589 -58.567027) (xy 427.39957 -58.578845) (xy 427.331632 -58.582802)
			(xy 427.263694 -58.578845) (xy 427.196675 -58.567027) (xy 427.131481 -58.547509) (xy 427.068993 -58.520555)
			(xy 427.010057 -58.486528) (xy 426.95547 -58.44589) (xy 426.90597 -58.399189) (xy 426.862227 -58.347057)
			(xy 426.824831 -58.2902) (xy 426.794289 -58.229385) (xy 426.771013 -58.165436) (xy 426.755319 -58.099218)
			(xy 426.747419 -58.031625) (xy 422.396968 -58.031625) (xy 422.428901 -58.05189) (xy 422.478154 -58.092635)
			(xy 422.521911 -58.139232) (xy 422.559484 -58.190947) (xy 422.590278 -58.246962) (xy 422.61381 -58.306395)
			(xy 422.629707 -58.368309) (xy 422.637718 -58.431727) (xy 422.63822 -58.463688) (xy 422.637718 -58.495649)
			(xy 422.629707 -58.559067) (xy 422.61381 -58.620981) (xy 422.590278 -58.680414) (xy 422.559484 -58.736429)
			(xy 422.521911 -58.788144) (xy 422.478154 -58.834741) (xy 422.428901 -58.875486) (xy 422.37493 -58.909737)
			(xy 422.317091 -58.936954) (xy 422.256298 -58.956707) (xy 422.193508 -58.968685) (xy 422.129712 -58.972699)
			(xy 422.065916 -58.968685) (xy 422.003126 -58.956707) (xy 421.942333 -58.936954) (xy 421.884494 -58.909737)
			(xy 421.830523 -58.875486) (xy 421.78127 -58.834741) (xy 421.737513 -58.788144) (xy 421.69994 -58.736429)
			(xy 421.669146 -58.680414) (xy 421.645614 -58.620981) (xy 421.629717 -58.559067) (xy 421.621706 -58.495649)
			(xy 420.721839 -58.495649) (xy 420.721561 -58.497738) (xy 420.704041 -58.562528) (xy 420.678153 -58.624451)
			(xy 420.644346 -58.682431) (xy 420.603207 -58.735462) (xy 420.555451 -58.782622) (xy 420.529004 -58.803286)
			(xy 420.520368 -58.80989) (xy 420.510208 -58.82767) (xy 420.499794 -58.922666) (xy 420.50589 -58.942224)
			(xy 420.512748 -58.950352) (xy 420.529888 -58.971135) (xy 420.558731 -59.016634) (xy 420.58088 -59.065741)
			(xy 420.595894 -59.117477) (xy 420.603473 -59.170813) (xy 420.603934 -59.197748) (xy 420.603448 -59.224999)
			(xy 420.595692 -59.278947) (xy 420.580337 -59.331242) (xy 420.557695 -59.380819) (xy 420.528229 -59.426669)
			(xy 420.520144 -59.436) (xy 427.59325 -59.436) (xy 427.597321 -59.380378) (xy 427.609447 -59.325941)
			(xy 427.62937 -59.27385) (xy 427.656666 -59.225215) (xy 427.690752 -59.181072) (xy 427.730901 -59.142363)
			(xy 427.776259 -59.109912) (xy 427.825859 -59.084411) (xy 427.878643 -59.066404) (xy 427.933486 -59.056274)
			(xy 427.98922 -59.054237) (xy 428.044657 -59.060337) (xy 428.098614 -59.074443) (xy 428.149943 -59.096255)
			(xy 428.197549 -59.125309) (xy 428.240417 -59.160984) (xy 428.277634 -59.202521) (xy 428.308407 -59.249034)
			(xy 428.332079 -59.299531) (xy 428.348147 -59.352938) (xy 428.356267 -59.408114) (xy 428.356776 -59.436)
			(xy 428.49699 -59.436) (xy 428.501003 -59.372204) (xy 428.512981 -59.309414) (xy 428.532734 -59.248621)
			(xy 428.559951 -59.190782) (xy 428.594202 -59.136811) (xy 428.634947 -59.087558) (xy 428.681544 -59.043801)
			(xy 428.733259 -59.006228) (xy 428.789274 -58.975434) (xy 428.848707 -58.951902) (xy 428.910621 -58.936005)
			(xy 428.974039 -58.927994) (xy 429.006 -58.927492) (xy 429.03728 -58.927911) (xy 429.099369 -58.935575)
			(xy 429.160047 -58.950801) (xy 429.218399 -58.973358) (xy 429.273542 -59.002904) (xy 429.324642 -59.038995)
			(xy 429.370928 -59.081083) (xy 429.411699 -59.128532) (xy 429.429418 -59.154314) (xy 429.43687 -59.164474)
			(xy 429.459001 -59.17646) (xy 429.471582 -59.177174) (xy 429.556418 -59.177174) (xy 429.569001 -59.176494)
			(xy 429.59112 -59.164472) (xy 429.598582 -59.154314) (xy 429.616344 -59.128567) (xy 429.657124 -59.081139)
			(xy 429.703411 -59.039068) (xy 429.754508 -59.00299) (xy 429.809642 -58.97345) (xy 429.867983 -58.950892)
			(xy 429.928649 -58.935657) (xy 429.990725 -58.927976) (xy 430.022 -58.927492) (xy 430.053961 -58.927994)
			(xy 430.117379 -58.936005) (xy 430.179293 -58.951902) (xy 430.238726 -58.975434) (xy 430.294741 -59.006228)
			(xy 430.346456 -59.043801) (xy 430.393053 -59.087558) (xy 430.433798 -59.136811) (xy 430.468049 -59.190782)
			(xy 430.495266 -59.248621) (xy 430.515019 -59.309414) (xy 430.526997 -59.372204) (xy 430.531011 -59.436)
			(xy 430.526997 -59.499796) (xy 430.515019 -59.562586) (xy 430.495266 -59.623379) (xy 430.468049 -59.681218)
			(xy 430.433798 -59.735189) (xy 430.393053 -59.784442) (xy 430.346456 -59.828199) (xy 430.294741 -59.865772)
			(xy 430.238726 -59.896566) (xy 430.179293 -59.920098) (xy 430.117379 -59.935995) (xy 430.053961 -59.944006)
			(xy 430.022 -59.944508) (xy 429.99072 -59.944089) (xy 429.928631 -59.936425) (xy 429.867953 -59.921199)
			(xy 429.809601 -59.898642) (xy 429.754458 -59.869096) (xy 429.703358 -59.833005) (xy 429.657072 -59.790917)
			(xy 429.616301 -59.743468) (xy 429.598582 -59.717686) (xy 429.59113 -59.707526) (xy 429.568999 -59.69554)
			(xy 429.556418 -59.694826) (xy 429.471582 -59.694826) (xy 429.458999 -59.695506) (xy 429.43688 -59.707528)
			(xy 429.429418 -59.717686) (xy 429.411656 -59.743433) (xy 429.370876 -59.790861) (xy 429.324589 -59.832932)
			(xy 429.273492 -59.86901) (xy 429.218358 -59.89855) (xy 429.160017 -59.921108) (xy 429.099351 -59.936343)
			(xy 429.037275 -59.944024) (xy 429.006 -59.944508) (xy 428.974039 -59.944006) (xy 428.910621 -59.935995)
			(xy 428.848707 -59.920098) (xy 428.789274 -59.896566) (xy 428.733259 -59.865772) (xy 428.681544 -59.828199)
			(xy 428.634947 -59.784442) (xy 428.594202 -59.735189) (xy 428.559951 -59.681218) (xy 428.532734 -59.623379)
			(xy 428.512981 -59.562586) (xy 428.501003 -59.499796) (xy 428.49699 -59.436) (xy 428.356776 -59.436)
			(xy 428.356267 -59.463886) (xy 428.348147 -59.519062) (xy 428.332079 -59.572469) (xy 428.308407 -59.622966)
			(xy 428.277634 -59.669479) (xy 428.240417 -59.711016) (xy 428.197549 -59.746691) (xy 428.149943 -59.775745)
			(xy 428.098614 -59.797557) (xy 428.044657 -59.811663) (xy 427.98922 -59.817763) (xy 427.933486 -59.815726)
			(xy 427.878643 -59.805596) (xy 427.825859 -59.787589) (xy 427.776259 -59.762088) (xy 427.730901 -59.729637)
			(xy 427.690752 -59.690928) (xy 427.656666 -59.646785) (xy 427.62937 -59.59815) (xy 427.609447 -59.546059)
			(xy 427.597321 -59.491622) (xy 427.59325 -59.436) (xy 420.520144 -59.436) (xy 420.492538 -59.46786)
			(xy 420.451347 -59.503551) (xy 420.405497 -59.533017) (xy 420.35592 -59.555659) (xy 420.303625 -59.571014)
			(xy 420.249677 -59.57877) (xy 420.195175 -59.57877) (xy 420.141227 -59.571014) (xy 420.088932 -59.555659)
			(xy 420.039355 -59.533017) (xy 419.993505 -59.503551) (xy 419.952314 -59.46786) (xy 419.916623 -59.426669)
			(xy 419.887157 -59.380819) (xy 419.864515 -59.331242) (xy 419.84916 -59.278947) (xy 419.841404 -59.224999)
			(xy 419.840918 -59.197748) (xy 419.841396 -59.170814) (xy 419.848983 -59.117484) (xy 419.864 -59.065752)
			(xy 419.886146 -59.016647) (xy 419.914982 -58.971148) (xy 419.932104 -58.950352) (xy 419.938962 -58.942224)
			(xy 419.945058 -58.922666) (xy 419.934644 -58.82767) (xy 419.924484 -58.80989) (xy 419.915848 -58.803286)
			(xy 419.889394 -58.782628) (xy 419.841627 -58.735477) (xy 419.800481 -58.682449) (xy 419.766672 -58.624467)
			(xy 419.740788 -58.562539) (xy 419.723281 -58.497744) (xy 419.714453 -58.431208) (xy 419.713918 -58.397648)
			(xy 418.4015 -58.397648) (xy 418.4015 -74.767948) (xy 421.29456 -74.767948) (xy 421.29456 -66.06794)
			(xy 421.295065 -65.962416) (xy 421.303149 -65.751522) (xy 421.319305 -65.541093) (xy 421.343508 -65.331436)
			(xy 421.375725 -65.122861) (xy 421.415907 -64.915673) (xy 421.463995 -64.710176) (xy 421.519919 -64.506672)
			(xy 421.583596 -64.305459) (xy 421.654934 -64.106832) (xy 421.733828 -63.911084) (xy 421.820161 -63.718502)
			(xy 421.913808 -63.529367) (xy 422.01463 -63.343958) (xy 422.12248 -63.162547) (xy 422.237199 -62.9854)
			(xy 422.358619 -62.812778) (xy 422.486562 -62.644932) (xy 422.62084 -62.48211) (xy 422.761256 -62.324551)
			(xy 422.907604 -62.172486) (xy 423.059669 -62.026138) (xy 423.217228 -61.885722) (xy 423.38005 -61.751444)
			(xy 423.547896 -61.623501) (xy 423.720518 -61.502081) (xy 423.897665 -61.387362) (xy 424.079076 -61.279512)
			(xy 424.264485 -61.17869) (xy 424.45362 -61.085043) (xy 424.646202 -60.99871) (xy 424.84195 -60.919816)
			(xy 425.040577 -60.848478) (xy 425.24179 -60.784801) (xy 425.445294 -60.728877) (xy 425.650791 -60.680789)
			(xy 425.857979 -60.640607) (xy 426.066554 -60.60839) (xy 426.276211 -60.584187) (xy 426.48664 -60.568031)
			(xy 426.697534 -60.559947) (xy 426.908582 -60.559947) (xy 427.119476 -60.568031) (xy 427.329905 -60.584187)
			(xy 427.539562 -60.60839) (xy 427.748137 -60.640607) (xy 427.955325 -60.680789) (xy 428.160822 -60.728877)
			(xy 428.364326 -60.784801) (xy 428.565539 -60.848478) (xy 428.764166 -60.919816) (xy 428.959914 -60.99871)
			(xy 429.152496 -61.085043) (xy 429.341631 -61.17869) (xy 429.52704 -61.279512) (xy 429.708451 -61.387362)
			(xy 429.885598 -61.502081) (xy 430.05822 -61.623501) (xy 430.226066 -61.751444) (xy 430.388888 -61.885722)
			(xy 430.546447 -62.026138) (xy 430.698512 -62.172486) (xy 430.84486 -62.324551) (xy 430.985276 -62.48211)
			(xy 431.119554 -62.644932) (xy 431.247497 -62.812778) (xy 431.368917 -62.9854) (xy 431.483636 -63.162547)
			(xy 431.591486 -63.343958) (xy 431.692308 -63.529367) (xy 431.785955 -63.718502) (xy 431.872288 -63.911084)
			(xy 431.951182 -64.106832) (xy 432.02252 -64.305459) (xy 432.086197 -64.506672) (xy 432.142121 -64.710176)
			(xy 432.190209 -64.915673) (xy 432.230391 -65.122861) (xy 432.262608 -65.331436) (xy 432.286811 -65.541093)
			(xy 432.302967 -65.751522) (xy 432.311051 -65.962416) (xy 432.311556 -66.06794) (xy 432.311556 -74.767948)
			(xy 432.311051 -74.873472) (xy 432.302967 -75.084366) (xy 432.286811 -75.294795) (xy 432.262608 -75.504452)
			(xy 432.230391 -75.713027) (xy 432.190209 -75.920215) (xy 432.142121 -76.125712) (xy 432.086197 -76.329216)
			(xy 432.02252 -76.530429) (xy 431.951182 -76.729056) (xy 431.872288 -76.924804) (xy 431.785955 -77.117386)
			(xy 431.692308 -77.306521) (xy 431.591486 -77.49193) (xy 431.483636 -77.673341) (xy 431.368917 -77.850488)
			(xy 431.247497 -78.02311) (xy 431.119554 -78.190956) (xy 430.985276 -78.353778) (xy 430.84486 -78.511337)
			(xy 430.698512 -78.663402) (xy 430.546447 -78.80975) (xy 430.388888 -78.950166) (xy 430.226066 -79.084444)
			(xy 430.05822 -79.212387) (xy 429.885598 -79.333807) (xy 429.708451 -79.448526) (xy 429.52704 -79.556376)
			(xy 429.341631 -79.657198) (xy 429.152496 -79.750845) (xy 428.959914 -79.837178) (xy 428.764166 -79.916072)
			(xy 428.565539 -79.98741) (xy 428.364326 -80.051087) (xy 428.160822 -80.107011) (xy 427.955325 -80.155099)
			(xy 427.748137 -80.195281) (xy 427.539562 -80.227498) (xy 427.329905 -80.251701) (xy 427.119476 -80.267857)
			(xy 426.908582 -80.275941) (xy 426.697534 -80.275941) (xy 426.48664 -80.267857) (xy 426.276211 -80.251701)
			(xy 426.066554 -80.227498) (xy 425.857979 -80.195281) (xy 425.650791 -80.155099) (xy 425.445294 -80.107011)
			(xy 425.24179 -80.051087) (xy 425.040577 -79.98741) (xy 424.84195 -79.916072) (xy 424.646202 -79.837178)
			(xy 424.45362 -79.750845) (xy 424.264485 -79.657198) (xy 424.079076 -79.556376) (xy 423.897665 -79.448526)
			(xy 423.720518 -79.333807) (xy 423.547896 -79.212387) (xy 423.38005 -79.084444) (xy 423.217228 -78.950166)
			(xy 423.059669 -78.80975) (xy 422.907604 -78.663402) (xy 422.761256 -78.511337) (xy 422.62084 -78.353778)
			(xy 422.486562 -78.190956) (xy 422.358619 -78.02311) (xy 422.237199 -77.850488) (xy 422.12248 -77.673341)
			(xy 422.01463 -77.49193) (xy 421.913808 -77.306521) (xy 421.820161 -77.117386) (xy 421.733828 -76.924804)
			(xy 421.654934 -76.729056) (xy 421.583596 -76.530429) (xy 421.519919 -76.329216) (xy 421.463995 -76.125712)
			(xy 421.415907 -75.920215) (xy 421.375725 -75.713027) (xy 421.343508 -75.504452) (xy 421.319305 -75.294795)
			(xy 421.303149 -75.084366) (xy 421.295065 -74.873472) (xy 421.29456 -74.767948) (xy 418.4015 -74.767948)
			(xy 418.4015 -85.232748) (xy 418.401932 -85.242814) (xy 418.409659 -85.261406) (xy 418.416486 -85.268816)
			(xy 427.07113 -93.923569) (xy 430.839874 -93.923569) (xy 430.839874 -93.859647) (xy 430.847885 -93.796229)
			(xy 430.863782 -93.734315) (xy 430.887314 -93.674882) (xy 430.918108 -93.618867) (xy 430.955681 -93.567152)
			(xy 430.999438 -93.520555) (xy 431.048691 -93.47981) (xy 431.102662 -93.445559) (xy 431.160501 -93.418342)
			(xy 431.221294 -93.398589) (xy 431.284084 -93.386611) (xy 431.34788 -93.382598) (xy 431.411676 -93.386611)
			(xy 431.474466 -93.398589) (xy 431.535259 -93.418342) (xy 431.593098 -93.445559) (xy 431.647069 -93.47981)
			(xy 431.696322 -93.520555) (xy 431.740079 -93.567152) (xy 431.777652 -93.618867) (xy 431.808446 -93.674882)
			(xy 431.831978 -93.734315) (xy 431.847875 -93.796229) (xy 431.855886 -93.859647) (xy 431.856388 -93.891608)
			(xy 431.855886 -93.923569) (xy 431.847875 -93.986987) (xy 431.831978 -94.048901) (xy 431.808446 -94.108334)
			(xy 431.777652 -94.164349) (xy 431.740079 -94.216064) (xy 431.696322 -94.262661) (xy 431.647069 -94.303406)
			(xy 431.593098 -94.337657) (xy 431.535259 -94.364874) (xy 431.474466 -94.384627) (xy 431.411676 -94.396605)
			(xy 431.34788 -94.400619) (xy 431.284084 -94.396605) (xy 431.221294 -94.384627) (xy 431.160501 -94.364874)
			(xy 431.102662 -94.337657) (xy 431.048691 -94.303406) (xy 430.999438 -94.262661) (xy 430.955681 -94.216064)
			(xy 430.918108 -94.164349) (xy 430.887314 -94.108334) (xy 430.863782 -94.048901) (xy 430.847885 -93.986987)
			(xy 430.839874 -93.923569) (xy 427.07113 -93.923569) (xy 431.738107 -98.590605) (xy 434.775861 -98.590605)
			(xy 434.779871 -98.526834) (xy 434.791838 -98.464067) (xy 434.811575 -98.403294) (xy 434.838769 -98.345472)
			(xy 434.872993 -98.291513) (xy 434.913708 -98.242266) (xy 434.936646 -98.220022) (xy 434.944266 -98.21291)
			(xy 434.952648 -98.193606) (xy 434.952648 -98.09861) (xy 434.944266 -98.079306) (xy 434.936646 -98.072194)
			(xy 434.913715 -98.049942) (xy 434.873 -98.000696) (xy 434.838775 -97.946737) (xy 434.811579 -97.888916)
			(xy 434.791841 -97.828144) (xy 434.779873 -97.765377) (xy 434.775861 -97.701605) (xy 434.779871 -97.637834)
			(xy 434.791838 -97.575067) (xy 434.811575 -97.514294) (xy 434.838769 -97.456472) (xy 434.872993 -97.402513)
			(xy 434.913708 -97.353266) (xy 434.936646 -97.331022) (xy 434.944266 -97.32391) (xy 434.952648 -97.304606)
			(xy 434.952648 -97.20961) (xy 434.944266 -97.190306) (xy 434.936646 -97.183194) (xy 434.915308 -97.16258)
			(xy 434.877099 -97.117189) (xy 434.84443 -97.06766) (xy 434.817746 -97.014667) (xy 434.797408 -96.958929)
			(xy 434.783694 -96.901203) (xy 434.77679 -96.842274) (xy 434.776372 -96.812608) (xy 434.776864 -96.781878)
			(xy 434.784271 -96.720866) (xy 434.798978 -96.661191) (xy 434.820771 -96.603725) (xy 434.849331 -96.549304)
			(xy 434.884243 -96.498722) (xy 434.924998 -96.452718) (xy 434.971 -96.411961) (xy 435.02158 -96.377046)
			(xy 435.075999 -96.348482) (xy 435.133465 -96.326686) (xy 435.193138 -96.311976) (xy 435.25415 -96.304565)
			(xy 435.28488 -96.3041) (xy 435.314546 -96.304545) (xy 435.373475 -96.311438) (xy 435.431202 -96.325143)
			(xy 435.48694 -96.345476) (xy 435.539933 -96.372159) (xy 435.58946 -96.404829) (xy 435.634846 -96.443042)
			(xy 435.655466 -96.464374) (xy 435.662578 -96.471994) (xy 435.681882 -96.480376) (xy 435.776878 -96.480376)
			(xy 435.796182 -96.471994) (xy 435.803294 -96.464374) (xy 435.82392 -96.443047) (xy 435.869308 -96.404836)
			(xy 435.918834 -96.372165) (xy 435.971825 -96.345479) (xy 436.027562 -96.32514) (xy 436.085286 -96.311425)
			(xy 436.144214 -96.304519) (xy 436.17388 -96.3041) (xy 436.204612 -96.304556) (xy 436.265628 -96.311963)
			(xy 436.325306 -96.32667) (xy 436.382777 -96.348464) (xy 436.437201 -96.377027) (xy 436.487786 -96.411941)
			(xy 436.533793 -96.452699) (xy 436.574551 -96.498705) (xy 436.609467 -96.549289) (xy 436.638031 -96.603712)
			(xy 436.659826 -96.661182) (xy 436.674535 -96.72086) (xy 436.681943 -96.781876) (xy 436.682388 -96.812608)
			(xy 436.681966 -96.842274) (xy 436.67507 -96.901205) (xy 436.66136 -96.958932) (xy 436.641024 -97.014671)
			(xy 436.614338 -97.067664) (xy 436.581664 -97.117189) (xy 436.543447 -97.162575) (xy 436.522114 -97.183194)
			(xy 436.514494 -97.190306) (xy 436.506112 -97.20961) (xy 436.506112 -97.304606) (xy 436.514494 -97.32391)
			(xy 436.522114 -97.331022) (xy 436.545062 -97.353257) (xy 436.585781 -97.402504) (xy 436.620008 -97.456464)
			(xy 436.647206 -97.514287) (xy 436.666944 -97.575062) (xy 436.678913 -97.637831) (xy 436.682923 -97.701605)
			(xy 436.678911 -97.765379) (xy 436.666941 -97.828148) (xy 436.647202 -97.888923) (xy 436.620003 -97.946746)
			(xy 436.585774 -98.000705) (xy 436.545055 -98.049951) (xy 436.522114 -98.072194) (xy 436.514494 -98.079306)
			(xy 436.506112 -98.09861) (xy 436.506112 -98.193606) (xy 436.514494 -98.21291) (xy 436.522114 -98.220022)
			(xy 436.545062 -98.242257) (xy 436.585781 -98.291504) (xy 436.620008 -98.345464) (xy 436.647206 -98.403287)
			(xy 436.666944 -98.464062) (xy 436.678913 -98.526831) (xy 436.682923 -98.590605) (xy 436.678911 -98.654379)
			(xy 436.666941 -98.717148) (xy 436.647202 -98.777923) (xy 436.620003 -98.835746) (xy 436.585774 -98.889705)
			(xy 436.545055 -98.938951) (xy 436.522114 -98.961194) (xy 436.514494 -98.968306) (xy 436.506112 -98.98761)
			(xy 436.506112 -99.082606) (xy 436.514494 -99.10191) (xy 436.522114 -99.109022) (xy 436.543452 -99.129636)
			(xy 436.581663 -99.175026) (xy 436.614333 -99.224555) (xy 436.641017 -99.277548) (xy 436.661354 -99.333286)
			(xy 436.675068 -99.391012) (xy 436.681971 -99.449942) (xy 436.682388 -99.479608) (xy 436.68197 -99.510341)
			(xy 436.67456 -99.571359) (xy 436.659849 -99.631039) (xy 436.638051 -99.68851) (xy 436.609486 -99.742935)
			(xy 436.574568 -99.79352) (xy 436.533807 -99.839527) (xy 436.487798 -99.880285) (xy 436.437211 -99.9152)
			(xy 436.382784 -99.943763) (xy 436.325312 -99.965557) (xy 436.265631 -99.980265) (xy 436.204613 -99.987672)
			(xy 436.17388 -99.988116) (xy 436.144214 -99.987693) (xy 436.085283 -99.980796) (xy 436.027557 -99.967086)
			(xy 435.971818 -99.94675) (xy 435.918826 -99.920064) (xy 435.8693 -99.887391) (xy 435.823914 -99.849175)
			(xy 435.803294 -99.827842) (xy 435.796182 -99.820222) (xy 435.776878 -99.81184) (xy 435.681882 -99.81184)
			(xy 435.662578 -99.820222) (xy 435.655466 -99.827842) (xy 435.634863 -99.849191) (xy 435.58947 -99.8874)
			(xy 435.53994 -99.920068) (xy 435.486945 -99.946751) (xy 435.431205 -99.967086) (xy 435.373477 -99.980798)
			(xy 435.314547 -99.987699) (xy 435.28488 -99.988116) (xy 435.254149 -99.987663) (xy 435.193135 -99.980252)
			(xy 435.133459 -99.965541) (xy 435.075992 -99.943745) (xy 435.02157 -99.915181) (xy 434.970988 -99.880265)
			(xy 434.924984 -99.839508) (xy 434.884227 -99.793502) (xy 434.849313 -99.74292) (xy 434.82075 -99.688497)
			(xy 434.798955 -99.631029) (xy 434.784246 -99.571353) (xy 434.776837 -99.510339) (xy 434.776372 -99.479608)
			(xy 434.776818 -99.449942) (xy 434.783711 -99.391013) (xy 434.797418 -99.333287) (xy 434.81775 -99.277549)
			(xy 434.844433 -99.224556) (xy 434.877102 -99.175029) (xy 434.915315 -99.129642) (xy 434.936646 -99.109022)
			(xy 434.944266 -99.10191) (xy 434.952648 -99.082606) (xy 434.952648 -98.98761) (xy 434.944266 -98.968306)
			(xy 434.936646 -98.961194) (xy 434.913715 -98.938942) (xy 434.873 -98.889696) (xy 434.838775 -98.835737)
			(xy 434.811579 -98.777916) (xy 434.791841 -98.717144) (xy 434.779873 -98.654377) (xy 434.775861 -98.590605)
			(xy 431.738107 -98.590605) (xy 438.498742 -105.351326) (xy 438.505591 -105.358723) (xy 438.513325 -105.377322)
			(xy 438.513728 -105.387394) (xy 438.513728 -123.045177) (xy 442.061086 -123.045177) (xy 442.061086 -122.981255)
			(xy 442.069097 -122.917837) (xy 442.084994 -122.855923) (xy 442.108526 -122.79649) (xy 442.13932 -122.740475)
			(xy 442.176893 -122.68876) (xy 442.22065 -122.642163) (xy 442.269903 -122.601418) (xy 442.323874 -122.567167)
			(xy 442.381713 -122.53995) (xy 442.442506 -122.520197) (xy 442.505296 -122.508219) (xy 442.569092 -122.504206)
			(xy 442.632888 -122.508219) (xy 442.695678 -122.520197) (xy 442.756471 -122.53995) (xy 442.81431 -122.567167)
			(xy 442.868281 -122.601418) (xy 442.917534 -122.642163) (xy 442.961291 -122.68876) (xy 442.998864 -122.740475)
			(xy 443.029658 -122.79649) (xy 443.05319 -122.855923) (xy 443.069087 -122.917837) (xy 443.077098 -122.981255)
			(xy 443.0776 -123.013216) (xy 443.077098 -123.045177) (xy 443.069087 -123.108595) (xy 443.05319 -123.170509)
			(xy 443.029658 -123.229942) (xy 442.998864 -123.285957) (xy 442.961291 -123.337672) (xy 442.917534 -123.384269)
			(xy 442.868281 -123.425014) (xy 442.81431 -123.459265) (xy 442.756471 -123.486482) (xy 442.695678 -123.506235)
			(xy 442.632888 -123.518213) (xy 442.569092 -123.522227) (xy 442.505296 -123.518213) (xy 442.442506 -123.506235)
			(xy 442.381713 -123.486482) (xy 442.323874 -123.459265) (xy 442.269903 -123.425014) (xy 442.22065 -123.384269)
			(xy 442.176893 -123.337672) (xy 442.13932 -123.285957) (xy 442.108526 -123.229942) (xy 442.084994 -123.170509)
			(xy 442.069097 -123.108595) (xy 442.061086 -123.045177) (xy 438.513728 -123.045177) (xy 438.513728 -129.045419)
			(xy 446.37426 -129.045419) (xy 446.37426 -128.981497) (xy 446.382271 -128.918079) (xy 446.398168 -128.856165)
			(xy 446.4217 -128.796732) (xy 446.452494 -128.740717) (xy 446.490067 -128.689002) (xy 446.533824 -128.642405)
			(xy 446.583077 -128.60166) (xy 446.637048 -128.567409) (xy 446.694887 -128.540192) (xy 446.75568 -128.520439)
			(xy 446.81847 -128.508461) (xy 446.882266 -128.504448) (xy 446.946062 -128.508461) (xy 447.008852 -128.520439)
			(xy 447.069645 -128.540192) (xy 447.127484 -128.567409) (xy 447.181455 -128.60166) (xy 447.230708 -128.642405)
			(xy 447.274465 -128.689002) (xy 447.312038 -128.740717) (xy 447.342832 -128.796732) (xy 447.366364 -128.856165)
			(xy 447.382261 -128.918079) (xy 447.390272 -128.981497) (xy 447.390774 -129.013458) (xy 447.390272 -129.045419)
			(xy 447.382261 -129.108837) (xy 447.366364 -129.170751) (xy 447.342832 -129.230184) (xy 447.312038 -129.286199)
			(xy 447.274465 -129.337914) (xy 447.230708 -129.384511) (xy 447.181455 -129.425256) (xy 447.127484 -129.459507)
			(xy 447.069645 -129.486724) (xy 447.008852 -129.506477) (xy 446.946062 -129.518455) (xy 446.882266 -129.522469)
			(xy 446.81847 -129.518455) (xy 446.75568 -129.506477) (xy 446.694887 -129.486724) (xy 446.637048 -129.459507)
			(xy 446.583077 -129.425256) (xy 446.533824 -129.384511) (xy 446.490067 -129.337914) (xy 446.452494 -129.286199)
			(xy 446.4217 -129.230184) (xy 446.398168 -129.170751) (xy 446.382271 -129.108837) (xy 446.37426 -129.045419)
			(xy 438.513728 -129.045419) (xy 438.513728 -129.078736) (xy 438.514158 -129.088803) (xy 438.521885 -129.107395)
			(xy 438.528714 -129.114804) (xy 439.739743 -130.325833) (xy 444.897758 -130.325833) (xy 444.897758 -130.261911)
			(xy 444.905769 -130.198493) (xy 444.921666 -130.136579) (xy 444.945198 -130.077146) (xy 444.975992 -130.021131)
			(xy 445.013565 -129.969416) (xy 445.057322 -129.922819) (xy 445.106575 -129.882074) (xy 445.160546 -129.847823)
			(xy 445.218385 -129.820606) (xy 445.279178 -129.800853) (xy 445.341968 -129.788875) (xy 445.405764 -129.784862)
			(xy 445.46956 -129.788875) (xy 445.53235 -129.800853) (xy 445.593143 -129.820606) (xy 445.650982 -129.847823)
			(xy 445.704953 -129.882074) (xy 445.754206 -129.922819) (xy 445.797963 -129.969416) (xy 445.835536 -130.021131)
			(xy 445.86633 -130.077146) (xy 445.889862 -130.136579) (xy 445.905759 -130.198493) (xy 445.91377 -130.261911)
			(xy 445.914272 -130.293872) (xy 445.91377 -130.325833) (xy 445.905759 -130.389251) (xy 445.889862 -130.451165)
			(xy 445.86633 -130.510598) (xy 445.835536 -130.566613) (xy 445.797963 -130.618328) (xy 445.754206 -130.664925)
			(xy 445.704953 -130.70567) (xy 445.650982 -130.739921) (xy 445.593143 -130.767138) (xy 445.53235 -130.786891)
			(xy 445.46956 -130.798869) (xy 445.405764 -130.802883) (xy 445.341968 -130.798869) (xy 445.279178 -130.786891)
			(xy 445.218385 -130.767138) (xy 445.160546 -130.739921) (xy 445.106575 -130.70567) (xy 445.057322 -130.664925)
			(xy 445.013565 -130.618328) (xy 444.975992 -130.566613) (xy 444.945198 -130.510598) (xy 444.921666 -130.451165)
			(xy 444.905769 -130.389251) (xy 444.897758 -130.325833) (xy 439.739743 -130.325833) (xy 450.51472 -141.10081)
			(xy 450.535294 -141.10843) (xy 450.54647 -141.107414) (xy 450.586602 -141.10589) (xy 450.617333 -141.106354)
			(xy 450.678347 -141.113763) (xy 450.738023 -141.128472) (xy 450.79549 -141.150267) (xy 450.849912 -141.178829)
			(xy 450.900494 -141.213744) (xy 450.946499 -141.254501) (xy 450.987256 -141.300506) (xy 451.022171 -141.351088)
			(xy 451.050733 -141.40551) (xy 451.072528 -141.462977) (xy 451.087237 -141.522653) (xy 451.094646 -141.583667)
			(xy 451.09511 -141.614398) (xy 451.094992 -141.628781) (xy 451.093339 -141.6575) (xy 451.091808 -141.671802)
			(xy 451.090538 -141.68374) (xy 451.098158 -141.70533) (xy 451.941184 -142.548356) (xy 451.941692 -142.548864)
			(xy 451.949076 -142.555439) (xy 451.967375 -142.562874) (xy 451.977252 -142.563342) (xy 455.84872 -142.563342)
			(xy 455.858788 -142.56377) (xy 455.877383 -142.571494) (xy 455.884788 -142.578328) (xy 455.958194 -142.651734)
			(xy 455.965589 -142.658589) (xy 455.984188 -142.666336) (xy 455.994262 -142.66672)
		)
		(stroke
			(width 0)
			(type solid)
		)
		(fill yes)
		(layer "B.Cu")
		(net "P5V_AUX")
	)
	(gr_poly
		(pts
			(xy 83.942428 -34.273236) (xy 83.952305 -34.272775) (xy 83.970604 -34.265333) (xy 83.977988 -34.258758)
			(xy 83.978242 -34.258504) (xy 85.163152 -33.073594) (xy 85.16366 -33.073086) (xy 85.170248 -33.065707)
			(xy 85.177711 -33.047408) (xy 85.178138 -33.037526) (xy 85.178138 -18.408142) (xy 85.177703 -18.398078)
			(xy 85.169966 -18.379495) (xy 85.163152 -18.372074) (xy 83.606132 -16.815054) (xy 83.598786 -16.808248)
			(xy 83.580322 -16.800532) (xy 83.570318 -16.800068) (xy 81.863692 -16.800068) (xy 81.863692 -16.800322)
			(xy 81.257394 -16.800322) (xy 81.228939 -16.799857) (xy 81.172516 -16.79243) (xy 81.117544 -16.777704)
			(xy 81.064964 -16.75593) (xy 81.015675 -16.727481) (xy 80.970519 -16.692844) (xy 80.950054 -16.673068)
			(xy 80.762094 -16.485108) (xy 80.442816 -16.16583) (xy 80.435468 -16.159029) (xy 80.417005 -16.151323)
			(xy 80.407002 -16.150844) (xy 79.270098 -16.150844) (xy 79.260029 -16.151269) (xy 79.241429 -16.158989)
			(xy 79.23403 -16.16583) (xy 78.429866 -16.969994) (xy 78.422466 -16.976836) (xy 78.403868 -16.984559)
			(xy 78.393798 -16.98498) (xy 76.580238 -16.98498) (xy 76.570173 -16.984545) (xy 76.551587 -16.976813)
			(xy 76.54417 -16.969994) (xy 75.740006 -16.16583) (xy 75.732662 -16.159015) (xy 75.7142 -16.151276)
			(xy 75.704192 -16.150844) (xy 74.607166 -16.150844) (xy 74.607166 -16.151098) (xy 74.210164 -16.151098)
			(xy 74.181707 -16.150637) (xy 74.12528 -16.143218) (xy 74.070303 -16.128498) (xy 74.017718 -16.10673)
			(xy 73.968423 -16.078285) (xy 73.923262 -16.043649) (xy 73.902824 -16.023844) (xy 73.80351 -15.92453)
			(xy 73.796113 -15.917679) (xy 73.777515 -15.909936) (xy 73.767442 -15.909544) (xy 71.499222 -15.909544)
			(xy 71.489159 -15.909983) (xy 71.470579 -15.917722) (xy 71.463154 -15.92453) (xy 70.861682 -16.526002)
			(xy 70.854316 -16.533114) (xy 70.846696 -16.55191) (xy 70.846696 -18.4912) (xy 74.739752 -18.4912)
			(xy 74.743823 -18.435578) (xy 74.755949 -18.381141) (xy 74.775872 -18.32905) (xy 74.803168 -18.280415)
			(xy 74.837254 -18.236272) (xy 74.877403 -18.197563) (xy 74.922761 -18.165112) (xy 74.972361 -18.139611)
			(xy 75.025145 -18.121604) (xy 75.079988 -18.111474) (xy 75.135722 -18.109437) (xy 75.191159 -18.115537)
			(xy 75.245116 -18.129643) (xy 75.296445 -18.151455) (xy 75.344051 -18.180509) (xy 75.386919 -18.216184)
			(xy 75.407115 -18.238724) (xy 79.540354 -18.238724) (xy 79.540817 -18.211149) (xy 79.548768 -18.156575)
			(xy 79.564492 -18.103715) (xy 79.587662 -18.053668) (xy 79.617796 -18.007479) (xy 79.654266 -17.966109)
			(xy 79.674974 -17.947894) (xy 79.683102 -17.940301) (xy 79.692448 -17.920142) (xy 79.693008 -17.909032)
			(xy 79.693008 -17.831816) (xy 79.692477 -17.820701) (xy 79.683115 -17.800541) (xy 79.674974 -17.792954)
			(xy 79.654281 -17.774724) (xy 79.61781 -17.733358) (xy 79.587676 -17.687172) (xy 79.564508 -17.637128)
			(xy 79.548787 -17.584269) (xy 79.540842 -17.529697) (xy 79.540354 -17.502124) (xy 79.54084 -17.474873)
			(xy 79.548596 -17.420925) (xy 79.563951 -17.36863) (xy 79.586593 -17.319053) (xy 79.616059 -17.273203)
			(xy 79.65175 -17.232012) (xy 79.692941 -17.196321) (xy 79.738791 -17.166855) (xy 79.788368 -17.144213)
			(xy 79.840663 -17.128858) (xy 79.894611 -17.121102) (xy 79.949113 -17.121102) (xy 80.003061 -17.128858)
			(xy 80.055356 -17.144213) (xy 80.104933 -17.166855) (xy 80.150783 -17.196321) (xy 80.191974 -17.232012)
			(xy 80.227665 -17.273203) (xy 80.257131 -17.319053) (xy 80.279773 -17.36863) (xy 80.295128 -17.420925)
			(xy 80.302884 -17.474873) (xy 80.30337 -17.502124) (xy 80.302862 -17.529697) (xy 80.29492 -17.584269)
			(xy 80.279204 -17.637128) (xy 80.256042 -17.687175) (xy 80.225916 -17.733365) (xy 80.189455 -17.774738)
			(xy 80.16875 -17.792954) (xy 80.160649 -17.800572) (xy 80.151287 -17.820712) (xy 80.150716 -17.831816)
			(xy 80.150716 -17.909032) (xy 80.151245 -17.920147) (xy 80.160611 -17.940305) (xy 80.16875 -17.947894)
			(xy 80.189471 -17.966094) (xy 80.225939 -18.007466) (xy 80.256068 -18.053659) (xy 80.279232 -18.103709)
			(xy 80.294947 -18.156573) (xy 80.302885 -18.211149) (xy 80.30337 -18.238724) (xy 80.302884 -18.265975)
			(xy 80.295128 -18.319923) (xy 80.279773 -18.372218) (xy 80.257131 -18.421795) (xy 80.227665 -18.467645)
			(xy 80.191974 -18.508836) (xy 80.150783 -18.544527) (xy 80.104933 -18.573993) (xy 80.055356 -18.596635)
			(xy 80.031233 -18.603718) (xy 81.593926 -18.603718) (xy 81.593926 -18.543782) (xy 81.601749 -18.48436)
			(xy 81.617262 -18.426467) (xy 81.640198 -18.371094) (xy 81.670165 -18.319188) (xy 81.706652 -18.271638)
			(xy 81.749032 -18.229258) (xy 81.796582 -18.192771) (xy 81.848488 -18.162804) (xy 81.903861 -18.139868)
			(xy 81.961754 -18.124355) (xy 82.021176 -18.116532) (xy 82.081112 -18.116532) (xy 82.140534 -18.124355)
			(xy 82.198427 -18.139868) (xy 82.2538 -18.162804) (xy 82.305706 -18.192771) (xy 82.353256 -18.229258)
			(xy 82.395636 -18.271638) (xy 82.432123 -18.319188) (xy 82.46209 -18.371094) (xy 82.485026 -18.426467)
			(xy 82.500539 -18.48436) (xy 82.508362 -18.543782) (xy 82.508852 -18.57375) (xy 82.508362 -18.603718)
			(xy 82.500539 -18.66314) (xy 82.485026 -18.721033) (xy 82.46209 -18.776406) (xy 82.432123 -18.828312)
			(xy 82.395636 -18.875862) (xy 82.353256 -18.918242) (xy 82.305706 -18.954729) (xy 82.2538 -18.984696)
			(xy 82.198427 -19.007632) (xy 82.140534 -19.023145) (xy 82.081112 -19.030968) (xy 82.021176 -19.030968)
			(xy 81.961754 -19.023145) (xy 81.903861 -19.007632) (xy 81.848488 -18.984696) (xy 81.796582 -18.954729)
			(xy 81.749032 -18.918242) (xy 81.706652 -18.875862) (xy 81.670165 -18.828312) (xy 81.640198 -18.776406)
			(xy 81.617262 -18.721033) (xy 81.601749 -18.66314) (xy 81.593926 -18.603718) (xy 80.031233 -18.603718)
			(xy 80.003061 -18.61199) (xy 79.949113 -18.619746) (xy 79.894611 -18.619746) (xy 79.840663 -18.61199)
			(xy 79.788368 -18.596635) (xy 79.738791 -18.573993) (xy 79.692941 -18.544527) (xy 79.65175 -18.508836)
			(xy 79.616059 -18.467645) (xy 79.586593 -18.421795) (xy 79.563951 -18.372218) (xy 79.548596 -18.319923)
			(xy 79.54084 -18.265975) (xy 79.540354 -18.238724) (xy 75.407115 -18.238724) (xy 75.424136 -18.257721)
			(xy 75.454909 -18.304234) (xy 75.478581 -18.354731) (xy 75.494649 -18.408138) (xy 75.502769 -18.463314)
			(xy 75.503278 -18.4912) (xy 75.502769 -18.519086) (xy 75.494649 -18.574262) (xy 75.478581 -18.627669)
			(xy 75.454909 -18.678166) (xy 75.424136 -18.724679) (xy 75.403249 -18.74799) (xy 77.221062 -18.74799)
			(xy 77.221062 -18.688054) (xy 77.228885 -18.628632) (xy 77.244398 -18.570739) (xy 77.267334 -18.515366)
			(xy 77.297301 -18.46346) (xy 77.333788 -18.41591) (xy 77.376168 -18.37353) (xy 77.423718 -18.337043)
			(xy 77.475624 -18.307076) (xy 77.530997 -18.28414) (xy 77.58889 -18.268627) (xy 77.648312 -18.260804)
			(xy 77.708248 -18.260804) (xy 77.76767 -18.268627) (xy 77.825563 -18.28414) (xy 77.880936 -18.307076)
			(xy 77.932842 -18.337043) (xy 77.980392 -18.37353) (xy 78.022772 -18.41591) (xy 78.059259 -18.46346)
			(xy 78.089226 -18.515366) (xy 78.112162 -18.570739) (xy 78.127675 -18.628632) (xy 78.135498 -18.688054)
			(xy 78.135988 -18.718022) (xy 78.135498 -18.74799) (xy 78.127675 -18.807412) (xy 78.112162 -18.865305)
			(xy 78.089226 -18.920678) (xy 78.059259 -18.972584) (xy 78.022772 -19.020134) (xy 77.980392 -19.062514)
			(xy 77.932842 -19.099001) (xy 77.880936 -19.128968) (xy 77.825563 -19.151904) (xy 77.76767 -19.167417)
			(xy 77.708248 -19.17524) (xy 77.648312 -19.17524) (xy 77.58889 -19.167417) (xy 77.530997 -19.151904)
			(xy 77.475624 -19.128968) (xy 77.423718 -19.099001) (xy 77.376168 -19.062514) (xy 77.333788 -19.020134)
			(xy 77.297301 -18.972584) (xy 77.267334 -18.920678) (xy 77.244398 -18.865305) (xy 77.228885 -18.807412)
			(xy 77.221062 -18.74799) (xy 75.403249 -18.74799) (xy 75.386919 -18.766216) (xy 75.344051 -18.801891)
			(xy 75.296445 -18.830945) (xy 75.245116 -18.852757) (xy 75.191159 -18.866863) (xy 75.135722 -18.872963)
			(xy 75.079988 -18.870926) (xy 75.025145 -18.860796) (xy 74.972361 -18.842789) (xy 74.922761 -18.817288)
			(xy 74.877403 -18.784837) (xy 74.837254 -18.746128) (xy 74.803168 -18.701985) (xy 74.775872 -18.65335)
			(xy 74.755949 -18.601259) (xy 74.743823 -18.546822) (xy 74.739752 -18.4912) (xy 70.846696 -18.4912)
			(xy 70.846696 -19.251672) (xy 76.02396 -19.251672) (xy 76.02396 -19.191736) (xy 76.031783 -19.132314)
			(xy 76.047296 -19.074421) (xy 76.070232 -19.019048) (xy 76.100199 -18.967142) (xy 76.136686 -18.919592)
			(xy 76.179066 -18.877212) (xy 76.226616 -18.840725) (xy 76.278522 -18.810758) (xy 76.333895 -18.787822)
			(xy 76.391788 -18.772309) (xy 76.45121 -18.764486) (xy 76.511146 -18.764486) (xy 76.570568 -18.772309)
			(xy 76.628461 -18.787822) (xy 76.683834 -18.810758) (xy 76.73574 -18.840725) (xy 76.78329 -18.877212)
			(xy 76.82567 -18.919592) (xy 76.862157 -18.967142) (xy 76.892124 -19.019048) (xy 76.91506 -19.074421)
			(xy 76.930573 -19.132314) (xy 76.938396 -19.191736) (xy 76.938886 -19.221704) (xy 76.938396 -19.251672)
			(xy 76.931073 -19.307298) (xy 78.398352 -19.307298) (xy 78.398352 -19.247362) (xy 78.406175 -19.18794)
			(xy 78.421688 -19.130047) (xy 78.444624 -19.074674) (xy 78.474591 -19.022768) (xy 78.511078 -18.975218)
			(xy 78.553458 -18.932838) (xy 78.601008 -18.896351) (xy 78.652914 -18.866384) (xy 78.708287 -18.843448)
			(xy 78.76618 -18.827935) (xy 78.825602 -18.820112) (xy 78.885538 -18.820112) (xy 78.94496 -18.827935)
			(xy 79.002853 -18.843448) (xy 79.058226 -18.866384) (xy 79.110132 -18.896351) (xy 79.157682 -18.932838)
			(xy 79.200062 -18.975218) (xy 79.236549 -19.022768) (xy 79.266516 -19.074674) (xy 79.289452 -19.130047)
			(xy 79.304965 -19.18794) (xy 79.312788 -19.247362) (xy 79.313278 -19.27733) (xy 79.312788 -19.307298)
			(xy 79.304965 -19.36672) (xy 79.289452 -19.424613) (xy 79.266516 -19.479986) (xy 79.236549 -19.531892)
			(xy 79.200062 -19.579442) (xy 79.157682 -19.621822) (xy 79.110132 -19.658309) (xy 79.058226 -19.688276)
			(xy 79.002853 -19.711212) (xy 78.94496 -19.726725) (xy 78.885538 -19.734548) (xy 78.825602 -19.734548)
			(xy 78.76618 -19.726725) (xy 78.708287 -19.711212) (xy 78.652914 -19.688276) (xy 78.601008 -19.658309)
			(xy 78.553458 -19.621822) (xy 78.511078 -19.579442) (xy 78.474591 -19.531892) (xy 78.444624 -19.479986)
			(xy 78.421688 -19.424613) (xy 78.406175 -19.36672) (xy 78.398352 -19.307298) (xy 76.931073 -19.307298)
			(xy 76.930573 -19.311094) (xy 76.91506 -19.368987) (xy 76.892124 -19.42436) (xy 76.862157 -19.476266)
			(xy 76.82567 -19.523816) (xy 76.78329 -19.566196) (xy 76.73574 -19.602683) (xy 76.683834 -19.63265)
			(xy 76.628461 -19.655586) (xy 76.570568 -19.671099) (xy 76.511146 -19.678922) (xy 76.45121 -19.678922)
			(xy 76.391788 -19.671099) (xy 76.333895 -19.655586) (xy 76.278522 -19.63265) (xy 76.226616 -19.602683)
			(xy 76.179066 -19.566196) (xy 76.136686 -19.523816) (xy 76.100199 -19.476266) (xy 76.070232 -19.42436)
			(xy 76.047296 -19.368987) (xy 76.031783 -19.311094) (xy 76.02396 -19.251672) (xy 70.846696 -19.251672)
			(xy 70.846696 -19.752567) (xy 80.871074 -19.752567) (xy 80.871074 -19.692633) (xy 80.878896 -19.633213)
			(xy 80.894407 -19.575322) (xy 80.917341 -19.519951) (xy 80.947306 -19.468046) (xy 80.98379 -19.420497)
			(xy 81.026167 -19.378116) (xy 81.073713 -19.341629) (xy 81.125615 -19.311659) (xy 81.180984 -19.28872)
			(xy 81.238874 -19.273204) (xy 81.298294 -19.265377) (xy 81.32826 -19.264884) (xy 81.358064 -19.265333)
			(xy 81.417168 -19.27306) (xy 81.474771 -19.288389) (xy 81.529898 -19.31106) (xy 81.581619 -19.340692)
			(xy 81.605628 -19.358356) (xy 81.61401 -19.36496) (xy 81.63433 -19.369786) (xy 81.728564 -19.353784)
			(xy 81.74609 -19.342354) (xy 81.751932 -19.333464) (xy 81.767147 -19.311192) (xy 81.80282 -19.270736)
			(xy 81.843836 -19.23571) (xy 81.889379 -19.206811) (xy 81.938538 -19.184617) (xy 81.990334 -19.169571)
			(xy 82.043733 -19.161972) (xy 82.070702 -19.161506) (xy 82.097954 -19.161964) (xy 82.151904 -19.169721)
			(xy 82.2042 -19.185077) (xy 82.253779 -19.207719) (xy 82.299631 -19.237186) (xy 82.340822 -19.272879)
			(xy 82.376515 -19.314071) (xy 82.405982 -19.359923) (xy 82.428624 -19.409502) (xy 82.443979 -19.461798)
			(xy 82.451736 -19.515748) (xy 82.451736 -19.570252) (xy 82.443979 -19.624202) (xy 82.428624 -19.676498)
			(xy 82.405982 -19.726077) (xy 82.376515 -19.771929) (xy 82.340822 -19.813121) (xy 82.299631 -19.848814)
			(xy 82.253779 -19.878281) (xy 82.2042 -19.900923) (xy 82.151904 -19.916279) (xy 82.097954 -19.924036)
			(xy 82.070702 -19.924522) (xy 82.046166 -19.924147) (xy 81.997497 -19.917865) (xy 81.950032 -19.905404)
			(xy 81.904554 -19.88697) (xy 81.882996 -19.875246) (xy 81.873598 -19.869912) (xy 81.85277 -19.867626)
			(xy 81.761838 -19.896328) (xy 81.745836 -19.910298) (xy 81.741264 -19.919696) (xy 81.728556 -19.945352)
			(xy 81.697647 -19.993547) (xy 81.660968 -20.037511) (xy 81.619093 -20.076557) (xy 81.572674 -20.110074)
			(xy 81.522437 -20.137541) (xy 81.469166 -20.158527) (xy 81.413695 -20.172705) (xy 81.356887 -20.179853)
			(xy 81.32826 -20.1803) (xy 81.298294 -20.179823) (xy 81.238874 -20.171996) (xy 81.180984 -20.15648)
			(xy 81.125615 -20.133541) (xy 81.073713 -20.103571) (xy 81.026167 -20.067084) (xy 80.98379 -20.024703)
			(xy 80.947306 -19.977154) (xy 80.917341 -19.925249) (xy 80.894407 -19.869878) (xy 80.878896 -19.811987)
			(xy 80.871074 -19.752567) (xy 70.846696 -19.752567) (xy 70.846696 -20.69084) (xy 70.866762 -20.71751)
			(xy 70.883018 -20.72259) (xy 70.908918 -20.730795) (xy 70.958267 -20.753518) (xy 71.003892 -20.783016)
			(xy 71.044868 -20.81869) (xy 71.080366 -20.859818) (xy 71.109667 -20.905569) (xy 71.132179 -20.955015)
			(xy 71.147444 -21.007155) (xy 71.155155 -21.060934) (xy 71.155155 -21.086568) (xy 76.194902 -21.086568)
			(xy 76.194902 -21.026632) (xy 76.202725 -20.96721) (xy 76.218238 -20.909317) (xy 76.241174 -20.853944)
			(xy 76.271141 -20.802038) (xy 76.307628 -20.754488) (xy 76.350008 -20.712108) (xy 76.397558 -20.675621)
			(xy 76.449464 -20.645654) (xy 76.504837 -20.622718) (xy 76.56273 -20.607205) (xy 76.622152 -20.599382)
			(xy 76.682088 -20.599382) (xy 76.74151 -20.607205) (xy 76.799403 -20.622718) (xy 76.854776 -20.645654)
			(xy 76.906682 -20.675621) (xy 76.954232 -20.712108) (xy 76.996612 -20.754488) (xy 77.033099 -20.802038)
			(xy 77.063066 -20.853944) (xy 77.086002 -20.909317) (xy 77.101515 -20.96721) (xy 77.109338 -21.026632)
			(xy 77.109828 -21.0566) (xy 77.109338 -21.086568) (xy 77.101515 -21.14599) (xy 77.086002 -21.203883)
			(xy 77.063066 -21.259256) (xy 77.033099 -21.311162) (xy 76.996612 -21.358712) (xy 76.954232 -21.401092)
			(xy 76.906682 -21.437579) (xy 76.889494 -21.447502) (xy 81.552016 -21.447502) (xy 81.552016 -21.387566)
			(xy 81.559839 -21.328144) (xy 81.575352 -21.270251) (xy 81.598288 -21.214878) (xy 81.628255 -21.162972)
			(xy 81.664742 -21.115422) (xy 81.707122 -21.073042) (xy 81.754672 -21.036555) (xy 81.806578 -21.006588)
			(xy 81.861951 -20.983652) (xy 81.919844 -20.968139) (xy 81.979266 -20.960316) (xy 82.039202 -20.960316)
			(xy 82.098624 -20.968139) (xy 82.156517 -20.983652) (xy 82.21189 -21.006588) (xy 82.263796 -21.036555)
			(xy 82.311346 -21.073042) (xy 82.353726 -21.115422) (xy 82.390213 -21.162972) (xy 82.42018 -21.214878)
			(xy 82.443116 -21.270251) (xy 82.458629 -21.328144) (xy 82.466452 -21.387566) (xy 82.466942 -21.417534)
			(xy 82.466452 -21.447502) (xy 82.458629 -21.506924) (xy 82.443116 -21.564817) (xy 82.42018 -21.62019)
			(xy 82.390213 -21.672096) (xy 82.353726 -21.719646) (xy 82.311346 -21.762026) (xy 82.263796 -21.798513)
			(xy 82.21189 -21.82848) (xy 82.156517 -21.851416) (xy 82.098624 -21.866929) (xy 82.039202 -21.874752)
			(xy 81.979266 -21.874752) (xy 81.919844 -21.866929) (xy 81.861951 -21.851416) (xy 81.806578 -21.82848)
			(xy 81.754672 -21.798513) (xy 81.707122 -21.762026) (xy 81.664742 -21.719646) (xy 81.628255 -21.672096)
			(xy 81.598288 -21.62019) (xy 81.575352 -21.564817) (xy 81.559839 -21.506924) (xy 81.552016 -21.447502)
			(xy 76.889494 -21.447502) (xy 76.854776 -21.467546) (xy 76.799403 -21.490482) (xy 76.74151 -21.505995)
			(xy 76.682088 -21.513818) (xy 76.622152 -21.513818) (xy 76.56273 -21.505995) (xy 76.504837 -21.490482)
			(xy 76.449464 -21.467546) (xy 76.397558 -21.437579) (xy 76.350008 -21.401092) (xy 76.307628 -21.358712)
			(xy 76.271141 -21.311162) (xy 76.241174 -21.259256) (xy 76.218238 -21.203883) (xy 76.202725 -21.14599)
			(xy 76.194902 -21.086568) (xy 71.155155 -21.086568) (xy 71.155156 -21.115263) (xy 71.147445 -21.169043)
			(xy 71.132179 -21.221183) (xy 71.109668 -21.270629) (xy 71.080367 -21.31638) (xy 71.044869 -21.357509)
			(xy 71.003893 -21.393183) (xy 70.958269 -21.422681) (xy 70.90892 -21.445404) (xy 70.883018 -21.453602)
			(xy 70.866762 -21.458682) (xy 70.846696 -21.485352) (xy 70.846696 -22.559768) (xy 75.48929 -22.559768)
			(xy 75.48929 -22.499832) (xy 75.497113 -22.44041) (xy 75.512626 -22.382517) (xy 75.535562 -22.327144)
			(xy 75.565529 -22.275238) (xy 75.602016 -22.227688) (xy 75.644396 -22.185308) (xy 75.691946 -22.148821)
			(xy 75.743852 -22.118854) (xy 75.799225 -22.095918) (xy 75.857118 -22.080405) (xy 75.91654 -22.072582)
			(xy 75.976476 -22.072582) (xy 76.035898 -22.080405) (xy 76.093791 -22.095918) (xy 76.149164 -22.118854)
			(xy 76.20107 -22.148821) (xy 76.24862 -22.185308) (xy 76.291 -22.227688) (xy 76.327487 -22.275238)
			(xy 76.357454 -22.327144) (xy 76.38039 -22.382517) (xy 76.395903 -22.44041) (xy 76.403726 -22.499832)
			(xy 76.404216 -22.5298) (xy 76.403726 -22.559768) (xy 76.395903 -22.61919) (xy 76.395354 -22.62124)
			(xy 78.970122 -22.62124) (xy 78.974193 -22.565618) (xy 78.986319 -22.511181) (xy 79.006242 -22.45909)
			(xy 79.033538 -22.410455) (xy 79.067624 -22.366312) (xy 79.107773 -22.327603) (xy 79.153131 -22.295152)
			(xy 79.202731 -22.269651) (xy 79.255515 -22.251644) (xy 79.310358 -22.241514) (xy 79.366092 -22.239477)
			(xy 79.421529 -22.245577) (xy 79.475486 -22.259683) (xy 79.526815 -22.281495) (xy 79.574421 -22.310549)
			(xy 79.617289 -22.346224) (xy 79.654506 -22.387761) (xy 79.685279 -22.434274) (xy 79.708951 -22.484771)
			(xy 79.725019 -22.538178) (xy 79.733139 -22.593354) (xy 79.733648 -22.62124) (xy 79.733365 -22.63673)
			(xy 80.05621 -22.63673) (xy 80.05621 -22.576794) (xy 80.064033 -22.517372) (xy 80.079546 -22.459479)
			(xy 80.102482 -22.404106) (xy 80.132449 -22.3522) (xy 80.168936 -22.30465) (xy 80.211316 -22.26227)
			(xy 80.258866 -22.225783) (xy 80.310772 -22.195816) (xy 80.366145 -22.17288) (xy 80.424038 -22.157367)
			(xy 80.48346 -22.149544) (xy 80.543396 -22.149544) (xy 80.602818 -22.157367) (xy 80.660711 -22.17288)
			(xy 80.716084 -22.195816) (xy 80.76799 -22.225783) (xy 80.81554 -22.26227) (xy 80.85792 -22.30465)
			(xy 80.894407 -22.3522) (xy 80.924374 -22.404106) (xy 80.94731 -22.459479) (xy 80.962823 -22.517372)
			(xy 80.970646 -22.576794) (xy 80.971136 -22.606762) (xy 80.970646 -22.63673) (xy 80.962823 -22.696152)
			(xy 80.94731 -22.754045) (xy 80.924374 -22.809418) (xy 80.894407 -22.861324) (xy 80.85792 -22.908874)
			(xy 80.81554 -22.951254) (xy 80.76799 -22.987741) (xy 80.716084 -23.017708) (xy 80.660711 -23.040644)
			(xy 80.602818 -23.056157) (xy 80.543396 -23.06398) (xy 80.48346 -23.06398) (xy 80.424038 -23.056157)
			(xy 80.366145 -23.040644) (xy 80.310772 -23.017708) (xy 80.258866 -22.987741) (xy 80.211316 -22.951254)
			(xy 80.168936 -22.908874) (xy 80.132449 -22.861324) (xy 80.102482 -22.809418) (xy 80.079546 -22.754045)
			(xy 80.064033 -22.696152) (xy 80.05621 -22.63673) (xy 79.733365 -22.63673) (xy 79.733139 -22.649126)
			(xy 79.725019 -22.704302) (xy 79.708951 -22.757709) (xy 79.685279 -22.808206) (xy 79.654506 -22.854719)
			(xy 79.617289 -22.896256) (xy 79.574421 -22.931931) (xy 79.526815 -22.960985) (xy 79.475486 -22.982797)
			(xy 79.421529 -22.996903) (xy 79.366092 -23.003003) (xy 79.310358 -23.000966) (xy 79.255515 -22.990836)
			(xy 79.202731 -22.972829) (xy 79.153131 -22.947328) (xy 79.107773 -22.914877) (xy 79.067624 -22.876168)
			(xy 79.033538 -22.832025) (xy 79.006242 -22.78339) (xy 78.986319 -22.731299) (xy 78.974193 -22.676862)
			(xy 78.970122 -22.62124) (xy 76.395354 -22.62124) (xy 76.38039 -22.677083) (xy 76.357454 -22.732456)
			(xy 76.327487 -22.784362) (xy 76.291 -22.831912) (xy 76.24862 -22.874292) (xy 76.20107 -22.910779)
			(xy 76.149164 -22.940746) (xy 76.093791 -22.963682) (xy 76.035898 -22.979195) (xy 75.976476 -22.987018)
			(xy 75.91654 -22.987018) (xy 75.857118 -22.979195) (xy 75.799225 -22.963682) (xy 75.743852 -22.940746)
			(xy 75.691946 -22.910779) (xy 75.644396 -22.874292) (xy 75.602016 -22.831912) (xy 75.565529 -22.784362)
			(xy 75.535562 -22.732456) (xy 75.512626 -22.677083) (xy 75.497113 -22.61919) (xy 75.48929 -22.559768)
			(xy 70.846696 -22.559768) (xy 70.846696 -24.344626) (xy 77.728046 -24.344626) (xy 77.728046 -24.28469)
			(xy 77.735869 -24.225268) (xy 77.751382 -24.167375) (xy 77.774318 -24.112002) (xy 77.804285 -24.060096)
			(xy 77.840772 -24.012546) (xy 77.883152 -23.970166) (xy 77.930702 -23.933679) (xy 77.982608 -23.903712)
			(xy 78.037981 -23.880776) (xy 78.095874 -23.865263) (xy 78.155296 -23.85744) (xy 78.215232 -23.85744)
			(xy 78.274654 -23.865263) (xy 78.332547 -23.880776) (xy 78.38792 -23.903712) (xy 78.439826 -23.933679)
			(xy 78.487376 -23.970166) (xy 78.529756 -24.012546) (xy 78.566243 -24.060096) (xy 78.59621 -24.112002)
			(xy 78.619146 -24.167375) (xy 78.634659 -24.225268) (xy 78.642482 -24.28469) (xy 78.642972 -24.314658)
			(xy 78.642482 -24.344626) (xy 78.634659 -24.404048) (xy 78.619146 -24.461941) (xy 78.59621 -24.517314)
			(xy 78.566243 -24.56922) (xy 78.529756 -24.61677) (xy 78.487376 -24.65915) (xy 78.439826 -24.695637)
			(xy 78.38792 -24.725604) (xy 78.332547 -24.74854) (xy 78.274654 -24.764053) (xy 78.215232 -24.771876)
			(xy 78.155296 -24.771876) (xy 78.095874 -24.764053) (xy 78.037981 -24.74854) (xy 77.982608 -24.725604)
			(xy 77.930702 -24.695637) (xy 77.883152 -24.65915) (xy 77.840772 -24.61677) (xy 77.804285 -24.56922)
			(xy 77.774318 -24.517314) (xy 77.751382 -24.461941) (xy 77.735869 -24.404048) (xy 77.728046 -24.344626)
			(xy 70.846696 -24.344626) (xy 70.846696 -24.973026) (xy 70.846268 -24.983094) (xy 70.838546 -25.001691)
			(xy 70.83171 -25.009094) (xy 69.661786 -26.179018) (xy 69.654933 -26.186413) (xy 69.647192 -26.205012)
			(xy 69.6468 -26.215086) (xy 69.6468 -26.698748) (xy 72.098702 -26.698748) (xy 72.098702 -26.644252)
			(xy 72.106457 -26.590311) (xy 72.121809 -26.538023) (xy 72.144446 -26.488451) (xy 72.173907 -26.442606)
			(xy 72.209592 -26.401419) (xy 72.250775 -26.36573) (xy 72.296618 -26.336265) (xy 72.346187 -26.313623)
			(xy 72.398474 -26.298265) (xy 72.452414 -26.290505) (xy 72.479662 -26.290016) (xy 72.506918 -26.290539)
			(xy 72.560875 -26.2983) (xy 72.613179 -26.313655) (xy 72.662769 -26.336293) (xy 72.708635 -26.365753)
			(xy 72.749845 -26.401436) (xy 72.785561 -26.442618) (xy 72.800718 -26.465276) (xy 72.808999 -26.477203)
			(xy 72.830935 -26.496207) (xy 72.857335 -26.508262) (xy 72.886062 -26.512392) (xy 72.914789 -26.508262)
			(xy 72.941189 -26.496207) (xy 72.963125 -26.477203) (xy 72.971406 -26.465276) (xy 72.986521 -26.442586)
			(xy 73.022236 -26.401392) (xy 73.063449 -26.365699) (xy 73.109321 -26.336234) (xy 73.15892 -26.313597)
			(xy 73.211235 -26.298247) (xy 73.265202 -26.290498) (xy 73.292462 -26.290016) (xy 73.319718 -26.290428)
			(xy 73.373677 -26.298181) (xy 73.425983 -26.313535) (xy 73.475571 -26.336177) (xy 73.521432 -26.365646)
			(xy 73.562631 -26.401342) (xy 73.598331 -26.442538) (xy 73.627805 -26.488396) (xy 73.650452 -26.537982)
			(xy 73.665811 -26.590286) (xy 73.673569 -26.644244) (xy 73.673569 -26.698756) (xy 73.665811 -26.752714)
			(xy 73.650452 -26.805018) (xy 73.627805 -26.854604) (xy 73.598331 -26.900462) (xy 73.562631 -26.941658)
			(xy 73.521432 -26.977354) (xy 73.475571 -27.006823) (xy 73.425983 -27.029465) (xy 73.373677 -27.044819)
			(xy 73.319718 -27.052572) (xy 73.292462 -27.053032) (xy 73.265206 -27.052515) (xy 73.211247 -27.044756)
			(xy 73.158942 -27.029401) (xy 73.109351 -27.006763) (xy 73.063485 -26.977302) (xy 73.022276 -26.941616)
			(xy 72.986561 -26.900432) (xy 72.971406 -26.877772) (xy 72.963125 -26.865845) (xy 72.941189 -26.846841)
			(xy 72.914789 -26.834786) (xy 72.886062 -26.830656) (xy 72.857335 -26.834786) (xy 72.830935 -26.846841)
			(xy 72.808999 -26.865845) (xy 72.800718 -26.877772) (xy 72.78557 -26.900439) (xy 72.749863 -26.941636)
			(xy 72.708656 -26.977332) (xy 72.662789 -27.006801) (xy 72.613195 -27.029442) (xy 72.560884 -27.044796)
			(xy 72.506921 -27.052549) (xy 72.479662 -27.053032) (xy 72.452414 -27.052495) (xy 72.398474 -27.044735)
			(xy 72.346187 -27.029377) (xy 72.296618 -27.006735) (xy 72.250775 -26.97727) (xy 72.209592 -26.941581)
			(xy 72.173907 -26.900394) (xy 72.144446 -26.854549) (xy 72.121809 -26.804977) (xy 72.106457 -26.752689)
			(xy 72.098702 -26.698748) (xy 69.6468 -26.698748) (xy 69.6468 -27.916124) (xy 70.955154 -27.916124)
			(xy 70.955705 -27.887386) (xy 70.964323 -27.830561) (xy 70.981367 -27.775671) (xy 71.006452 -27.723959)
			(xy 71.039011 -27.676594) (xy 71.058278 -27.655266) (xy 71.064882 -27.648154) (xy 71.071994 -27.630628)
			(xy 71.071994 -27.54122) (xy 71.064882 -27.523694) (xy 71.058278 -27.516582) (xy 71.039025 -27.495239)
			(xy 71.006455 -27.447882) (xy 70.981358 -27.396175) (xy 70.964304 -27.341287) (xy 70.955677 -27.284462)
			(xy 70.955154 -27.255724) (xy 70.95564 -27.228473) (xy 70.963396 -27.174525) (xy 70.978751 -27.12223)
			(xy 71.001393 -27.072653) (xy 71.030859 -27.026803) (xy 71.06655 -26.985612) (xy 71.107741 -26.949921)
			(xy 71.153591 -26.920455) (xy 71.203168 -26.897813) (xy 71.255463 -26.882458) (xy 71.309411 -26.874702)
			(xy 71.363913 -26.874702) (xy 71.417861 -26.882458) (xy 71.470156 -26.897813) (xy 71.519733 -26.920455)
			(xy 71.565583 -26.949921) (xy 71.606774 -26.985612) (xy 71.642465 -27.026803) (xy 71.671931 -27.072653)
			(xy 71.694573 -27.12223) (xy 71.709928 -27.174525) (xy 71.717684 -27.228473) (xy 71.71817 -27.255724)
			(xy 71.717642 -27.284463) (xy 71.709018 -27.341289) (xy 71.691968 -27.396179) (xy 71.666877 -27.447891)
			(xy 71.634315 -27.495254) (xy 71.615046 -27.516582) (xy 71.608442 -27.523694) (xy 71.60133 -27.54122)
			(xy 71.60133 -27.630628) (xy 71.608442 -27.648154) (xy 71.615046 -27.655266) (xy 71.634325 -27.676586)
			(xy 71.666891 -27.723949) (xy 71.691982 -27.775663) (xy 71.709031 -27.830555) (xy 71.717651 -27.887384)
			(xy 71.71817 -27.916124) (xy 71.717684 -27.943375) (xy 71.709928 -27.997323) (xy 71.694573 -28.049618)
			(xy 71.671931 -28.099195) (xy 71.642465 -28.145045) (xy 71.606774 -28.186236) (xy 71.565583 -28.221927)
			(xy 71.519733 -28.251393) (xy 71.470156 -28.274035) (xy 71.417861 -28.28939) (xy 71.363913 -28.297146)
			(xy 71.309411 -28.297146) (xy 71.255463 -28.28939) (xy 71.203168 -28.274035) (xy 71.153591 -28.251393)
			(xy 71.107741 -28.221927) (xy 71.06655 -28.186236) (xy 71.030859 -28.145045) (xy 71.001393 -28.099195)
			(xy 70.978751 -28.049618) (xy 70.963396 -27.997323) (xy 70.95564 -27.943375) (xy 70.955154 -27.916124)
			(xy 69.6468 -27.916124) (xy 69.6468 -28.652724) (xy 76.117958 -28.652724) (xy 76.118394 -28.626408)
			(xy 76.12562 -28.574273) (xy 76.139937 -28.523625) (xy 76.161075 -28.475424) (xy 76.188632 -28.430582)
			(xy 76.222087 -28.38995) (xy 76.241148 -28.3718) (xy 76.248544 -28.364273) (xy 76.257073 -28.344997)
			(xy 76.257658 -28.334462) (xy 76.257658 -28.259786) (xy 76.257162 -28.249232) (xy 76.248605 -28.229936)
			(xy 76.241148 -28.222448) (xy 76.222053 -28.204329) (xy 76.188574 -28.163706) (xy 76.161005 -28.118863)
			(xy 76.139868 -28.070652) (xy 76.125568 -28.019991) (xy 76.118375 -27.967845) (xy 76.117958 -27.941524)
			(xy 76.11842 -27.913949) (xy 76.12637 -27.859375) (xy 76.142095 -27.806514) (xy 76.165265 -27.756468)
			(xy 76.1954 -27.710279) (xy 76.23187 -27.668909) (xy 76.252578 -27.650694) (xy 76.260707 -27.643102)
			(xy 76.270052 -27.622942) (xy 76.270612 -27.611832) (xy 76.270612 -27.534616) (xy 76.270079 -27.523501)
			(xy 76.260719 -27.503341) (xy 76.252578 -27.495754) (xy 76.231885 -27.477523) (xy 76.195415 -27.436158)
			(xy 76.165281 -27.389972) (xy 76.142112 -27.339928) (xy 76.126391 -27.287069) (xy 76.118446 -27.232497)
			(xy 76.117958 -27.204924) (xy 76.118444 -27.177673) (xy 76.1262 -27.123725) (xy 76.141555 -27.07143)
			(xy 76.164197 -27.021853) (xy 76.193663 -26.976003) (xy 76.229354 -26.934812) (xy 76.270545 -26.899121)
			(xy 76.316395 -26.869655) (xy 76.365972 -26.847013) (xy 76.418267 -26.831658) (xy 76.472215 -26.823902)
			(xy 76.526717 -26.823902) (xy 76.580665 -26.831658) (xy 76.63296 -26.847013) (xy 76.682537 -26.869655)
			(xy 76.728387 -26.899121) (xy 76.769578 -26.934812) (xy 76.805269 -26.976003) (xy 76.834735 -27.021853)
			(xy 76.857377 -27.07143) (xy 76.872732 -27.123725) (xy 76.880488 -27.177673) (xy 76.880974 -27.204924)
			(xy 76.880465 -27.232497) (xy 76.872523 -27.287068) (xy 76.856807 -27.339928) (xy 76.833645 -27.389974)
			(xy 76.80352 -27.436165) (xy 76.767058 -27.477537) (xy 76.746354 -27.495754) (xy 76.738254 -27.503372)
			(xy 76.728891 -27.523512) (xy 76.72832 -27.534616) (xy 76.72832 -27.611832) (xy 76.728848 -27.622947)
			(xy 76.738214 -27.643106) (xy 76.746354 -27.650694) (xy 76.767056 -27.668915) (xy 76.803529 -27.710281)
			(xy 76.833664 -27.756468) (xy 76.856831 -27.806514) (xy 76.872549 -27.859376) (xy 76.880489 -27.91395)
			(xy 76.880974 -27.941524) (xy 76.880525 -27.96784) (xy 76.873305 -28.019975) (xy 76.858992 -28.070623)
			(xy 76.837857 -28.118826) (xy 76.8103 -28.163667) (xy 76.776845 -28.204298) (xy 76.757784 -28.222448)
			(xy 76.750357 -28.229948) (xy 76.741848 -28.249244) (xy 76.741274 -28.259786) (xy 76.741274 -28.334462)
			(xy 76.741818 -28.34501) (xy 76.750344 -28.364305) (xy 76.757784 -28.3718) (xy 76.77686 -28.389938)
			(xy 76.810339 -28.430557) (xy 76.837911 -28.475397) (xy 76.85905 -28.523604) (xy 76.873355 -28.574261)
			(xy 76.880553 -28.626405) (xy 76.880974 -28.652724) (xy 78.625954 -28.652724) (xy 78.626391 -28.626408)
			(xy 78.633617 -28.574273) (xy 78.647934 -28.523626) (xy 78.669071 -28.475424) (xy 78.696629 -28.430582)
			(xy 78.730083 -28.38995) (xy 78.749144 -28.3718) (xy 78.756539 -28.364273) (xy 78.765069 -28.344997)
			(xy 78.765654 -28.334462) (xy 78.765654 -28.259786) (xy 78.76516 -28.249232) (xy 78.756601 -28.229936)
			(xy 78.749144 -28.222448) (xy 78.730048 -28.20433) (xy 78.69657 -28.163707) (xy 78.669 -28.118863)
			(xy 78.647864 -28.070652) (xy 78.633564 -28.019991) (xy 78.626371 -27.967845) (xy 78.625954 -27.941524)
			(xy 78.626417 -27.913949) (xy 78.634368 -27.859375) (xy 78.650092 -27.806515) (xy 78.673262 -27.756468)
			(xy 78.703396 -27.710279) (xy 78.739866 -27.668909) (xy 78.760574 -27.650694) (xy 78.768702 -27.643101)
			(xy 78.778048 -27.622942) (xy 78.778608 -27.611832) (xy 78.778608 -27.534616) (xy 78.778077 -27.523501)
			(xy 78.768715 -27.503341) (xy 78.760574 -27.495754) (xy 78.739881 -27.477524) (xy 78.70341 -27.436158)
			(xy 78.673276 -27.389972) (xy 78.650108 -27.339928) (xy 78.634387 -27.287069) (xy 78.626442 -27.232497)
			(xy 78.625954 -27.204924) (xy 78.62644 -27.177673) (xy 78.634196 -27.123725) (xy 78.649551 -27.07143)
			(xy 78.672193 -27.021853) (xy 78.701659 -26.976003) (xy 78.73735 -26.934812) (xy 78.778541 -26.899121)
			(xy 78.824391 -26.869655) (xy 78.873968 -26.847013) (xy 78.926263 -26.831658) (xy 78.980211 -26.823902)
			(xy 79.034713 -26.823902) (xy 79.088661 -26.831658) (xy 79.140956 -26.847013) (xy 79.190533 -26.869655)
			(xy 79.236383 -26.899121) (xy 79.277574 -26.934812) (xy 79.313265 -26.976003) (xy 79.342731 -27.021853)
			(xy 79.365373 -27.07143) (xy 79.380728 -27.123725) (xy 79.388484 -27.177673) (xy 79.38897 -27.204924)
			(xy 79.388462 -27.232497) (xy 79.38052 -27.287069) (xy 79.364804 -27.339928) (xy 79.341642 -27.389975)
			(xy 79.311516 -27.436165) (xy 79.275055 -27.477538) (xy 79.25435 -27.495754) (xy 79.246249 -27.503372)
			(xy 79.236887 -27.523512) (xy 79.236316 -27.534616) (xy 79.236316 -27.611832) (xy 79.236845 -27.622947)
			(xy 79.246211 -27.643105) (xy 79.25435 -27.650694) (xy 79.275071 -27.668894) (xy 79.311539 -27.710266)
			(xy 79.341668 -27.756459) (xy 79.364832 -27.806509) (xy 79.380547 -27.859373) (xy 79.388485 -27.913949)
			(xy 79.38897 -27.941524) (xy 79.388522 -27.96784) (xy 79.381302 -28.019975) (xy 79.366989 -28.070624)
			(xy 79.345854 -28.118826) (xy 79.318297 -28.163668) (xy 79.284841 -28.204299) (xy 79.26578 -28.222448)
			(xy 79.258352 -28.229947) (xy 79.249843 -28.249244) (xy 79.24927 -28.259786) (xy 79.24927 -28.334462)
			(xy 79.249815 -28.34501) (xy 79.25834 -28.364304) (xy 79.26578 -28.3718) (xy 79.284856 -28.389939)
			(xy 79.318335 -28.430558) (xy 79.345906 -28.475397) (xy 79.367046 -28.523604) (xy 79.381351 -28.574261)
			(xy 79.388549 -28.626405) (xy 79.38897 -28.652724) (xy 79.388484 -28.679975) (xy 79.380728 -28.733923)
			(xy 79.365373 -28.786218) (xy 79.342731 -28.835795) (xy 79.313265 -28.881645) (xy 79.277574 -28.922836)
			(xy 79.236383 -28.958527) (xy 79.190533 -28.987993) (xy 79.140956 -29.010635) (xy 79.088661 -29.02599)
			(xy 79.034713 -29.033746) (xy 78.980211 -29.033746) (xy 78.926263 -29.02599) (xy 78.873968 -29.010635)
			(xy 78.824391 -28.987993) (xy 78.778541 -28.958527) (xy 78.73735 -28.922836) (xy 78.701659 -28.881645)
			(xy 78.672193 -28.835795) (xy 78.649551 -28.786218) (xy 78.634196 -28.733923) (xy 78.62644 -28.679975)
			(xy 78.625954 -28.652724) (xy 76.880974 -28.652724) (xy 76.880488 -28.679975) (xy 76.872732 -28.733923)
			(xy 76.857377 -28.786218) (xy 76.834735 -28.835795) (xy 76.805269 -28.881645) (xy 76.769578 -28.922836)
			(xy 76.728387 -28.958527) (xy 76.682537 -28.987993) (xy 76.63296 -29.010635) (xy 76.580665 -29.02599)
			(xy 76.526717 -29.033746) (xy 76.472215 -29.033746) (xy 76.418267 -29.02599) (xy 76.365972 -29.010635)
			(xy 76.316395 -28.987993) (xy 76.270545 -28.958527) (xy 76.229354 -28.922836) (xy 76.193663 -28.881645)
			(xy 76.164197 -28.835795) (xy 76.141555 -28.786218) (xy 76.1262 -28.733923) (xy 76.118444 -28.679975)
			(xy 76.117958 -28.652724) (xy 69.6468 -28.652724) (xy 69.6468 -28.807918) (xy 69.646373 -28.817987)
			(xy 69.638654 -28.836586) (xy 69.631814 -28.843986) (xy 69.280786 -29.195014) (xy 69.273391 -29.201868)
			(xy 69.254792 -29.20961) (xy 69.244718 -29.21) (xy 67.35826 -29.21) (xy 67.348193 -29.210431) (xy 67.329599 -29.218155)
			(xy 67.322192 -29.224986) (xy 67.15603 -29.391148) (xy 71.463702 -29.391148) (xy 71.463702 -29.336652)
			(xy 71.471457 -29.282711) (xy 71.486809 -29.230423) (xy 71.509446 -29.180851) (xy 71.538907 -29.135006)
			(xy 71.574592 -29.093819) (xy 71.615775 -29.05813) (xy 71.661618 -29.028665) (xy 71.711187 -29.006023)
			(xy 71.763474 -28.990665) (xy 71.817414 -28.982905) (xy 71.844662 -28.982416) (xy 71.873578 -28.982956)
			(xy 71.930749 -28.991679) (xy 71.985947 -29.008933) (xy 72.037909 -29.03432) (xy 72.085444 -29.06726)
			(xy 72.127461 -29.106998) (xy 72.145652 -29.129482) (xy 72.153225 -29.138232) (xy 72.173976 -29.148419)
			(xy 72.18553 -29.14904) (xy 72.265794 -29.14904) (xy 72.277365 -29.148487) (xy 72.298137 -29.138282)
			(xy 72.305672 -29.129482) (xy 72.323874 -29.107008) (xy 72.365892 -29.067273) (xy 72.413425 -29.034334)
			(xy 72.465384 -29.008944) (xy 72.520579 -28.991685) (xy 72.577747 -28.982953) (xy 72.606662 -28.982416)
			(xy 72.633918 -28.982828) (xy 72.687877 -28.990581) (xy 72.740183 -29.005935) (xy 72.789771 -29.028577)
			(xy 72.835632 -29.058046) (xy 72.876831 -29.093742) (xy 72.912531 -29.134938) (xy 72.942005 -29.180796)
			(xy 72.964652 -29.230382) (xy 72.980011 -29.282686) (xy 72.987769 -29.336644) (xy 72.987769 -29.391156)
			(xy 72.980011 -29.445114) (xy 72.964652 -29.497418) (xy 72.942005 -29.547004) (xy 72.912531 -29.592862)
			(xy 72.876831 -29.634058) (xy 72.835632 -29.669754) (xy 72.789771 -29.699223) (xy 72.740183 -29.721865)
			(xy 72.687877 -29.737219) (xy 72.633918 -29.744972) (xy 72.606662 -29.745432) (xy 72.577745 -29.744895)
			(xy 72.520574 -29.736173) (xy 72.465374 -29.718921) (xy 72.413412 -29.693533) (xy 72.365878 -29.660591)
			(xy 72.323862 -29.620851) (xy 72.305672 -29.598366) (xy 72.298124 -29.58959) (xy 72.277354 -29.579416)
			(xy 72.265794 -29.578808) (xy 72.18553 -29.578808) (xy 72.173964 -29.579393) (xy 72.153193 -29.589577)
			(xy 72.145652 -29.598366) (xy 72.127423 -29.620817) (xy 72.085412 -29.660556) (xy 72.037885 -29.6935)
			(xy 71.985931 -29.718894) (xy 71.93074 -29.736157) (xy 71.873576 -29.744893) (xy 71.844662 -29.745432)
			(xy 71.817414 -29.744895) (xy 71.763474 -29.737135) (xy 71.711187 -29.721777) (xy 71.661618 -29.699135)
			(xy 71.615775 -29.66967) (xy 71.574592 -29.633981) (xy 71.538907 -29.592794) (xy 71.509446 -29.546949)
			(xy 71.486809 -29.497377) (xy 71.471457 -29.445089) (xy 71.463702 -29.391148) (xy 67.15603 -29.391148)
			(xy 65.790322 -30.756856) (xy 66.673204 -30.756856) (xy 66.673204 -30.69692) (xy 66.681027 -30.637498)
			(xy 66.69654 -30.579605) (xy 66.719476 -30.524232) (xy 66.749443 -30.472326) (xy 66.78593 -30.424776)
			(xy 66.82831 -30.382396) (xy 66.87586 -30.345909) (xy 66.927766 -30.315942) (xy 66.983139 -30.293006)
			(xy 67.041032 -30.277493) (xy 67.100454 -30.26967) (xy 67.16039 -30.26967) (xy 67.219812 -30.277493)
			(xy 67.277705 -30.293006) (xy 67.333078 -30.315942) (xy 67.384984 -30.345909) (xy 67.432534 -30.382396)
			(xy 67.474914 -30.424776) (xy 67.511401 -30.472326) (xy 67.541368 -30.524232) (xy 67.564304 -30.579605)
			(xy 67.579817 -30.637498) (xy 67.58764 -30.69692) (xy 67.58813 -30.726888) (xy 67.58764 -30.756856)
			(xy 67.583527 -30.788098) (xy 67.99248 -30.788098) (xy 67.99248 -30.728162) (xy 68.000303 -30.66874)
			(xy 68.015816 -30.610847) (xy 68.038752 -30.555474) (xy 68.068719 -30.503568) (xy 68.105206 -30.456018)
			(xy 68.147586 -30.413638) (xy 68.195136 -30.377151) (xy 68.247042 -30.347184) (xy 68.302415 -30.324248)
			(xy 68.360308 -30.308735) (xy 68.41973 -30.300912) (xy 68.479666 -30.300912) (xy 68.539088 -30.308735)
			(xy 68.596981 -30.324248) (xy 68.652354 -30.347184) (xy 68.70426 -30.377151) (xy 68.75181 -30.413638)
			(xy 68.79419 -30.456018) (xy 68.830677 -30.503568) (xy 68.860644 -30.555474) (xy 68.867887 -30.57296)
			(xy 69.594204 -30.57296) (xy 69.594204 -30.513024) (xy 69.602027 -30.453602) (xy 69.61754 -30.395709)
			(xy 69.640476 -30.340336) (xy 69.670443 -30.28843) (xy 69.70693 -30.24088) (xy 69.74931 -30.1985)
			(xy 69.79686 -30.162013) (xy 69.848766 -30.132046) (xy 69.904139 -30.10911) (xy 69.962032 -30.093597)
			(xy 70.021454 -30.085774) (xy 70.08139 -30.085774) (xy 70.140812 -30.093597) (xy 70.198705 -30.10911)
			(xy 70.254078 -30.132046) (xy 70.305984 -30.162013) (xy 70.353534 -30.1985) (xy 70.395914 -30.24088)
			(xy 70.432401 -30.28843) (xy 70.462368 -30.340336) (xy 70.485304 -30.395709) (xy 70.500817 -30.453602)
			(xy 70.50864 -30.513024) (xy 70.50913 -30.542992) (xy 70.50864 -30.57296) (xy 70.500817 -30.632382)
			(xy 70.485304 -30.690275) (xy 70.462368 -30.745648) (xy 70.432401 -30.797554) (xy 70.395914 -30.845104)
			(xy 70.353534 -30.887484) (xy 70.305984 -30.923971) (xy 70.254078 -30.953938) (xy 70.198705 -30.976874)
			(xy 70.140812 -30.992387) (xy 70.08139 -31.00021) (xy 70.021454 -31.00021) (xy 69.962032 -30.992387)
			(xy 69.904139 -30.976874) (xy 69.848766 -30.953938) (xy 69.79686 -30.923971) (xy 69.74931 -30.887484)
			(xy 69.70693 -30.845104) (xy 69.670443 -30.797554) (xy 69.640476 -30.745648) (xy 69.61754 -30.690275)
			(xy 69.602027 -30.632382) (xy 69.594204 -30.57296) (xy 68.867887 -30.57296) (xy 68.88358 -30.610847)
			(xy 68.899093 -30.66874) (xy 68.906916 -30.728162) (xy 68.907406 -30.75813) (xy 68.906916 -30.788098)
			(xy 68.899093 -30.84752) (xy 68.88358 -30.905413) (xy 68.860644 -30.960786) (xy 68.830677 -31.012692)
			(xy 68.79419 -31.060242) (xy 68.75181 -31.102622) (xy 68.70426 -31.139109) (xy 68.652354 -31.169076)
			(xy 68.596981 -31.192012) (xy 68.539088 -31.207525) (xy 68.479666 -31.215348) (xy 68.41973 -31.215348)
			(xy 68.360308 -31.207525) (xy 68.302415 -31.192012) (xy 68.247042 -31.169076) (xy 68.195136 -31.139109)
			(xy 68.147586 -31.102622) (xy 68.105206 -31.060242) (xy 68.068719 -31.012692) (xy 68.038752 -30.960786)
			(xy 68.015816 -30.905413) (xy 68.000303 -30.84752) (xy 67.99248 -30.788098) (xy 67.583527 -30.788098)
			(xy 67.579817 -30.816278) (xy 67.564304 -30.874171) (xy 67.541368 -30.929544) (xy 67.511401 -30.98145)
			(xy 67.474914 -31.029) (xy 67.432534 -31.07138) (xy 67.384984 -31.107867) (xy 67.333078 -31.137834)
			(xy 67.277705 -31.16077) (xy 67.219812 -31.176283) (xy 67.16039 -31.184106) (xy 67.100454 -31.184106)
			(xy 67.041032 -31.176283) (xy 66.983139 -31.16077) (xy 66.927766 -31.137834) (xy 66.87586 -31.107867)
			(xy 66.82831 -31.07138) (xy 66.78593 -31.029) (xy 66.749443 -30.98145) (xy 66.719476 -30.929544)
			(xy 66.69654 -30.874171) (xy 66.681027 -30.816278) (xy 66.673204 -30.756856) (xy 65.790322 -30.756856)
			(xy 64.837564 -31.709614) (xy 64.830713 -31.71701) (xy 64.822974 -31.735609) (xy 64.822578 -31.745682)
			(xy 64.822578 -31.983168) (xy 67.106782 -31.983168) (xy 67.106782 -31.923232) (xy 67.114605 -31.86381)
			(xy 67.130118 -31.805917) (xy 67.153054 -31.750544) (xy 67.183021 -31.698638) (xy 67.219508 -31.651088)
			(xy 67.261888 -31.608708) (xy 67.309438 -31.572221) (xy 67.361344 -31.542254) (xy 67.416717 -31.519318)
			(xy 67.47461 -31.503805) (xy 67.534032 -31.495982) (xy 67.593968 -31.495982) (xy 67.65339 -31.503805)
			(xy 67.711283 -31.519318) (xy 67.766656 -31.542254) (xy 67.818562 -31.572221) (xy 67.866112 -31.608708)
			(xy 67.908492 -31.651088) (xy 67.944979 -31.698638) (xy 67.974946 -31.750544) (xy 67.997882 -31.805917)
			(xy 68.013395 -31.86381) (xy 68.021218 -31.923232) (xy 68.021708 -31.9532) (xy 68.021218 -31.983168)
			(xy 68.013395 -32.04259) (xy 67.997882 -32.100483) (xy 67.974946 -32.155856) (xy 67.944979 -32.207762)
			(xy 67.908492 -32.255312) (xy 67.866112 -32.297692) (xy 67.818562 -32.334179) (xy 67.766656 -32.364146)
			(xy 67.711283 -32.387082) (xy 67.65339 -32.402595) (xy 67.593968 -32.410418) (xy 67.534032 -32.410418)
			(xy 67.47461 -32.402595) (xy 67.416717 -32.387082) (xy 67.361344 -32.364146) (xy 67.309438 -32.334179)
			(xy 67.261888 -32.297692) (xy 67.219508 -32.255312) (xy 67.183021 -32.207762) (xy 67.153054 -32.155856)
			(xy 67.130118 -32.100483) (xy 67.114605 -32.04259) (xy 67.106782 -31.983168) (xy 64.822578 -31.983168)
			(xy 64.822578 -32.91713) (xy 69.669404 -32.91713) (xy 69.673475 -32.861508) (xy 69.685601 -32.807071)
			(xy 69.705524 -32.75498) (xy 69.73282 -32.706345) (xy 69.766906 -32.662202) (xy 69.807055 -32.623493)
			(xy 69.852413 -32.591042) (xy 69.902013 -32.565541) (xy 69.954797 -32.547534) (xy 70.00964 -32.537404)
			(xy 70.065374 -32.535367) (xy 70.120811 -32.541467) (xy 70.174768 -32.555573) (xy 70.226097 -32.577385)
			(xy 70.273703 -32.606439) (xy 70.316571 -32.642114) (xy 70.353788 -32.683651) (xy 70.384561 -32.730164)
			(xy 70.408233 -32.780661) (xy 70.424301 -32.834068) (xy 70.432421 -32.889244) (xy 70.43293 -32.91713)
			(xy 70.432421 -32.945016) (xy 70.424301 -33.000192) (xy 70.408233 -33.053599) (xy 70.384561 -33.104096)
			(xy 70.353788 -33.150609) (xy 70.316571 -33.192146) (xy 70.273703 -33.227821) (xy 70.226097 -33.256875)
			(xy 70.174768 -33.278687) (xy 70.120811 -33.292793) (xy 70.065374 -33.298893) (xy 70.00964 -33.296856)
			(xy 69.954797 -33.286726) (xy 69.902013 -33.268719) (xy 69.852413 -33.243218) (xy 69.807055 -33.210767)
			(xy 69.766906 -33.172058) (xy 69.73282 -33.127915) (xy 69.705524 -33.07928) (xy 69.685601 -33.027189)
			(xy 69.673475 -32.972752) (xy 69.669404 -32.91713) (xy 64.822578 -32.91713) (xy 64.822578 -33.717484)
			(xy 64.823049 -33.727356) (xy 64.830507 -33.74564) (xy 64.837056 -33.753044) (xy 64.83731 -33.753298)
			(xy 65.342262 -34.25825) (xy 65.34277 -34.258758) (xy 65.350152 -34.265337) (xy 65.368451 -34.272781)
			(xy 65.37833 -34.273236)
		)
		(stroke
			(width 0)
			(type solid)
		)
		(fill yes)
		(layer "B.Cu")
		(net "GND")
	)
	(gr_poly
		(pts
			(xy 284.066488 -440.515248) (xy 284.076558 -440.514826) (xy 284.095161 -440.507108) (xy 284.102556 -440.500262)
			(xy 285.106872 -439.495946) (xy 285.113713 -439.488546) (xy 285.121432 -439.469947) (xy 285.121858 -439.459878)
			(xy 285.121858 -434.247036) (xy 285.121422 -434.236972) (xy 285.113686 -434.218388) (xy 285.106872 -434.210968)
			(xy 284.151578 -433.255674) (xy 284.144727 -433.248278) (xy 284.13699 -433.229679) (xy 284.136592 -433.219606)
			(xy 284.136592 -430.354486) (xy 284.136166 -430.344417) (xy 284.128447 -430.325817) (xy 284.121606 -430.318418)
			(xy 283.691838 -429.88865) (xy 283.684439 -429.881808) (xy 283.66584 -429.874088) (xy 283.65577 -429.873664)
			(xy 280.922476 -429.873664) (xy 280.912408 -429.873236) (xy 280.893814 -429.865511) (xy 280.886408 -429.858678)
			(xy 280.062432 -429.034702) (xy 280.055582 -429.027305) (xy 280.047842 -429.008707) (xy 280.047446 -428.998634)
			(xy 280.047446 -428.974758) (xy 280.047014 -428.964692) (xy 280.039283 -428.946104) (xy 280.03246 -428.93869)
			(xy 278.026368 -426.932598) (xy 278.018968 -426.925757) (xy 278.00037 -426.918034) (xy 277.9903 -426.917612)
			(xy 267.357606 -426.917612) (xy 267.347536 -426.918034) (xy 267.328931 -426.925749) (xy 267.321538 -426.932598)
			(xy 265.578082 -428.676054) (xy 265.570685 -428.682903) (xy 265.552086 -428.690638) (xy 265.542014 -428.69104)
			(xy 265.530076 -428.69104) (xy 265.530076 -428.972734) (xy 275.548676 -428.972734) (xy 275.554079 -428.90404)
			(xy 275.567519 -428.836458) (xy 275.588809 -428.770923) (xy 275.617655 -428.708345) (xy 275.653655 -428.649592)
			(xy 275.696312 -428.595477) (xy 275.745033 -428.54675) (xy 275.799144 -428.504088) (xy 275.857894 -428.468082)
			(xy 275.920469 -428.439231) (xy 275.986001 -428.417934) (xy 276.053583 -428.404487) (xy 276.122276 -428.399077)
			(xy 276.191129 -428.401778) (xy 276.259187 -428.412553) (xy 276.325507 -428.431253) (xy 276.389169 -428.457618)
			(xy 276.449292 -428.491283) (xy 276.50504 -428.531782) (xy 276.555643 -428.578552) (xy 276.600397 -428.630945)
			(xy 276.638683 -428.688236) (xy 276.66997 -428.749629) (xy 276.693824 -428.814274) (xy 276.709915 -428.881275)
			(xy 276.718019 -428.949703) (xy 276.718522 -428.984156) (xy 276.717991 -429.02035) (xy 276.70907 -429.092185)
			(xy 276.700742 -429.127412) (xy 276.698729 -429.1366) (xy 276.700964 -429.155265) (xy 276.70506 -429.163734)
			(xy 276.719792 -429.190912) (xy 276.72447 -429.198822) (xy 276.738259 -429.210943) (xy 276.746716 -429.214534)
			(xy 276.77368 -429.225161) (xy 276.82431 -429.253362) (xy 276.870092 -429.288896) (xy 276.909973 -429.330946)
			(xy 276.943036 -429.378543) (xy 276.96852 -429.430594) (xy 276.985839 -429.4859) (xy 276.994594 -429.543189)
			(xy 276.995128 -429.572166) (xy 276.994613 -429.599417) (xy 276.993639 -429.606193) (xy 278.589219 -429.606193)
			(xy 278.589219 -429.538139) (xy 278.597119 -429.470546) (xy 278.612813 -429.404328) (xy 278.636089 -429.340379)
			(xy 278.666631 -429.279564) (xy 278.704027 -429.222707) (xy 278.74777 -429.170575) (xy 278.79727 -429.123874)
			(xy 278.851857 -429.083236) (xy 278.910793 -429.049209) (xy 278.973281 -429.022255) (xy 279.038475 -429.002737)
			(xy 279.105494 -428.990919) (xy 279.173432 -428.986963) (xy 279.24137 -428.990919) (xy 279.308389 -429.002737)
			(xy 279.373583 -429.022255) (xy 279.436071 -429.049209) (xy 279.495007 -429.083236) (xy 279.549594 -429.123874)
			(xy 279.599094 -429.170575) (xy 279.642837 -429.222707) (xy 279.680233 -429.279564) (xy 279.710775 -429.340379)
			(xy 279.734051 -429.404328) (xy 279.749745 -429.470546) (xy 279.757645 -429.538139) (xy 279.75814 -429.572166)
			(xy 279.757645 -429.606193) (xy 279.749745 -429.673786) (xy 279.734051 -429.740004) (xy 279.710775 -429.803953)
			(xy 279.680233 -429.864768) (xy 279.642837 -429.921625) (xy 279.599094 -429.973757) (xy 279.549594 -430.020458)
			(xy 279.495007 -430.061096) (xy 279.436071 -430.095123) (xy 279.373583 -430.122077) (xy 279.308389 -430.141595)
			(xy 279.24137 -430.153413) (xy 279.173432 -430.15737) (xy 279.105494 -430.153413) (xy 279.038475 -430.141595)
			(xy 278.973281 -430.122077) (xy 278.910793 -430.095123) (xy 278.851857 -430.061096) (xy 278.79727 -430.020458)
			(xy 278.74777 -429.973757) (xy 278.704027 -429.921625) (xy 278.666631 -429.864768) (xy 278.636089 -429.803953)
			(xy 278.612813 -429.740004) (xy 278.597119 -429.673786) (xy 278.589219 -429.606193) (xy 276.993639 -429.606193)
			(xy 276.986861 -429.653365) (xy 276.971511 -429.705661) (xy 276.948874 -429.755239) (xy 276.919411 -429.801092)
			(xy 276.883723 -429.842284) (xy 276.842535 -429.877979) (xy 276.796687 -429.907448) (xy 276.747111 -429.930092)
			(xy 276.694818 -429.94545) (xy 276.640871 -429.953209) (xy 276.61362 -429.953674) (xy 276.586593 -429.953189)
			(xy 276.533081 -429.945549) (xy 276.481183 -429.930434) (xy 276.431938 -429.908145) (xy 276.386331 -429.87913)
			(xy 276.345276 -429.843968) (xy 276.309594 -429.803364) (xy 276.279999 -429.758131) (xy 276.257085 -429.709174)
			(xy 276.241309 -429.657473) (xy 276.236684 -429.63084) (xy 276.234827 -429.62181) (xy 276.225728 -429.605795)
			(xy 276.218904 -429.599598) (xy 276.195282 -429.58004) (xy 276.18777 -429.574344) (xy 276.169912 -429.568357)
			(xy 276.160484 -429.568356) (xy 276.133814 -429.568864) (xy 276.099361 -429.568422) (xy 276.030933 -429.560325)
			(xy 275.96393 -429.544241) (xy 275.899282 -429.520393) (xy 275.837886 -429.489112) (xy 275.780591 -429.450832)
			(xy 275.728194 -429.406083) (xy 275.681419 -429.355485) (xy 275.640915 -429.299741) (xy 275.607244 -429.239622)
			(xy 275.580872 -429.175962) (xy 275.562166 -429.109644) (xy 275.551384 -429.041586) (xy 275.548676 -428.972734)
			(xy 265.530076 -428.972734) (xy 265.530076 -433.130706) (xy 266.885409 -433.130706) (xy 266.885409 -432.953414)
			(xy 266.893363 -432.7763) (xy 266.909256 -432.599721) (xy 266.933054 -432.424033) (xy 266.964711 -432.24959)
			(xy 267.004162 -432.076743) (xy 267.051329 -431.90584) (xy 267.106115 -431.737225) (xy 267.168411 -431.571237)
			(xy 267.238091 -431.408212) (xy 267.315016 -431.248477) (xy 267.399029 -431.092354) (xy 267.489962 -430.940158)
			(xy 267.587632 -430.792194) (xy 267.691842 -430.648762) (xy 267.802382 -430.510149) (xy 267.919029 -430.376635)
			(xy 268.041549 -430.248489) (xy 268.169695 -430.125969) (xy 268.303209 -430.009322) (xy 268.441822 -429.898782)
			(xy 268.585254 -429.794572) (xy 268.733218 -429.696902) (xy 268.885414 -429.605969) (xy 269.041537 -429.521956)
			(xy 269.201272 -429.445031) (xy 269.364297 -429.375351) (xy 269.530285 -429.313055) (xy 269.6989 -429.258269)
			(xy 269.869803 -429.211102) (xy 270.04265 -429.171651) (xy 270.217093 -429.139994) (xy 270.392781 -429.116196)
			(xy 270.56936 -429.100303) (xy 270.746474 -429.092349) (xy 270.923766 -429.092349) (xy 271.10088 -429.100303)
			(xy 271.277459 -429.116196) (xy 271.453147 -429.139994) (xy 271.62759 -429.171651) (xy 271.800437 -429.211102)
			(xy 271.97134 -429.258269) (xy 272.139955 -429.313055) (xy 272.305943 -429.375351) (xy 272.468968 -429.445031)
			(xy 272.628703 -429.521956) (xy 272.784826 -429.605969) (xy 272.937022 -429.696902) (xy 273.084986 -429.794572)
			(xy 273.228418 -429.898782) (xy 273.367031 -430.009322) (xy 273.500545 -430.125969) (xy 273.628691 -430.248489)
			(xy 273.751211 -430.376635) (xy 273.867858 -430.510149) (xy 273.978398 -430.648762) (xy 274.082006 -430.791366)
			(xy 277.234902 -430.791366) (xy 277.238973 -430.735744) (xy 277.251099 -430.681307) (xy 277.271022 -430.629216)
			(xy 277.298318 -430.580581) (xy 277.332404 -430.536438) (xy 277.372553 -430.497729) (xy 277.417911 -430.465278)
			(xy 277.467511 -430.439777) (xy 277.520295 -430.42177) (xy 277.575138 -430.41164) (xy 277.630872 -430.409603)
			(xy 277.686309 -430.415703) (xy 277.740266 -430.429809) (xy 277.791595 -430.451621) (xy 277.839201 -430.480675)
			(xy 277.882069 -430.51635) (xy 277.919286 -430.557887) (xy 277.950059 -430.6044) (xy 277.973731 -430.654897)
			(xy 277.989799 -430.708304) (xy 277.997919 -430.76348) (xy 277.998428 -430.791366) (xy 277.997919 -430.819252)
			(xy 277.989799 -430.874428) (xy 277.973731 -430.927835) (xy 277.950059 -430.978332) (xy 277.919286 -431.024845)
			(xy 277.882069 -431.066382) (xy 277.839201 -431.102057) (xy 277.791595 -431.131111) (xy 277.740266 -431.152923)
			(xy 277.686309 -431.167029) (xy 277.630872 -431.173129) (xy 277.575138 -431.171092) (xy 277.520295 -431.160962)
			(xy 277.467511 -431.142955) (xy 277.417911 -431.117454) (xy 277.372553 -431.085003) (xy 277.332404 -431.046294)
			(xy 277.298318 -431.002151) (xy 277.271022 -430.953516) (xy 277.251099 -430.901425) (xy 277.238973 -430.846988)
			(xy 277.234902 -430.791366) (xy 274.082006 -430.791366) (xy 274.082608 -430.792194) (xy 274.180278 -430.940158)
			(xy 274.271211 -431.092354) (xy 274.355224 -431.248477) (xy 274.432149 -431.408212) (xy 274.501829 -431.571237)
			(xy 274.564125 -431.737225) (xy 274.618911 -431.90584) (xy 274.666078 -432.076743) (xy 274.705529 -432.24959)
			(xy 274.737186 -432.424033) (xy 274.760984 -432.599721) (xy 274.776877 -432.7763) (xy 274.784831 -432.953414)
			(xy 274.785328 -433.04206) (xy 274.784831 -433.130706) (xy 274.776877 -433.30782) (xy 274.760984 -433.484399)
			(xy 274.737186 -433.660087) (xy 274.705529 -433.83453) (xy 274.676018 -433.963826) (xy 277.872188 -433.963826)
			(xy 277.876259 -433.908204) (xy 277.888385 -433.853767) (xy 277.908308 -433.801676) (xy 277.935604 -433.753041)
			(xy 277.96969 -433.708898) (xy 278.009839 -433.670189) (xy 278.055197 -433.637738) (xy 278.104797 -433.612237)
			(xy 278.157581 -433.59423) (xy 278.212424 -433.5841) (xy 278.268158 -433.582063) (xy 278.323595 -433.588163)
			(xy 278.377552 -433.602269) (xy 278.428881 -433.624081) (xy 278.476487 -433.653135) (xy 278.519355 -433.68881)
			(xy 278.556572 -433.730347) (xy 278.587345 -433.77686) (xy 278.611017 -433.827357) (xy 278.627085 -433.880764)
			(xy 278.635205 -433.93594) (xy 278.635714 -433.963826) (xy 278.635205 -433.991712) (xy 278.627085 -434.046888)
			(xy 278.611017 -434.100295) (xy 278.587345 -434.150792) (xy 278.556572 -434.197305) (xy 278.519355 -434.238842)
			(xy 278.476487 -434.274517) (xy 278.428881 -434.303571) (xy 278.377552 -434.325383) (xy 278.323595 -434.339489)
			(xy 278.268158 -434.345589) (xy 278.212424 -434.343552) (xy 278.157581 -434.333422) (xy 278.104797 -434.315415)
			(xy 278.055197 -434.289914) (xy 278.009839 -434.257463) (xy 277.96969 -434.218754) (xy 277.935604 -434.174611)
			(xy 277.908308 -434.125976) (xy 277.888385 -434.073885) (xy 277.876259 -434.019448) (xy 277.872188 -433.963826)
			(xy 274.676018 -433.963826) (xy 274.666078 -434.007377) (xy 274.618911 -434.17828) (xy 274.564125 -434.346895)
			(xy 274.501829 -434.512883) (xy 274.440668 -434.655976) (xy 282.358084 -434.655976) (xy 282.358579 -434.621949)
			(xy 282.366479 -434.554356) (xy 282.382173 -434.488138) (xy 282.405449 -434.424189) (xy 282.435991 -434.363374)
			(xy 282.473387 -434.306517) (xy 282.51713 -434.254385) (xy 282.56663 -434.207684) (xy 282.621217 -434.167046)
			(xy 282.680153 -434.133019) (xy 282.742641 -434.106065) (xy 282.807835 -434.086547) (xy 282.874854 -434.074729)
			(xy 282.942792 -434.070773) (xy 283.01073 -434.074729) (xy 283.077749 -434.086547) (xy 283.142943 -434.106065)
			(xy 283.205431 -434.133019) (xy 283.264367 -434.167046) (xy 283.318954 -434.207684) (xy 283.368454 -434.254385)
			(xy 283.412197 -434.306517) (xy 283.449593 -434.363374) (xy 283.480135 -434.424189) (xy 283.503411 -434.488138)
			(xy 283.519105 -434.554356) (xy 283.527005 -434.621949) (xy 283.5275 -434.655976) (xy 283.527036 -434.69013)
			(xy 283.519075 -434.757973) (xy 283.50326 -434.824426) (xy 283.479805 -434.888581) (xy 283.44903 -434.949565)
			(xy 283.411356 -435.006545) (xy 283.367297 -435.058745) (xy 283.317452 -435.105452) (xy 283.290264 -435.12613)
			(xy 283.282879 -435.132073) (xy 283.272837 -435.148135) (xy 283.270706 -435.157372) (xy 283.26461 -435.187852)
			(xy 283.263305 -435.197028) (xy 283.266551 -435.21526) (xy 283.27096 -435.223412) (xy 283.283618 -435.245589)
			(xy 283.303571 -435.292593) (xy 283.317075 -435.341838) (xy 283.32389 -435.392444) (xy 283.3243 -435.417976)
			(xy 283.323814 -435.445227) (xy 283.316058 -435.499175) (xy 283.300703 -435.55147) (xy 283.278061 -435.601047)
			(xy 283.248595 -435.646897) (xy 283.212904 -435.688088) (xy 283.171713 -435.723779) (xy 283.125863 -435.753245)
			(xy 283.076286 -435.775887) (xy 283.023991 -435.791242) (xy 282.970043 -435.798998) (xy 282.915541 -435.798998)
			(xy 282.861593 -435.791242) (xy 282.809298 -435.775887) (xy 282.759721 -435.753245) (xy 282.713871 -435.723779)
			(xy 282.67268 -435.688088) (xy 282.636989 -435.646897) (xy 282.607523 -435.601047) (xy 282.584881 -435.55147)
			(xy 282.569526 -435.499175) (xy 282.56177 -435.445227) (xy 282.561284 -435.417976) (xy 282.561681 -435.392443)
			(xy 282.568496 -435.341835) (xy 282.582 -435.292588) (xy 282.601953 -435.245582) (xy 282.614624 -435.223412)
			(xy 282.619056 -435.215269) (xy 282.622298 -435.197029) (xy 282.620974 -435.187852) (xy 282.614878 -435.157372)
			(xy 282.612709 -435.148149) (xy 282.602678 -435.132096) (xy 282.59532 -435.12613) (xy 282.568119 -435.105471)
			(xy 282.518281 -435.058757) (xy 282.474227 -435.006552) (xy 282.436559 -434.949569) (xy 282.40579 -434.888583)
			(xy 282.382339 -434.824426) (xy 282.366526 -434.757973) (xy 282.358566 -434.69013) (xy 282.358084 -434.655976)
			(xy 274.440668 -434.655976) (xy 274.432149 -434.675908) (xy 274.355224 -434.835643) (xy 274.271211 -434.991766)
			(xy 274.180278 -435.143962) (xy 274.082608 -435.291926) (xy 273.978398 -435.435358) (xy 273.867858 -435.573971)
			(xy 273.751211 -435.707485) (xy 273.628691 -435.835631) (xy 273.500545 -435.958151) (xy 273.367031 -436.074798)
			(xy 273.228418 -436.185338) (xy 273.084986 -436.289548) (xy 272.937022 -436.387218) (xy 272.784826 -436.478151)
			(xy 272.628703 -436.562164) (xy 272.468968 -436.639089) (xy 272.305943 -436.708769) (xy 272.139955 -436.771065)
			(xy 271.97134 -436.825851) (xy 271.800437 -436.873018) (xy 271.62759 -436.912469) (xy 271.453147 -436.944126)
			(xy 271.277459 -436.967924) (xy 271.10088 -436.983817) (xy 270.923766 -436.991771) (xy 270.746474 -436.991771)
			(xy 270.56936 -436.983817) (xy 270.392781 -436.967924) (xy 270.217093 -436.944126) (xy 270.04265 -436.912469)
			(xy 269.869803 -436.873018) (xy 269.6989 -436.825851) (xy 269.530285 -436.771065) (xy 269.364297 -436.708769)
			(xy 269.201272 -436.639089) (xy 269.041537 -436.562164) (xy 268.885414 -436.478151) (xy 268.733218 -436.387218)
			(xy 268.585254 -436.289548) (xy 268.441822 -436.185338) (xy 268.303209 -436.074798) (xy 268.169695 -435.958151)
			(xy 268.041549 -435.835631) (xy 267.919029 -435.707485) (xy 267.802382 -435.573971) (xy 267.691842 -435.435358)
			(xy 267.587632 -435.291926) (xy 267.489962 -435.143962) (xy 267.399029 -434.991766) (xy 267.315016 -434.835643)
			(xy 267.238091 -434.675908) (xy 267.168411 -434.512883) (xy 267.106115 -434.346895) (xy 267.051329 -434.17828)
			(xy 267.004162 -434.007377) (xy 266.964711 -433.83453) (xy 266.933054 -433.660087) (xy 266.909256 -433.484399)
			(xy 266.893363 -433.30782) (xy 266.885409 -433.130706) (xy 265.530076 -433.130706) (xy 265.530076 -436.22468)
			(xy 265.529638 -436.234743) (xy 265.5219 -436.253324) (xy 265.51509 -436.260748) (xy 264.691368 -437.08447)
			(xy 264.683969 -437.091315) (xy 264.665371 -437.099042) (xy 264.6553 -437.099456) (xy 229.780592 -437.099456)
			(xy 229.770524 -437.099882) (xy 229.751927 -437.107605) (xy 229.744524 -437.114442) (xy 229.378764 -437.480202)
			(xy 229.371417 -437.487007) (xy 229.352954 -437.494726) (xy 229.34295 -437.495188) (xy 207.03413 -437.495188)
			(xy 207.02414 -437.494656) (xy 207.005702 -437.486949) (xy 206.998316 -437.480202) (xy 206.632556 -437.114442)
			(xy 206.625157 -437.107598) (xy 206.606558 -437.099873) (xy 206.596488 -437.099456) (xy 199.533002 -437.099456)
			(xy 199.522933 -437.099032) (xy 199.504332 -437.091313) (xy 199.496934 -437.08447) (xy 198.613268 -436.200804)
			(xy 198.61022 -436.198518) (xy 198.536696 -436.142527) (xy 198.394359 -436.024618) (xy 198.257693 -435.900181)
			(xy 198.126996 -435.769488) (xy 198.002555 -435.632826) (xy 197.884643 -435.490492) (xy 197.828662 -435.41696)
			(xy 197.826376 -435.413912) (xy 195.322698 -432.910234) (xy 195.315862 -432.902832) (xy 195.308152 -432.884234)
			(xy 195.307712 -432.874166) (xy 195.307712 -431.05578) (xy 195.307262 -431.045753) (xy 195.299672 -431.027194)
			(xy 195.29298 -431.019712) (xy 195.27139 -430.998376) (xy 195.264347 -430.991952) (xy 195.246858 -430.9844)
			(xy 195.237354 -430.983644) (xy 195.202854 -430.981908) (xy 195.134588 -430.971329) (xy 195.068045 -430.952781)
			(xy 195.004149 -430.926523) (xy 194.943793 -430.89292) (xy 194.887815 -430.85244) (xy 194.836997 -430.805647)
			(xy 194.792045 -430.753193) (xy 194.753586 -430.695808) (xy 194.722156 -430.634292) (xy 194.698192 -430.569502)
			(xy 194.682028 -430.502339) (xy 194.67389 -430.43374) (xy 194.67389 -430.364659) (xy 194.682029 -430.29606)
			(xy 194.698192 -430.228898) (xy 194.722156 -430.164107) (xy 194.753587 -430.102591) (xy 194.792046 -430.045206)
			(xy 194.836997 -429.992752) (xy 194.887816 -429.945959) (xy 194.943793 -429.90548) (xy 195.00415 -429.871877)
			(xy 195.068045 -429.845618) (xy 195.134589 -429.827071) (xy 195.202855 -429.816492) (xy 195.237354 -429.814736)
			(xy 195.246863 -429.814011) (xy 195.264353 -429.806441) (xy 195.27139 -429.800004) (xy 195.29298 -429.778668)
			(xy 195.299755 -429.771243) (xy 195.30734 -429.752646) (xy 195.307712 -429.7426) (xy 195.307712 -429.37938)
			(xy 195.307268 -429.369222) (xy 195.299415 -429.350485) (xy 195.292472 -429.343058) (xy 195.232782 -429.284892)
			(xy 195.21424 -429.277526) (xy 195.203572 -429.27778) (xy 195.189602 -429.278034) (xy 195.155573 -429.277558)
			(xy 195.087974 -429.269658) (xy 195.02175 -429.253962) (xy 194.957796 -429.230685) (xy 194.896977 -429.200141)
			(xy 194.840115 -429.162742) (xy 194.787979 -429.118995) (xy 194.741274 -429.069491) (xy 194.700632 -429.0149)
			(xy 194.666603 -428.95596) (xy 194.639646 -428.893467) (xy 194.620127 -428.828268) (xy 194.608309 -428.761243)
			(xy 194.604351 -428.6933) (xy 194.608309 -428.625357) (xy 194.620127 -428.558332) (xy 194.639646 -428.493133)
			(xy 194.666603 -428.43064) (xy 194.700632 -428.3717) (xy 194.741274 -428.317109) (xy 194.787979 -428.267605)
			(xy 194.840115 -428.223858) (xy 194.896977 -428.186459) (xy 194.957796 -428.155915) (xy 195.02175 -428.132638)
			(xy 195.087974 -428.116942) (xy 195.155573 -428.109042) (xy 195.189602 -428.108618) (xy 195.203572 -428.108872)
			(xy 195.21424 -428.109126) (xy 195.232782 -428.10176) (xy 195.292472 -428.043594) (xy 195.299421 -428.036169)
			(xy 195.307281 -428.017432) (xy 195.307712 -428.007272) (xy 195.307712 -426.332396) (xy 195.307397 -426.32337)
			(xy 195.301205 -426.306419) (xy 195.289491 -426.292689) (xy 195.281804 -426.287946) (xy 195.192396 -426.237908)
			(xy 195.165218 -426.238416) (xy 195.15328 -426.245528) (xy 195.126232 -426.261432) (xy 195.068711 -426.2865)
			(xy 195.008305 -426.303476) (xy 194.946147 -426.312042) (xy 194.914774 -426.312584) (xy 194.884809 -426.312092)
			(xy 194.825392 -426.304267) (xy 194.767505 -426.288753) (xy 194.712138 -426.265817) (xy 194.660238 -426.23585)
			(xy 194.612694 -426.199365) (xy 194.570318 -426.156987) (xy 194.533836 -426.10944) (xy 194.503872 -426.057539)
			(xy 194.480939 -426.00217) (xy 194.465428 -425.944282) (xy 194.457606 -425.884865) (xy 194.457606 -425.824935)
			(xy 194.465428 -425.765518) (xy 194.480939 -425.70763) (xy 194.503872 -425.652261) (xy 194.533836 -425.60036)
			(xy 194.570318 -425.552813) (xy 194.612694 -425.510435) (xy 194.660238 -425.47395) (xy 194.712138 -425.443983)
			(xy 194.767505 -425.421047) (xy 194.825392 -425.405533) (xy 194.884809 -425.397708) (xy 194.914774 -425.397168)
			(xy 194.946148 -425.397683) (xy 195.008309 -425.406253) (xy 195.068716 -425.423235) (xy 195.126236 -425.448311)
			(xy 195.15328 -425.464224) (xy 195.165218 -425.471336) (xy 195.192396 -425.471844) (xy 195.281804 -425.421806)
			(xy 195.28948 -425.417059) (xy 195.301154 -425.403309) (xy 195.307364 -425.386375) (xy 195.307712 -425.377356)
			(xy 195.307712 -422.263062) (xy 195.307282 -422.252995) (xy 195.29956 -422.234399) (xy 195.292726 -422.226994)
			(xy 195.259198 -422.193466) (xy 195.252393 -422.186119) (xy 195.244673 -422.167656) (xy 195.244212 -422.157652)
			(xy 195.244212 -420.765986) (xy 195.243735 -420.756019) (xy 195.236162 -420.73758) (xy 195.22948 -420.730172)
			(xy 194.140074 -419.640766) (xy 194.132677 -419.633917) (xy 194.114078 -419.626181) (xy 194.104006 -419.62578)
			(xy 190.829184 -419.62578) (xy 190.819115 -419.626205) (xy 190.800512 -419.633922) (xy 190.793116 -419.640766)
			(xy 190.606426 -419.827456) (xy 190.599622 -419.834803) (xy 190.591905 -419.853266) (xy 190.59144 -419.86327)
			(xy 190.59144 -420.901368) (xy 190.592042 -420.913688) (xy 190.603506 -420.935499) (xy 190.613284 -420.943024)
			(xy 190.692024 -420.997634) (xy 190.716408 -421.000936) (xy 190.728346 -420.996618) (xy 190.753716 -420.987685)
			(xy 190.806023 -420.975144) (xy 190.85944 -420.968831) (xy 190.886334 -420.968424) (xy 190.916298 -420.968916)
			(xy 190.975713 -420.976742) (xy 191.033598 -420.992257) (xy 191.088964 -421.015193) (xy 191.140862 -421.04516)
			(xy 191.188404 -421.081644) (xy 191.230778 -421.124021) (xy 191.267259 -421.171567) (xy 191.297222 -421.223467)
			(xy 191.320154 -421.278834) (xy 191.335664 -421.33672) (xy 191.343486 -421.396136) (xy 191.343486 -421.456064)
			(xy 191.335664 -421.51548) (xy 191.320154 -421.573366) (xy 191.297222 -421.628733) (xy 191.267259 -421.680633)
			(xy 191.230778 -421.728179) (xy 191.188404 -421.770556) (xy 191.140862 -421.80704) (xy 191.088964 -421.837007)
			(xy 191.033598 -421.859943) (xy 190.975713 -421.875458) (xy 190.916298 -421.883284) (xy 190.886334 -421.88384)
			(xy 190.859441 -421.883434) (xy 190.806028 -421.877099) (xy 190.753722 -421.864561) (xy 190.728346 -421.855646)
			(xy 190.716408 -421.851328) (xy 190.692024 -421.85463) (xy 190.613284 -421.90924) (xy 190.603619 -421.916855)
			(xy 190.592215 -421.938615) (xy 190.59144 -421.950896) (xy 190.59144 -423.3418) (xy 190.591965 -423.352726)
			(xy 190.601057 -423.372596) (xy 190.608966 -423.380154) (xy 190.675514 -423.437812) (xy 190.696342 -423.443908)
			(xy 190.707518 -423.442384) (xy 190.720971 -423.440583) (xy 190.748048 -423.438675) (xy 190.76162 -423.438574)
			(xy 190.789731 -423.439075) (xy 190.845344 -423.447322) (xy 190.899147 -423.463635) (xy 190.949976 -423.487662)
			(xy 190.996733 -423.518882) (xy 191.017906 -423.53738) (xy 191.024764 -423.54373) (xy 191.041528 -423.550334)
			(xy 191.126618 -423.552366) (xy 191.143636 -423.546524) (xy 191.151002 -423.540428) (xy 191.177257 -423.519332)
			(xy 191.233751 -423.482658) (xy 191.294085 -423.452719) (xy 191.357459 -423.429911) (xy 191.423035 -423.414536)
			(xy 191.489943 -423.406799) (xy 191.52362 -423.406316) (xy 191.558956 -423.406829) (xy 191.629113 -423.41535)
			(xy 191.69773 -423.432266) (xy 191.763809 -423.457329) (xy 191.826385 -423.490174) (xy 191.884545 -423.530323)
			(xy 191.937442 -423.577189) (xy 191.984305 -423.630089) (xy 192.024449 -423.688253) (xy 192.057289 -423.750831)
			(xy 192.082347 -423.816912) (xy 192.090513 -423.85005) (xy 193.098402 -423.85005) (xy 193.098402 -423.790114)
			(xy 193.106225 -423.730692) (xy 193.121738 -423.672799) (xy 193.144674 -423.617426) (xy 193.174641 -423.56552)
			(xy 193.211128 -423.51797) (xy 193.253508 -423.47559) (xy 193.301058 -423.439103) (xy 193.352964 -423.409136)
			(xy 193.408337 -423.3862) (xy 193.46623 -423.370687) (xy 193.525652 -423.362864) (xy 193.585588 -423.362864)
			(xy 193.64501 -423.370687) (xy 193.702903 -423.3862) (xy 193.758276 -423.409136) (xy 193.810182 -423.439103)
			(xy 193.857732 -423.47559) (xy 193.900112 -423.51797) (xy 193.936599 -423.56552) (xy 193.966566 -423.617426)
			(xy 193.989502 -423.672799) (xy 194.005015 -423.730692) (xy 194.012838 -423.790114) (xy 194.013328 -423.820082)
			(xy 194.012838 -423.85005) (xy 194.005015 -423.909472) (xy 193.989502 -423.967365) (xy 193.966566 -424.022738)
			(xy 193.936599 -424.074644) (xy 193.900112 -424.122194) (xy 193.857732 -424.164574) (xy 193.810182 -424.201061)
			(xy 193.758276 -424.231028) (xy 193.702903 -424.253964) (xy 193.64501 -424.269477) (xy 193.585588 -424.2773)
			(xy 193.525652 -424.2773) (xy 193.46623 -424.269477) (xy 193.408337 -424.253964) (xy 193.352964 -424.231028)
			(xy 193.301058 -424.201061) (xy 193.253508 -424.164574) (xy 193.211128 -424.122194) (xy 193.174641 -424.074644)
			(xy 193.144674 -424.022738) (xy 193.121738 -423.967365) (xy 193.106225 -423.909472) (xy 193.098402 -423.85005)
			(xy 192.090513 -423.85005) (xy 192.099257 -423.885531) (xy 192.107773 -423.955688) (xy 192.108328 -423.991024)
			(xy 192.107864 -424.024174) (xy 192.100361 -424.090047) (xy 192.085454 -424.154649) (xy 192.063334 -424.217149)
			(xy 192.034285 -424.276746) (xy 192.016888 -424.304968) (xy 192.0113 -424.313858) (xy 192.007998 -424.334686)
			(xy 192.032128 -424.427396) (xy 192.045082 -424.443906) (xy 192.05448 -424.448986) (xy 192.080076 -424.463368)
			(xy 192.126905 -424.498778) (xy 192.167751 -424.540949) (xy 192.201648 -424.588884) (xy 192.227796 -424.641449)
			(xy 192.245574 -424.697402) (xy 192.254564 -424.755419) (xy 192.25514 -424.784774) (xy 192.254654 -424.812025)
			(xy 192.246898 -424.865973) (xy 192.231543 -424.918268) (xy 192.208901 -424.967845) (xy 192.179435 -425.013695)
			(xy 192.143744 -425.054886) (xy 192.102553 -425.090577) (xy 192.056703 -425.120043) (xy 192.007126 -425.142685)
			(xy 191.954831 -425.15804) (xy 191.900883 -425.165796) (xy 191.846381 -425.165796) (xy 191.792433 -425.15804)
			(xy 191.740138 -425.142685) (xy 191.690561 -425.120043) (xy 191.644711 -425.090577) (xy 191.60352 -425.054886)
			(xy 191.567829 -425.013695) (xy 191.538363 -424.967845) (xy 191.515721 -424.918268) (xy 191.500366 -424.865973)
			(xy 191.49261 -424.812025) (xy 191.492124 -424.784774) (xy 191.492466 -424.761291) (xy 191.498193 -424.714675)
			(xy 191.503554 -424.69181) (xy 191.506348 -424.681396) (xy 191.502792 -424.660822) (xy 191.450722 -424.580304)
			(xy 191.433196 -424.568874) (xy 191.422528 -424.566842) (xy 191.388106 -424.560277) (xy 191.321026 -424.539998)
			(xy 191.256852 -424.511846) (xy 191.196503 -424.476224) (xy 191.140845 -424.433644) (xy 191.090676 -424.384715)
			(xy 191.046716 -424.330141) (xy 191.009595 -424.270702) (xy 190.994284 -424.239182) (xy 190.99022 -424.2308)
			(xy 190.977266 -424.2181) (xy 190.899542 -424.183556) (xy 190.881508 -424.182286) (xy 190.872618 -424.18508)
			(xy 190.851282 -424.190922) (xy 190.844424 -424.1927) (xy 190.832486 -424.199304) (xy 190.827406 -424.204384)
			(xy 190.820569 -424.211749) (xy 190.812834 -424.230278) (xy 190.812841 -424.250357) (xy 190.820589 -424.268881)
			(xy 190.827406 -424.276266) (xy 191.285622 -424.734482) (xy 191.292464 -424.741881) (xy 191.300181 -424.76048)
			(xy 191.300608 -424.77055) (xy 191.300608 -426.600874) (xy 191.300172 -426.610938) (xy 191.292439 -426.629524)
			(xy 191.285622 -426.636942) (xy 191.051688 -426.870876) (xy 191.044322 -426.885608) (xy 191.043306 -426.893736)
			(xy 191.039381 -426.918311) (xy 191.02465 -426.965845) (xy 191.00248 -427.010399) (xy 190.973446 -427.050816)
			(xy 190.956184 -427.068742) (xy 190.68288 -427.341792) (xy 190.676103 -427.349217) (xy 190.668509 -427.367814)
			(xy 190.668148 -427.37786) (xy 190.668148 -427.878744) (xy 191.96226 -427.878744) (xy 191.96226 -427.818808)
			(xy 191.970083 -427.759386) (xy 191.985596 -427.701493) (xy 192.008532 -427.64612) (xy 192.038499 -427.594214)
			(xy 192.074986 -427.546664) (xy 192.117366 -427.504284) (xy 192.164916 -427.467797) (xy 192.216822 -427.43783)
			(xy 192.272195 -427.414894) (xy 192.330088 -427.399381) (xy 192.38951 -427.391558) (xy 192.449446 -427.391558)
			(xy 192.508868 -427.399381) (xy 192.566761 -427.414894) (xy 192.622134 -427.43783) (xy 192.67404 -427.467797)
			(xy 192.72159 -427.504284) (xy 192.76397 -427.546664) (xy 192.800457 -427.594214) (xy 192.830424 -427.64612)
			(xy 192.85336 -427.701493) (xy 192.868873 -427.759386) (xy 192.876696 -427.818808) (xy 192.877186 -427.848776)
			(xy 192.876696 -427.878744) (xy 192.868873 -427.938166) (xy 192.85336 -427.996059) (xy 192.830424 -428.051432)
			(xy 192.800457 -428.103338) (xy 192.76397 -428.150888) (xy 192.72159 -428.193268) (xy 192.67404 -428.229755)
			(xy 192.622134 -428.259722) (xy 192.566761 -428.282658) (xy 192.508868 -428.298171) (xy 192.449446 -428.305994)
			(xy 192.38951 -428.305994) (xy 192.330088 -428.298171) (xy 192.272195 -428.282658) (xy 192.216822 -428.259722)
			(xy 192.164916 -428.229755) (xy 192.117366 -428.193268) (xy 192.074986 -428.150888) (xy 192.038499 -428.103338)
			(xy 192.008532 -428.051432) (xy 191.985596 -427.996059) (xy 191.970083 -427.938166) (xy 191.96226 -427.878744)
			(xy 190.668148 -427.878744) (xy 190.668148 -428.904908) (xy 190.668858 -428.917636) (xy 190.681001 -428.940012)
			(xy 190.691262 -428.94758) (xy 190.77432 -429.000666) (xy 190.799974 -429.002698) (xy 190.811912 -428.99711)
			(xy 190.840648 -428.984418) (xy 190.900245 -428.964551) (xy 190.961627 -428.951178) (xy 191.024087 -428.944452)
			(xy 191.055498 -428.944024) (xy 191.089524 -428.944499) (xy 191.157116 -428.9524) (xy 191.223333 -428.968093)
			(xy 191.287281 -428.991368) (xy 191.348094 -429.021909) (xy 191.404951 -429.059304) (xy 191.457081 -429.103047)
			(xy 191.503781 -429.152546) (xy 191.544419 -429.207132) (xy 191.578445 -429.266066) (xy 191.605399 -429.328553)
			(xy 191.624917 -429.393745) (xy 191.636734 -429.460763) (xy 191.640691 -429.5287) (xy 191.636734 -429.596637)
			(xy 191.624917 -429.663655) (xy 191.605399 -429.728847) (xy 191.578445 -429.791334) (xy 191.544419 -429.850268)
			(xy 191.503781 -429.904854) (xy 191.457081 -429.954353) (xy 191.404951 -429.998096) (xy 191.348094 -430.035491)
			(xy 191.287281 -430.066032) (xy 191.223333 -430.089307) (xy 191.157116 -430.105) (xy 191.089524 -430.112901)
			(xy 191.055498 -430.11344) (xy 191.024085 -430.113045) (xy 190.961617 -430.10634) (xy 190.900231 -430.092966)
			(xy 190.840636 -430.073077) (xy 190.811912 -430.060354) (xy 190.799974 -430.054766) (xy 190.77432 -430.056798)
			(xy 190.691262 -430.109884) (xy 190.684321 -430.114741) (xy 190.673885 -430.128074) (xy 190.66839 -430.144089)
			(xy 190.668148 -430.152556) (xy 190.668148 -430.923657) (xy 191.810888 -430.923657) (xy 191.810888 -430.859735)
			(xy 191.818899 -430.796317) (xy 191.834796 -430.734403) (xy 191.858328 -430.67497) (xy 191.889122 -430.618955)
			(xy 191.926695 -430.56724) (xy 191.970452 -430.520643) (xy 192.019705 -430.479898) (xy 192.073676 -430.445647)
			(xy 192.131515 -430.41843) (xy 192.192308 -430.398677) (xy 192.255098 -430.386699) (xy 192.318894 -430.382686)
			(xy 192.38269 -430.386699) (xy 192.44548 -430.398677) (xy 192.506273 -430.41843) (xy 192.564112 -430.445647)
			(xy 192.618083 -430.479898) (xy 192.667336 -430.520643) (xy 192.711093 -430.56724) (xy 192.748666 -430.618955)
			(xy 192.77946 -430.67497) (xy 192.802992 -430.734403) (xy 192.818889 -430.796317) (xy 192.8269 -430.859735)
			(xy 192.827402 -430.891696) (xy 192.8269 -430.923657) (xy 192.818889 -430.987075) (xy 192.802992 -431.048989)
			(xy 192.77946 -431.108422) (xy 192.748666 -431.164437) (xy 192.711093 -431.216152) (xy 192.667336 -431.262749)
			(xy 192.618083 -431.303494) (xy 192.564112 -431.337745) (xy 192.506273 -431.364962) (xy 192.44548 -431.384715)
			(xy 192.38269 -431.396693) (xy 192.318894 -431.400707) (xy 192.255098 -431.396693) (xy 192.192308 -431.384715)
			(xy 192.131515 -431.364962) (xy 192.073676 -431.337745) (xy 192.019705 -431.303494) (xy 191.970452 -431.262749)
			(xy 191.926695 -431.216152) (xy 191.889122 -431.164437) (xy 191.858328 -431.108422) (xy 191.834796 -431.048989)
			(xy 191.818899 -430.987075) (xy 191.810888 -430.923657) (xy 190.668148 -430.923657) (xy 190.668148 -431.499264)
			(xy 190.667531 -431.527747) (xy 190.657052 -431.58374) (xy 190.64732 -431.610516) (xy 190.643764 -431.619406)
			(xy 190.643764 -432.504088) (xy 191.422032 -432.504088) (xy 191.425998 -432.419557) (xy 191.437863 -432.33577)
			(xy 191.457521 -432.253461) (xy 191.484801 -432.173355) (xy 191.519462 -432.096156) (xy 191.5612 -432.022541)
			(xy 191.609647 -431.953158) (xy 191.664379 -431.888617) (xy 191.724915 -431.829485) (xy 191.790721 -431.776281)
			(xy 191.861221 -431.729473) (xy 191.935793 -431.689472) (xy 192.013784 -431.65663) (xy 192.094508 -431.631236)
			(xy 192.177255 -431.613513) (xy 192.261297 -431.603615) (xy 192.345898 -431.601632) (xy 192.430312 -431.607579)
			(xy 192.513799 -431.621404) (xy 192.595624 -431.642987) (xy 192.675068 -431.672137) (xy 192.751434 -431.708598)
			(xy 192.82405 -431.75205) (xy 192.892278 -431.802111) (xy 192.955518 -431.858341) (xy 193.013215 -431.920246)
			(xy 193.064862 -431.987282) (xy 193.110004 -432.058859) (xy 193.148246 -432.134349) (xy 193.17925 -432.213088)
			(xy 193.202745 -432.294385) (xy 193.218524 -432.377524) (xy 193.226448 -432.461776) (xy 193.226944 -432.504088)
			(xy 193.226448 -432.5464) (xy 193.218524 -432.630652) (xy 193.202745 -432.713791) (xy 193.17925 -432.795088)
			(xy 193.148246 -432.873827) (xy 193.110004 -432.949317) (xy 193.064862 -433.020894) (xy 193.013215 -433.08793)
			(xy 192.955518 -433.149835) (xy 192.892278 -433.206065) (xy 192.82405 -433.256126) (xy 192.751434 -433.299578)
			(xy 192.675068 -433.336039) (xy 192.595624 -433.365189) (xy 192.513799 -433.386772) (xy 192.430312 -433.400597)
			(xy 192.345898 -433.406544) (xy 192.261297 -433.404561) (xy 192.177255 -433.394663) (xy 192.094508 -433.37694)
			(xy 192.013784 -433.351546) (xy 191.935793 -433.318704) (xy 191.861221 -433.278703) (xy 191.790721 -433.231895)
			(xy 191.724915 -433.178691) (xy 191.664379 -433.119559) (xy 191.609647 -433.055018) (xy 191.5612 -432.985635)
			(xy 191.519462 -432.91202) (xy 191.484801 -432.834821) (xy 191.457521 -432.754715) (xy 191.437863 -432.672406)
			(xy 191.425998 -432.588619) (xy 191.422032 -432.504088) (xy 190.643764 -432.504088) (xy 190.643764 -432.578764)
			(xy 190.643328 -432.588828) (xy 190.635594 -432.607413) (xy 190.628778 -432.614832) (xy 189.377828 -433.865782)
			(xy 189.370426 -433.872619) (xy 189.351828 -433.88033) (xy 189.34176 -433.880768) (xy 186.920124 -433.880768)
			(xy 186.910073 -433.881273) (xy 186.891511 -433.888993) (xy 186.884056 -433.895754) (xy 186.388756 -434.391054)
			(xy 186.381912 -434.398453) (xy 186.374188 -434.417052) (xy 186.37377 -434.427122) (xy 186.37377 -435.044088)
			(xy 191.295024 -435.044088) (xy 191.299053 -434.953082) (xy 191.31111 -434.862788) (xy 191.3311 -434.773913)
			(xy 191.358866 -434.687153) (xy 191.394192 -434.603186) (xy 191.4368 -434.52267) (xy 191.486358 -434.446234)
			(xy 191.542477 -434.374478) (xy 191.604718 -434.307962) (xy 191.672595 -434.247207) (xy 191.745575 -434.192689)
			(xy 191.823088 -434.144835) (xy 191.904527 -434.104018) (xy 191.989255 -434.070559) (xy 192.076609 -434.044718)
			(xy 192.165904 -434.0267) (xy 192.256442 -434.016643) (xy 192.347515 -434.014628) (xy 192.43841 -434.02067)
			(xy 192.528415 -434.034721) (xy 192.616826 -434.056672) (xy 192.702951 -434.086351) (xy 192.786116 -434.123525)
			(xy 192.86567 -434.167904) (xy 192.94099 -434.219141) (xy 193.011488 -434.276834) (xy 193.07661 -434.340531)
			(xy 193.135848 -434.409735) (xy 193.188738 -434.483904) (xy 193.234867 -434.562456) (xy 193.273872 -434.644779)
			(xy 193.305449 -434.730226) (xy 193.32935 -434.81813) (xy 193.345389 -434.907802) (xy 193.35344 -434.99854)
			(xy 193.353944 -435.044088) (xy 193.35344 -435.089636) (xy 193.345389 -435.180374) (xy 193.32935 -435.270046)
			(xy 193.305449 -435.35795) (xy 193.273872 -435.443397) (xy 193.234867 -435.52572) (xy 193.188738 -435.604272)
			(xy 193.135848 -435.678441) (xy 193.07661 -435.747645) (xy 193.011488 -435.811342) (xy 192.94099 -435.869035)
			(xy 192.86567 -435.920272) (xy 192.786116 -435.964651) (xy 192.702951 -436.001825) (xy 192.616826 -436.031504)
			(xy 192.528415 -436.053455) (xy 192.43841 -436.067506) (xy 192.347515 -436.073548) (xy 192.256442 -436.071533)
			(xy 192.165904 -436.061476) (xy 192.076609 -436.043458) (xy 191.989255 -436.017617) (xy 191.904527 -435.984158)
			(xy 191.823088 -435.943341) (xy 191.745575 -435.895487) (xy 191.672595 -435.840969) (xy 191.604718 -435.780214)
			(xy 191.542477 -435.713698) (xy 191.486358 -435.641942) (xy 191.4368 -435.565506) (xy 191.394192 -435.48499)
			(xy 191.358866 -435.401023) (xy 191.3311 -435.314263) (xy 191.31111 -435.225388) (xy 191.299053 -435.135094)
			(xy 191.295024 -435.044088) (xy 186.37377 -435.044088) (xy 186.37377 -438.358788) (xy 191.295528 -438.358788)
			(xy 191.295528 -436.809388) (xy 191.295937 -436.787159) (xy 191.30366 -436.743377) (xy 191.318868 -436.701601)
			(xy 191.3411 -436.663101) (xy 191.36968 -436.629046) (xy 191.40374 -436.600473) (xy 191.442244 -436.578248)
			(xy 191.484023 -436.563047) (xy 191.527807 -436.555333) (xy 191.550036 -436.55488) (xy 193.099436 -436.55488)
			(xy 193.121661 -436.555343) (xy 193.165434 -436.563067) (xy 193.207201 -436.578274) (xy 193.245693 -436.600502)
			(xy 193.279742 -436.629075) (xy 193.308312 -436.663126) (xy 193.330536 -436.701621) (xy 193.345739 -436.74339)
			(xy 193.353459 -436.787163) (xy 193.353944 -436.809388) (xy 193.353944 -437.601614) (xy 276.028912 -437.601614)
			(xy 276.029428 -437.567053) (xy 276.037577 -437.498413) (xy 276.053762 -437.431213) (xy 276.077758 -437.366391)
			(xy 276.10923 -437.304849) (xy 276.147739 -437.247448) (xy 276.192747 -437.194988) (xy 276.243627 -437.148202)
			(xy 276.299669 -437.10774) (xy 276.360091 -437.074169) (xy 276.391878 -437.060594) (xy 276.406102 -437.054752)
			(xy 276.423374 -437.029098) (xy 276.423374 -436.90413) (xy 276.406102 -436.878476) (xy 276.391878 -436.872634)
			(xy 276.360097 -436.859045) (xy 276.299675 -436.825475) (xy 276.243632 -436.785016) (xy 276.192751 -436.738231)
			(xy 276.147742 -436.685772) (xy 276.109231 -436.628373) (xy 276.077758 -436.566834) (xy 276.053759 -436.502012)
			(xy 276.037571 -436.434813) (xy 276.02942 -436.366175) (xy 276.028912 -436.331614) (xy 276.029417 -436.296276)
			(xy 276.037935 -436.226116) (xy 276.054848 -436.157494) (xy 276.079909 -436.091411) (xy 276.112753 -436.02883)
			(xy 276.152901 -435.970665) (xy 276.199768 -435.917764) (xy 276.25267 -435.870898) (xy 276.310835 -435.83075)
			(xy 276.373416 -435.797907) (xy 276.439499 -435.772846) (xy 276.508122 -435.755934) (xy 276.578282 -435.747417)
			(xy 276.61362 -435.746906) (xy 276.645769 -435.74736) (xy 276.709679 -435.754407) (xy 276.772429 -435.768425)
			(xy 276.833262 -435.789245) (xy 276.86254 -435.802532) (xy 276.873208 -435.807612) (xy 276.895814 -435.807358)
			(xy 276.987762 -435.763162) (xy 277.001986 -435.74589) (xy 277.00478 -435.73446) (xy 277.011881 -435.707058)
			(xy 277.033095 -435.654579) (xy 277.06183 -435.605811) (xy 277.097457 -435.561824) (xy 277.139191 -435.523584)
			(xy 277.186118 -435.49193) (xy 277.237207 -435.467558) (xy 277.291336 -435.451002) (xy 277.347318 -435.442627)
			(xy 277.37562 -435.442106) (xy 277.402871 -435.442565) (xy 277.456819 -435.450324) (xy 277.509113 -435.465682)
			(xy 277.55869 -435.488325) (xy 277.604539 -435.517793) (xy 277.645729 -435.553486) (xy 277.681419 -435.594677)
			(xy 277.710885 -435.640528) (xy 277.733525 -435.690106) (xy 277.74888 -435.742401) (xy 277.756636 -435.796349)
			(xy 277.756636 -435.850851) (xy 277.74888 -435.904799) (xy 277.733525 -435.957094) (xy 277.710885 -436.006672)
			(xy 277.681419 -436.052523) (xy 277.645729 -436.093714) (xy 277.604539 -436.129407) (xy 277.55869 -436.158875)
			(xy 277.509113 -436.181518) (xy 277.456819 -436.196876) (xy 277.402871 -436.204635) (xy 277.37562 -436.205122)
			(xy 277.360441 -436.204963) (xy 277.330179 -436.20255) (xy 277.315168 -436.200296) (xy 277.303738 -436.198518)
			(xy 277.282148 -436.204868) (xy 277.205948 -436.27294) (xy 277.197312 -436.293514) (xy 277.19782 -436.305198)
			(xy 277.198328 -436.331614) (xy 277.197811 -436.366175) (xy 277.18966 -436.434813) (xy 277.173473 -436.502012)
			(xy 277.149476 -436.566834) (xy 277.120387 -436.623714) (xy 282.066236 -436.623714) (xy 282.070307 -436.568092)
			(xy 282.082433 -436.513655) (xy 282.102356 -436.461564) (xy 282.129652 -436.412929) (xy 282.163738 -436.368786)
			(xy 282.203887 -436.330077) (xy 282.249245 -436.297626) (xy 282.298845 -436.272125) (xy 282.351629 -436.254118)
			(xy 282.406472 -436.243988) (xy 282.462206 -436.241951) (xy 282.517643 -436.248051) (xy 282.5716 -436.262157)
			(xy 282.622929 -436.283969) (xy 282.670535 -436.313023) (xy 282.713403 -436.348698) (xy 282.75062 -436.390235)
			(xy 282.781393 -436.436748) (xy 282.805065 -436.487245) (xy 282.821133 -436.540652) (xy 282.829253 -436.595828)
			(xy 282.829762 -436.623714) (xy 282.829253 -436.6516) (xy 282.821133 -436.706776) (xy 282.805065 -436.760183)
			(xy 282.781393 -436.81068) (xy 282.75062 -436.857193) (xy 282.713403 -436.89873) (xy 282.670535 -436.934405)
			(xy 282.622929 -436.963459) (xy 282.5716 -436.985271) (xy 282.517643 -436.999377) (xy 282.462206 -437.005477)
			(xy 282.406472 -437.00344) (xy 282.351629 -436.99331) (xy 282.298845 -436.975303) (xy 282.249245 -436.949802)
			(xy 282.203887 -436.917351) (xy 282.163738 -436.878642) (xy 282.129652 -436.834499) (xy 282.102356 -436.785864)
			(xy 282.082433 -436.733773) (xy 282.070307 -436.679336) (xy 282.066236 -436.623714) (xy 277.120387 -436.623714)
			(xy 277.118004 -436.628374) (xy 277.079495 -436.685775) (xy 277.034487 -436.738235) (xy 276.983609 -436.785022)
			(xy 276.927568 -436.825485) (xy 276.867148 -436.859057) (xy 276.835362 -436.872634) (xy 276.821138 -436.878476)
			(xy 276.803866 -436.90413) (xy 276.803866 -437.029098) (xy 276.821138 -437.054752) (xy 276.835362 -437.060594)
			(xy 276.86254 -437.072532) (xy 276.873208 -437.077612) (xy 276.895814 -437.077358) (xy 276.987762 -437.033162)
			(xy 277.001986 -437.01589) (xy 277.00478 -437.00446) (xy 277.011881 -436.977058) (xy 277.033095 -436.924579)
			(xy 277.06183 -436.875811) (xy 277.097457 -436.831824) (xy 277.139191 -436.793584) (xy 277.186118 -436.76193)
			(xy 277.237207 -436.737558) (xy 277.291336 -436.721002) (xy 277.347318 -436.712627) (xy 277.37562 -436.712106)
			(xy 277.402871 -436.712565) (xy 277.456819 -436.720324) (xy 277.509113 -436.735682) (xy 277.55869 -436.758325)
			(xy 277.604539 -436.787793) (xy 277.645729 -436.823486) (xy 277.681419 -436.864677) (xy 277.710885 -436.910528)
			(xy 277.733525 -436.960106) (xy 277.74888 -437.012401) (xy 277.756636 -437.066349) (xy 277.756636 -437.120851)
			(xy 277.74888 -437.174799) (xy 277.733525 -437.227094) (xy 277.710885 -437.276672) (xy 277.681419 -437.322523)
			(xy 277.645729 -437.363714) (xy 277.604539 -437.399407) (xy 277.55869 -437.428875) (xy 277.509113 -437.451518)
			(xy 277.456819 -437.466876) (xy 277.402871 -437.474635) (xy 277.37562 -437.475122) (xy 277.360441 -437.474963)
			(xy 277.330179 -437.47255) (xy 277.315168 -437.470296) (xy 277.303738 -437.468518) (xy 277.282148 -437.474868)
			(xy 277.205948 -437.54294) (xy 277.197312 -437.563514) (xy 277.19782 -437.575198) (xy 277.198328 -437.601614)
			(xy 277.197833 -437.635641) (xy 277.189933 -437.703234) (xy 277.174239 -437.769452) (xy 277.150963 -437.833401)
			(xy 277.120421 -437.894216) (xy 277.101038 -437.923686) (xy 281.436316 -437.923686) (xy 281.440387 -437.868064)
			(xy 281.452513 -437.813627) (xy 281.472436 -437.761536) (xy 281.499732 -437.712901) (xy 281.533818 -437.668758)
			(xy 281.573967 -437.630049) (xy 281.619325 -437.597598) (xy 281.668925 -437.572097) (xy 281.721709 -437.55409)
			(xy 281.776552 -437.54396) (xy 281.832286 -437.541923) (xy 281.887723 -437.548023) (xy 281.94168 -437.562129)
			(xy 281.993009 -437.583941) (xy 282.040615 -437.612995) (xy 282.083483 -437.64867) (xy 282.1207 -437.690207)
			(xy 282.151473 -437.73672) (xy 282.175145 -437.787217) (xy 282.191213 -437.840624) (xy 282.199333 -437.8958)
			(xy 282.199842 -437.923686) (xy 282.199333 -437.951572) (xy 282.191213 -438.006748) (xy 282.175145 -438.060155)
			(xy 282.151473 -438.110652) (xy 282.1207 -438.157165) (xy 282.083483 -438.198702) (xy 282.040615 -438.234377)
			(xy 281.993009 -438.263431) (xy 281.94168 -438.285243) (xy 281.887723 -438.299349) (xy 281.832286 -438.305449)
			(xy 281.776552 -438.303412) (xy 281.721709 -438.293282) (xy 281.668925 -438.275275) (xy 281.619325 -438.249774)
			(xy 281.573967 -438.217323) (xy 281.533818 -438.178614) (xy 281.499732 -438.134471) (xy 281.472436 -438.085836)
			(xy 281.452513 -438.033745) (xy 281.440387 -437.979308) (xy 281.436316 -437.923686) (xy 277.101038 -437.923686)
			(xy 277.083025 -437.951073) (xy 277.039282 -438.003205) (xy 276.989782 -438.049906) (xy 276.935195 -438.090544)
			(xy 276.876259 -438.124571) (xy 276.813771 -438.151525) (xy 276.748577 -438.171043) (xy 276.681558 -438.182861)
			(xy 276.61362 -438.186818) (xy 276.545682 -438.182861) (xy 276.478663 -438.171043) (xy 276.413469 -438.151525)
			(xy 276.350981 -438.124571) (xy 276.292045 -438.090544) (xy 276.237458 -438.049906) (xy 276.187958 -438.003205)
			(xy 276.144215 -437.951073) (xy 276.106819 -437.894216) (xy 276.076277 -437.833401) (xy 276.053001 -437.769452)
			(xy 276.037307 -437.703234) (xy 276.029407 -437.635641) (xy 276.028912 -437.601614) (xy 193.353944 -437.601614)
			(xy 193.353944 -438.358788) (xy 193.353413 -438.38101) (xy 193.349764 -438.401714) (xy 276.993602 -438.401714)
			(xy 276.997673 -438.346092) (xy 277.009799 -438.291655) (xy 277.029722 -438.239564) (xy 277.057018 -438.190929)
			(xy 277.091104 -438.146786) (xy 277.131253 -438.108077) (xy 277.176611 -438.075626) (xy 277.226211 -438.050125)
			(xy 277.278995 -438.032118) (xy 277.333838 -438.021988) (xy 277.389572 -438.019951) (xy 277.445009 -438.026051)
			(xy 277.498966 -438.040157) (xy 277.550295 -438.061969) (xy 277.597901 -438.091023) (xy 277.640769 -438.126698)
			(xy 277.677986 -438.168235) (xy 277.708759 -438.214748) (xy 277.732431 -438.265245) (xy 277.748499 -438.318652)
			(xy 277.756619 -438.373828) (xy 277.757128 -438.401714) (xy 277.756619 -438.4296) (xy 277.748499 -438.484776)
			(xy 277.732431 -438.538183) (xy 277.708759 -438.58868) (xy 277.677986 -438.635193) (xy 277.640769 -438.67673)
			(xy 277.597901 -438.712405) (xy 277.550295 -438.741459) (xy 277.498966 -438.763271) (xy 277.445009 -438.777377)
			(xy 277.389572 -438.783477) (xy 277.333838 -438.78144) (xy 277.278995 -438.77131) (xy 277.226211 -438.753303)
			(xy 277.176611 -438.727802) (xy 277.131253 -438.695351) (xy 277.091104 -438.656642) (xy 277.057018 -438.612499)
			(xy 277.029722 -438.563864) (xy 277.009799 -438.511773) (xy 276.997673 -438.457336) (xy 276.993602 -438.401714)
			(xy 193.349764 -438.401714) (xy 193.345698 -438.424779) (xy 193.3305 -438.466543) (xy 193.308281 -438.505034)
			(xy 193.279717 -438.539083) (xy 193.245674 -438.567654) (xy 193.207187 -438.58988) (xy 193.165425 -438.605085)
			(xy 193.121658 -438.612809) (xy 193.099436 -438.613296) (xy 191.550036 -438.613296) (xy 191.52781 -438.612819)
			(xy 191.484032 -438.605105) (xy 191.442259 -438.589906) (xy 191.40376 -438.567683) (xy 191.369706 -438.539111)
			(xy 191.341131 -438.50506) (xy 191.318904 -438.466563) (xy 191.303701 -438.424791) (xy 191.295983 -438.381014)
			(xy 191.295528 -438.358788) (xy 186.37377 -438.358788) (xy 186.37377 -440.083702) (xy 186.374193 -440.093773)
			(xy 186.381904 -440.112379) (xy 186.388756 -440.11977) (xy 186.62142 -440.352434) (xy 186.628816 -440.359284)
			(xy 186.647415 -440.367022) (xy 186.657488 -440.36742) (xy 193.545714 -440.36742) (xy 193.555784 -440.366995)
			(xy 193.574386 -440.359279) (xy 193.581782 -440.352434) (xy 194.684904 -439.249312) (xy 194.692302 -439.242465)
			(xy 194.7109 -439.23473) (xy 194.720972 -439.234326) (xy 278.072342 -439.234326) (xy 278.082408 -439.234757)
			(xy 278.100999 -439.242485) (xy 278.10841 -439.249312) (xy 279.35936 -440.500262) (xy 279.36676 -440.507103)
			(xy 279.385359 -440.514822) (xy 279.395428 -440.515248)
		)
		(stroke
			(width 0)
			(type solid)
		)
		(fill yes)
		(layer "B.Cu")
		(net "P3V3_AUX")
	)
	(gr_poly
		(pts
			(xy 21.338794 -198.181722) (xy 21.340064 -198.161656) (xy 21.342349 -198.133947) (xy 21.354197 -198.079628)
			(xy 21.374065 -198.027702) (xy 21.401502 -197.979347) (xy 21.435886 -197.935658) (xy 21.476438 -197.897625)
			(xy 21.52224 -197.866109) (xy 21.572253 -197.841826) (xy 21.625345 -197.825325) (xy 21.680312 -197.81698)
			(xy 21.735908 -197.81698) (xy 21.790875 -197.825325) (xy 21.843967 -197.841826) (xy 21.89398 -197.866109)
			(xy 21.939782 -197.897625) (xy 21.980334 -197.935658) (xy 22.014718 -197.979347) (xy 22.042155 -198.027702)
			(xy 22.062023 -198.079628) (xy 22.073871 -198.133947) (xy 22.076156 -198.161656) (xy 22.077426 -198.181722)
			(xy 22.106636 -198.209154) (xy 24.77897 -198.209154) (xy 24.80818 -198.181976) (xy 24.80945 -198.16191)
			(xy 24.81167 -198.136183) (xy 24.822857 -198.085773) (xy 24.841463 -198.037605) (xy 24.867071 -197.992766)
			(xy 24.899103 -197.952266) (xy 24.936838 -197.917018) (xy 24.979424 -197.887815) (xy 25.025901 -197.865318)
			(xy 25.075223 -197.850031) (xy 25.126278 -197.842301) (xy 25.177914 -197.842301) (xy 25.228969 -197.850031)
			(xy 25.278291 -197.865318) (xy 25.324768 -197.887815) (xy 25.367354 -197.917018) (xy 25.405089 -197.952266)
			(xy 25.437121 -197.992766) (xy 25.462729 -198.037605) (xy 25.481335 -198.085773) (xy 25.492522 -198.136183)
			(xy 25.494742 -198.16191) (xy 25.496012 -198.181976) (xy 25.525222 -198.209154) (xy 28.853638 -198.209154)
			(xy 28.882848 -198.181722) (xy 28.884118 -198.161656) (xy 28.886403 -198.133947) (xy 28.898251 -198.079628)
			(xy 28.918119 -198.027702) (xy 28.945556 -197.979347) (xy 28.97994 -197.935658) (xy 29.020492 -197.897625)
			(xy 29.066294 -197.866109) (xy 29.116307 -197.841826) (xy 29.169399 -197.825325) (xy 29.224366 -197.81698)
			(xy 29.279962 -197.81698) (xy 29.334929 -197.825325) (xy 29.388021 -197.841826) (xy 29.438034 -197.866109)
			(xy 29.483836 -197.897625) (xy 29.524388 -197.935658) (xy 29.558772 -197.979347) (xy 29.586209 -198.027702)
			(xy 29.606077 -198.079628) (xy 29.617925 -198.133947) (xy 29.62021 -198.161656) (xy 29.62148 -198.181722)
			(xy 29.65069 -198.209154) (xy 32.32277 -198.209154) (xy 32.35198 -198.181976) (xy 32.35325 -198.16191)
			(xy 32.35547 -198.136183) (xy 32.366657 -198.085773) (xy 32.385263 -198.037605) (xy 32.410871 -197.992766)
			(xy 32.442903 -197.952266) (xy 32.480638 -197.917018) (xy 32.523224 -197.887815) (xy 32.569701 -197.865318)
			(xy 32.619023 -197.850031) (xy 32.670078 -197.842301) (xy 32.721714 -197.842301) (xy 32.772769 -197.850031)
			(xy 32.822091 -197.865318) (xy 32.868568 -197.887815) (xy 32.911154 -197.917018) (xy 32.948889 -197.952266)
			(xy 32.980921 -197.992766) (xy 33.006529 -198.037605) (xy 33.025135 -198.085773) (xy 33.036322 -198.136183)
			(xy 33.038542 -198.16191) (xy 33.039812 -198.181976) (xy 33.069022 -198.209154) (xy 36.397438 -198.209154)
			(xy 36.426648 -198.181722) (xy 36.427918 -198.161656) (xy 36.430203 -198.133947) (xy 36.442051 -198.079628)
			(xy 36.461919 -198.027702) (xy 36.489356 -197.979347) (xy 36.52374 -197.935658) (xy 36.564292 -197.897625)
			(xy 36.610094 -197.866109) (xy 36.660107 -197.841826) (xy 36.713199 -197.825325) (xy 36.768166 -197.81698)
			(xy 36.823762 -197.81698) (xy 36.878729 -197.825325) (xy 36.931821 -197.841826) (xy 36.981834 -197.866109)
			(xy 37.027636 -197.897625) (xy 37.068188 -197.935658) (xy 37.102572 -197.979347) (xy 37.130009 -198.027702)
			(xy 37.149877 -198.079628) (xy 37.161725 -198.133947) (xy 37.16401 -198.161656) (xy 37.16528 -198.181722)
			(xy 37.19449 -198.209154) (xy 39.866824 -198.209154) (xy 39.896034 -198.181976) (xy 39.897304 -198.16191)
			(xy 39.899524 -198.136183) (xy 39.910711 -198.085773) (xy 39.929317 -198.037605) (xy 39.954925 -197.992766)
			(xy 39.986957 -197.952266) (xy 40.024692 -197.917018) (xy 40.067278 -197.887815) (xy 40.113755 -197.865318)
			(xy 40.163077 -197.850031) (xy 40.214132 -197.842301) (xy 40.265768 -197.842301) (xy 40.316823 -197.850031)
			(xy 40.366145 -197.865318) (xy 40.412622 -197.887815) (xy 40.455208 -197.917018) (xy 40.492943 -197.952266)
			(xy 40.524975 -197.992766) (xy 40.550583 -198.037605) (xy 40.569189 -198.085773) (xy 40.580376 -198.136183)
			(xy 40.582596 -198.16191) (xy 40.583866 -198.181976) (xy 40.613076 -198.209154) (xy 43.941492 -198.209154)
			(xy 43.970702 -198.181722) (xy 43.971972 -198.161656) (xy 43.974257 -198.133947) (xy 43.986105 -198.079628)
			(xy 44.005973 -198.027702) (xy 44.03341 -197.979347) (xy 44.067794 -197.935658) (xy 44.108346 -197.897625)
			(xy 44.154148 -197.866109) (xy 44.204161 -197.841826) (xy 44.257253 -197.825325) (xy 44.31222 -197.81698)
			(xy 44.367816 -197.81698) (xy 44.422783 -197.825325) (xy 44.475875 -197.841826) (xy 44.525888 -197.866109)
			(xy 44.57169 -197.897625) (xy 44.612242 -197.935658) (xy 44.646626 -197.979347) (xy 44.674063 -198.027702)
			(xy 44.693931 -198.079628) (xy 44.705779 -198.133947) (xy 44.708064 -198.161656) (xy 44.709334 -198.181722)
			(xy 44.738544 -198.209154) (xy 47.410878 -198.209154) (xy 47.440088 -198.181976) (xy 47.441358 -198.16191)
			(xy 47.443578 -198.136183) (xy 47.454765 -198.085773) (xy 47.473371 -198.037605) (xy 47.498979 -197.992766)
			(xy 47.531011 -197.952266) (xy 47.568746 -197.917018) (xy 47.611332 -197.887815) (xy 47.657809 -197.865318)
			(xy 47.707131 -197.850031) (xy 47.758186 -197.842301) (xy 47.809822 -197.842301) (xy 47.860877 -197.850031)
			(xy 47.910199 -197.865318) (xy 47.956676 -197.887815) (xy 47.999262 -197.917018) (xy 48.036997 -197.952266)
			(xy 48.069029 -197.992766) (xy 48.094637 -198.037605) (xy 48.113243 -198.085773) (xy 48.12443 -198.136183)
			(xy 48.12665 -198.16191) (xy 48.12792 -198.181976) (xy 48.15713 -198.209154) (xy 51.485546 -198.209154)
			(xy 51.514756 -198.181722) (xy 51.516026 -198.161656) (xy 51.518311 -198.133947) (xy 51.530159 -198.079628)
			(xy 51.550027 -198.027702) (xy 51.577464 -197.979347) (xy 51.611848 -197.935658) (xy 51.6524 -197.897625)
			(xy 51.698202 -197.866109) (xy 51.748215 -197.841826) (xy 51.801307 -197.825325) (xy 51.856274 -197.81698)
			(xy 51.91187 -197.81698) (xy 51.966837 -197.825325) (xy 52.019929 -197.841826) (xy 52.069942 -197.866109)
			(xy 52.115744 -197.897625) (xy 52.156296 -197.935658) (xy 52.19068 -197.979347) (xy 52.218117 -198.027702)
			(xy 52.237985 -198.079628) (xy 52.249833 -198.133947) (xy 52.252118 -198.161656) (xy 52.253388 -198.181722)
			(xy 52.282598 -198.209154) (xy 57.062116 -198.209154) (xy 57.072184 -198.208727) (xy 57.09078 -198.201003)
			(xy 57.098184 -198.194168) (xy 57.953148 -197.339204) (xy 57.960001 -197.331808) (xy 57.967745 -197.31321)
			(xy 57.968134 -197.303136) (xy 57.968134 -195.947792) (xy 57.967596 -195.937804) (xy 57.959884 -195.919371)
			(xy 57.953148 -195.911978) (xy 57.838594 -195.797424) (xy 57.816611 -195.774828) (xy 57.777318 -195.725528)
			(xy 57.743795 -195.672136) (xy 57.716463 -195.615325) (xy 57.695667 -195.555811) (xy 57.681669 -195.494341)
			(xy 57.674644 -195.43169) (xy 57.674256 -195.400168) (xy 57.674736 -195.366427) (xy 57.682786 -195.299428)
			(xy 57.698815 -195.233878) (xy 57.722591 -195.170724) (xy 57.737756 -195.14058) (xy 57.742145 -195.131216)
			(xy 57.743732 -195.110619) (xy 57.740804 -195.100702) (xy 57.731307 -195.071552) (xy 57.717983 -195.011706)
			(xy 57.711269 -194.950763) (xy 57.710832 -194.920108) (xy 57.710832 -194.9196) (xy 57.711306 -194.888019)
			(xy 57.718433 -194.82526) (xy 57.725056 -194.794378) (xy 57.726557 -194.78624) (xy 57.724868 -194.769788)
			(xy 57.721754 -194.76212) (xy 57.709657 -194.734633) (xy 57.690726 -194.677636) (xy 57.677984 -194.618946)
			(xy 57.671577 -194.559231) (xy 57.671208 -194.529202) (xy 57.671208 -194.528694) (xy 57.671676 -194.496643)
			(xy 57.679001 -194.432961) (xy 57.693532 -194.370527) (xy 57.71508 -194.310155) (xy 57.743365 -194.252631)
			(xy 57.778017 -194.198702) (xy 57.797954 -194.173602) (xy 57.805188 -194.163659) (xy 57.810248 -194.139635)
			(xy 57.807606 -194.127628) (xy 57.799097 -194.095531) (xy 57.789925 -194.029765) (xy 57.789318 -193.996564)
			(xy 57.789741 -193.967786) (xy 57.796631 -193.910644) (xy 57.810319 -193.854739) (xy 57.820052 -193.827654)
			(xy 57.824624 -193.815716) (xy 57.821576 -193.791332) (xy 57.767982 -193.713608) (xy 57.76341 -193.707766)
			(xy 57.75678 -193.701277) (xy 57.7401 -193.693196) (xy 57.730898 -193.692018) (xy 57.726326 -193.691764)
			(xy 56.358282 -193.691764) (xy 56.348215 -193.692192) (xy 56.329621 -193.699918) (xy 56.322214 -193.70675)
			(xy 56.250586 -193.778378) (xy 56.243743 -193.785777) (xy 56.236023 -193.804376) (xy 56.2356 -193.814446)
			(xy 56.2356 -194.279774) (xy 56.236037 -194.289838) (xy 56.24377 -194.308423) (xy 56.250586 -194.315842)
			(xy 56.322214 -194.38747) (xy 56.329612 -194.394317) (xy 56.34821 -194.402052) (xy 56.358282 -194.402456)
			(xy 56.483758 -194.402456) (xy 56.515394 -194.402948) (xy 56.578126 -194.411202) (xy 56.639244 -194.427574)
			(xy 56.697701 -194.451783) (xy 56.752499 -194.483416) (xy 56.802698 -194.521932) (xy 56.847441 -194.56667)
			(xy 56.88596 -194.616866) (xy 56.917598 -194.671661) (xy 56.941813 -194.730116) (xy 56.95819 -194.791233)
			(xy 56.966449 -194.853964) (xy 56.966449 -194.917236) (xy 56.95819 -194.979967) (xy 56.941813 -195.041084)
			(xy 56.917598 -195.099539) (xy 56.88596 -195.154334) (xy 56.847441 -195.20453) (xy 56.802698 -195.249268)
			(xy 56.752499 -195.287784) (xy 56.697701 -195.319417) (xy 56.639244 -195.343626) (xy 56.578126 -195.359998)
			(xy 56.515394 -195.368252) (xy 56.483758 -195.368672) (xy 55.737252 -195.368672) (xy 55.70544 -195.368163)
			(xy 55.642366 -195.35981) (xy 55.580934 -195.343254) (xy 55.522205 -195.318781) (xy 55.467193 -195.286815)
			(xy 55.416852 -195.247908) (xy 55.394098 -195.22567) (xy 55.386986 -195.218558) (xy 55.361332 -195.207382)
			(xy 55.356491 -195.205382) (xy 55.346248 -195.20321) (xy 55.341012 -195.203064) (xy 55.152036 -195.203064)
			(xy 55.117238 -195.217034) (xy 55.093108 -195.23837) (xy 55.07482 -195.25361) (xy 55.07482 -195.263008)
			(xy 55.061104 -195.263008) (xy 55.048404 -195.271136) (xy 55.020608 -195.288265) (xy 54.961194 -195.31533)
			(xy 54.898536 -195.333678) (xy 54.833907 -195.342936) (xy 54.801262 -195.343526) (xy 54.773315 -195.343117)
			(xy 54.717836 -195.336326) (xy 54.663597 -195.322826) (xy 54.611408 -195.302817) (xy 54.562046 -195.276599)
			(xy 54.516246 -195.244561) (xy 54.495192 -195.226178) (xy 54.486761 -195.219344) (xy 54.466071 -195.212855)
			(xy 54.444541 -195.215428) (xy 54.434994 -195.22059) (xy 54.405145 -195.237929) (xy 54.341763 -195.265273)
			(xy 54.275264 -195.283793) (xy 54.206872 -195.29315) (xy 54.172358 -195.293742) (xy 54.142004 -195.293304)
			(xy 54.081727 -195.286082) (xy 54.022739 -195.271733) (xy 53.96588 -195.250463) (xy 53.911958 -195.222573)
			(xy 53.86174 -195.188461) (xy 53.815942 -195.148611) (xy 53.775215 -195.103592) (xy 53.740139 -195.054043)
			(xy 53.725318 -195.02755) (xy 53.71846 -195.01485) (xy 53.694076 -195.000626) (xy 53.589174 -195.002912)
			(xy 53.544724 -195.03136) (xy 53.527538 -195.065198) (xy 53.485399 -195.128317) (xy 53.43513 -195.185174)
			(xy 53.406802 -195.21043) (xy 53.432534 -195.233331) (xy 53.478782 -195.284383) (xy 53.518436 -195.340711)
			(xy 53.550899 -195.401467) (xy 53.575684 -195.46574) (xy 53.592419 -195.532562) (xy 53.600851 -195.600929)
			(xy 53.601366 -195.635372) (xy 53.60091 -195.666881) (xy 53.593827 -195.729499) (xy 53.57978 -195.790932)
			(xy 53.558947 -195.850406) (xy 53.531589 -195.907176) (xy 53.498049 -195.960527) (xy 53.45875 -196.009789)
			(xy 53.436774 -196.032374) (xy 52.980844 -196.488558) (xy 52.25288 -196.488558) (xy 52.25213 -196.515996)
			(xy 52.24351 -196.570203) (xy 52.226952 -196.622533) (xy 52.202822 -196.671832) (xy 52.171652 -196.71701)
			(xy 52.13413 -196.75707) (xy 52.091086 -196.791127) (xy 52.043471 -196.818428) (xy 51.992335 -196.838372)
			(xy 51.938808 -196.850517) (xy 51.884072 -196.854596) (xy 51.829336 -196.850517) (xy 51.775809 -196.838372)
			(xy 51.724673 -196.818428) (xy 51.677058 -196.791127) (xy 51.634014 -196.75707) (xy 51.596492 -196.71701)
			(xy 51.565322 -196.671832) (xy 51.541192 -196.622533) (xy 51.524634 -196.570203) (xy 51.516014 -196.515996)
			(xy 51.515264 -196.488558) (xy 51.483839 -196.487823) (xy 51.421442 -196.480213) (xy 51.360283 -196.465684)
			(xy 51.301129 -196.44442) (xy 51.244719 -196.416685) (xy 51.191756 -196.382826) (xy 51.142905 -196.343267)
			(xy 51.120548 -196.321172) (xy 51.097907 -196.343532) (xy 51.04842 -196.383538) (xy 50.994731 -196.417699)
			(xy 50.937527 -196.445577) (xy 50.87754 -196.466815) (xy 50.815539 -196.481142) (xy 50.752315 -196.488375)
			(xy 50.720498 -196.488812) (xy 50.688969 -196.488386) (xy 50.626309 -196.481325) (xy 50.564833 -196.467293)
			(xy 50.505315 -196.446465) (xy 50.448503 -196.419104) (xy 50.395112 -196.385554) (xy 50.345814 -196.346236)
			(xy 50.323242 -196.32422) (xy 49.806098 -195.807076) (xy 49.784117 -195.78448) (xy 49.744828 -195.735178)
			(xy 49.711309 -195.681786) (xy 49.683982 -195.624975) (xy 49.663191 -195.56546) (xy 49.649197 -195.503991)
			(xy 49.642178 -195.441341) (xy 49.64176 -195.40982) (xy 49.64176 -195.387214) (xy 49.642263 -195.352981)
			(xy 49.650572 -195.285022) (xy 49.66708 -195.218577) (xy 49.691543 -195.154631) (xy 49.723598 -195.094134)
			(xy 49.762769 -195.037981) (xy 49.808476 -194.987007) (xy 49.86004 -194.941967) (xy 49.916697 -194.903529)
			(xy 49.977607 -194.872264) (xy 50.041865 -194.848634) (xy 50.075084 -194.840352) (xy 50.092356 -194.836288)
			(xy 50.1142 -194.808856) (xy 50.1142 -193.941446) (xy 50.113767 -193.93138) (xy 50.106039 -193.91279)
			(xy 50.099214 -193.905378) (xy 49.900586 -193.70675) (xy 49.893189 -193.6999) (xy 49.874591 -193.692163)
			(xy 49.864518 -193.691764) (xy 48.823118 -193.691764) (xy 48.813056 -193.692204) (xy 48.794479 -193.699946)
			(xy 48.78705 -193.70675) (xy 48.732186 -193.761614) (xy 48.725332 -193.769009) (xy 48.71759 -193.787608)
			(xy 48.7172 -193.797682) (xy 48.7172 -194.254374) (xy 48.717637 -194.264438) (xy 48.72537 -194.283023)
			(xy 48.732186 -194.290442) (xy 48.829214 -194.38747) (xy 48.836612 -194.394317) (xy 48.85521 -194.402052)
			(xy 48.865282 -194.402456) (xy 48.939704 -194.402456) (xy 48.971337 -194.402973) (xy 49.034061 -194.411232)
			(xy 49.095171 -194.427606) (xy 49.153621 -194.451818) (xy 49.208411 -194.483451) (xy 49.258602 -194.521965)
			(xy 49.303338 -194.566701) (xy 49.341852 -194.616893) (xy 49.373484 -194.671683) (xy 49.397695 -194.730133)
			(xy 49.414069 -194.791243) (xy 49.422327 -194.853967) (xy 49.422327 -194.917233) (xy 49.414069 -194.979957)
			(xy 49.397695 -195.041067) (xy 49.373484 -195.099517) (xy 49.341852 -195.154307) (xy 49.303338 -195.204499)
			(xy 49.258602 -195.249235) (xy 49.208411 -195.287749) (xy 49.153621 -195.319382) (xy 49.095171 -195.343594)
			(xy 49.034061 -195.359968) (xy 48.971337 -195.368227) (xy 48.939704 -195.368672) (xy 48.193198 -195.368672)
			(xy 48.161385 -195.368166) (xy 48.098308 -195.359818) (xy 48.036872 -195.343267) (xy 47.978139 -195.318798)
			(xy 47.923123 -195.286835) (xy 47.872777 -195.24793) (xy 47.850044 -195.22567) (xy 47.842932 -195.218558)
			(xy 47.817278 -195.207382) (xy 47.812438 -195.205378) (xy 47.802195 -195.203196) (xy 47.796958 -195.203064)
			(xy 47.58055 -195.203064) (xy 47.570757 -195.203581) (xy 47.552677 -195.211123) (xy 47.538824 -195.224975)
			(xy 47.531282 -195.243055) (xy 47.530766 -195.252848) (xy 47.530766 -195.263008) (xy 47.262542 -195.263008)
			(xy 47.243108 -195.262539) (xy 47.204832 -195.255762) (xy 47.168279 -195.24254) (xy 47.134526 -195.22326)
			(xy 47.119286 -195.211192) (xy 47.112682 -195.205604) (xy 47.088298 -195.196714) (xy 47.08401 -195.195194)
			(xy 47.075066 -195.193533) (xy 47.070518 -195.193412) (xy 46.94809 -195.193412) (xy 46.944283 -195.193477)
			(xy 46.936756 -195.194623) (xy 46.933104 -195.195698) (xy 46.92523 -195.197984) (xy 46.918626 -195.202556)
			(xy 46.893002 -195.21986) (xy 46.838358 -195.248799) (xy 46.780605 -195.270887) (xy 46.720596 -195.285796)
			(xy 46.659221 -195.293307) (xy 46.628304 -195.293742) (xy 46.597952 -195.293301) (xy 46.537679 -195.286073)
			(xy 46.478695 -195.27172) (xy 46.421841 -195.250445) (xy 46.367923 -195.222553) (xy 46.317711 -195.188438)
			(xy 46.271918 -195.148588) (xy 46.231196 -195.103568) (xy 46.196125 -195.05402) (xy 46.181264 -195.02755)
			(xy 46.174406 -195.01485) (xy 46.150022 -195.000626) (xy 46.04512 -195.002912) (xy 46.00067 -195.03136)
			(xy 45.986689 -195.059122) (xy 45.953471 -195.111663) (xy 45.914652 -195.160213) (xy 45.892974 -195.18249)
			(xy 45.864018 -195.211446) (xy 45.889594 -195.234349) (xy 45.935548 -195.285358) (xy 45.974942 -195.341588)
			(xy 46.00719 -195.402199) (xy 46.03181 -195.466289) (xy 46.048435 -195.532902) (xy 46.056818 -195.601044)
			(xy 46.057312 -195.635372) (xy 46.056856 -195.666881) (xy 46.049773 -195.7295) (xy 46.035728 -195.790933)
			(xy 46.014896 -195.850409) (xy 45.987539 -195.90718) (xy 45.954002 -195.960533) (xy 45.914704 -196.009797)
			(xy 45.89272 -196.032374) (xy 45.46219 -196.463158) (xy 44.708064 -196.463158) (xy 44.708826 -196.484748)
			(xy 44.708826 -196.485256) (xy 44.70831 -196.512856) (xy 44.700083 -196.567439) (xy 44.683813 -196.620186)
			(xy 44.659863 -196.669919) (xy 44.628768 -196.715526) (xy 44.591223 -196.75599) (xy 44.548066 -196.790407)
			(xy 44.500262 -196.818006) (xy 44.448878 -196.838173) (xy 44.395063 -196.850456) (xy 44.340018 -196.854581)
			(xy 44.284973 -196.850456) (xy 44.231158 -196.838173) (xy 44.179774 -196.818006) (xy 44.13197 -196.790407)
			(xy 44.088813 -196.75599) (xy 44.051268 -196.715526) (xy 44.020173 -196.669919) (xy 43.996223 -196.620186)
			(xy 43.979953 -196.567439) (xy 43.971726 -196.512856) (xy 43.97121 -196.485256) (xy 43.97121 -196.484494)
			(xy 43.971972 -196.463158) (xy 43.938219 -196.462367) (xy 43.871262 -196.453699) (xy 43.805826 -196.437068)
			(xy 43.742855 -196.412714) (xy 43.683256 -196.380988) (xy 43.627891 -196.342348) (xy 43.577555 -196.29735)
			(xy 43.532976 -196.246643) (xy 43.513502 -196.219064) (xy 43.403012 -196.219064) (xy 43.376596 -196.22643)
			(xy 43.342814 -196.244972) (xy 43.329606 -196.251322) (xy 43.314112 -196.27596) (xy 43.314112 -196.279008)
			(xy 43.233086 -196.279008) (xy 43.229784 -196.279262) (xy 43.216583 -196.281031) (xy 43.190016 -196.282939)
			(xy 43.176698 -196.283072) (xy 43.163381 -196.282929) (xy 43.136813 -196.281023) (xy 43.123612 -196.279262)
			(xy 43.12031 -196.279008) (xy 43.04665 -196.279008) (xy 43.024326 -196.278484) (xy 42.980545 -196.269723)
			(xy 42.939331 -196.252551) (xy 42.902281 -196.227634) (xy 42.870834 -196.195939) (xy 42.84621 -196.158694)
			(xy 42.829363 -196.117346) (xy 42.820947 -196.073498) (xy 42.82059 -196.05117) (xy 42.820844 -196.05117)
			(xy 42.820844 -196.038978) (xy 42.817796 -196.030596) (xy 42.807293 -195.999375) (xy 42.795935 -195.934496)
			(xy 42.79519 -195.901564) (xy 42.795901 -195.868629) (xy 42.807263 -195.803745) (xy 42.817796 -195.772532)
			(xy 42.820844 -195.76415) (xy 42.820844 -195.751958) (xy 42.82059 -195.751958) (xy 42.820934 -195.731665)
			(xy 42.827942 -195.691693) (xy 42.84194 -195.653602) (xy 42.851832 -195.63588) (xy 42.860722 -195.620894)
			(xy 42.856404 -195.586604) (xy 42.585386 -195.315586) (xy 42.578532 -195.308191) (xy 42.57079 -195.289592)
			(xy 42.5704 -195.279518) (xy 42.5704 -193.966846) (xy 42.569967 -193.95678) (xy 42.562239 -193.93819)
			(xy 42.555414 -193.930778) (xy 42.331386 -193.70675) (xy 42.323989 -193.6999) (xy 42.305391 -193.692163)
			(xy 42.295318 -193.691764) (xy 41.296082 -193.691764) (xy 41.286015 -193.692192) (xy 41.267421 -193.699918)
			(xy 41.260014 -193.70675) (xy 41.188386 -193.778378) (xy 41.181543 -193.785777) (xy 41.173823 -193.804376)
			(xy 41.1734 -193.814446) (xy 41.1734 -194.228974) (xy 41.173837 -194.239038) (xy 41.18157 -194.257623)
			(xy 41.188386 -194.265042) (xy 41.310814 -194.38747) (xy 41.318212 -194.394317) (xy 41.33681 -194.402052)
			(xy 41.346882 -194.402456) (xy 41.39565 -194.402456) (xy 41.427287 -194.402948) (xy 41.490019 -194.411201)
			(xy 41.551138 -194.427572) (xy 41.609596 -194.451781) (xy 41.664395 -194.483414) (xy 41.714595 -194.521929)
			(xy 41.759338 -194.566667) (xy 41.797859 -194.616864) (xy 41.829497 -194.671659) (xy 41.853712 -194.730115)
			(xy 41.870089 -194.791232) (xy 41.878349 -194.853963) (xy 41.878349 -194.917237) (xy 41.870089 -194.979968)
			(xy 41.853712 -195.041085) (xy 41.829497 -195.099541) (xy 41.797859 -195.154336) (xy 41.759338 -195.204533)
			(xy 41.714595 -195.249271) (xy 41.664395 -195.287786) (xy 41.609596 -195.319419) (xy 41.551138 -195.343628)
			(xy 41.490019 -195.359999) (xy 41.427287 -195.368252) (xy 41.39565 -195.368672) (xy 40.649398 -195.368672)
			(xy 40.617585 -195.368166) (xy 40.554508 -195.359818) (xy 40.493072 -195.343267) (xy 40.434339 -195.318798)
			(xy 40.379323 -195.286835) (xy 40.328977 -195.24793) (xy 40.306244 -195.22567) (xy 40.299132 -195.218558)
			(xy 40.273478 -195.207382) (xy 40.268638 -195.205378) (xy 40.258395 -195.203196) (xy 40.253158 -195.203064)
			(xy 40.03675 -195.203064) (xy 40.026957 -195.203581) (xy 40.008877 -195.211123) (xy 39.995024 -195.224975)
			(xy 39.987482 -195.243055) (xy 39.986966 -195.252848) (xy 39.986966 -195.263008) (xy 39.718742 -195.263008)
			(xy 39.699308 -195.262539) (xy 39.661032 -195.255762) (xy 39.624479 -195.24254) (xy 39.590726 -195.22326)
			(xy 39.575486 -195.211192) (xy 39.568882 -195.205604) (xy 39.544498 -195.196714) (xy 39.54021 -195.195194)
			(xy 39.531266 -195.193533) (xy 39.526718 -195.193412) (xy 39.404036 -195.193412) (xy 39.40023 -195.193481)
			(xy 39.392705 -195.194635) (xy 39.38905 -195.195698) (xy 39.381176 -195.197984) (xy 39.374572 -195.202556)
			(xy 39.348947 -195.219858) (xy 39.294303 -195.24879) (xy 39.236549 -195.270872) (xy 39.17654 -195.285775)
			(xy 39.115166 -195.293279) (xy 39.08425 -195.293742) (xy 39.053896 -195.293303) (xy 38.99362 -195.286081)
			(xy 38.934633 -195.271731) (xy 38.877774 -195.25046) (xy 38.823853 -195.22257) (xy 38.773636 -195.188457)
			(xy 38.727839 -195.148608) (xy 38.687112 -195.103588) (xy 38.652037 -195.054039) (xy 38.63721 -195.02755)
			(xy 38.630352 -195.01485) (xy 38.605968 -195.000626) (xy 38.501066 -195.002912) (xy 38.456616 -195.03136)
			(xy 38.442634 -195.059121) (xy 38.409413 -195.11166) (xy 38.370592 -195.160207) (xy 38.34892 -195.18249)
			(xy 38.319964 -195.211446) (xy 38.345538 -195.23435) (xy 38.391489 -195.28536) (xy 38.43088 -195.341591)
			(xy 38.463125 -195.402202) (xy 38.487743 -195.466292) (xy 38.504367 -195.532903) (xy 38.512749 -195.601045)
			(xy 38.513258 -195.635372) (xy 38.512802 -195.666881) (xy 38.505719 -195.729499) (xy 38.491672 -195.790931)
			(xy 38.470839 -195.850406) (xy 38.44348 -195.907175) (xy 38.40994 -195.960526) (xy 38.37064 -196.009788)
			(xy 38.348666 -196.032374) (xy 37.9349 -196.446394) (xy 37.16274 -196.446394) (xy 37.163689 -196.456018)
			(xy 37.164706 -196.475332) (xy 37.164772 -196.485002) (xy 37.164772 -196.485256) (xy 37.164256 -196.512856)
			(xy 37.156029 -196.567439) (xy 37.139759 -196.620186) (xy 37.115809 -196.669919) (xy 37.084714 -196.715526)
			(xy 37.047169 -196.75599) (xy 37.004012 -196.790407) (xy 36.956208 -196.818006) (xy 36.904824 -196.838173)
			(xy 36.851009 -196.850456) (xy 36.795964 -196.854581) (xy 36.740919 -196.850456) (xy 36.687104 -196.838173)
			(xy 36.63572 -196.818006) (xy 36.587916 -196.790407) (xy 36.544759 -196.75599) (xy 36.507214 -196.715526)
			(xy 36.476119 -196.669919) (xy 36.452169 -196.620186) (xy 36.435899 -196.567439) (xy 36.427672 -196.512856)
			(xy 36.427156 -196.485256) (xy 36.427156 -196.484748) (xy 36.427225 -196.475141) (xy 36.428244 -196.455955)
			(xy 36.429188 -196.446394) (xy 36.395854 -196.445245) (xy 36.329796 -196.436008) (xy 36.265297 -196.419009)
			(xy 36.203267 -196.394488) (xy 36.14458 -196.362789) (xy 36.090062 -196.324359) (xy 36.040482 -196.279741)
			(xy 35.996539 -196.229561) (xy 35.977322 -196.2023) (xy 35.866832 -196.2023) (xy 35.840416 -196.209666)
			(xy 35.806634 -196.228208) (xy 35.793426 -196.234558) (xy 35.777932 -196.259196) (xy 35.777932 -196.262244)
			(xy 35.696906 -196.262244) (xy 35.693604 -196.262498) (xy 35.680403 -196.264267) (xy 35.653836 -196.266177)
			(xy 35.640518 -196.266308) (xy 35.6272 -196.266166) (xy 35.600633 -196.264262) (xy 35.587432 -196.262498)
			(xy 35.58413 -196.262244) (xy 35.51047 -196.262244) (xy 35.488147 -196.261722) (xy 35.444368 -196.252963)
			(xy 35.403155 -196.235792) (xy 35.366109 -196.210874) (xy 35.334667 -196.179177) (xy 35.310049 -196.141931)
			(xy 35.29321 -196.100581) (xy 35.284805 -196.056733) (xy 35.28441 -196.034406) (xy 35.284664 -196.034406)
			(xy 35.284664 -196.022214) (xy 35.281616 -196.013832) (xy 35.271109 -195.982612) (xy 35.259745 -195.917733)
			(xy 35.25901 -195.8848) (xy 35.259726 -195.851866) (xy 35.271099 -195.786986) (xy 35.281616 -195.755768)
			(xy 35.284664 -195.747386) (xy 35.284664 -195.735194) (xy 35.28441 -195.735194) (xy 35.284856 -195.712287)
			(xy 35.293809 -195.667363) (xy 35.30219 -195.64604) (xy 35.308032 -195.631816) (xy 35.30219 -195.60159)
			(xy 35.066986 -195.366386) (xy 35.060132 -195.358991) (xy 35.05239 -195.340392) (xy 35.052 -195.330318)
			(xy 35.052 -194.829176) (xy 35.052428 -194.819108) (xy 35.060148 -194.80051) (xy 35.066986 -194.793108)
			(xy 35.087814 -194.77228) (xy 35.094667 -194.764885) (xy 35.102407 -194.746286) (xy 35.1028 -194.736212)
			(xy 35.1028 -193.899282) (xy 35.102373 -193.889213) (xy 35.094654 -193.870614) (xy 35.087814 -193.863214)
			(xy 34.93135 -193.70675) (xy 34.923951 -193.699906) (xy 34.905352 -193.692182) (xy 34.895282 -193.691764)
			(xy 33.752282 -193.691764) (xy 33.742215 -193.692192) (xy 33.723621 -193.699918) (xy 33.716214 -193.70675)
			(xy 33.644586 -193.778378) (xy 33.637743 -193.785777) (xy 33.630023 -193.804376) (xy 33.6296 -193.814446)
			(xy 33.6296 -194.161918) (xy 33.630027 -194.171987) (xy 33.637746 -194.190586) (xy 33.644586 -194.197986)
			(xy 33.716214 -194.269614) (xy 33.723609 -194.276468) (xy 33.742208 -194.28421) (xy 33.752282 -194.2846)
			(xy 34.192718 -194.2846) (xy 34.202787 -194.285027) (xy 34.221386 -194.292746) (xy 34.228786 -194.299586)
			(xy 34.325814 -194.396614) (xy 34.332668 -194.404009) (xy 34.34041 -194.422608) (xy 34.3408 -194.432682)
			(xy 34.3408 -195.254118) (xy 34.340373 -195.264187) (xy 34.332654 -195.282786) (xy 34.325814 -195.290186)
			(xy 34.228786 -195.387214) (xy 34.221391 -195.394068) (xy 34.202792 -195.40181) (xy 34.192718 -195.4022)
			(xy 30.983682 -195.4022) (xy 30.973613 -195.402627) (xy 30.955014 -195.410346) (xy 30.947614 -195.417186)
			(xy 30.931866 -195.432934) (xy 30.943746 -195.465216) (xy 30.960458 -195.531946) (xy 30.968907 -195.600215)
			(xy 30.969458 -195.63461) (xy 30.969458 -195.635372) (xy 30.969002 -195.666881) (xy 30.961919 -195.729499)
			(xy 30.947872 -195.790931) (xy 30.927039 -195.850406) (xy 30.89968 -195.907175) (xy 30.86614 -195.960526)
			(xy 30.82684 -196.009788) (xy 30.804866 -196.032374) (xy 30.348936 -196.488558) (xy 29.620972 -196.488558)
			(xy 29.620222 -196.515996) (xy 29.611602 -196.570203) (xy 29.595044 -196.622533) (xy 29.570914 -196.671832)
			(xy 29.539744 -196.71701) (xy 29.502222 -196.75707) (xy 29.459178 -196.791127) (xy 29.411563 -196.818428)
			(xy 29.360427 -196.838372) (xy 29.3069 -196.850517) (xy 29.252164 -196.854596) (xy 29.197428 -196.850517)
			(xy 29.143901 -196.838372) (xy 29.092765 -196.818428) (xy 29.04515 -196.791127) (xy 29.002106 -196.75707)
			(xy 28.964584 -196.71701) (xy 28.933414 -196.671832) (xy 28.909284 -196.622533) (xy 28.892726 -196.570203)
			(xy 28.884106 -196.515996) (xy 28.883356 -196.488558) (xy 28.86329 -196.488558) (xy 28.82923 -196.488059)
			(xy 28.761609 -196.479822) (xy 28.69548 -196.463469) (xy 28.631814 -196.439242) (xy 28.571544 -196.407494)
			(xy 28.515554 -196.368693) (xy 28.464666 -196.323406) (xy 28.419627 -196.2723) (xy 28.399994 -196.244464)
			(xy 28.289504 -196.244464) (xy 28.263088 -196.25183) (xy 28.229306 -196.270372) (xy 28.216098 -196.276722)
			(xy 28.200604 -196.30136) (xy 28.200604 -196.304408) (xy 28.119578 -196.304408) (xy 28.116276 -196.304662)
			(xy 28.103075 -196.30643) (xy 28.076508 -196.308338) (xy 28.06319 -196.308472) (xy 28.049873 -196.308329)
			(xy 28.023305 -196.306422) (xy 28.010104 -196.304662) (xy 28.006802 -196.304408) (xy 27.933142 -196.304408)
			(xy 27.910812 -196.303893) (xy 27.867017 -196.295145) (xy 27.825786 -196.277981) (xy 27.788721 -196.253067)
			(xy 27.75726 -196.22137) (xy 27.732623 -196.18412) (xy 27.715767 -196.142762) (xy 27.707347 -196.098903)
			(xy 27.707082 -196.07657) (xy 27.707336 -196.07657) (xy 27.707336 -196.064378) (xy 27.704288 -196.055996)
			(xy 27.693785 -196.024775) (xy 27.682428 -195.959896) (xy 27.681682 -195.926964) (xy 27.682392 -195.894029)
			(xy 27.693754 -195.829145) (xy 27.704288 -195.797932) (xy 27.707336 -195.78955) (xy 27.707336 -195.777358)
			(xy 27.707082 -195.777358) (xy 27.707507 -195.754756) (xy 27.716216 -195.710403) (xy 27.733522 -195.668648)
			(xy 27.74569 -195.649596) (xy 27.75008 -195.642506) (xy 27.754499 -195.626437) (xy 27.754326 -195.6181)
			(xy 27.752294 -195.588382) (xy 27.751381 -195.579147) (xy 27.743817 -195.562218) (xy 27.737562 -195.555362)
			(xy 27.497786 -195.315586) (xy 27.490932 -195.308191) (xy 27.48319 -195.289592) (xy 27.4828 -195.279518)
			(xy 27.4828 -193.873882) (xy 27.482373 -193.863813) (xy 27.474654 -193.845214) (xy 27.467814 -193.837814)
			(xy 27.33675 -193.70675) (xy 27.329351 -193.699906) (xy 27.310752 -193.692182) (xy 27.300682 -193.691764)
			(xy 26.208482 -193.691764) (xy 26.198415 -193.692192) (xy 26.179821 -193.699918) (xy 26.172414 -193.70675)
			(xy 26.118058 -193.761106) (xy 26.111206 -193.768502) (xy 26.103465 -193.787101) (xy 26.103072 -193.797174)
			(xy 26.103072 -194.220846) (xy 26.103503 -194.230913) (xy 26.111226 -194.249508) (xy 26.118058 -194.256914)
			(xy 26.248614 -194.38747) (xy 26.256012 -194.394317) (xy 26.27461 -194.402052) (xy 26.284682 -194.402456)
			(xy 26.307796 -194.402456) (xy 26.339431 -194.402951) (xy 26.402159 -194.411209) (xy 26.463272 -194.427584)
			(xy 26.521726 -194.451795) (xy 26.576519 -194.48343) (xy 26.626714 -194.521945) (xy 26.671452 -194.566683)
			(xy 26.709968 -194.616878) (xy 26.741603 -194.671671) (xy 26.765815 -194.730124) (xy 26.782191 -194.791237)
			(xy 26.790449 -194.853965) (xy 26.790449 -194.917235) (xy 26.782191 -194.979963) (xy 26.765815 -195.041076)
			(xy 26.741603 -195.099529) (xy 26.709968 -195.154322) (xy 26.671452 -195.204517) (xy 26.626714 -195.249255)
			(xy 26.576519 -195.28777) (xy 26.521726 -195.319405) (xy 26.463272 -195.343616) (xy 26.402159 -195.359991)
			(xy 26.339431 -195.368249) (xy 26.307796 -195.368672) (xy 25.56129 -195.368672) (xy 25.529477 -195.368165)
			(xy 25.466401 -195.359817) (xy 25.404966 -195.343264) (xy 25.346233 -195.318795) (xy 25.291218 -195.286831)
			(xy 25.240872 -195.247926) (xy 25.218136 -195.22567) (xy 25.211024 -195.218558) (xy 25.18537 -195.207382)
			(xy 25.18053 -195.205378) (xy 25.170286 -195.203199) (xy 25.16505 -195.203064) (xy 24.948642 -195.203064)
			(xy 24.93885 -195.203583) (xy 24.920773 -195.211126) (xy 24.906923 -195.224978) (xy 24.899382 -195.243056)
			(xy 24.898858 -195.252848) (xy 24.898858 -195.263008) (xy 24.630634 -195.263008) (xy 24.6112 -195.262538)
			(xy 24.572925 -195.25576) (xy 24.536373 -195.242537) (xy 24.502621 -195.223256) (xy 24.487378 -195.211192)
			(xy 24.480774 -195.205604) (xy 24.45639 -195.196714) (xy 24.452102 -195.195195) (xy 24.443158 -195.193535)
			(xy 24.43861 -195.193412) (xy 24.316182 -195.193412) (xy 24.312375 -195.193478) (xy 24.304849 -195.194624)
			(xy 24.301196 -195.195698) (xy 24.293322 -195.197984) (xy 24.286718 -195.202556) (xy 24.261094 -195.21986)
			(xy 24.20645 -195.248798) (xy 24.148696 -195.270885) (xy 24.088688 -195.285793) (xy 24.027312 -195.293303)
			(xy 23.996396 -195.293742) (xy 23.966044 -195.2933) (xy 23.905772 -195.286072) (xy 23.846789 -195.271718)
			(xy 23.789935 -195.250443) (xy 23.736018 -195.22255) (xy 23.685807 -195.188435) (xy 23.640015 -195.148584)
			(xy 23.599293 -195.103564) (xy 23.564222 -195.054016) (xy 23.549356 -195.02755) (xy 23.542498 -195.01485)
			(xy 23.518114 -195.000626) (xy 23.413212 -195.002912) (xy 23.368762 -195.03136) (xy 23.354781 -195.059122)
			(xy 23.321562 -195.111662) (xy 23.282743 -195.160212) (xy 23.261066 -195.18249) (xy 23.23211 -195.211446)
			(xy 23.257686 -195.234349) (xy 23.303641 -195.285358) (xy 23.343035 -195.341587) (xy 23.375284 -195.402198)
			(xy 23.399904 -195.466288) (xy 23.41653 -195.532901) (xy 23.424913 -195.601044) (xy 23.425404 -195.635372)
			(xy 23.424948 -195.666881) (xy 23.417865 -195.7295) (xy 23.40382 -195.790933) (xy 23.382988 -195.850408)
			(xy 23.355631 -195.907179) (xy 23.322093 -195.960532) (xy 23.282795 -196.009796) (xy 23.260812 -196.032374)
			(xy 22.804882 -196.488558) (xy 22.076918 -196.488558) (xy 22.076227 -196.51475) (xy 22.068355 -196.56655)
			(xy 22.053231 -196.616715) (xy 22.03116 -196.664234) (xy 22.002586 -196.708152) (xy 21.968085 -196.747584)
			(xy 21.92835 -196.781737) (xy 21.884183 -196.809923) (xy 21.836471 -196.831574) (xy 21.786175 -196.846256)
			(xy 21.734307 -196.853672) (xy 21.70811 -196.854064) (xy 21.681914 -196.853606) (xy 21.630049 -196.846194)
			(xy 21.579754 -196.831517) (xy 21.532042 -196.809872) (xy 21.487873 -196.781694) (xy 21.448136 -196.747549)
			(xy 21.41363 -196.708125) (xy 21.385049 -196.664215) (xy 21.362969 -196.616703) (xy 21.347834 -196.566545)
			(xy 21.339949 -196.514749) (xy 21.339302 -196.488558) (xy 21.319236 -196.488558) (xy 21.285177 -196.488056)
			(xy 21.21756 -196.479813) (xy 21.151436 -196.463455) (xy 21.087774 -196.439224) (xy 21.027509 -196.407473)
			(xy 20.971524 -196.368669) (xy 20.920642 -196.323382) (xy 20.875608 -196.272275) (xy 20.85594 -196.244464)
			(xy 20.74545 -196.244464) (xy 20.719034 -196.25183) (xy 20.685252 -196.270372) (xy 20.672044 -196.276722)
			(xy 20.656804 -196.30136) (xy 20.656804 -196.304408) (xy 20.575524 -196.304408) (xy 20.572222 -196.304662)
			(xy 20.559021 -196.306429) (xy 20.532454 -196.308333) (xy 20.519136 -196.308472) (xy 20.505819 -196.308327)
			(xy 20.479252 -196.306417) (xy 20.46605 -196.304662) (xy 20.462748 -196.304408) (xy 20.389088 -196.304408)
			(xy 20.366761 -196.303888) (xy 20.322975 -196.295132) (xy 20.281754 -196.277964) (xy 20.244698 -196.253048)
			(xy 20.213245 -196.221352) (xy 20.188615 -196.184105) (xy 20.171765 -196.142753) (xy 20.163347 -196.0989)
			(xy 20.163028 -196.07657) (xy 20.163028 -196.064378) (xy 20.160234 -196.055996) (xy 20.14973 -196.024775)
			(xy 20.138371 -195.959896) (xy 20.137628 -195.926964) (xy 20.138338 -195.894029) (xy 20.149698 -195.829144)
			(xy 20.160234 -195.797932) (xy 20.163028 -195.78955) (xy 20.163028 -195.777358) (xy 20.163412 -195.754444)
			(xy 20.172341 -195.7095) (xy 20.190148 -195.667279) (xy 20.202652 -195.648072) (xy 20.213066 -195.632832)
			(xy 20.209764 -195.596764) (xy 19.953986 -195.340986) (xy 19.947132 -195.333591) (xy 19.93939 -195.314992)
			(xy 19.939 -195.304918) (xy 19.939 -193.839846) (xy 19.938567 -193.82978) (xy 19.930839 -193.81119)
			(xy 19.924014 -193.803778) (xy 19.826986 -193.70675) (xy 19.819589 -193.6999) (xy 19.800991 -193.692163)
			(xy 19.790918 -193.691764) (xy 18.474182 -193.691764) (xy 18.464115 -193.692192) (xy 18.445521 -193.699918)
			(xy 18.438114 -193.70675) (xy 18.19656 -193.948304) (xy 18.189708 -193.9557) (xy 18.181965 -193.974298)
			(xy 18.181574 -193.984372) (xy 18.181574 -196.277738) (xy 18.182003 -196.287806) (xy 18.189725 -196.306403)
			(xy 18.19656 -196.313806) (xy 19.218148 -197.335394) (xy 21.364197 -197.335394) (xy 21.368227 -197.282896)
			(xy 21.380224 -197.231628) (xy 21.399907 -197.182793) (xy 21.426813 -197.137534) (xy 21.460313 -197.096913)
			(xy 21.499621 -197.061882) (xy 21.543816 -197.033262) (xy 21.591861 -197.011723) (xy 21.642632 -196.997771)
			(xy 21.694937 -196.991733) (xy 21.747551 -196.99375) (xy 21.799241 -197.003774) (xy 21.848794 -197.021572)
			(xy 21.89505 -197.046725) (xy 21.936924 -197.078644) (xy 21.973436 -197.116582) (xy 22.003728 -197.159648)
			(xy 22.027091 -197.206833) (xy 22.042977 -197.257032) (xy 22.051014 -197.309068) (xy 22.051518 -197.335394)
			(xy 24.782795 -197.335394) (xy 24.78673 -197.281623) (xy 24.798453 -197.228999) (xy 24.817713 -197.178642)
			(xy 24.844099 -197.131625) (xy 24.877051 -197.088952) (xy 24.915864 -197.051531) (xy 24.959712 -197.020161)
			(xy 25.00766 -196.995509) (xy 25.058687 -196.978101) (xy 25.111705 -196.968308) (xy 25.165584 -196.966339)
			(xy 25.219175 -196.972236) (xy 25.271336 -196.985872) (xy 25.320956 -197.006959) (xy 25.366977 -197.035045)
			(xy 25.408419 -197.069533) (xy 25.444397 -197.109687) (xy 25.474145 -197.154651) (xy 25.49703 -197.203468)
			(xy 25.512562 -197.255097) (xy 25.520412 -197.308437) (xy 25.520904 -197.335394) (xy 28.908251 -197.335394)
			(xy 28.912281 -197.282896) (xy 28.924278 -197.231628) (xy 28.943961 -197.182793) (xy 28.970867 -197.137534)
			(xy 29.004367 -197.096913) (xy 29.043675 -197.061882) (xy 29.08787 -197.033262) (xy 29.135915 -197.011723)
			(xy 29.186686 -196.997771) (xy 29.238991 -196.991733) (xy 29.291605 -196.99375) (xy 29.343295 -197.003774)
			(xy 29.392848 -197.021572) (xy 29.439104 -197.046725) (xy 29.480978 -197.078644) (xy 29.51749 -197.116582)
			(xy 29.547782 -197.159648) (xy 29.571145 -197.206833) (xy 29.587031 -197.257032) (xy 29.595068 -197.309068)
			(xy 29.595572 -197.335394) (xy 32.326595 -197.335394) (xy 32.33053 -197.281623) (xy 32.342253 -197.228999)
			(xy 32.361513 -197.178642) (xy 32.387899 -197.131625) (xy 32.420851 -197.088952) (xy 32.459664 -197.051531)
			(xy 32.503512 -197.020161) (xy 32.55146 -196.995509) (xy 32.602487 -196.978101) (xy 32.655505 -196.968308)
			(xy 32.709384 -196.966339) (xy 32.762975 -196.972236) (xy 32.815136 -196.985872) (xy 32.864756 -197.006959)
			(xy 32.910777 -197.035045) (xy 32.952219 -197.069533) (xy 32.988197 -197.109687) (xy 33.017945 -197.154651)
			(xy 33.04083 -197.203468) (xy 33.056362 -197.255097) (xy 33.064212 -197.308437) (xy 33.064704 -197.335394)
			(xy 36.452051 -197.335394) (xy 36.456081 -197.282896) (xy 36.468078 -197.231628) (xy 36.487761 -197.182793)
			(xy 36.514667 -197.137534) (xy 36.548167 -197.096913) (xy 36.587475 -197.061882) (xy 36.63167 -197.033262)
			(xy 36.679715 -197.011723) (xy 36.730486 -196.997771) (xy 36.782791 -196.991733) (xy 36.835405 -196.99375)
			(xy 36.887095 -197.003774) (xy 36.936648 -197.021572) (xy 36.982904 -197.046725) (xy 37.024778 -197.078644)
			(xy 37.06129 -197.116582) (xy 37.091582 -197.159648) (xy 37.114945 -197.206833) (xy 37.130831 -197.257032)
			(xy 37.138868 -197.309068) (xy 37.139372 -197.335394) (xy 39.870649 -197.335394) (xy 39.874584 -197.281623)
			(xy 39.886307 -197.228999) (xy 39.905567 -197.178642) (xy 39.931953 -197.131625) (xy 39.964905 -197.088952)
			(xy 40.003718 -197.051531) (xy 40.047566 -197.020161) (xy 40.095514 -196.995509) (xy 40.146541 -196.978101)
			(xy 40.199559 -196.968308) (xy 40.253438 -196.966339) (xy 40.307029 -196.972236) (xy 40.35919 -196.985872)
			(xy 40.40881 -197.006959) (xy 40.454831 -197.035045) (xy 40.496273 -197.069533) (xy 40.532251 -197.109687)
			(xy 40.561999 -197.154651) (xy 40.584884 -197.203468) (xy 40.600416 -197.255097) (xy 40.608266 -197.308437)
			(xy 40.608758 -197.335394) (xy 43.996105 -197.335394) (xy 44.000135 -197.282896) (xy 44.012132 -197.231628)
			(xy 44.031815 -197.182793) (xy 44.058721 -197.137534) (xy 44.092221 -197.096913) (xy 44.131529 -197.061882)
			(xy 44.175724 -197.033262) (xy 44.223769 -197.011723) (xy 44.27454 -196.997771) (xy 44.326845 -196.991733)
			(xy 44.379459 -196.99375) (xy 44.431149 -197.003774) (xy 44.480702 -197.021572) (xy 44.526958 -197.046725)
			(xy 44.568832 -197.078644) (xy 44.605344 -197.116582) (xy 44.635636 -197.159648) (xy 44.658999 -197.206833)
			(xy 44.674885 -197.257032) (xy 44.682922 -197.309068) (xy 44.683426 -197.335394) (xy 47.414703 -197.335394)
			(xy 47.418638 -197.281623) (xy 47.430361 -197.228999) (xy 47.449621 -197.178642) (xy 47.476007 -197.131625)
			(xy 47.508959 -197.088952) (xy 47.547772 -197.051531) (xy 47.59162 -197.020161) (xy 47.639568 -196.995509)
			(xy 47.690595 -196.978101) (xy 47.743613 -196.968308) (xy 47.797492 -196.966339) (xy 47.851083 -196.972236)
			(xy 47.903244 -196.985872) (xy 47.952864 -197.006959) (xy 47.998885 -197.035045) (xy 48.040327 -197.069533)
			(xy 48.076305 -197.109687) (xy 48.106053 -197.154651) (xy 48.128938 -197.203468) (xy 48.14447 -197.255097)
			(xy 48.15232 -197.308437) (xy 48.152812 -197.335394) (xy 51.540159 -197.335394) (xy 51.544189 -197.282896)
			(xy 51.556186 -197.231628) (xy 51.575869 -197.182793) (xy 51.602775 -197.137534) (xy 51.636275 -197.096913)
			(xy 51.675583 -197.061882) (xy 51.719778 -197.033262) (xy 51.767823 -197.011723) (xy 51.818594 -196.997771)
			(xy 51.870899 -196.991733) (xy 51.923513 -196.99375) (xy 51.975203 -197.003774) (xy 52.024756 -197.021572)
			(xy 52.071012 -197.046725) (xy 52.112886 -197.078644) (xy 52.149398 -197.116582) (xy 52.17969 -197.159648)
			(xy 52.203053 -197.206833) (xy 52.218939 -197.257032) (xy 52.226976 -197.309068) (xy 52.22748 -197.335394)
			(xy 54.958757 -197.335394) (xy 54.962692 -197.281623) (xy 54.974415 -197.228999) (xy 54.993675 -197.178642)
			(xy 55.020061 -197.131625) (xy 55.053013 -197.088952) (xy 55.091826 -197.051531) (xy 55.135674 -197.020161)
			(xy 55.183622 -196.995509) (xy 55.234649 -196.978101) (xy 55.287667 -196.968308) (xy 55.341546 -196.966339)
			(xy 55.395137 -196.972236) (xy 55.447298 -196.985872) (xy 55.496918 -197.006959) (xy 55.542939 -197.035045)
			(xy 55.584381 -197.069533) (xy 55.620359 -197.109687) (xy 55.650107 -197.154651) (xy 55.672992 -197.203468)
			(xy 55.688524 -197.255097) (xy 55.696374 -197.308437) (xy 55.696866 -197.335394) (xy 55.696374 -197.362351)
			(xy 55.688524 -197.415691) (xy 55.672992 -197.46732) (xy 55.650107 -197.516137) (xy 55.620359 -197.561101)
			(xy 55.584381 -197.601255) (xy 55.542939 -197.635743) (xy 55.496918 -197.663829) (xy 55.447298 -197.684916)
			(xy 55.395137 -197.698552) (xy 55.341546 -197.704449) (xy 55.287667 -197.70248) (xy 55.234649 -197.692687)
			(xy 55.183622 -197.675279) (xy 55.135674 -197.650627) (xy 55.091826 -197.619257) (xy 55.053013 -197.581836)
			(xy 55.020061 -197.539163) (xy 54.993675 -197.492146) (xy 54.974415 -197.441789) (xy 54.962692 -197.389165)
			(xy 54.958757 -197.335394) (xy 52.22748 -197.335394) (xy 52.226976 -197.36172) (xy 52.218939 -197.413756)
			(xy 52.203053 -197.463955) (xy 52.17969 -197.51114) (xy 52.149398 -197.554206) (xy 52.112886 -197.592144)
			(xy 52.071012 -197.624063) (xy 52.024756 -197.649216) (xy 51.975203 -197.667014) (xy 51.923513 -197.677038)
			(xy 51.870899 -197.679055) (xy 51.818594 -197.673017) (xy 51.767823 -197.659065) (xy 51.719778 -197.637526)
			(xy 51.675583 -197.608906) (xy 51.636275 -197.573875) (xy 51.602775 -197.533254) (xy 51.575869 -197.487995)
			(xy 51.556186 -197.43916) (xy 51.544189 -197.387892) (xy 51.540159 -197.335394) (xy 48.152812 -197.335394)
			(xy 48.15232 -197.362351) (xy 48.14447 -197.415691) (xy 48.128938 -197.46732) (xy 48.106053 -197.516137)
			(xy 48.076305 -197.561101) (xy 48.040327 -197.601255) (xy 47.998885 -197.635743) (xy 47.952864 -197.663829)
			(xy 47.903244 -197.684916) (xy 47.851083 -197.698552) (xy 47.797492 -197.704449) (xy 47.743613 -197.70248)
			(xy 47.690595 -197.692687) (xy 47.639568 -197.675279) (xy 47.59162 -197.650627) (xy 47.547772 -197.619257)
			(xy 47.508959 -197.581836) (xy 47.476007 -197.539163) (xy 47.449621 -197.492146) (xy 47.430361 -197.441789)
			(xy 47.418638 -197.389165) (xy 47.414703 -197.335394) (xy 44.683426 -197.335394) (xy 44.682922 -197.36172)
			(xy 44.674885 -197.413756) (xy 44.658999 -197.463955) (xy 44.635636 -197.51114) (xy 44.605344 -197.554206)
			(xy 44.568832 -197.592144) (xy 44.526958 -197.624063) (xy 44.480702 -197.649216) (xy 44.431149 -197.667014)
			(xy 44.379459 -197.677038) (xy 44.326845 -197.679055) (xy 44.27454 -197.673017) (xy 44.223769 -197.659065)
			(xy 44.175724 -197.637526) (xy 44.131529 -197.608906) (xy 44.092221 -197.573875) (xy 44.058721 -197.533254)
			(xy 44.031815 -197.487995) (xy 44.012132 -197.43916) (xy 44.000135 -197.387892) (xy 43.996105 -197.335394)
			(xy 40.608758 -197.335394) (xy 40.608266 -197.362351) (xy 40.600416 -197.415691) (xy 40.584884 -197.46732)
			(xy 40.561999 -197.516137) (xy 40.532251 -197.561101) (xy 40.496273 -197.601255) (xy 40.454831 -197.635743)
			(xy 40.40881 -197.663829) (xy 40.35919 -197.684916) (xy 40.307029 -197.698552) (xy 40.253438 -197.704449)
			(xy 40.199559 -197.70248) (xy 40.146541 -197.692687) (xy 40.095514 -197.675279) (xy 40.047566 -197.650627)
			(xy 40.003718 -197.619257) (xy 39.964905 -197.581836) (xy 39.931953 -197.539163) (xy 39.905567 -197.492146)
			(xy 39.886307 -197.441789) (xy 39.874584 -197.389165) (xy 39.870649 -197.335394) (xy 37.139372 -197.335394)
			(xy 37.138868 -197.36172) (xy 37.130831 -197.413756) (xy 37.114945 -197.463955) (xy 37.091582 -197.51114)
			(xy 37.06129 -197.554206) (xy 37.024778 -197.592144) (xy 36.982904 -197.624063) (xy 36.936648 -197.649216)
			(xy 36.887095 -197.667014) (xy 36.835405 -197.677038) (xy 36.782791 -197.679055) (xy 36.730486 -197.673017)
			(xy 36.679715 -197.659065) (xy 36.63167 -197.637526) (xy 36.587475 -197.608906) (xy 36.548167 -197.573875)
			(xy 36.514667 -197.533254) (xy 36.487761 -197.487995) (xy 36.468078 -197.43916) (xy 36.456081 -197.387892)
			(xy 36.452051 -197.335394) (xy 33.064704 -197.335394) (xy 33.064212 -197.362351) (xy 33.056362 -197.415691)
			(xy 33.04083 -197.46732) (xy 33.017945 -197.516137) (xy 32.988197 -197.561101) (xy 32.952219 -197.601255)
			(xy 32.910777 -197.635743) (xy 32.864756 -197.663829) (xy 32.815136 -197.684916) (xy 32.762975 -197.698552)
			(xy 32.709384 -197.704449) (xy 32.655505 -197.70248) (xy 32.602487 -197.692687) (xy 32.55146 -197.675279)
			(xy 32.503512 -197.650627) (xy 32.459664 -197.619257) (xy 32.420851 -197.581836) (xy 32.387899 -197.539163)
			(xy 32.361513 -197.492146) (xy 32.342253 -197.441789) (xy 32.33053 -197.389165) (xy 32.326595 -197.335394)
			(xy 29.595572 -197.335394) (xy 29.595068 -197.36172) (xy 29.587031 -197.413756) (xy 29.571145 -197.463955)
			(xy 29.547782 -197.51114) (xy 29.51749 -197.554206) (xy 29.480978 -197.592144) (xy 29.439104 -197.624063)
			(xy 29.392848 -197.649216) (xy 29.343295 -197.667014) (xy 29.291605 -197.677038) (xy 29.238991 -197.679055)
			(xy 29.186686 -197.673017) (xy 29.135915 -197.659065) (xy 29.08787 -197.637526) (xy 29.043675 -197.608906)
			(xy 29.004367 -197.573875) (xy 28.970867 -197.533254) (xy 28.943961 -197.487995) (xy 28.924278 -197.43916)
			(xy 28.912281 -197.387892) (xy 28.908251 -197.335394) (xy 25.520904 -197.335394) (xy 25.520412 -197.362351)
			(xy 25.512562 -197.415691) (xy 25.49703 -197.46732) (xy 25.474145 -197.516137) (xy 25.444397 -197.561101)
			(xy 25.408419 -197.601255) (xy 25.366977 -197.635743) (xy 25.320956 -197.663829) (xy 25.271336 -197.684916)
			(xy 25.219175 -197.698552) (xy 25.165584 -197.704449) (xy 25.111705 -197.70248) (xy 25.058687 -197.692687)
			(xy 25.00766 -197.675279) (xy 24.959712 -197.650627) (xy 24.915864 -197.619257) (xy 24.877051 -197.581836)
			(xy 24.844099 -197.539163) (xy 24.817713 -197.492146) (xy 24.798453 -197.441789) (xy 24.78673 -197.389165)
			(xy 24.782795 -197.335394) (xy 22.051518 -197.335394) (xy 22.051014 -197.36172) (xy 22.042977 -197.413756)
			(xy 22.027091 -197.463955) (xy 22.003728 -197.51114) (xy 21.973436 -197.554206) (xy 21.936924 -197.592144)
			(xy 21.89505 -197.624063) (xy 21.848794 -197.649216) (xy 21.799241 -197.667014) (xy 21.747551 -197.677038)
			(xy 21.694937 -197.679055) (xy 21.642632 -197.673017) (xy 21.591861 -197.659065) (xy 21.543816 -197.637526)
			(xy 21.499621 -197.608906) (xy 21.460313 -197.573875) (xy 21.426813 -197.533254) (xy 21.399907 -197.487995)
			(xy 21.380224 -197.43916) (xy 21.368227 -197.387892) (xy 21.364197 -197.335394) (xy 19.218148 -197.335394)
			(xy 20.076922 -198.194168) (xy 20.08432 -198.201015) (xy 20.102919 -198.208746) (xy 20.11299 -198.209154)
			(xy 21.309584 -198.209154)
		)
		(stroke
			(width 0)
			(type solid)
		)
		(fill yes)
		(layer "B.Cu")
		(net "P3V3")
	)
	(gr_poly
		(pts
			(xy 414.537398 -41.93032) (xy 414.547469 -41.929898) (xy 414.566076 -41.922186) (xy 414.573466 -41.915334)
			(xy 414.584134 -41.904666) (xy 414.590982 -41.897269) (xy 414.598715 -41.87867) (xy 414.59912 -41.868598)
			(xy 414.59912 -33.490662) (xy 414.598691 -33.480594) (xy 414.590969 -33.461998) (xy 414.584134 -33.454594)
			(xy 412.119826 -30.990286) (xy 412.112428 -30.983442) (xy 412.093828 -30.975721) (xy 412.083758 -30.9753)
			(xy 380.203202 -30.9753) (xy 380.193775 -30.975679) (xy 380.176199 -30.982503) (xy 380.162285 -30.995227)
			(xy 380.157736 -31.003494) (xy 380.143372 -31.031385) (xy 380.108777 -31.083721) (xy 380.068008 -31.131407)
			(xy 380.021684 -31.173716) (xy 379.970509 -31.210008) (xy 379.915259 -31.239732) (xy 379.856774 -31.262435)
			(xy 379.795941 -31.277774) (xy 379.733683 -31.285515) (xy 379.702314 -31.285942) (xy 379.673698 -31.285553)
			(xy 379.616828 -31.279129) (xy 379.561038 -31.266361) (xy 379.533912 -31.25724) (xy 379.520958 -31.252668)
			(xy 379.49378 -31.258002) (xy 379.406658 -31.334964) (xy 379.398022 -31.361126) (xy 379.40107 -31.374588)
			(xy 379.405143 -31.39466) (xy 379.409471 -31.435389) (xy 379.409706 -31.455868) (xy 379.40922 -31.483119)
			(xy 379.401464 -31.537067) (xy 379.386109 -31.589362) (xy 379.363467 -31.638939) (xy 379.334001 -31.684789)
			(xy 379.29831 -31.72598) (xy 379.257119 -31.761671) (xy 379.211269 -31.791137) (xy 379.161692 -31.813779)
			(xy 379.109397 -31.829134) (xy 379.055449 -31.83689) (xy 379.000947 -31.83689) (xy 378.946999 -31.829134)
			(xy 378.894704 -31.813779) (xy 378.845127 -31.791137) (xy 378.799277 -31.761671) (xy 378.758086 -31.72598)
			(xy 378.722395 -31.684789) (xy 378.692929 -31.638939) (xy 378.670287 -31.589362) (xy 378.654932 -31.537067)
			(xy 378.647176 -31.483119) (xy 378.64669 -31.455868) (xy 378.647204 -31.427178) (xy 378.655795 -31.370446)
			(xy 378.672795 -31.315643) (xy 378.697818 -31.264007) (xy 378.730298 -31.216707) (xy 378.769503 -31.17481)
			(xy 378.791724 -31.156656) (xy 378.804424 -31.146496) (xy 378.813314 -31.115508) (xy 378.776484 -31.009336)
			(xy 378.772539 -30.999585) (xy 378.758252 -30.984178) (xy 378.738985 -30.975796) (xy 378.728478 -30.9753)
			(xy 377.364498 -30.9753) (xy 377.35326 -30.975886) (xy 377.332954 -30.985516) (xy 377.325382 -30.993842)
			(xy 377.268232 -31.063184) (xy 377.262644 -31.085028) (xy 377.264676 -31.096204) (xy 377.267994 -31.114246)
			(xy 377.271559 -31.150759) (xy 377.271788 -31.169102) (xy 377.271302 -31.196353) (xy 377.263546 -31.250301)
			(xy 377.248191 -31.302596) (xy 377.225549 -31.352173) (xy 377.196083 -31.398023) (xy 377.160392 -31.439214)
			(xy 377.119201 -31.474905) (xy 377.073351 -31.504371) (xy 377.023774 -31.527013) (xy 376.971479 -31.542368)
			(xy 376.917531 -31.550124) (xy 376.863029 -31.550124) (xy 376.809081 -31.542368) (xy 376.756786 -31.527013)
			(xy 376.707209 -31.504371) (xy 376.661359 -31.474905) (xy 376.620168 -31.439214) (xy 376.584477 -31.398023)
			(xy 376.555011 -31.352173) (xy 376.532369 -31.302596) (xy 376.517014 -31.250301) (xy 376.509258 -31.196353)
			(xy 376.508772 -31.169102) (xy 376.509016 -31.15076) (xy 376.512579 -31.114248) (xy 376.515884 -31.096204)
			(xy 376.517916 -31.085028) (xy 376.512328 -31.063184) (xy 376.455178 -30.993842) (xy 376.447579 -30.985552)
			(xy 376.427289 -30.975916) (xy 376.416062 -30.9753) (xy 375.539762 -30.9753) (xy 375.529695 -30.97487)
			(xy 375.511101 -30.967146) (xy 375.503694 -30.960314) (xy 367.857786 -23.314406) (xy 367.850387 -23.307561)
			(xy 367.831789 -23.299831) (xy 367.821718 -23.29942) (xy 363.175042 -23.29942) (xy 363.164976 -23.298987)
			(xy 363.146385 -23.29126) (xy 363.138974 -23.284434) (xy 362.933996 -23.079456) (xy 362.915708 -23.071836)
			(xy 362.905802 -23.071582) (xy 362.883774 -23.070853) (xy 362.840456 -23.062744) (xy 362.799185 -23.047289)
			(xy 362.761196 -23.024951) (xy 362.727626 -22.996399) (xy 362.699481 -22.962487) (xy 362.677604 -22.924231)
			(xy 362.662648 -22.882776) (xy 362.655064 -22.839363) (xy 362.654596 -22.817328) (xy 362.654596 -21.598128)
			(xy 362.655135 -21.573578) (xy 362.664493 -21.525379) (xy 362.682924 -21.479871) (xy 362.709744 -21.438745)
			(xy 362.743957 -21.403528) (xy 362.763816 -21.389086) (xy 362.773485 -21.381472) (xy 362.7849 -21.359713)
			(xy 362.78566 -21.34743) (xy 362.78566 -19.185382) (xy 362.786088 -19.175315) (xy 362.793814 -19.156721)
			(xy 362.800646 -19.149314) (xy 366.034574 -15.915386) (xy 366.041421 -15.907988) (xy 366.049154 -15.88939)
			(xy 366.04956 -15.879318) (xy 366.04956 -14.049248) (xy 366.02416 -14.0208) (xy 366.004856 -14.01826)
			(xy 365.977384 -14.014519) (xy 365.923845 -14.000117) (xy 365.872957 -13.978112) (xy 365.825794 -13.948966)
			(xy 365.783351 -13.913295) (xy 365.746523 -13.871852) (xy 365.716087 -13.825511) (xy 365.692686 -13.775249)
			(xy 365.676813 -13.722128) (xy 365.668803 -13.667267) (xy 365.668306 -13.639546) (xy 365.668824 -13.611245)
			(xy 365.677191 -13.555265) (xy 365.693733 -13.501134) (xy 365.718087 -13.45004) (xy 365.74972 -13.403102)
			(xy 365.787938 -13.361351) (xy 365.831903 -13.325701) (xy 365.856012 -13.31087) (xy 365.866426 -13.304774)
			(xy 365.879126 -13.28547) (xy 365.89081 -13.193776) (xy 365.891703 -13.182183) (xy 365.884152 -13.160218)
			(xy 365.876332 -13.151612) (xy 365.835946 -13.111226) (xy 365.828546 -13.104385) (xy 365.809947 -13.096667)
			(xy 365.799878 -13.09624) (xy 364.864904 -13.09624) (xy 364.852289 -13.096847) (xy 364.830038 -13.108721)
			(xy 364.822486 -13.118846) (xy 364.768638 -13.200126) (xy 364.766352 -13.225526) (xy 364.771178 -13.23721)
			(xy 364.783787 -13.268568) (xy 364.80154 -13.333782) (xy 364.810491 -13.400774) (xy 364.811056 -13.434568)
			(xy 364.810554 -13.466529) (xy 364.802543 -13.529947) (xy 364.786646 -13.591861) (xy 364.763114 -13.651294)
			(xy 364.73232 -13.707309) (xy 364.694747 -13.759024) (xy 364.65099 -13.805621) (xy 364.601737 -13.846366)
			(xy 364.547766 -13.880617) (xy 364.489927 -13.907834) (xy 364.429134 -13.927587) (xy 364.366344 -13.939565)
			(xy 364.302548 -13.943579) (xy 364.238752 -13.939565) (xy 364.175962 -13.927587) (xy 364.115169 -13.907834)
			(xy 364.05733 -13.880617) (xy 364.003359 -13.846366) (xy 363.954106 -13.805621) (xy 363.910349 -13.759024)
			(xy 363.872776 -13.707309) (xy 363.841982 -13.651294) (xy 363.81845 -13.591861) (xy 363.802553 -13.529947)
			(xy 363.794542 -13.466529) (xy 363.79404 -13.434568) (xy 363.794596 -13.400774) (xy 363.803557 -13.333783)
			(xy 363.821315 -13.268571) (xy 363.833918 -13.23721) (xy 363.838744 -13.225526) (xy 363.836458 -13.200126)
			(xy 363.78261 -13.118846) (xy 363.775046 -13.10874) (xy 363.752798 -13.096878) (xy 363.740192 -13.09624)
			(xy 323.002402 -13.09624) (xy 322.992333 -13.096664) (xy 322.973731 -13.104382) (xy 322.966334 -13.111226)
			(xy 320.706404 -15.371156) (xy 362.324041 -15.371156) (xy 362.324041 -15.316644) (xy 362.331799 -15.262688)
			(xy 362.347158 -15.210384) (xy 362.369805 -15.1608) (xy 362.399278 -15.114943) (xy 362.434977 -15.073747)
			(xy 362.476176 -15.038052) (xy 362.522036 -15.008584) (xy 362.571624 -14.985943) (xy 362.623929 -14.97059)
			(xy 362.677886 -14.962838) (xy 362.705142 -14.962378) (xy 362.731301 -14.962788) (xy 362.783129 -14.969943)
			(xy 362.833493 -14.984111) (xy 362.881449 -15.005029) (xy 362.926097 -15.032302) (xy 362.966599 -15.06542)
			(xy 363.002197 -15.103762) (xy 363.017562 -15.124938) (xy 363.023912 -15.133828) (xy 363.041692 -15.14475)
			(xy 363.13745 -15.15745) (xy 363.157516 -15.151608) (xy 363.165898 -15.14475) (xy 363.192219 -15.123379)
			(xy 363.248936 -15.086226) (xy 363.309572 -15.055888) (xy 363.373312 -15.032771) (xy 363.439299 -15.017187)
			(xy 363.506647 -15.009346) (xy 363.540548 -15.00886) (xy 363.574571 -15.009421) (xy 363.642156 -15.017326)
			(xy 363.708367 -15.033023) (xy 363.772307 -15.0563) (xy 363.833113 -15.086843) (xy 363.889963 -15.124237)
			(xy 363.942087 -15.167979) (xy 363.988781 -15.217475) (xy 364.029413 -15.272058) (xy 364.063435 -15.330988)
			(xy 364.090385 -15.39347) (xy 364.1099 -15.458657) (xy 364.121715 -15.525669) (xy 364.125672 -15.5936)
			(xy 364.121715 -15.661531) (xy 364.1099 -15.728543) (xy 364.090385 -15.79373) (xy 364.063435 -15.856212)
			(xy 364.029413 -15.915142) (xy 363.988781 -15.969725) (xy 363.942087 -16.019221) (xy 363.889963 -16.062963)
			(xy 363.833113 -16.100357) (xy 363.772307 -16.1309) (xy 363.708367 -16.154177) (xy 363.642156 -16.169874)
			(xy 363.574571 -16.177779) (xy 363.540548 -16.178276) (xy 363.506614 -16.177779) (xy 363.439203 -16.169927)
			(xy 363.373155 -16.154322) (xy 363.309357 -16.131174) (xy 363.248669 -16.100796) (xy 363.191906 -16.063595)
			(xy 363.139832 -16.020072) (xy 363.093148 -15.970813) (xy 363.052481 -15.916479) (xy 363.018379 -15.857802)
			(xy 362.9913 -15.795572) (xy 362.980986 -15.76324) (xy 362.977938 -15.752826) (xy 362.964222 -15.737078)
			(xy 362.877354 -15.695168) (xy 362.856272 -15.694406) (xy 362.846112 -15.69847) (xy 362.82361 -15.707031)
			(xy 362.776983 -15.719026) (xy 362.729215 -15.725048) (xy 362.705142 -15.725394) (xy 362.677886 -15.724962)
			(xy 362.623929 -15.71721) (xy 362.571624 -15.701857) (xy 362.522036 -15.679216) (xy 362.476176 -15.649748)
			(xy 362.434977 -15.614053) (xy 362.399278 -15.572857) (xy 362.369805 -15.527) (xy 362.347158 -15.477416)
			(xy 362.331799 -15.425112) (xy 362.324041 -15.371156) (xy 320.706404 -15.371156) (xy 319.050205 -17.027355)
			(xy 328.726794 -17.027355) (xy 328.726794 -16.963433) (xy 328.734805 -16.900015) (xy 328.750702 -16.838101)
			(xy 328.774234 -16.778668) (xy 328.805028 -16.722653) (xy 328.842601 -16.670938) (xy 328.886358 -16.624341)
			(xy 328.935611 -16.583596) (xy 328.989582 -16.549345) (xy 329.047421 -16.522128) (xy 329.108214 -16.502375)
			(xy 329.171004 -16.490397) (xy 329.2348 -16.486384) (xy 329.298596 -16.490397) (xy 329.361386 -16.502375)
			(xy 329.422179 -16.522128) (xy 329.480018 -16.549345) (xy 329.533989 -16.583596) (xy 329.583242 -16.624341)
			(xy 329.626999 -16.670938) (xy 329.664572 -16.722653) (xy 329.695366 -16.778668) (xy 329.718898 -16.838101)
			(xy 329.734795 -16.900015) (xy 329.742806 -16.963433) (xy 329.743308 -16.995394) (xy 329.742806 -17.027355)
			(xy 331.751934 -17.027355) (xy 331.751934 -16.963433) (xy 331.759945 -16.900015) (xy 331.775842 -16.838101)
			(xy 331.799374 -16.778668) (xy 331.830168 -16.722653) (xy 331.867741 -16.670938) (xy 331.911498 -16.624341)
			(xy 331.960751 -16.583596) (xy 332.014722 -16.549345) (xy 332.072561 -16.522128) (xy 332.133354 -16.502375)
			(xy 332.196144 -16.490397) (xy 332.25994 -16.486384) (xy 332.323736 -16.490397) (xy 332.386526 -16.502375)
			(xy 332.447319 -16.522128) (xy 332.505158 -16.549345) (xy 332.559129 -16.583596) (xy 332.608382 -16.624341)
			(xy 332.652139 -16.670938) (xy 332.689712 -16.722653) (xy 332.720506 -16.778668) (xy 332.744038 -16.838101)
			(xy 332.759935 -16.900015) (xy 332.767946 -16.963433) (xy 332.768448 -16.995394) (xy 332.767946 -17.027355)
			(xy 332.765764 -17.044627) (xy 334.777074 -17.044627) (xy 334.777074 -16.980705) (xy 334.785085 -16.917287)
			(xy 334.800982 -16.855373) (xy 334.824514 -16.79594) (xy 334.855308 -16.739925) (xy 334.892881 -16.68821)
			(xy 334.936638 -16.641613) (xy 334.985891 -16.600868) (xy 335.039862 -16.566617) (xy 335.097701 -16.5394)
			(xy 335.158494 -16.519647) (xy 335.221284 -16.507669) (xy 335.28508 -16.503656) (xy 335.348876 -16.507669)
			(xy 335.411666 -16.519647) (xy 335.472459 -16.5394) (xy 335.530298 -16.566617) (xy 335.584269 -16.600868)
			(xy 335.633522 -16.641613) (xy 335.677279 -16.68821) (xy 335.714852 -16.739925) (xy 335.745646 -16.79594)
			(xy 335.769178 -16.855373) (xy 335.785075 -16.917287) (xy 335.793086 -16.980705) (xy 335.793588 -17.012666)
			(xy 335.793222 -17.035991) (xy 337.802214 -17.035991) (xy 337.802214 -16.972069) (xy 337.810225 -16.908651)
			(xy 337.826122 -16.846737) (xy 337.849654 -16.787304) (xy 337.880448 -16.731289) (xy 337.918021 -16.679574)
			(xy 337.961778 -16.632977) (xy 338.011031 -16.592232) (xy 338.065002 -16.557981) (xy 338.122841 -16.530764)
			(xy 338.183634 -16.511011) (xy 338.246424 -16.499033) (xy 338.31022 -16.49502) (xy 338.374016 -16.499033)
			(xy 338.436806 -16.511011) (xy 338.497599 -16.530764) (xy 338.555438 -16.557981) (xy 338.609409 -16.592232)
			(xy 338.658662 -16.632977) (xy 338.702419 -16.679574) (xy 338.739992 -16.731289) (xy 338.770786 -16.787304)
			(xy 338.794318 -16.846737) (xy 338.810215 -16.908651) (xy 338.818226 -16.972069) (xy 338.818728 -17.00403)
			(xy 338.818362 -17.027355) (xy 340.827354 -17.027355) (xy 340.827354 -16.963433) (xy 340.835365 -16.900015)
			(xy 340.851262 -16.838101) (xy 340.874794 -16.778668) (xy 340.905588 -16.722653) (xy 340.943161 -16.670938)
			(xy 340.986918 -16.624341) (xy 341.036171 -16.583596) (xy 341.090142 -16.549345) (xy 341.147981 -16.522128)
			(xy 341.208774 -16.502375) (xy 341.271564 -16.490397) (xy 341.33536 -16.486384) (xy 341.399156 -16.490397)
			(xy 341.461946 -16.502375) (xy 341.522739 -16.522128) (xy 341.580578 -16.549345) (xy 341.634549 -16.583596)
			(xy 341.683802 -16.624341) (xy 341.727559 -16.670938) (xy 341.765132 -16.722653) (xy 341.795926 -16.778668)
			(xy 341.819458 -16.838101) (xy 341.835355 -16.900015) (xy 341.843366 -16.963433) (xy 341.843868 -16.995394)
			(xy 341.843366 -17.027355) (xy 341.835355 -17.090773) (xy 341.829128 -17.115024) (xy 345.376482 -17.115024)
			(xy 345.376482 -17.055088) (xy 345.384305 -16.995666) (xy 345.399818 -16.937773) (xy 345.422754 -16.8824)
			(xy 345.452721 -16.830494) (xy 345.489208 -16.782944) (xy 345.531588 -16.740564) (xy 345.579138 -16.704077)
			(xy 345.631044 -16.67411) (xy 345.686417 -16.651174) (xy 345.74431 -16.635661) (xy 345.803732 -16.627838)
			(xy 345.863668 -16.627838) (xy 345.92309 -16.635661) (xy 345.980983 -16.651174) (xy 346.036356 -16.67411)
			(xy 346.088262 -16.704077) (xy 346.135812 -16.740564) (xy 346.178192 -16.782944) (xy 346.214679 -16.830494)
			(xy 346.244646 -16.8824) (xy 346.267582 -16.937773) (xy 346.283095 -16.995666) (xy 346.290918 -17.055088)
			(xy 346.291408 -17.085056) (xy 346.290918 -17.115024) (xy 346.283095 -17.174446) (xy 346.267582 -17.232339)
			(xy 346.244646 -17.287712) (xy 346.214679 -17.339618) (xy 346.178192 -17.387168) (xy 346.135812 -17.429548)
			(xy 346.088262 -17.466035) (xy 346.036356 -17.496002) (xy 345.980983 -17.518938) (xy 345.92309 -17.534451)
			(xy 345.863668 -17.542274) (xy 345.803732 -17.542274) (xy 345.74431 -17.534451) (xy 345.686417 -17.518938)
			(xy 345.631044 -17.496002) (xy 345.579138 -17.466035) (xy 345.531588 -17.429548) (xy 345.489208 -17.387168)
			(xy 345.452721 -17.339618) (xy 345.422754 -17.287712) (xy 345.399818 -17.232339) (xy 345.384305 -17.174446)
			(xy 345.376482 -17.115024) (xy 341.829128 -17.115024) (xy 341.819458 -17.152687) (xy 341.795926 -17.21212)
			(xy 341.765132 -17.268135) (xy 341.727559 -17.31985) (xy 341.683802 -17.366447) (xy 341.634549 -17.407192)
			(xy 341.580578 -17.441443) (xy 341.522739 -17.46866) (xy 341.461946 -17.488413) (xy 341.399156 -17.500391)
			(xy 341.33536 -17.504405) (xy 341.271564 -17.500391) (xy 341.208774 -17.488413) (xy 341.147981 -17.46866)
			(xy 341.090142 -17.441443) (xy 341.036171 -17.407192) (xy 340.986918 -17.366447) (xy 340.943161 -17.31985)
			(xy 340.905588 -17.268135) (xy 340.874794 -17.21212) (xy 340.851262 -17.152687) (xy 340.835365 -17.090773)
			(xy 340.827354 -17.027355) (xy 338.818362 -17.027355) (xy 338.818226 -17.035991) (xy 338.810215 -17.099409)
			(xy 338.794318 -17.161323) (xy 338.770786 -17.220756) (xy 338.739992 -17.276771) (xy 338.702419 -17.328486)
			(xy 338.658662 -17.375083) (xy 338.609409 -17.415828) (xy 338.555438 -17.450079) (xy 338.497599 -17.477296)
			(xy 338.436806 -17.497049) (xy 338.374016 -17.509027) (xy 338.31022 -17.513041) (xy 338.246424 -17.509027)
			(xy 338.183634 -17.497049) (xy 338.122841 -17.477296) (xy 338.065002 -17.450079) (xy 338.011031 -17.415828)
			(xy 337.961778 -17.375083) (xy 337.918021 -17.328486) (xy 337.880448 -17.276771) (xy 337.849654 -17.220756)
			(xy 337.826122 -17.161323) (xy 337.810225 -17.099409) (xy 337.802214 -17.035991) (xy 335.793222 -17.035991)
			(xy 335.793086 -17.044627) (xy 335.785075 -17.108045) (xy 335.769178 -17.169959) (xy 335.745646 -17.229392)
			(xy 335.714852 -17.285407) (xy 335.677279 -17.337122) (xy 335.633522 -17.383719) (xy 335.584269 -17.424464)
			(xy 335.530298 -17.458715) (xy 335.472459 -17.485932) (xy 335.411666 -17.505685) (xy 335.348876 -17.517663)
			(xy 335.28508 -17.521677) (xy 335.221284 -17.517663) (xy 335.158494 -17.505685) (xy 335.097701 -17.485932)
			(xy 335.039862 -17.458715) (xy 334.985891 -17.424464) (xy 334.936638 -17.383719) (xy 334.892881 -17.337122)
			(xy 334.855308 -17.285407) (xy 334.824514 -17.229392) (xy 334.800982 -17.169959) (xy 334.785085 -17.108045)
			(xy 334.777074 -17.044627) (xy 332.765764 -17.044627) (xy 332.759935 -17.090773) (xy 332.744038 -17.152687)
			(xy 332.720506 -17.21212) (xy 332.689712 -17.268135) (xy 332.652139 -17.31985) (xy 332.608382 -17.366447)
			(xy 332.559129 -17.407192) (xy 332.505158 -17.441443) (xy 332.447319 -17.46866) (xy 332.386526 -17.488413)
			(xy 332.323736 -17.500391) (xy 332.25994 -17.504405) (xy 332.196144 -17.500391) (xy 332.133354 -17.488413)
			(xy 332.072561 -17.46866) (xy 332.014722 -17.441443) (xy 331.960751 -17.407192) (xy 331.911498 -17.366447)
			(xy 331.867741 -17.31985) (xy 331.830168 -17.268135) (xy 331.799374 -17.21212) (xy 331.775842 -17.152687)
			(xy 331.759945 -17.090773) (xy 331.751934 -17.027355) (xy 329.742806 -17.027355) (xy 329.734795 -17.090773)
			(xy 329.718898 -17.152687) (xy 329.695366 -17.21212) (xy 329.664572 -17.268135) (xy 329.626999 -17.31985)
			(xy 329.583242 -17.366447) (xy 329.533989 -17.407192) (xy 329.480018 -17.441443) (xy 329.422179 -17.46866)
			(xy 329.361386 -17.488413) (xy 329.298596 -17.500391) (xy 329.2348 -17.504405) (xy 329.171004 -17.500391)
			(xy 329.108214 -17.488413) (xy 329.047421 -17.46866) (xy 328.989582 -17.441443) (xy 328.935611 -17.407192)
			(xy 328.886358 -17.366447) (xy 328.842601 -17.31985) (xy 328.805028 -17.268135) (xy 328.774234 -17.21212)
			(xy 328.750702 -17.152687) (xy 328.734805 -17.090773) (xy 328.726794 -17.027355) (xy 319.050205 -17.027355)
			(xy 318.492886 -17.584674) (xy 318.486042 -17.592072) (xy 318.478321 -17.610672) (xy 318.4779 -17.620742)
			(xy 318.4779 -18.250154) (xy 318.478126 -18.256528) (xy 318.481331 -18.268868) (xy 318.48425 -18.274538)
			(xy 318.499273 -18.303019) (xy 318.520581 -18.363779) (xy 318.531367 -18.427256) (xy 318.532002 -18.45945)
			(xy 318.531333 -18.491641) (xy 318.52054 -18.555114) (xy 318.499267 -18.615881) (xy 318.48425 -18.644362)
			(xy 318.481313 -18.650026) (xy 318.478093 -18.662369) (xy 318.4779 -18.668746) (xy 318.4779 -21.067776)
			(xy 318.494156 -21.092922) (xy 318.507872 -21.099018) (xy 318.537358 -21.112747) (xy 318.592885 -21.146621)
			(xy 318.643639 -21.1873) (xy 318.688791 -21.234119) (xy 318.727602 -21.286314) (xy 318.75944 -21.343033)
			(xy 318.783785 -21.403349) (xy 318.800239 -21.466277) (xy 318.808532 -21.53079) (xy 318.808531 -21.595834)
			(xy 318.800234 -21.660347) (xy 318.783777 -21.723274) (xy 318.75943 -21.783589) (xy 318.727589 -21.840306)
			(xy 318.688775 -21.8925) (xy 318.643621 -21.939317) (xy 318.592865 -21.979993) (xy 318.537337 -22.013864)
			(xy 318.507872 -22.027642) (xy 318.494156 -22.033738) (xy 318.4779 -22.058884) (xy 318.4779 -22.485604)
			(xy 318.478319 -22.494926) (xy 318.485004 -22.512331) (xy 318.497484 -22.526183) (xy 318.505586 -22.530816)
			(xy 318.599058 -22.578568) (xy 318.627506 -22.576282) (xy 318.63919 -22.5679) (xy 318.665314 -22.549513)
			(xy 318.721295 -22.518734) (xy 318.780693 -22.495214) (xy 318.842571 -22.479325) (xy 318.905952 -22.471317)
			(xy 318.937894 -22.470872) (xy 318.969858 -22.471353) (xy 319.033282 -22.479364) (xy 319.095201 -22.495262)
			(xy 319.15464 -22.518795) (xy 319.21066 -22.549592) (xy 319.262379 -22.587167) (xy 319.308981 -22.630928)
			(xy 319.34973 -22.680185) (xy 319.383984 -22.734161) (xy 319.411204 -22.792004) (xy 319.430958 -22.852803)
			(xy 319.442937 -22.915598) (xy 319.446952 -22.9794) (xy 319.442937 -23.043202) (xy 319.430958 -23.105997)
			(xy 319.411204 -23.166796) (xy 319.383984 -23.224639) (xy 319.34973 -23.278615) (xy 319.308981 -23.327872)
			(xy 319.262379 -23.371633) (xy 319.21066 -23.409208) (xy 319.15464 -23.440005) (xy 319.095201 -23.463538)
			(xy 319.033282 -23.479436) (xy 318.969858 -23.487447) (xy 318.937894 -23.487888) (xy 318.905954 -23.487387)
			(xy 318.842579 -23.479382) (xy 318.780706 -23.463499) (xy 318.721311 -23.439988) (xy 318.66533 -23.40922)
			(xy 318.63919 -23.39086) (xy 318.627506 -23.382478) (xy 318.599058 -23.380192) (xy 318.505586 -23.427944)
			(xy 318.497483 -23.432565) (xy 318.485032 -23.446435) (xy 318.478359 -23.463837) (xy 318.4779 -23.473156)
			(xy 318.4779 -23.619417) (xy 319.397882 -23.619417) (xy 319.397882 -23.555495) (xy 319.405893 -23.492077)
			(xy 319.42179 -23.430163) (xy 319.445322 -23.37073) (xy 319.476116 -23.314715) (xy 319.513689 -23.263)
			(xy 319.557446 -23.216403) (xy 319.606699 -23.175658) (xy 319.66067 -23.141407) (xy 319.718509 -23.11419)
			(xy 319.779302 -23.094437) (xy 319.842092 -23.082459) (xy 319.905888 -23.078446) (xy 319.969684 -23.082459)
			(xy 320.032474 -23.094437) (xy 320.093267 -23.11419) (xy 320.151106 -23.141407) (xy 320.205077 -23.175658)
			(xy 320.25433 -23.216403) (xy 320.298087 -23.263) (xy 320.33566 -23.314715) (xy 320.366454 -23.37073)
			(xy 320.389986 -23.430163) (xy 320.405883 -23.492077) (xy 320.413894 -23.555495) (xy 320.414396 -23.587456)
			(xy 320.413894 -23.619417) (xy 320.405883 -23.682835) (xy 320.389986 -23.744749) (xy 320.366454 -23.804182)
			(xy 320.33566 -23.860197) (xy 320.298087 -23.911912) (xy 320.25433 -23.958509) (xy 320.205077 -23.999254)
			(xy 320.151106 -24.033505) (xy 320.093267 -24.060722) (xy 320.032474 -24.080475) (xy 319.969684 -24.092453)
			(xy 319.905888 -24.096467) (xy 319.842092 -24.092453) (xy 319.779302 -24.080475) (xy 319.718509 -24.060722)
			(xy 319.66067 -24.033505) (xy 319.606699 -23.999254) (xy 319.557446 -23.958509) (xy 319.513689 -23.911912)
			(xy 319.476116 -23.860197) (xy 319.445322 -23.804182) (xy 319.42179 -23.744749) (xy 319.405893 -23.682835)
			(xy 319.397882 -23.619417) (xy 318.4779 -23.619417) (xy 318.4779 -23.767796) (xy 318.494156 -23.792942)
			(xy 318.507872 -23.799038) (xy 318.537357 -23.812771) (xy 318.592882 -23.84665) (xy 318.643634 -23.887333)
			(xy 318.688785 -23.934154) (xy 318.727597 -23.986351) (xy 318.759436 -24.04307) (xy 318.783784 -24.103386)
			(xy 318.800242 -24.166314) (xy 318.808542 -24.230828) (xy 318.809116 -24.26335) (xy 318.808624 -24.294953)
			(xy 318.800755 -24.357668) (xy 318.785158 -24.41892) (xy 318.774064 -24.448516) (xy 318.769492 -24.460454)
			(xy 318.77254 -24.485346) (xy 318.826896 -24.565102) (xy 318.834422 -24.574997) (xy 318.85639 -24.586575)
			(xy 318.868806 -24.5872) (xy 321.672458 -24.5872) (xy 321.682523 -24.586766) (xy 321.701113 -24.579037)
			(xy 321.708526 -24.572214) (xy 322.046854 -24.233886) (xy 322.053703 -24.226489) (xy 322.06144 -24.20789)
			(xy 322.06184 -24.197818) (xy 322.06184 -21.943822) (xy 322.062279 -21.933759) (xy 322.070017 -21.915179)
			(xy 322.076826 -21.907754) (xy 326.278494 -17.706086) (xy 326.285888 -17.699229) (xy 326.304487 -17.691479)
			(xy 326.314562 -17.6911) (xy 347.367098 -17.6911) (xy 347.377168 -17.691523) (xy 347.395773 -17.699237)
			(xy 347.403166 -17.706086) (xy 356.399846 -26.702766) (xy 367.122708 -26.702766) (xy 367.126779 -26.647144)
			(xy 367.138905 -26.592707) (xy 367.158828 -26.540616) (xy 367.186124 -26.491981) (xy 367.22021 -26.447838)
			(xy 367.260359 -26.409129) (xy 367.305717 -26.376678) (xy 367.355317 -26.351177) (xy 367.408101 -26.33317)
			(xy 367.462944 -26.32304) (xy 367.518678 -26.321003) (xy 367.574115 -26.327103) (xy 367.628072 -26.341209)
			(xy 367.679401 -26.363021) (xy 367.727007 -26.392075) (xy 367.769875 -26.42775) (xy 367.807092 -26.469287)
			(xy 367.837865 -26.5158) (xy 367.861537 -26.566297) (xy 367.877605 -26.619704) (xy 367.885725 -26.67488)
			(xy 367.886234 -26.702766) (xy 367.885725 -26.730652) (xy 367.877605 -26.785828) (xy 367.861537 -26.839235)
			(xy 367.837865 -26.889732) (xy 367.807092 -26.936245) (xy 367.769875 -26.977782) (xy 367.727007 -27.013457)
			(xy 367.679401 -27.042511) (xy 367.628072 -27.064323) (xy 367.574115 -27.078429) (xy 367.518678 -27.084529)
			(xy 367.462944 -27.082492) (xy 367.408101 -27.072362) (xy 367.355317 -27.054355) (xy 367.305717 -27.028854)
			(xy 367.260359 -26.996403) (xy 367.22021 -26.957694) (xy 367.186124 -26.913551) (xy 367.158828 -26.864916)
			(xy 367.138905 -26.812825) (xy 367.126779 -26.758388) (xy 367.122708 -26.702766) (xy 356.399846 -26.702766)
			(xy 356.986543 -27.289463) (xy 362.50092 -27.289463) (xy 362.50092 -27.225541) (xy 362.508931 -27.162123)
			(xy 362.524828 -27.100209) (xy 362.54836 -27.040776) (xy 362.579154 -26.984761) (xy 362.616727 -26.933046)
			(xy 362.660484 -26.886449) (xy 362.709737 -26.845704) (xy 362.763708 -26.811453) (xy 362.821547 -26.784236)
			(xy 362.88234 -26.764483) (xy 362.94513 -26.752505) (xy 363.008926 -26.748492) (xy 363.072722 -26.752505)
			(xy 363.135512 -26.764483) (xy 363.196305 -26.784236) (xy 363.254144 -26.811453) (xy 363.308115 -26.845704)
			(xy 363.357368 -26.886449) (xy 363.401125 -26.933046) (xy 363.438698 -26.984761) (xy 363.469492 -27.040776)
			(xy 363.493024 -27.100209) (xy 363.508921 -27.162123) (xy 363.509322 -27.1653) (xy 363.984284 -27.1653)
			(xy 363.988355 -27.109678) (xy 364.000481 -27.055241) (xy 364.020404 -27.00315) (xy 364.0477 -26.954515)
			(xy 364.081786 -26.910372) (xy 364.121935 -26.871663) (xy 364.167293 -26.839212) (xy 364.216893 -26.813711)
			(xy 364.269677 -26.795704) (xy 364.32452 -26.785574) (xy 364.380254 -26.783537) (xy 364.435691 -26.789637)
			(xy 364.489648 -26.803743) (xy 364.540977 -26.825555) (xy 364.588583 -26.854609) (xy 364.631451 -26.890284)
			(xy 364.668668 -26.931821) (xy 364.699441 -26.978334) (xy 364.723113 -27.028831) (xy 364.739181 -27.082238)
			(xy 364.747301 -27.137414) (xy 364.74781 -27.1653) (xy 364.747301 -27.193186) (xy 364.739181 -27.248362)
			(xy 364.726503 -27.2905) (xy 365.00939 -27.2905) (xy 365.013405 -27.226701) (xy 365.025384 -27.163907)
			(xy 365.045139 -27.103111) (xy 365.072359 -27.04527) (xy 365.106613 -26.991297) (xy 365.147363 -26.942043)
			(xy 365.193965 -26.898285) (xy 365.245684 -26.860713) (xy 365.301704 -26.82992) (xy 365.361142 -26.806392)
			(xy 365.423061 -26.790499) (xy 365.486483 -26.782492) (xy 365.518446 -26.782014) (xy 365.549723 -26.782509)
			(xy 365.611808 -26.790166) (xy 365.672483 -26.805383) (xy 365.730833 -26.827929) (xy 365.785976 -26.857466)
			(xy 365.837077 -26.893545) (xy 365.883366 -26.935621) (xy 365.924142 -26.98306) (xy 365.941864 -27.008836)
			(xy 365.949338 -27.018976) (xy 365.971453 -27.030971) (xy 365.984028 -27.031696) (xy 366.068864 -27.031696)
			(xy 366.081441 -27.030975) (xy 366.10356 -27.018981) (xy 366.111028 -27.008836) (xy 366.128767 -26.983073)
			(xy 366.16955 -26.935644) (xy 366.21584 -26.893573) (xy 366.26694 -26.857496) (xy 366.322078 -26.827958)
			(xy 366.380422 -26.805403) (xy 366.441091 -26.790172) (xy 366.50317 -26.782495) (xy 366.534446 -26.782014)
			(xy 366.566407 -26.782475) (xy 366.629823 -26.790491) (xy 366.691735 -26.806393) (xy 366.751165 -26.829928)
			(xy 366.807178 -26.860725) (xy 366.858889 -26.8983) (xy 366.905484 -26.942059) (xy 366.946227 -26.991313)
			(xy 366.980476 -27.045285) (xy 367.007691 -27.103123) (xy 367.027442 -27.163916) (xy 367.039419 -27.226705)
			(xy 367.043433 -27.2905) (xy 367.041421 -27.322483) (xy 368.94744 -27.322483) (xy 368.94744 -27.258561)
			(xy 368.955451 -27.195143) (xy 368.971348 -27.133229) (xy 368.99488 -27.073796) (xy 369.025674 -27.017781)
			(xy 369.063247 -26.966066) (xy 369.107004 -26.919469) (xy 369.156257 -26.878724) (xy 369.210228 -26.844473)
			(xy 369.268067 -26.817256) (xy 369.32886 -26.797503) (xy 369.39165 -26.785525) (xy 369.455446 -26.781512)
			(xy 369.519242 -26.785525) (xy 369.582032 -26.797503) (xy 369.642825 -26.817256) (xy 369.700664 -26.844473)
			(xy 369.754635 -26.878724) (xy 369.803888 -26.919469) (xy 369.847645 -26.966066) (xy 369.885218 -27.017781)
			(xy 369.916012 -27.073796) (xy 369.939544 -27.133229) (xy 369.955441 -27.195143) (xy 369.963452 -27.258561)
			(xy 369.963954 -27.290522) (xy 369.963452 -27.322483) (xy 369.955441 -27.385901) (xy 369.939544 -27.447815)
			(xy 369.916012 -27.507248) (xy 369.885218 -27.563263) (xy 369.847645 -27.614978) (xy 369.803888 -27.661575)
			(xy 369.754635 -27.70232) (xy 369.700664 -27.736571) (xy 369.642825 -27.763788) (xy 369.582032 -27.783541)
			(xy 369.519242 -27.795519) (xy 369.455446 -27.799533) (xy 369.39165 -27.795519) (xy 369.32886 -27.783541)
			(xy 369.268067 -27.763788) (xy 369.210228 -27.736571) (xy 369.156257 -27.70232) (xy 369.107004 -27.661575)
			(xy 369.063247 -27.614978) (xy 369.025674 -27.563263) (xy 368.99488 -27.507248) (xy 368.971348 -27.447815)
			(xy 368.955451 -27.385901) (xy 368.94744 -27.322483) (xy 367.041421 -27.322483) (xy 367.039419 -27.354295)
			(xy 367.027442 -27.417084) (xy 367.007691 -27.477877) (xy 366.980476 -27.535715) (xy 366.946227 -27.589687)
			(xy 366.905484 -27.638941) (xy 366.858889 -27.6827) (xy 366.807178 -27.720275) (xy 366.751165 -27.751072)
			(xy 366.691735 -27.774607) (xy 366.629823 -27.790509) (xy 366.566407 -27.798525) (xy 366.534446 -27.79903)
			(xy 366.503167 -27.798566) (xy 366.441081 -27.790907) (xy 366.380404 -27.775688) (xy 366.322053 -27.753137)
			(xy 366.26691 -27.723597) (xy 366.215809 -27.687513) (xy 366.169522 -27.645431) (xy 366.128749 -27.597987)
			(xy 366.111028 -27.572208) (xy 366.103548 -27.562072) (xy 366.081438 -27.550073) (xy 366.068864 -27.549348)
			(xy 365.984028 -27.549348) (xy 365.971454 -27.550087) (xy 365.949337 -27.56207) (xy 365.941864 -27.572208)
			(xy 365.924144 -27.597985) (xy 365.883357 -27.645412) (xy 365.837063 -27.68748) (xy 365.78596 -27.723555)
			(xy 365.73082 -27.753092) (xy 365.672474 -27.775645) (xy 365.611803 -27.790874) (xy 365.549723 -27.798549)
			(xy 365.518446 -27.79903) (xy 365.486483 -27.798508) (xy 365.423061 -27.790501) (xy 365.361142 -27.774608)
			(xy 365.301704 -27.75108) (xy 365.245684 -27.720287) (xy 365.193965 -27.682715) (xy 365.147363 -27.638957)
			(xy 365.106613 -27.589703) (xy 365.072359 -27.53573) (xy 365.045139 -27.477889) (xy 365.025384 -27.417093)
			(xy 365.013405 -27.354299) (xy 365.00939 -27.2905) (xy 364.726503 -27.2905) (xy 364.723113 -27.301769)
			(xy 364.699441 -27.352266) (xy 364.668668 -27.398779) (xy 364.631451 -27.440316) (xy 364.588583 -27.475991)
			(xy 364.540977 -27.505045) (xy 364.489648 -27.526857) (xy 364.435691 -27.540963) (xy 364.380254 -27.547063)
			(xy 364.32452 -27.545026) (xy 364.269677 -27.534896) (xy 364.216893 -27.516889) (xy 364.167293 -27.491388)
			(xy 364.121935 -27.458937) (xy 364.081786 -27.420228) (xy 364.0477 -27.376085) (xy 364.020404 -27.32745)
			(xy 364.000481 -27.275359) (xy 363.988355 -27.220922) (xy 363.984284 -27.1653) (xy 363.509322 -27.1653)
			(xy 363.516932 -27.225541) (xy 363.517434 -27.257502) (xy 363.516932 -27.289463) (xy 363.508921 -27.352881)
			(xy 363.493024 -27.414795) (xy 363.469492 -27.474228) (xy 363.438698 -27.530243) (xy 363.401125 -27.581958)
			(xy 363.357368 -27.628555) (xy 363.308115 -27.6693) (xy 363.254144 -27.703551) (xy 363.196305 -27.730768)
			(xy 363.135512 -27.750521) (xy 363.072722 -27.762499) (xy 363.008926 -27.766513) (xy 362.94513 -27.762499)
			(xy 362.88234 -27.750521) (xy 362.821547 -27.730768) (xy 362.763708 -27.703551) (xy 362.709737 -27.6693)
			(xy 362.660484 -27.628555) (xy 362.616727 -27.581958) (xy 362.579154 -27.530243) (xy 362.54836 -27.474228)
			(xy 362.524828 -27.414795) (xy 362.508931 -27.352881) (xy 362.50092 -27.289463) (xy 356.986543 -27.289463)
			(xy 360.232452 -30.535372) (xy 366.785652 -30.535372) (xy 366.786155 -30.501238) (xy 366.795282 -30.433582)
			(xy 366.81338 -30.367755) (xy 366.840125 -30.304943) (xy 366.875035 -30.246276) (xy 366.917482 -30.192807)
			(xy 366.966703 -30.145501) (xy 366.993932 -30.124908) (xy 367.003076 -30.118304) (xy 367.01349 -30.099508)
			(xy 367.021872 -30.000702) (xy 367.014506 -29.980128) (xy 367.006632 -29.972) (xy 366.986521 -29.950492)
			(xy 366.952454 -29.902468) (xy 366.926167 -29.849781) (xy 366.908285 -29.793682) (xy 366.899232 -29.735502)
			(xy 366.898682 -29.706062) (xy 366.899142 -29.67881) (xy 366.906904 -29.624862) (xy 366.922263 -29.572568)
			(xy 366.944908 -29.522991) (xy 366.974377 -29.477141) (xy 367.010071 -29.435952) (xy 367.051264 -29.400261)
			(xy 367.097115 -29.370795) (xy 367.146694 -29.348153) (xy 367.19899 -29.332798) (xy 367.252938 -29.32504)
			(xy 367.28019 -29.324554) (xy 367.290178 -29.324602) (xy 367.310127 -29.325619) (xy 367.320068 -29.326586)
			(xy 367.332006 -29.327856) (xy 367.354358 -29.319728) (xy 367.42624 -29.242512) (xy 367.432844 -29.219906)
			(xy 367.430812 -29.207968) (xy 367.427143 -29.18599) (xy 367.4232 -29.141603) (xy 367.422938 -29.119322)
			(xy 367.423358 -29.088589) (xy 367.430765 -29.02757) (xy 367.445474 -28.967889) (xy 367.46727 -28.910416)
			(xy 367.495835 -28.85599) (xy 367.530752 -28.805404) (xy 367.571513 -28.759396) (xy 367.617523 -28.718637)
			(xy 367.66811 -28.683722) (xy 367.722538 -28.65516) (xy 367.780012 -28.633367) (xy 367.839693 -28.618661)
			(xy 367.900713 -28.611257) (xy 367.931446 -28.610814) (xy 367.962885 -28.611298) (xy 368.025281 -28.619079)
			(xy 368.086244 -28.634482) (xy 368.144848 -28.657271) (xy 368.172746 -28.671774) (xy 368.183414 -28.677616)
			(xy 368.207036 -28.678124) (xy 368.303048 -28.63342) (xy 368.31778 -28.614878) (xy 368.32032 -28.60294)
			(xy 368.327244 -28.572131) (xy 368.34767 -28.512379) (xy 368.375338 -28.455615) (xy 368.409821 -28.402714)
			(xy 368.450588 -28.35449) (xy 368.497012 -28.311684) (xy 368.548379 -28.274955) (xy 368.603899 -28.244869)
			(xy 368.662716 -28.221889) (xy 368.723926 -28.206367) (xy 368.786586 -28.198544) (xy 368.81816 -28.198064)
			(xy 368.84889 -28.198575) (xy 368.909903 -28.205979) (xy 368.969578 -28.220683) (xy 369.027046 -28.242473)
			(xy 369.081469 -28.271031) (xy 369.132052 -28.305941) (xy 369.178059 -28.346693) (xy 369.218817 -28.392694)
			(xy 369.253734 -28.443273) (xy 369.2823 -28.497691) (xy 369.304097 -28.555157) (xy 369.318809 -28.61483)
			(xy 369.326221 -28.675842) (xy 369.326668 -28.706572) (xy 369.326097 -28.739267) (xy 369.317718 -28.804119)
			(xy 369.301095 -28.867361) (xy 369.276502 -28.927951) (xy 369.244344 -28.984888) (xy 369.205153 -29.037233)
			(xy 369.159575 -29.084122) (xy 369.108363 -29.124781) (xy 369.052361 -29.15854) (xy 369.02263 -29.172154)
			(xy 369.012724 -29.176472) (xy 368.998246 -29.19222) (xy 368.967766 -29.284676) (xy 368.969798 -29.306012)
			(xy 368.975132 -29.31541) (xy 368.987004 -29.337059) (xy 369.005699 -29.382759) (xy 369.018354 -29.430486)
			(xy 369.024759 -29.479444) (xy 369.02517 -29.504132) (xy 369.024775 -29.531387) (xy 369.017012 -29.585343)
			(xy 369.00165 -29.637644) (xy 368.979001 -29.687227) (xy 368.949527 -29.733082) (xy 368.913826 -29.774275)
			(xy 368.872626 -29.809969) (xy 368.826766 -29.839435) (xy 368.777179 -29.862075) (xy 368.724874 -29.877427)
			(xy 368.670917 -29.88518) (xy 368.643662 -29.88564) (xy 368.614636 -29.885062) (xy 368.557251 -29.876289)
			(xy 368.501858 -29.85892) (xy 368.449737 -29.833358) (xy 368.402092 -29.800192) (xy 368.360023 -29.760188)
			(xy 368.324503 -29.714272) (xy 368.296352 -29.663502) (xy 368.285776 -29.636466) (xy 368.281966 -29.626306)
			(xy 368.267488 -29.611066) (xy 368.17808 -29.57449) (xy 368.157252 -29.574998) (xy 368.147346 -29.57957)
			(xy 368.113422 -29.594819) (xy 368.042214 -29.616302) (xy 367.968635 -29.62717) (xy 367.931446 -29.62783)
			(xy 367.895917 -29.62718) (xy 367.825557 -29.617236) (xy 367.791238 -29.608018) (xy 367.779554 -29.604716)
			(xy 367.75644 -29.609034) (xy 367.672112 -29.672534) (xy 367.661698 -29.693616) (xy 367.661698 -29.706062)
			(xy 367.661226 -29.734244) (xy 367.652919 -29.789994) (xy 367.636508 -29.843917) (xy 367.612351 -29.894843)
			(xy 367.580971 -29.941666) (xy 367.562384 -29.962856) (xy 367.554764 -29.970984) (xy 367.54816 -29.991812)
			(xy 367.559844 -30.09011) (xy 367.57102 -30.108652) (xy 367.580418 -30.115002) (xy 367.605734 -30.132786)
			(xy 367.652263 -30.173566) (xy 367.693502 -30.219688) (xy 367.728841 -30.270473) (xy 367.757758 -30.32517)
			(xy 367.779825 -30.382971) (xy 367.794717 -30.443022) (xy 367.802215 -30.504437) (xy 367.802668 -30.535372)
			(xy 367.802166 -30.567333) (xy 367.794155 -30.630751) (xy 367.778258 -30.692665) (xy 367.754726 -30.752098)
			(xy 367.723932 -30.808113) (xy 367.686359 -30.859828) (xy 367.642602 -30.906425) (xy 367.593349 -30.94717)
			(xy 367.539378 -30.981421) (xy 367.481539 -31.008638) (xy 367.420746 -31.028391) (xy 367.357956 -31.040369)
			(xy 367.29416 -31.044383) (xy 367.230364 -31.040369) (xy 367.167574 -31.028391) (xy 367.106781 -31.008638)
			(xy 367.048942 -30.981421) (xy 366.994971 -30.94717) (xy 366.945718 -30.906425) (xy 366.901961 -30.859828)
			(xy 366.864388 -30.808113) (xy 366.833594 -30.752098) (xy 366.810062 -30.692665) (xy 366.794165 -30.630751)
			(xy 366.786154 -30.567333) (xy 366.785652 -30.535372) (xy 360.232452 -30.535372) (xy 361.665223 -31.968143)
			(xy 369.231412 -31.968143) (xy 369.231412 -31.904221) (xy 369.239423 -31.840803) (xy 369.25532 -31.778889)
			(xy 369.278852 -31.719456) (xy 369.309646 -31.663441) (xy 369.347219 -31.611726) (xy 369.390976 -31.565129)
			(xy 369.440229 -31.524384) (xy 369.4942 -31.490133) (xy 369.552039 -31.462916) (xy 369.612832 -31.443163)
			(xy 369.675622 -31.431185) (xy 369.739418 -31.427172) (xy 369.803214 -31.431185) (xy 369.866004 -31.443163)
			(xy 369.926797 -31.462916) (xy 369.984636 -31.490133) (xy 370.038607 -31.524384) (xy 370.08786 -31.565129)
			(xy 370.131617 -31.611726) (xy 370.16919 -31.663441) (xy 370.199984 -31.719456) (xy 370.223516 -31.778889)
			(xy 370.239413 -31.840803) (xy 370.247424 -31.904221) (xy 370.247926 -31.936182) (xy 370.247424 -31.968143)
			(xy 370.239413 -32.031561) (xy 370.223516 -32.093475) (xy 370.199984 -32.152908) (xy 370.16919 -32.208923)
			(xy 370.131617 -32.260638) (xy 370.08786 -32.307235) (xy 370.038607 -32.34798) (xy 369.984636 -32.382231)
			(xy 369.926797 -32.409448) (xy 369.866004 -32.429201) (xy 369.803214 -32.441179) (xy 369.739418 -32.445193)
			(xy 369.675622 -32.441179) (xy 369.612832 -32.429201) (xy 369.552039 -32.409448) (xy 369.4942 -32.382231)
			(xy 369.440229 -32.34798) (xy 369.390976 -32.307235) (xy 369.347219 -32.260638) (xy 369.309646 -32.208923)
			(xy 369.278852 -32.152908) (xy 369.25532 -32.093475) (xy 369.239423 -32.031561) (xy 369.231412 -31.968143)
			(xy 361.665223 -31.968143) (xy 362.270548 -32.573468) (xy 370.77345 -32.573468) (xy 370.777521 -32.517846)
			(xy 370.789647 -32.463409) (xy 370.80957 -32.411318) (xy 370.836866 -32.362683) (xy 370.870952 -32.31854)
			(xy 370.911101 -32.279831) (xy 370.956459 -32.24738) (xy 371.006059 -32.221879) (xy 371.058843 -32.203872)
			(xy 371.113686 -32.193742) (xy 371.16942 -32.191705) (xy 371.224857 -32.197805) (xy 371.278814 -32.211911)
			(xy 371.330143 -32.233723) (xy 371.377749 -32.262777) (xy 371.420617 -32.298452) (xy 371.457834 -32.339989)
			(xy 371.488607 -32.386502) (xy 371.512279 -32.436999) (xy 371.528347 -32.490406) (xy 371.536467 -32.545582)
			(xy 371.536976 -32.573468) (xy 371.536467 -32.601354) (xy 371.528347 -32.65653) (xy 371.512279 -32.709937)
			(xy 371.488607 -32.760434) (xy 371.457834 -32.806947) (xy 371.420617 -32.848484) (xy 371.377749 -32.884159)
			(xy 371.330143 -32.913213) (xy 371.278814 -32.935025) (xy 371.224857 -32.949131) (xy 371.16942 -32.955231)
			(xy 371.113686 -32.953194) (xy 371.058843 -32.943064) (xy 371.006059 -32.925057) (xy 370.956459 -32.899556)
			(xy 370.911101 -32.867105) (xy 370.870952 -32.828396) (xy 370.836866 -32.784253) (xy 370.80957 -32.735618)
			(xy 370.789647 -32.683527) (xy 370.777521 -32.62909) (xy 370.77345 -32.573468) (xy 362.270548 -32.573468)
			(xy 362.747052 -33.049972) (xy 365.599216 -33.049972) (xy 365.603287 -32.99435) (xy 365.615413 -32.939913)
			(xy 365.635336 -32.887822) (xy 365.662632 -32.839187) (xy 365.696718 -32.795044) (xy 365.736867 -32.756335)
			(xy 365.782225 -32.723884) (xy 365.831825 -32.698383) (xy 365.884609 -32.680376) (xy 365.939452 -32.670246)
			(xy 365.995186 -32.668209) (xy 366.050623 -32.674309) (xy 366.10458 -32.688415) (xy 366.155909 -32.710227)
			(xy 366.203515 -32.739281) (xy 366.246383 -32.774956) (xy 366.2836 -32.816493) (xy 366.314373 -32.863006)
			(xy 366.338045 -32.913503) (xy 366.354113 -32.96691) (xy 366.362233 -33.022086) (xy 366.362742 -33.049972)
			(xy 366.362233 -33.077858) (xy 366.354113 -33.133034) (xy 366.338045 -33.186441) (xy 366.314373 -33.236938)
			(xy 366.2836 -33.283451) (xy 366.246383 -33.324988) (xy 366.203515 -33.360663) (xy 366.155909 -33.389717)
			(xy 366.10458 -33.411529) (xy 366.050623 -33.425635) (xy 365.995186 -33.431735) (xy 365.939452 -33.429698)
			(xy 365.884609 -33.419568) (xy 365.831825 -33.401561) (xy 365.782225 -33.37606) (xy 365.736867 -33.343609)
			(xy 365.696718 -33.3049) (xy 365.662632 -33.260757) (xy 365.635336 -33.212122) (xy 365.615413 -33.160031)
			(xy 365.603287 -33.105594) (xy 365.599216 -33.049972) (xy 362.747052 -33.049972) (xy 363.359911 -33.662831)
			(xy 376.382274 -33.662831) (xy 376.382274 -33.598909) (xy 376.390285 -33.535491) (xy 376.406182 -33.473577)
			(xy 376.429714 -33.414144) (xy 376.460508 -33.358129) (xy 376.498081 -33.306414) (xy 376.541838 -33.259817)
			(xy 376.591091 -33.219072) (xy 376.645062 -33.184821) (xy 376.702901 -33.157604) (xy 376.763694 -33.137851)
			(xy 376.826484 -33.125873) (xy 376.89028 -33.12186) (xy 376.954076 -33.125873) (xy 377.016866 -33.137851)
			(xy 377.077659 -33.157604) (xy 377.135498 -33.184821) (xy 377.189469 -33.219072) (xy 377.238722 -33.259817)
			(xy 377.282479 -33.306414) (xy 377.302665 -33.334198) (xy 379.484888 -33.334198) (xy 379.488959 -33.278576)
			(xy 379.501085 -33.224139) (xy 379.521008 -33.172048) (xy 379.548304 -33.123413) (xy 379.58239 -33.07927)
			(xy 379.622539 -33.040561) (xy 379.667897 -33.00811) (xy 379.717497 -32.982609) (xy 379.770281 -32.964602)
			(xy 379.825124 -32.954472) (xy 379.880858 -32.952435) (xy 379.936295 -32.958535) (xy 379.990252 -32.972641)
			(xy 380.041581 -32.994453) (xy 380.089187 -33.023507) (xy 380.132055 -33.059182) (xy 380.169272 -33.100719)
			(xy 380.200045 -33.147232) (xy 380.223717 -33.197729) (xy 380.239785 -33.251136) (xy 380.247905 -33.306312)
			(xy 380.248414 -33.334198) (xy 380.247905 -33.362084) (xy 380.239785 -33.41726) (xy 380.223717 -33.470667)
			(xy 380.200045 -33.521164) (xy 380.169272 -33.567677) (xy 380.132055 -33.609214) (xy 380.089187 -33.644889)
			(xy 380.041581 -33.673943) (xy 379.990252 -33.695755) (xy 379.936295 -33.709861) (xy 379.880858 -33.715961)
			(xy 379.825124 -33.713924) (xy 379.770281 -33.703794) (xy 379.717497 -33.685787) (xy 379.667897 -33.660286)
			(xy 379.622539 -33.627835) (xy 379.58239 -33.589126) (xy 379.548304 -33.544983) (xy 379.521008 -33.496348)
			(xy 379.501085 -33.444257) (xy 379.488959 -33.38982) (xy 379.484888 -33.334198) (xy 377.302665 -33.334198)
			(xy 377.320052 -33.358129) (xy 377.350846 -33.414144) (xy 377.374378 -33.473577) (xy 377.390275 -33.535491)
			(xy 377.398286 -33.598909) (xy 377.398788 -33.63087) (xy 377.398286 -33.662831) (xy 377.390275 -33.726249)
			(xy 377.374378 -33.788163) (xy 377.350846 -33.847596) (xy 377.320052 -33.903611) (xy 377.282479 -33.955326)
			(xy 377.238722 -34.001923) (xy 377.189469 -34.042668) (xy 377.135498 -34.076919) (xy 377.077659 -34.104136)
			(xy 377.016866 -34.123889) (xy 376.954076 -34.135867) (xy 376.89028 -34.139881) (xy 376.826484 -34.135867)
			(xy 376.763694 -34.123889) (xy 376.702901 -34.104136) (xy 376.645062 -34.076919) (xy 376.591091 -34.042668)
			(xy 376.541838 -34.001923) (xy 376.498081 -33.955326) (xy 376.460508 -33.903611) (xy 376.429714 -33.847596)
			(xy 376.406182 -33.788163) (xy 376.390285 -33.726249) (xy 376.382274 -33.662831) (xy 363.359911 -33.662831)
			(xy 363.907789 -34.210709) (xy 377.608332 -34.210709) (xy 377.608332 -34.146787) (xy 377.616343 -34.083369)
			(xy 377.63224 -34.021455) (xy 377.655772 -33.962022) (xy 377.686566 -33.906007) (xy 377.724139 -33.854292)
			(xy 377.767896 -33.807695) (xy 377.817149 -33.76695) (xy 377.87112 -33.732699) (xy 377.928959 -33.705482)
			(xy 377.989752 -33.685729) (xy 378.052542 -33.673751) (xy 378.116338 -33.669738) (xy 378.180134 -33.673751)
			(xy 378.242924 -33.685729) (xy 378.303717 -33.705482) (xy 378.361556 -33.732699) (xy 378.415527 -33.76695)
			(xy 378.46478 -33.807695) (xy 378.508537 -33.854292) (xy 378.54611 -33.906007) (xy 378.576904 -33.962022)
			(xy 378.600436 -34.021455) (xy 378.616333 -34.083369) (xy 378.624344 -34.146787) (xy 378.624846 -34.178748)
			(xy 378.624344 -34.210709) (xy 378.616333 -34.274127) (xy 378.600436 -34.336041) (xy 378.576904 -34.395474)
			(xy 378.54611 -34.451489) (xy 378.508537 -34.503204) (xy 378.46478 -34.549801) (xy 378.415527 -34.590546)
			(xy 378.361556 -34.624797) (xy 378.303717 -34.652014) (xy 378.242924 -34.671767) (xy 378.180134 -34.683745)
			(xy 378.116338 -34.687759) (xy 378.052542 -34.683745) (xy 377.989752 -34.671767) (xy 377.928959 -34.652014)
			(xy 377.87112 -34.624797) (xy 377.817149 -34.590546) (xy 377.767896 -34.549801) (xy 377.724139 -34.503204)
			(xy 377.686566 -34.451489) (xy 377.655772 -34.395474) (xy 377.63224 -34.336041) (xy 377.616343 -34.274127)
			(xy 377.608332 -34.210709) (xy 363.907789 -34.210709) (xy 364.08995 -34.39287) (xy 364.097297 -34.399676)
			(xy 364.115759 -34.407395) (xy 364.125764 -34.407856) (xy 367.861088 -34.407856) (xy 367.895026 -34.408331)
			(xy 367.962411 -34.416484) (xy 368.02832 -34.432708) (xy 368.09179 -34.456768) (xy 368.151892 -34.48831)
			(xy 368.180112 -34.50717) (xy 368.186716 -34.511488) (xy 368.20094 -34.51606) (xy 368.2111 -34.51606)
			(xy 369.132612 -35.437572) (xy 371.09781 -35.437572) (xy 371.098374 -35.404015) (xy 371.107216 -35.337486)
			(xy 371.124731 -35.272698) (xy 371.150614 -35.210776) (xy 371.184415 -35.152795) (xy 371.225547 -35.099763)
			(xy 371.273296 -35.0526) (xy 371.29974 -35.031934) (xy 371.308376 -35.02533) (xy 371.318536 -35.00755)
			(xy 371.32895 -34.912554) (xy 371.322854 -34.892996) (xy 371.315996 -34.884868) (xy 371.298873 -34.864072)
			(xy 371.270025 -34.818577) (xy 371.247873 -34.769474) (xy 371.232855 -34.71774) (xy 371.225273 -34.664407)
			(xy 371.22481 -34.637472) (xy 371.225296 -34.610221) (xy 371.233052 -34.556273) (xy 371.248407 -34.503978)
			(xy 371.271049 -34.454401) (xy 371.300515 -34.408551) (xy 371.336206 -34.36736) (xy 371.377397 -34.331669)
			(xy 371.423247 -34.302203) (xy 371.472824 -34.279561) (xy 371.525119 -34.264206) (xy 371.579067 -34.25645)
			(xy 371.633569 -34.25645) (xy 371.687517 -34.264206) (xy 371.739812 -34.279561) (xy 371.789389 -34.302203)
			(xy 371.835239 -34.331669) (xy 371.87643 -34.36736) (xy 371.912121 -34.408551) (xy 371.941587 -34.454401)
			(xy 371.964229 -34.503978) (xy 371.979584 -34.556273) (xy 371.98734 -34.610221) (xy 371.987826 -34.637472)
			(xy 371.987373 -34.664407) (xy 371.979781 -34.717739) (xy 371.96476 -34.769472) (xy 371.942608 -34.818576)
			(xy 371.913766 -34.864074) (xy 371.89664 -34.884868) (xy 371.889782 -34.892996) (xy 371.883686 -34.912554)
			(xy 371.8941 -35.00755) (xy 371.90426 -35.02533) (xy 371.912896 -35.031934) (xy 371.939369 -35.052568)
			(xy 371.987134 -35.099725) (xy 372.028277 -35.152757) (xy 372.062083 -35.210744) (xy 372.087963 -35.272675)
			(xy 372.105468 -35.337473) (xy 372.114292 -35.404011) (xy 372.114826 -35.437572) (xy 372.114324 -35.469533)
			(xy 372.106313 -35.532951) (xy 372.090416 -35.594865) (xy 372.066884 -35.654298) (xy 372.03609 -35.710313)
			(xy 371.998517 -35.762028) (xy 371.95476 -35.808625) (xy 371.905507 -35.84937) (xy 371.851536 -35.883621)
			(xy 371.793697 -35.910838) (xy 371.732904 -35.930591) (xy 371.670114 -35.942569) (xy 371.606318 -35.946583)
			(xy 371.542522 -35.942569) (xy 371.479732 -35.930591) (xy 371.418939 -35.910838) (xy 371.3611 -35.883621)
			(xy 371.307129 -35.84937) (xy 371.257876 -35.808625) (xy 371.214119 -35.762028) (xy 371.176546 -35.710313)
			(xy 371.145752 -35.654298) (xy 371.12222 -35.594865) (xy 371.106323 -35.532951) (xy 371.098312 -35.469533)
			(xy 371.09781 -35.437572) (xy 369.132612 -35.437572) (xy 373.429784 -39.734744) (xy 373.437195 -39.741426)
			(xy 373.45563 -39.749007) (xy 373.465598 -39.749476) (xy 410.991558 -39.749476) (xy 411.023084 -39.749921)
			(xy 411.08574 -39.756987) (xy 411.147211 -39.771024) (xy 411.206724 -39.791856) (xy 411.26353 -39.819219)
			(xy 411.316915 -39.852771) (xy 411.366208 -39.892089) (xy 411.388814 -39.914068) (xy 411.42412 -39.949374)
			(xy 411.431465 -39.956184) (xy 411.449928 -39.963914) (xy 411.459934 -39.96436) (xy 412.157418 -39.96436)
			(xy 412.167485 -39.964788) (xy 412.186079 -39.972514) (xy 412.193486 -39.979346) (xy 413.949896 -41.735756)
			(xy 413.957308 -41.742435) (xy 413.975743 -41.75001) (xy 413.98571 -41.750488) (xy 414.061656 -41.750488)
			(xy 414.093183 -41.750917) (xy 414.155841 -41.757983) (xy 414.217314 -41.77202) (xy 414.276828 -41.792853)
			(xy 414.333635 -41.820217) (xy 414.387022 -41.85377) (xy 414.436315 -41.89309) (xy 414.458912 -41.91508)
			(xy 414.459166 -41.915334) (xy 414.466511 -41.922142) (xy 414.484975 -41.92986) (xy 414.49498 -41.93032)
		)
		(stroke
			(width 0)
			(type solid)
		)
		(fill yes)
		(layer "B.Cu")
		(net "P5V_AUX")
	)
	(gr_poly
		(pts
			(xy 44.5897 -363.52226) (xy 45.10532 -363.52226) (xy 131.0513 -363.52226) (xy 133.671564 -360.901996)
			(xy 133.671564 -329.660758) (xy 133.671132 -329.650692) (xy 133.663403 -329.632102) (xy 133.656578 -329.62469)
			(xy 132.922264 -328.890376) (xy 132.914867 -328.883527) (xy 132.896268 -328.875794) (xy 132.886196 -328.87539)
			(xy 110.571026 -328.87539) (xy 110.560962 -328.875826) (xy 110.542376 -328.883558) (xy 110.534958 -328.890376)
			(xy 110.345728 -329.079606) (xy 110.33888 -329.087004) (xy 110.331143 -329.105602) (xy 110.330742 -329.115674)
			(xy 110.330742 -331.222096) (xy 110.330318 -331.232165) (xy 110.322598 -331.250765) (xy 110.315756 -331.258164)
			(xy 110.047532 -331.526388) (xy 110.04013 -331.533225) (xy 110.021532 -331.540936) (xy 110.011464 -331.541374)
			(xy 109.807248 -331.541374) (xy 109.797181 -331.541806) (xy 109.778588 -331.549531) (xy 109.77118 -331.55636)
			(xy 109.768386 -331.559154) (xy 109.761146 -331.565862) (xy 109.742941 -331.573449) (xy 109.73308 -331.573886)
			(xy 100.280216 -331.573886) (xy 100.27038 -331.573347) (xy 100.252224 -331.565755) (xy 100.24491 -331.559154)
			(xy 100.242116 -331.55636) (xy 100.234716 -331.54952) (xy 100.216117 -331.541807) (xy 100.206048 -331.541374)
			(xy 100.188776 -331.541374) (xy 100.178935 -331.540846) (xy 100.160765 -331.533268) (xy 100.15347 -331.526642)
			(xy 99.704398 -331.07757) (xy 99.697686 -331.070332) (xy 99.690097 -331.052126) (xy 99.689666 -331.042264)
			(xy 99.689666 -327.28027) (xy 99.689237 -327.270203) (xy 99.681511 -327.25161) (xy 99.67468 -327.244202)
			(xy 99.57308 -327.142602) (xy 99.56568 -327.135759) (xy 99.547082 -327.128031) (xy 99.537012 -327.127616)
			(xy 98.21164 -327.127616) (xy 98.201801 -327.127082) (xy 98.183636 -327.1195) (xy 98.176334 -327.112884)
			(xy 97.668842 -326.605138) (xy 97.661442 -326.598297) (xy 97.642844 -326.590577) (xy 97.632774 -326.590152)
			(xy 70.189344 -326.590152) (xy 70.179279 -326.590587) (xy 70.160695 -326.598321) (xy 70.153276 -326.605138)
			(xy 68.524628 -328.233786) (xy 68.517792 -328.241188) (xy 68.510084 -328.259786) (xy 68.509642 -328.269854)
			(xy 68.509642 -331.219556) (xy 68.509207 -331.22962) (xy 68.501472 -331.248205) (xy 68.494656 -331.255624)
			(xy 66.44386 -333.30642) (xy 66.43701 -333.313817) (xy 66.429274 -333.332415) (xy 66.428874 -333.342488)
			(xy 66.428874 -334.783684) (xy 66.42938 -334.793734) (xy 66.437103 -334.812294) (xy 66.44386 -334.819752)
			(xy 66.492882 -334.86852) (xy 66.500292 -334.875205) (xy 66.518727 -334.88279) (xy 66.528696 -334.883252)
			(xy 68.35775 -334.883252) (xy 68.36759 -334.883783) (xy 68.385761 -334.89136) (xy 68.393056 -334.897984)
			(xy 68.676012 -335.18094) (xy 68.682721 -335.188179) (xy 68.690305 -335.206385) (xy 68.690744 -335.216246)
			(xy 68.690744 -337.166204) (xy 68.691169 -337.176273) (xy 68.69889 -337.194872) (xy 68.70573 -337.202272)
			(xy 68.745608 -337.24215) (xy 68.753004 -337.249001) (xy 68.771603 -337.25674) (xy 68.781676 -337.257136)
			(xy 70.437502 -337.257136) (xy 70.442522 -337.257049) (xy 70.452378 -337.255139) (xy 70.45706 -337.253326)
			(xy 70.474332 -337.24596) (xy 70.478897 -337.243954) (xy 70.487214 -337.238457) (xy 70.490842 -337.235038)
			(xy 70.530212 -337.195668) (xy 70.536562 -337.187794) (xy 70.536562 -335.206594) (xy 70.540626 -335.202784)
			(xy 70.540626 -335.04124) (xy 70.541161 -335.031402) (xy 70.548748 -335.013241) (xy 70.555358 -335.005934)
			(xy 70.634098 -334.927194) (xy 70.641335 -334.920478) (xy 70.65954 -334.912878) (xy 70.669404 -334.912462)
			(xy 73.776586 -334.912462) (xy 73.776586 -334.917288) (xy 76.705206 -334.917288) (xy 76.715049 -334.917812)
			(xy 76.733228 -334.925381) (xy 76.740512 -334.93202) (xy 76.991972 -335.18348) (xy 76.998694 -335.190714)
			(xy 77.006307 -335.20892) (xy 77.006704 -335.218786) (xy 77.006704 -337.119468) (xy 77.00714 -337.129533)
			(xy 77.014872 -337.148119) (xy 77.02169 -337.155536) (xy 77.110844 -337.24469) (xy 77.118244 -337.251531)
			(xy 77.136843 -337.259251) (xy 77.146912 -337.259676) (xy 78.753462 -337.259676) (xy 78.758481 -337.259583)
			(xy 78.768331 -337.25766) (xy 78.77302 -337.255866) (xy 78.790292 -337.2485) (xy 78.794852 -337.246487)
			(xy 78.803158 -337.240979) (xy 78.806802 -337.237578) (xy 78.8416 -337.20278) (xy 78.848443 -337.19538)
			(xy 78.85617 -337.176782) (xy 78.856586 -337.166712) (xy 78.856586 -335.244186) (xy 78.857111 -335.234344)
			(xy 78.864683 -335.216167) (xy 78.871318 -335.20888) (xy 79.09179 -334.988408) (xy 79.092298 -334.988408)
			(xy 79.108554 -334.971898) (xy 79.115794 -334.965191) (xy 79.133999 -334.95761) (xy 79.14386 -334.957166)
			(xy 82.608166 -334.957166) (xy 82.62946 -334.957596) (xy 82.671619 -334.963635) (xy 82.71253 -334.975474)
			(xy 82.732118 -334.983836) (xy 82.742024 -334.988408) (xy 85.09762 -334.988408) (xy 85.107461 -334.988935)
			(xy 85.125635 -334.99651) (xy 85.132926 -335.00314) (xy 85.298788 -335.169002) (xy 85.305505 -335.176238)
			(xy 85.313107 -335.194444) (xy 85.31352 -335.204308) (xy 85.31352 -335.558638) (xy 85.314028 -335.562448)
			(xy 85.316708 -335.581066) (xy 85.319632 -335.61857) (xy 85.31987 -335.637378) (xy 85.31987 -335.637886)
			(xy 85.319621 -335.656694) (xy 85.316701 -335.694197) (xy 85.314028 -335.712816) (xy 85.31352 -335.716626)
			(xy 85.31352 -336.358738) (xy 85.314028 -336.362548) (xy 85.316713 -336.381229) (xy 85.319634 -336.41886)
			(xy 85.31987 -336.437732) (xy 85.31987 -337.06054) (xy 85.3203 -337.070608) (xy 85.328021 -337.089204)
			(xy 85.334856 -337.096608) (xy 85.46846 -337.230212) (xy 85.475858 -337.237058) (xy 85.494457 -337.244785)
			(xy 85.504528 -337.245198) (xy 87.060278 -337.245198) (xy 87.065297 -337.245103) (xy 87.075146 -337.243178)
			(xy 87.079836 -337.241388) (xy 87.097108 -337.234022) (xy 87.101673 -337.232016) (xy 87.10999 -337.22652)
			(xy 87.113618 -337.2231) (xy 87.148416 -337.188302) (xy 87.155272 -337.180908) (xy 87.16302 -337.162309)
			(xy 87.163402 -337.152234) (xy 87.163402 -335.244186) (xy 87.163928 -335.234344) (xy 87.171501 -335.216169)
			(xy 87.178134 -335.20888) (xy 87.385906 -335.001108) (xy 87.393143 -334.994392) (xy 87.411348 -334.986792)
			(xy 87.421212 -334.986376) (xy 87.432134 -334.986376) (xy 87.456264 -334.976216) (xy 87.46095 -334.974414)
			(xy 87.470802 -334.972488) (xy 87.475822 -334.972406) (xy 93.361764 -334.972406) (xy 93.371829 -334.972841)
			(xy 93.390416 -334.980572) (xy 93.397832 -334.987392) (xy 93.41612 -335.00568) (xy 93.655388 -335.245202)
			(xy 93.662105 -335.252438) (xy 93.669707 -335.270644) (xy 93.67012 -335.280508) (xy 93.67012 -337.13039)
			(xy 93.670542 -337.140461) (xy 93.678256 -337.159066) (xy 93.685106 -337.166458) (xy 93.82506 -337.306412)
			(xy 93.832458 -337.313258) (xy 93.851057 -337.320985) (xy 93.861128 -337.321398) (xy 95.416878 -337.321398)
			(xy 95.421897 -337.321303) (xy 95.431746 -337.319378) (xy 95.436436 -337.317588) (xy 95.453708 -337.310222)
			(xy 95.458273 -337.308216) (xy 95.46659 -337.30272) (xy 95.470218 -337.2993) (xy 95.505016 -337.264502)
			(xy 95.511872 -337.257108) (xy 95.51962 -337.238509) (xy 95.520002 -337.228434) (xy 95.520002 -335.320132)
			(xy 95.52052 -335.310383) (xy 95.527974 -335.292359) (xy 95.53448 -335.28508) (xy 95.580962 -335.238598)
			(xy 95.580962 -335.227422) (xy 95.772986 -335.035398) (xy 95.780222 -335.02868) (xy 95.798427 -335.021075)
			(xy 95.808292 -335.020666) (xy 99.403154 -335.020666) (xy 99.410674 -335.020959) (xy 99.425019 -335.025485)
			(xy 99.431348 -335.029556) (xy 99.437952 -335.033874) (xy 99.452176 -335.038446) (xy 99.48418 -335.038446)
			(xy 99.494018 -335.038983) (xy 99.512181 -335.046566) (xy 99.519486 -335.053178) (xy 99.821492 -335.355184)
			(xy 99.828212 -335.36242) (xy 99.835819 -335.380625) (xy 99.836224 -335.39049) (xy 99.836224 -340.079076)
			(xy 99.836662 -340.08914) (xy 99.844398 -340.107722) (xy 99.85121 -340.115144) (xy 99.885246 -340.14918)
			(xy 99.892646 -340.156022) (xy 99.911244 -340.163742) (xy 99.921314 -340.164166) (xy 100.125276 -340.164166)
			(xy 100.137976 -340.160864) (xy 100.143818 -340.157308) (xy 100.172784 -340.141333) (xy 100.233964 -340.116179)
			(xy 100.297886 -340.099159) (xy 100.363474 -340.09056) (xy 100.396548 -340.089998) (xy 101.41839 -340.089998)
			(xy 101.449122 -340.090443) (xy 101.510139 -340.097851) (xy 101.569818 -340.112559) (xy 101.627289 -340.134354)
			(xy 101.681713 -340.162918) (xy 101.732298 -340.197833) (xy 101.778305 -340.238592) (xy 101.819064 -340.284599)
			(xy 101.85398 -340.335183) (xy 101.882544 -340.389608) (xy 101.904339 -340.447078) (xy 101.919049 -340.506757)
			(xy 101.926457 -340.567774) (xy 101.926898 -340.598506) (xy 101.92668 -340.617568) (xy 101.923756 -340.655581)
			(xy 101.921056 -340.674452) (xy 101.920548 -340.678262) (xy 101.920548 -341.319612) (xy 101.921056 -341.323422)
			(xy 101.923742 -341.342103) (xy 101.926665 -341.379734) (xy 101.926898 -341.398606) (xy 101.926898 -342.021414)
			(xy 101.927324 -342.031483) (xy 101.935042 -342.050084) (xy 101.941884 -342.057482) (xy 102.07117 -342.186768)
			(xy 102.078571 -342.193607) (xy 102.097169 -342.201321) (xy 102.107238 -342.201754) (xy 103.653082 -342.201754)
			(xy 103.663145 -342.201315) (xy 103.681723 -342.193574) (xy 103.68915 -342.186768) (xy 103.755444 -342.120474)
			(xy 103.762292 -342.113077) (xy 103.770026 -342.094478) (xy 103.77043 -342.084406) (xy 103.77043 -340.566248)
			(xy 103.770943 -340.556496) (xy 103.778385 -340.538462) (xy 103.784908 -340.531196) (xy 103.842312 -340.474046)
			(xy 103.848873 -340.466801) (xy 103.856336 -340.448757) (xy 103.85679 -340.438994) (xy 103.85679 -340.221316)
			(xy 103.857328 -340.211479) (xy 103.864917 -340.193321) (xy 103.871522 -340.18601) (xy 104.093772 -339.964014)
			(xy 104.101007 -339.957292) (xy 104.119212 -339.949679) (xy 104.129078 -339.949282) (xy 108.77931 -339.949282)
			(xy 108.789153 -339.949807) (xy 108.807331 -339.957376) (xy 108.814616 -339.964014) (xy 109.485684 -340.635082)
			(xy 109.492519 -340.642484) (xy 109.500226 -340.661083) (xy 109.50067 -340.67115) (xy 109.50067 -348.441264)
			(xy 109.500235 -348.451328) (xy 109.4925 -348.469913) (xy 109.485684 -348.477332) (xy 107.857544 -350.105472)
			(xy 107.850144 -350.112313) (xy 107.831545 -350.120031) (xy 107.821476 -350.120458) (xy 103.50881 -350.120458)
			(xy 103.502142 -350.120651) (xy 103.489266 -350.124122) (xy 103.48341 -350.127316) (xy 103.456994 -350.143064)
			(xy 103.448358 -350.1517) (xy 103.444802 -350.157288) (xy 103.429887 -350.180974) (xy 103.394213 -350.224107)
			(xy 103.35262 -350.261564) (xy 103.306001 -350.292543) (xy 103.255356 -350.316378) (xy 103.201772 -350.332558)
			(xy 103.146399 -350.340736) (xy 103.090425 -350.340736) (xy 103.035052 -350.332558) (xy 102.981468 -350.316378)
			(xy 102.930823 -350.292543) (xy 102.884204 -350.261564) (xy 102.842611 -350.224107) (xy 102.806937 -350.180974)
			(xy 102.792022 -350.157288) (xy 102.788466 -350.1517) (xy 102.77983 -350.143064) (xy 102.753414 -350.127316)
			(xy 102.747535 -350.12418) (xy 102.734673 -350.120719) (xy 102.728014 -350.120458) (xy 95.9993 -350.120458)
			(xy 95.989231 -350.120883) (xy 95.970632 -350.128604) (xy 95.963232 -350.135444) (xy 95.553022 -350.545654)
			(xy 95.545656 -350.552766) (xy 95.538036 -350.571562) (xy 95.538036 -353.54641) (xy 95.537609 -353.556478)
			(xy 95.529885 -353.575074) (xy 95.52305 -353.582478) (xy 94.332044 -354.773484) (xy 94.332044 -354.777802)
			(xy 94.126558 -354.983288) (xy 94.119158 -354.990129) (xy 94.10056 -354.99785) (xy 94.09049 -354.998274)
			(xy 86.285832 -354.998274) (xy 86.275768 -354.997838) (xy 86.257184 -354.990103) (xy 86.249764 -354.983288)
			(xy 85.155278 -353.888802) (xy 85.148166 -353.881436) (xy 85.12937 -353.873816) (xy 82.21218 -353.873816)
			(xy 82.210656 -353.873816) (xy 82.20075 -353.875086) (xy 82.193652 -353.876972) (xy 82.180873 -353.884195)
			(xy 82.175604 -353.88931) (xy 82.16773 -353.897438) (xy 82.160331 -353.90428) (xy 82.141732 -353.911999)
			(xy 82.131662 -353.912424) (xy 65.130934 -353.912424) (xy 65.120869 -353.91199) (xy 65.102279 -353.904261)
			(xy 65.094866 -353.897438) (xy 63.64097 -352.443542) (xy 63.64272 -352.438974) (xy 63.644635 -352.429382)
			(xy 63.64478 -352.424492) (xy 63.64478 -351.02546) (xy 63.644349 -351.015393) (xy 63.636622 -350.996801)
			(xy 63.629794 -350.989392) (xy 63.586614 -350.946212) (xy 63.579502 -350.938846) (xy 63.560706 -350.931226)
			(xy 62.280038 -350.931226) (xy 62.269812 -350.931701) (xy 62.251049 -350.939831) (xy 62.243716 -350.946974)
			(xy 62.193932 -350.999806) (xy 62.190511 -351.003682) (xy 62.185146 -351.012516) (xy 62.183264 -351.017332)
			(xy 62.179708 -351.026984) (xy 62.180216 -351.037398) (xy 62.180978 -351.06102) (xy 62.180513 -351.088271)
			(xy 62.172754 -351.142218) (xy 62.157396 -351.194512) (xy 62.134752 -351.244088) (xy 62.105283 -351.289936)
			(xy 62.069589 -351.331124) (xy 62.028396 -351.366813) (xy 61.982544 -351.396276) (xy 61.932965 -351.418913)
			(xy 61.880669 -351.434264) (xy 61.826721 -351.442017) (xy 61.79947 -351.442528) (xy 61.799216 -351.442528)
			(xy 61.771498 -351.442052) (xy 61.71664 -351.434065) (xy 61.66352 -351.418212) (xy 61.63818 -351.406968)
			(xy 61.616844 -351.402142) (xy 60.254388 -351.402142) (xy 60.248807 -351.40229) (xy 60.237914 -351.40473)
			(xy 60.232798 -351.406968) (xy 60.214764 -351.41535) (xy 60.209943 -351.417769) (xy 60.201367 -351.424307)
			(xy 60.197746 -351.428304) (xy 60.179545 -351.448628) (xy 60.138332 -351.48438) (xy 60.092448 -351.513897)
			(xy 60.042828 -351.536578) (xy 59.990483 -351.551961) (xy 59.936481 -351.559731) (xy 59.881923 -351.559731)
			(xy 59.827921 -351.551961) (xy 59.775576 -351.536578) (xy 59.725956 -351.513897) (xy 59.680072 -351.48438)
			(xy 59.638859 -351.448628) (xy 59.620658 -351.428304) (xy 59.617052 -351.42429) (xy 59.608473 -351.417748)
			(xy 59.60364 -351.41535) (xy 59.585606 -351.406968) (xy 59.580491 -351.404732) (xy 59.569597 -351.402305)
			(xy 59.564016 -351.402142) (xy 58.083958 -351.402142) (xy 58.074117 -351.402671) (xy 58.055943 -351.410245)
			(xy 58.048652 -351.416874) (xy 57.91708 -351.548446) (xy 57.910373 -351.555686) (xy 57.902792 -351.573891)
			(xy 57.902348 -351.583752) (xy 57.902348 -357.000302) (xy 57.901923 -357.010371) (xy 57.894202 -357.02897)
			(xy 57.887362 -357.03637) (xy 56.430418 -358.493314) (xy 56.423019 -358.500157) (xy 56.40442 -358.507875)
			(xy 56.39435 -358.5083) (xy 46.478698 -358.5083) (xy 46.468628 -358.508724) (xy 46.450024 -358.516439)
			(xy 46.44263 -358.523286) (xy 44.763182 -360.202734) (xy 44.756573 -360.208815) (xy 44.740264 -360.216306)
			(xy 44.722371 -360.217702) (xy 44.705097 -360.212831) (xy 44.69765 -360.207814) (xy 44.691046 -360.202988)
			(xy 44.675806 -360.198162) (xy 40.700198 -360.198162) (xy 40.690129 -360.197738) (xy 40.671528 -360.190019)
			(xy 40.66413 -360.183176) (xy 35.50158 -355.020626) (xy 35.494168 -355.013942) (xy 35.475735 -355.006345)
			(xy 35.455797 -355.006345) (xy 35.437364 -355.013942) (xy 35.429952 -355.020626) (xy 35.404298 -355.04628)
			(xy 35.3969 -355.053128) (xy 35.378302 -355.060865) (xy 35.36823 -355.061266) (xy 31.77159 -355.061266)
			(xy 31.761521 -355.06084) (xy 31.742923 -355.05312) (xy 31.735522 -355.04628) (xy 30.692852 -354.00361)
			(xy 30.689235 -354.000175) (xy 30.680918 -353.994672) (xy 30.676342 -353.992688) (xy 30.663134 -353.987354)
			(xy 30.658554 -353.985292) (xy 30.650234 -353.97967) (xy 30.646624 -353.976178) (xy 30.425136 -353.75469)
			(xy 30.418287 -353.747293) (xy 30.410551 -353.728694) (xy 30.41015 -353.718622) (xy 30.41015 -351.06483)
			(xy 30.409713 -351.054767) (xy 30.401975 -351.036185) (xy 30.395164 -351.028762) (xy 30.385004 -351.018602)
			(xy 30.381566 -351.014987) (xy 30.376056 -351.006673) (xy 30.374082 -351.002092) (xy 30.36697 -350.985328)
			(xy 30.364958 -350.980824) (xy 30.359456 -350.972639) (xy 30.356048 -350.969072) (xy 30.333188 -350.946212)
			(xy 30.325789 -350.939366) (xy 30.307191 -350.931634) (xy 30.29712 -350.931226) (xy 29.006038 -350.931226)
			(xy 28.995812 -350.931701) (xy 28.977049 -350.939831) (xy 28.969716 -350.946974) (xy 28.91282 -351.007426)
			(xy 28.905708 -351.027238) (xy 28.906216 -351.037906) (xy 28.906978 -351.06102) (xy 28.906513 -351.088271)
			(xy 28.898754 -351.142218) (xy 28.883396 -351.194512) (xy 28.860752 -351.244088) (xy 28.831283 -351.289936)
			(xy 28.795589 -351.331124) (xy 28.754396 -351.366813) (xy 28.708544 -351.396276) (xy 28.658965 -351.418913)
			(xy 28.606669 -351.434264) (xy 28.552721 -351.442017) (xy 28.52547 -351.442528) (xy 28.497794 -351.442037)
			(xy 28.443024 -351.434039) (xy 28.389987 -351.418199) (xy 28.364688 -351.406968) (xy 28.354528 -351.402142)
			(xy 26.980388 -351.402142) (xy 26.974742 -351.402265) (xy 26.963716 -351.4047) (xy 26.958544 -351.406968)
			(xy 26.930604 -351.420176) (xy 26.923746 -351.428304) (xy 26.905545 -351.448628) (xy 26.864332 -351.48438)
			(xy 26.818448 -351.513897) (xy 26.768828 -351.536578) (xy 26.716483 -351.551961) (xy 26.662481 -351.559731)
			(xy 26.607923 -351.559731) (xy 26.553921 -351.551961) (xy 26.501576 -351.536578) (xy 26.451956 -351.513897)
			(xy 26.406072 -351.48438) (xy 26.364859 -351.448628) (xy 26.346658 -351.428304) (xy 26.3398 -351.420176)
			(xy 26.31186 -351.406968) (xy 26.306686 -351.404706) (xy 26.295662 -351.402268) (xy 26.290016 -351.402142)
			(xy 25.72512 -351.402142) (xy 25.715057 -351.402581) (xy 25.696478 -351.410321) (xy 25.689052 -351.417128)
			(xy 25.561036 -351.545144) (xy 25.554193 -351.552543) (xy 25.546469 -351.571142) (xy 25.54605 -351.581212)
			(xy 25.54605 -354.695506) (xy 25.546476 -354.705575) (xy 25.554197 -354.724173) (xy 25.561036 -354.731574)
			(xy 26.073862 -355.2444) (xy 28.446982 -355.2444) (xy 28.451053 -355.188778) (xy 28.463179 -355.134341)
			(xy 28.483102 -355.08225) (xy 28.510398 -355.033615) (xy 28.544484 -354.989472) (xy 28.584633 -354.950763)
			(xy 28.629991 -354.918312) (xy 28.679591 -354.892811) (xy 28.732375 -354.874804) (xy 28.787218 -354.864674)
			(xy 28.842952 -354.862637) (xy 28.898389 -354.868737) (xy 28.952346 -354.882843) (xy 29.003675 -354.904655)
			(xy 29.051281 -354.933709) (xy 29.094149 -354.969384) (xy 29.131366 -355.010921) (xy 29.162139 -355.057434)
			(xy 29.185811 -355.107931) (xy 29.201879 -355.161338) (xy 29.209999 -355.216514) (xy 29.210508 -355.2444)
			(xy 29.209999 -355.272286) (xy 29.201879 -355.327462) (xy 29.185811 -355.380869) (xy 29.162139 -355.431366)
			(xy 29.131366 -355.477879) (xy 29.094149 -355.519416) (xy 29.051281 -355.555091) (xy 29.003675 -355.584145)
			(xy 28.952346 -355.605957) (xy 28.898389 -355.620063) (xy 28.842952 -355.626163) (xy 28.787218 -355.624126)
			(xy 28.732375 -355.613996) (xy 28.679591 -355.595989) (xy 28.629991 -355.570488) (xy 28.584633 -355.538037)
			(xy 28.544484 -355.499328) (xy 28.510398 -355.455185) (xy 28.483102 -355.40655) (xy 28.463179 -355.354459)
			(xy 28.451053 -355.300022) (xy 28.446982 -355.2444) (xy 26.073862 -355.2444) (xy 26.683462 -355.854)
			(xy 31.291782 -355.854) (xy 31.295853 -355.798378) (xy 31.307979 -355.743941) (xy 31.327902 -355.69185)
			(xy 31.355198 -355.643215) (xy 31.389284 -355.599072) (xy 31.429433 -355.560363) (xy 31.474791 -355.527912)
			(xy 31.524391 -355.502411) (xy 31.577175 -355.484404) (xy 31.632018 -355.474274) (xy 31.687752 -355.472237)
			(xy 31.743189 -355.478337) (xy 31.797146 -355.492443) (xy 31.848475 -355.514255) (xy 31.896081 -355.543309)
			(xy 31.938949 -355.578984) (xy 31.976166 -355.620521) (xy 32.006939 -355.667034) (xy 32.030611 -355.717531)
			(xy 32.046679 -355.770938) (xy 32.054799 -355.826114) (xy 32.055308 -355.854) (xy 32.054799 -355.881886)
			(xy 32.05449 -355.883984) (xy 32.359328 -355.883984) (xy 32.359328 -355.824016) (xy 32.367156 -355.76456)
			(xy 32.382677 -355.706635) (xy 32.405626 -355.651231) (xy 32.43561 -355.599297) (xy 32.472116 -355.551721)
			(xy 32.514521 -355.509316) (xy 32.562097 -355.47281) (xy 32.614031 -355.442826) (xy 32.669435 -355.419877)
			(xy 32.72736 -355.404356) (xy 32.786816 -355.396528) (xy 32.846784 -355.396528) (xy 32.90624 -355.404356)
			(xy 32.964165 -355.419877) (xy 33.019569 -355.442826) (xy 33.071503 -355.47281) (xy 33.119079 -355.509316)
			(xy 33.161484 -355.551721) (xy 33.19799 -355.599297) (xy 33.227974 -355.651231) (xy 33.250923 -355.706635)
			(xy 33.266444 -355.76456) (xy 33.268791 -355.782384) (xy 34.594528 -355.782384) (xy 34.594528 -355.722416)
			(xy 34.602356 -355.66296) (xy 34.617877 -355.605035) (xy 34.640826 -355.549631) (xy 34.67081 -355.497697)
			(xy 34.707316 -355.450121) (xy 34.749721 -355.407716) (xy 34.797297 -355.37121) (xy 34.849231 -355.341226)
			(xy 34.904635 -355.318277) (xy 34.96256 -355.302756) (xy 35.022016 -355.294928) (xy 35.081984 -355.294928)
			(xy 35.14144 -355.302756) (xy 35.199365 -355.318277) (xy 35.254769 -355.341226) (xy 35.306703 -355.37121)
			(xy 35.354279 -355.407716) (xy 35.396684 -355.450121) (xy 35.43319 -355.497697) (xy 35.463174 -355.549631)
			(xy 35.486123 -355.605035) (xy 35.501644 -355.66296) (xy 35.509472 -355.722416) (xy 35.509962 -355.7524)
			(xy 35.509472 -355.782384) (xy 35.501644 -355.84184) (xy 35.486123 -355.899765) (xy 35.463174 -355.955169)
			(xy 35.43319 -356.007103) (xy 35.396684 -356.054679) (xy 35.354279 -356.097084) (xy 35.306703 -356.13359)
			(xy 35.254769 -356.163574) (xy 35.199365 -356.186523) (xy 35.14144 -356.202044) (xy 35.081984 -356.209872)
			(xy 35.022016 -356.209872) (xy 34.96256 -356.202044) (xy 34.904635 -356.186523) (xy 34.849231 -356.163574)
			(xy 34.797297 -356.13359) (xy 34.749721 -356.097084) (xy 34.707316 -356.054679) (xy 34.67081 -356.007103)
			(xy 34.640826 -355.955169) (xy 34.617877 -355.899765) (xy 34.602356 -355.84184) (xy 34.594528 -355.782384)
			(xy 33.268791 -355.782384) (xy 33.274272 -355.824016) (xy 33.274762 -355.854) (xy 33.274272 -355.883984)
			(xy 33.266444 -355.94344) (xy 33.250923 -356.001365) (xy 33.227974 -356.056769) (xy 33.19799 -356.108703)
			(xy 33.161484 -356.156279) (xy 33.119079 -356.198684) (xy 33.071503 -356.23519) (xy 33.019569 -356.265174)
			(xy 32.964165 -356.288123) (xy 32.90624 -356.303644) (xy 32.846784 -356.311472) (xy 32.786816 -356.311472)
			(xy 32.72736 -356.303644) (xy 32.669435 -356.288123) (xy 32.614031 -356.265174) (xy 32.562097 -356.23519)
			(xy 32.514521 -356.198684) (xy 32.472116 -356.156279) (xy 32.43561 -356.108703) (xy 32.405626 -356.056769)
			(xy 32.382677 -356.001365) (xy 32.367156 -355.94344) (xy 32.359328 -355.883984) (xy 32.05449 -355.883984)
			(xy 32.046679 -355.937062) (xy 32.030611 -355.990469) (xy 32.006939 -356.040966) (xy 31.976166 -356.087479)
			(xy 31.938949 -356.129016) (xy 31.896081 -356.164691) (xy 31.848475 -356.193745) (xy 31.797146 -356.215557)
			(xy 31.743189 -356.229663) (xy 31.687752 -356.235763) (xy 31.632018 -356.233726) (xy 31.577175 -356.223596)
			(xy 31.524391 -356.205589) (xy 31.474791 -356.180088) (xy 31.429433 -356.147637) (xy 31.389284 -356.108928)
			(xy 31.355198 -356.064785) (xy 31.327902 -356.01615) (xy 31.307979 -355.964059) (xy 31.295853 -355.909622)
			(xy 31.291782 -355.854) (xy 26.683462 -355.854) (xy 27.063192 -356.23373) (xy 27.070035 -356.24113)
			(xy 27.077759 -356.259728) (xy 27.078178 -356.269798) (xy 27.078178 -356.417368) (xy 27.889182 -356.417368)
			(xy 27.889182 -356.357432) (xy 27.897005 -356.29801) (xy 27.912518 -356.240117) (xy 27.935454 -356.184744)
			(xy 27.965421 -356.132838) (xy 28.001908 -356.085288) (xy 28.044288 -356.042908) (xy 28.091838 -356.006421)
			(xy 28.143744 -355.976454) (xy 28.199117 -355.953518) (xy 28.25701 -355.938005) (xy 28.316432 -355.930182)
			(xy 28.376368 -355.930182) (xy 28.43579 -355.938005) (xy 28.493683 -355.953518) (xy 28.549056 -355.976454)
			(xy 28.600962 -356.006421) (xy 28.648512 -356.042908) (xy 28.690892 -356.085288) (xy 28.727379 -356.132838)
			(xy 28.757346 -356.184744) (xy 28.780282 -356.240117) (xy 28.795795 -356.29801) (xy 28.803618 -356.357432)
			(xy 28.804108 -356.3874) (xy 28.803618 -356.417368) (xy 28.795795 -356.47679) (xy 28.780282 -356.534683)
			(xy 28.760489 -356.582468) (xy 30.543482 -356.582468) (xy 30.543482 -356.522532) (xy 30.551305 -356.46311)
			(xy 30.566818 -356.405217) (xy 30.589754 -356.349844) (xy 30.619721 -356.297938) (xy 30.656208 -356.250388)
			(xy 30.698588 -356.208008) (xy 30.746138 -356.171521) (xy 30.798044 -356.141554) (xy 30.853417 -356.118618)
			(xy 30.91131 -356.103105) (xy 30.970732 -356.095282) (xy 31.030668 -356.095282) (xy 31.09009 -356.103105)
			(xy 31.147983 -356.118618) (xy 31.203356 -356.141554) (xy 31.255262 -356.171521) (xy 31.302812 -356.208008)
			(xy 31.345192 -356.250388) (xy 31.381679 -356.297938) (xy 31.411646 -356.349844) (xy 31.434582 -356.405217)
			(xy 31.450095 -356.46311) (xy 31.457918 -356.522532) (xy 31.458408 -356.5525) (xy 31.457918 -356.582468)
			(xy 31.450095 -356.64189) (xy 31.434582 -356.699783) (xy 31.411646 -356.755156) (xy 31.381679 -356.807062)
			(xy 31.345192 -356.854612) (xy 31.302812 -356.896992) (xy 31.255262 -356.933479) (xy 31.203356 -356.963446)
			(xy 31.147983 -356.986382) (xy 31.09009 -357.001895) (xy 31.030668 -357.009718) (xy 30.970732 -357.009718)
			(xy 30.91131 -357.001895) (xy 30.853417 -356.986382) (xy 30.798044 -356.963446) (xy 30.746138 -356.933479)
			(xy 30.698588 -356.896992) (xy 30.656208 -356.854612) (xy 30.619721 -356.807062) (xy 30.589754 -356.755156)
			(xy 30.566818 -356.699783) (xy 30.551305 -356.64189) (xy 30.543482 -356.582468) (xy 28.760489 -356.582468)
			(xy 28.757346 -356.590056) (xy 28.727379 -356.641962) (xy 28.690892 -356.689512) (xy 28.648512 -356.731892)
			(xy 28.600962 -356.768379) (xy 28.549056 -356.798346) (xy 28.493683 -356.821282) (xy 28.43579 -356.836795)
			(xy 28.376368 -356.844618) (xy 28.316432 -356.844618) (xy 28.25701 -356.836795) (xy 28.199117 -356.821282)
			(xy 28.143744 -356.798346) (xy 28.091838 -356.768379) (xy 28.044288 -356.731892) (xy 28.001908 -356.689512)
			(xy 27.965421 -356.641962) (xy 27.935454 -356.590056) (xy 27.912518 -356.534683) (xy 27.897005 -356.47679)
			(xy 27.889182 -356.417368) (xy 27.078178 -356.417368) (xy 27.078178 -357.299768) (xy 27.078613 -357.309833)
			(xy 27.086342 -357.328422) (xy 27.093164 -357.335836) (xy 27.484578 -357.72725) (xy 27.491978 -357.73409)
			(xy 27.510577 -357.741804) (xy 27.520646 -357.742236) (xy 27.530806 -357.742236) (xy 27.539537 -357.741886)
			(xy 27.555978 -357.736007) (xy 27.569459 -357.724912) (xy 27.57424 -357.717598) (xy 27.589226 -357.692706)
			(xy 27.593839 -357.684277) (xy 27.59699 -357.665337) (xy 27.595322 -357.655876) (xy 27.592782 -357.644192)
			(xy 27.59075 -357.639366) (xy 27.580572 -357.615083) (xy 27.566222 -357.564424) (xy 27.558955 -357.512276)
			(xy 27.558492 -357.48595) (xy 27.558978 -357.458699) (xy 27.566734 -357.404751) (xy 27.582089 -357.352456)
			(xy 27.604731 -357.302879) (xy 27.634197 -357.257029) (xy 27.669888 -357.215838) (xy 27.711079 -357.180147)
			(xy 27.756929 -357.150681) (xy 27.806506 -357.128039) (xy 27.858801 -357.112684) (xy 27.912749 -357.104928)
			(xy 27.967251 -357.104928) (xy 28.021199 -357.112684) (xy 28.073494 -357.128039) (xy 28.123071 -357.150681)
			(xy 28.168921 -357.180147) (xy 28.210112 -357.215838) (xy 28.245803 -357.257029) (xy 28.275269 -357.302879)
			(xy 28.297911 -357.352456) (xy 28.313266 -357.404751) (xy 28.321022 -357.458699) (xy 28.321508 -357.48595)
			(xy 28.321508 -357.486204) (xy 28.320879 -357.517249) (xy 28.310799 -357.578516) (xy 28.301442 -357.608124)
			(xy 28.297378 -357.620062) (xy 28.300934 -357.644192) (xy 28.356306 -357.721154) (xy 28.360116 -357.725726)
			(xy 28.367613 -357.733163) (xy 28.386908 -357.74168) (xy 28.397454 -357.742236) (xy 30.174946 -357.742236)
			(xy 30.184733 -357.741789) (xy 30.202888 -357.734474) (xy 30.210252 -357.728012) (xy 30.261052 -357.67899)
			(xy 30.267799 -357.671869) (xy 30.275785 -357.653971) (xy 30.276546 -357.644192) (xy 30.277912 -357.617574)
			(xy 30.287154 -357.565082) (xy 30.303613 -357.514387) (xy 30.326968 -357.466478) (xy 30.356765 -357.422285)
			(xy 30.392424 -357.382671) (xy 30.433249 -357.348405) (xy 30.478446 -357.320157) (xy 30.527136 -357.298474)
			(xy 30.57837 -357.28378) (xy 30.63115 -357.276361) (xy 30.6578 -357.275892) (xy 30.685895 -357.276398)
			(xy 30.741477 -357.284651) (xy 30.795249 -357.300963) (xy 30.846048 -357.324982) (xy 30.892776 -357.356189)
			(xy 30.934425 -357.393909) (xy 30.970094 -357.437328) (xy 30.999012 -357.485507) (xy 31.020554 -357.537404)
			(xy 31.034254 -357.5919) (xy 31.03753 -357.619808) (xy 31.088076 -357.665528) (xy 33.184846 -357.665528)
			(xy 33.194912 -357.66596) (xy 33.213502 -357.673689) (xy 33.220914 -357.680514) (xy 33.227768 -357.687368)
			(xy 33.781982 -357.687368) (xy 33.781982 -357.627432) (xy 33.789805 -357.56801) (xy 33.805318 -357.510117)
			(xy 33.828254 -357.454744) (xy 33.858221 -357.402838) (xy 33.894708 -357.355288) (xy 33.937088 -357.312908)
			(xy 33.984638 -357.276421) (xy 34.036544 -357.246454) (xy 34.091917 -357.223518) (xy 34.14981 -357.208005)
			(xy 34.209232 -357.200182) (xy 34.269168 -357.200182) (xy 34.32859 -357.208005) (xy 34.386483 -357.223518)
			(xy 34.441856 -357.246454) (xy 34.493762 -357.276421) (xy 34.541312 -357.312908) (xy 34.583692 -357.355288)
			(xy 34.620179 -357.402838) (xy 34.650146 -357.454744) (xy 34.673082 -357.510117) (xy 34.688595 -357.56801)
			(xy 34.696418 -357.627432) (xy 34.696908 -357.6574) (xy 34.696418 -357.687368) (xy 34.688595 -357.74679)
			(xy 34.673082 -357.804683) (xy 34.650146 -357.860056) (xy 34.620179 -357.911962) (xy 34.583692 -357.959512)
			(xy 34.541312 -358.001892) (xy 34.493762 -358.038379) (xy 34.441856 -358.068346) (xy 34.386483 -358.091282)
			(xy 34.32859 -358.106795) (xy 34.269168 -358.114618) (xy 34.209232 -358.114618) (xy 34.14981 -358.106795)
			(xy 34.091917 -358.091282) (xy 34.036544 -358.068346) (xy 33.984638 -358.038379) (xy 33.937088 -358.001892)
			(xy 33.894708 -357.959512) (xy 33.858221 -357.911962) (xy 33.828254 -357.860056) (xy 33.805318 -357.804683)
			(xy 33.789805 -357.74679) (xy 33.781982 -357.687368) (xy 33.227768 -357.687368) (xy 34.850651 -359.310251)
			(xy 35.686978 -359.310251) (xy 35.686978 -359.255749) (xy 35.694734 -359.201801) (xy 35.710089 -359.149506)
			(xy 35.732731 -359.099929) (xy 35.762197 -359.054079) (xy 35.797888 -359.012888) (xy 35.839079 -358.977197)
			(xy 35.884929 -358.947731) (xy 35.934506 -358.925089) (xy 35.986801 -358.909734) (xy 36.040749 -358.901978)
			(xy 36.068 -358.901492) (xy 36.096113 -358.902001) (xy 36.151727 -358.910272) (xy 36.205524 -358.926621)
			(xy 36.256337 -358.950693) (xy 36.303064 -358.981965) (xy 36.344692 -359.019761) (xy 36.362894 -359.041192)
			(xy 36.364672 -359.043224) (xy 36.370584 -359.049129) (xy 36.385216 -359.057172) (xy 36.393374 -359.058972)
			(xy 36.403534 -359.059734) (xy 36.483798 -359.057448) (xy 36.489546 -359.057163) (xy 36.500699 -359.054333)
			(xy 36.505896 -359.05186) (xy 36.510819 -359.049106) (xy 36.519409 -359.041801) (xy 36.522914 -359.037382)
			(xy 36.523422 -359.036874) (xy 36.541538 -359.013348) (xy 36.583847 -358.971689) (xy 36.632098 -358.937087)
			(xy 36.685127 -358.910377) (xy 36.741653 -358.892204) (xy 36.800312 -358.883007) (xy 36.83 -358.882442)
			(xy 36.857255 -358.882828) (xy 36.91121 -358.890585) (xy 36.963511 -358.905943) (xy 37.013095 -358.928587)
			(xy 37.058951 -358.958057) (xy 37.100147 -358.993753) (xy 37.135843 -359.034949) (xy 37.165313 -359.080805)
			(xy 37.187957 -359.130389) (xy 37.203315 -359.18269) (xy 37.211072 -359.236645) (xy 37.211072 -359.291155)
			(xy 37.203315 -359.34511) (xy 37.187957 -359.397411) (xy 37.165313 -359.446995) (xy 37.135843 -359.492851)
			(xy 37.100147 -359.534047) (xy 37.058951 -359.569743) (xy 37.013095 -359.599213) (xy 36.963511 -359.621857)
			(xy 36.91121 -359.637215) (xy 36.857255 -359.644972) (xy 36.83 -359.645458) (xy 36.801888 -359.644931)
			(xy 36.746275 -359.636661) (xy 36.692479 -359.620314) (xy 36.641667 -359.596246) (xy 36.594939 -359.564978)
			(xy 36.553309 -359.527187) (xy 36.535106 -359.505758) (xy 36.533328 -359.503726) (xy 36.527423 -359.497814)
			(xy 36.512786 -359.489776) (xy 36.504626 -359.487978) (xy 36.494466 -359.487216) (xy 36.414202 -359.489502)
			(xy 36.408454 -359.489782) (xy 36.3973 -359.492615) (xy 36.392104 -359.49509) (xy 36.387187 -359.497853)
			(xy 36.378594 -359.505152) (xy 36.375086 -359.509568) (xy 36.374578 -359.510076) (xy 36.356449 -359.533592)
			(xy 36.314144 -359.575253) (xy 36.265896 -359.609858) (xy 36.21287 -359.63657) (xy 36.156345 -359.654745)
			(xy 36.097687 -359.663943) (xy 36.068 -359.664508) (xy 36.040749 -359.664022) (xy 35.986801 -359.656266)
			(xy 35.934506 -359.640911) (xy 35.884929 -359.618269) (xy 35.839079 -359.588803) (xy 35.797888 -359.553112)
			(xy 35.762197 -359.511921) (xy 35.732731 -359.466071) (xy 35.710089 -359.416494) (xy 35.694734 -359.364199)
			(xy 35.686978 -359.310251) (xy 34.850651 -359.310251) (xy 36.331652 -360.791252) (xy 36.339051 -360.798095)
			(xy 36.35765 -360.805818) (xy 36.36772 -360.806238) (xy 39.31285 -360.806238) (xy 39.322915 -360.806671)
			(xy 39.341503 -360.814402) (xy 39.348918 -360.821224) (xy 40.276272 -361.748578) (xy 40.283109 -361.755979)
			(xy 40.29082 -361.774578) (xy 40.291258 -361.784646) (xy 40.291258 -362.237173) (xy 46.11521 -362.237173)
			(xy 46.116397 -362.18417) (xy 46.124915 -362.131842) (xy 46.140599 -362.081199) (xy 46.163147 -362.033216)
			(xy 46.192124 -361.988819) (xy 46.209204 -361.968542) (xy 46.2153 -361.96143) (xy 46.22165 -361.944666)
			(xy 46.22165 -361.885992) (xy 46.209204 -361.885992) (xy 46.209204 -361.844336) (xy 46.203616 -361.828588)
			(xy 46.198282 -361.82173) (xy 46.182115 -361.800718) (xy 46.155154 -361.755069) (xy 46.134777 -361.706124)
			(xy 46.121377 -361.65483) (xy 46.11521 -361.602173) (xy 46.116397 -361.54917) (xy 46.124915 -361.496842)
			(xy 46.140599 -361.446199) (xy 46.163147 -361.398216) (xy 46.192124 -361.353819) (xy 46.209204 -361.333542)
			(xy 46.2153 -361.32643) (xy 46.22165 -361.309666) (xy 46.22165 -361.250992) (xy 46.209204 -361.250992)
			(xy 46.209204 -361.209336) (xy 46.203616 -361.193588) (xy 46.198282 -361.18673) (xy 46.182115 -361.165718)
			(xy 46.155154 -361.120069) (xy 46.134777 -361.071124) (xy 46.121377 -361.01983) (xy 46.11521 -360.967173)
			(xy 46.116397 -360.91417) (xy 46.124915 -360.861842) (xy 46.140599 -360.811199) (xy 46.163147 -360.763216)
			(xy 46.192124 -360.718819) (xy 46.209204 -360.698542) (xy 46.2153 -360.69143) (xy 46.22165 -360.674666)
			(xy 46.22165 -360.615992) (xy 46.209204 -360.615992) (xy 46.209204 -360.574336) (xy 46.203616 -360.558588)
			(xy 46.198282 -360.55173) (xy 46.182115 -360.530718) (xy 46.155154 -360.485069) (xy 46.134777 -360.436124)
			(xy 46.121377 -360.38483) (xy 46.11521 -360.332173) (xy 46.116397 -360.27917) (xy 46.124915 -360.226842)
			(xy 46.140599 -360.176199) (xy 46.163147 -360.128216) (xy 46.192124 -360.083819) (xy 46.209204 -360.063542)
			(xy 46.2153 -360.05643) (xy 46.22165 -360.039666) (xy 46.22165 -359.980992) (xy 46.209204 -359.980992)
			(xy 46.209204 -359.939336) (xy 46.203616 -359.923588) (xy 46.198282 -359.91673) (xy 46.182639 -359.896397)
			(xy 46.156335 -359.852353) (xy 46.136178 -359.805179) (xy 46.122533 -359.755726) (xy 46.115645 -359.70489)
			(xy 46.115224 -359.67924) (xy 46.115693 -359.651987) (xy 46.123445 -359.598034) (xy 46.138798 -359.545735)
			(xy 46.161438 -359.496152) (xy 46.190905 -359.450298) (xy 46.226598 -359.409104) (xy 46.267791 -359.373409)
			(xy 46.313645 -359.343942) (xy 46.363227 -359.3213) (xy 46.415526 -359.305947) (xy 46.469479 -359.298193)
			(xy 46.496732 -359.297732) (xy 46.524103 -359.298172) (xy 46.578284 -359.305995) (xy 46.630788 -359.321489)
			(xy 46.680534 -359.344337) (xy 46.726499 -359.374068) (xy 46.74743 -359.391712) (xy 46.754542 -359.397808)
			(xy 46.771306 -359.404158) (xy 46.82998 -359.404158) (xy 46.82998 -359.391712) (xy 46.871636 -359.391712)
			(xy 46.887384 -359.386124) (xy 46.894242 -359.38079) (xy 46.915274 -359.36465) (xy 46.96092 -359.337688)
			(xy 47.00986 -359.317308) (xy 47.061152 -359.303905) (xy 47.113806 -359.297736) (xy 47.166807 -359.29892)
			(xy 47.219133 -359.307434) (xy 47.269775 -359.323115) (xy 47.317757 -359.34566) (xy 47.362153 -359.374633)
			(xy 47.38243 -359.391712) (xy 47.389542 -359.397808) (xy 47.406306 -359.404158) (xy 47.46498 -359.404158)
			(xy 47.46498 -359.391712) (xy 47.506636 -359.391712) (xy 47.522384 -359.386124) (xy 47.529242 -359.38079)
			(xy 47.549585 -359.36516) (xy 47.593626 -359.338855) (xy 47.640798 -359.318695) (xy 47.690248 -359.305046)
			(xy 47.741082 -359.298155) (xy 47.766732 -359.297732) (xy 47.793558 -359.298162) (xy 47.846678 -359.305703)
			(xy 47.898219 -359.320605) (xy 47.947167 -359.342574) (xy 47.992559 -359.371178) (xy 48.033501 -359.405853)
			(xy 48.069187 -359.445917) (xy 48.098914 -359.490581) (xy 48.122097 -359.538966) (xy 48.13828 -359.590119)
			(xy 48.14316 -359.616502) (xy 48.145428 -359.627188) (xy 48.157541 -359.645343) (xy 48.166528 -359.651554)
			(xy 48.240442 -359.697274) (xy 48.251364 -359.698798) (xy 48.256735 -359.699348) (xy 48.267492 -359.698444)
			(xy 48.2727 -359.69702) (xy 48.299566 -359.689457) (xy 48.354777 -359.681295) (xy 48.382682 -359.680764)
			(xy 48.410053 -359.681225) (xy 48.464233 -359.689042) (xy 48.516736 -359.704531) (xy 48.566483 -359.727374)
			(xy 48.612449 -359.757101) (xy 48.63338 -359.774744) (xy 48.640492 -359.78084) (xy 48.657256 -359.78719)
			(xy 48.71593 -359.78719) (xy 48.71593 -359.774744) (xy 48.757586 -359.774744) (xy 48.773334 -359.769156)
			(xy 48.780192 -359.763822) (xy 48.801186 -359.747631) (xy 48.846838 -359.720668) (xy 48.895785 -359.700291)
			(xy 48.947083 -359.68689) (xy 48.999743 -359.680725) (xy 49.052749 -359.681915) (xy 49.105079 -359.690436)
			(xy 49.155724 -359.706124) (xy 49.203707 -359.728678) (xy 49.248104 -359.757661) (xy 49.26838 -359.774744)
			(xy 49.275492 -359.78084) (xy 49.292256 -359.78719) (xy 49.35093 -359.78719) (xy 49.35093 -359.774744)
			(xy 49.392586 -359.774744) (xy 49.408334 -359.769156) (xy 49.415192 -359.763822) (xy 49.436186 -359.747631)
			(xy 49.481838 -359.720668) (xy 49.530785 -359.700291) (xy 49.582083 -359.68689) (xy 49.634743 -359.680725)
			(xy 49.687749 -359.681915) (xy 49.740079 -359.690436) (xy 49.790724 -359.706124) (xy 49.838707 -359.728678)
			(xy 49.883104 -359.757661) (xy 49.90338 -359.774744) (xy 49.910492 -359.78084) (xy 49.927256 -359.78719)
			(xy 49.98593 -359.78719) (xy 49.98593 -359.774744) (xy 50.027586 -359.774744) (xy 50.043334 -359.769156)
			(xy 50.050192 -359.763822) (xy 50.07051 -359.74816) (xy 50.114559 -359.721861) (xy 50.161737 -359.701709)
			(xy 50.211193 -359.688067) (xy 50.262031 -359.681183) (xy 50.287682 -359.680764) (xy 50.288444 -359.680764)
			(xy 50.320835 -359.68146) (xy 50.38468 -359.692447) (xy 50.415444 -359.702608) (xy 50.426112 -359.701592)
			(xy 50.431239 -359.700973) (xy 50.441096 -359.697895) (xy 50.44567 -359.695496) (xy 50.510186 -359.660444)
			(xy 50.519022 -359.655115) (xy 50.531881 -359.63901) (xy 50.535078 -359.629202) (xy 50.535078 -359.628948)
			(xy 50.535078 -359.628694) (xy 50.542731 -359.601997) (xy 50.5647 -359.550991) (xy 50.593834 -359.503711)
			(xy 50.629516 -359.461154) (xy 50.670991 -359.424222) (xy 50.717384 -359.393694) (xy 50.767713 -359.370216)
			(xy 50.820915 -359.354285) (xy 50.875864 -359.346236) (xy 50.903632 -359.345738) (xy 50.932527 -359.346241)
			(xy 50.989656 -359.354951) (xy 51.044816 -359.372184) (xy 51.096745 -359.397542) (xy 51.120802 -359.413556)
			(xy 51.128676 -359.419144) (xy 51.147218 -359.423462) (xy 51.22418 -359.413048) (xy 51.233317 -359.411429)
			(xy 51.2496 -359.402562) (xy 51.25593 -359.395776) (xy 51.256184 -359.395522) (xy 51.256438 -359.395268)
			(xy 51.274628 -359.3744) (xy 51.316043 -359.337667) (xy 51.362335 -359.307309) (xy 51.41253 -359.283965)
			(xy 51.465574 -359.268126) (xy 51.520351 -359.260125) (xy 51.54803 -359.259632) (xy 51.573982 -359.26006)
			(xy 51.625404 -359.267112) (xy 51.675397 -359.281066) (xy 51.723038 -359.301667) (xy 51.767447 -359.328534)
			(xy 51.807806 -359.36117) (xy 51.825906 -359.379774) (xy 51.832764 -359.38714) (xy 51.85029 -359.395268)
			(xy 51.930046 -359.39984) (xy 51.939608 -359.399966) (xy 51.957751 -359.39396) (xy 51.965352 -359.388156)
			(xy 51.965352 -359.387902) (xy 51.965606 -359.387902) (xy 51.986326 -359.370947) (xy 52.031651 -359.34245)
			(xy 52.080513 -359.320564) (xy 52.131953 -359.305717) (xy 52.184963 -359.298202) (xy 52.211732 -359.297732)
			(xy 52.239103 -359.298172) (xy 52.293284 -359.305995) (xy 52.345788 -359.321489) (xy 52.395534 -359.344337)
			(xy 52.441499 -359.374068) (xy 52.46243 -359.391712) (xy 52.469542 -359.397808) (xy 52.486306 -359.404158)
			(xy 52.54498 -359.404158) (xy 52.54498 -359.391712) (xy 52.586636 -359.391712) (xy 52.602384 -359.386124)
			(xy 52.609242 -359.38079) (xy 52.629585 -359.36516) (xy 52.673626 -359.338855) (xy 52.720798 -359.318695)
			(xy 52.770248 -359.305046) (xy 52.821082 -359.298155) (xy 52.846732 -359.297732) (xy 52.873988 -359.298125)
			(xy 52.927943 -359.305888) (xy 52.980245 -359.32125) (xy 53.029828 -359.343899) (xy 53.075683 -359.373374)
			(xy 53.116876 -359.409075) (xy 53.152569 -359.450275) (xy 53.182036 -359.496136) (xy 53.204675 -359.545723)
			(xy 53.220028 -359.598027) (xy 53.22778 -359.651984) (xy 53.22824 -359.67924) (xy 53.22824 -359.679748)
			(xy 53.227732 -359.707668) (xy 53.219544 -359.762905) (xy 53.203395 -359.81636) (xy 53.179628 -359.866891)
			(xy 53.148752 -359.913419) (xy 53.13045 -359.93451) (xy 53.1241 -359.941622) (xy 53.117496 -359.958894)
			(xy 53.11775 -360.046016) (xy 53.124354 -360.063288) (xy 53.130704 -360.070146) (xy 53.149106 -360.091278)
			(xy 53.180168 -360.137913) (xy 53.204071 -360.188592) (xy 53.2203 -360.242224) (xy 53.228505 -360.297653)
			(xy 53.229002 -360.32567) (xy 53.228517 -360.352922) (xy 53.220764 -360.406873) (xy 53.205411 -360.459171)
			(xy 53.182772 -360.508751) (xy 53.153306 -360.554605) (xy 53.117615 -360.595798) (xy 53.076424 -360.631492)
			(xy 53.030572 -360.66096) (xy 52.980993 -360.683603) (xy 52.928696 -360.698959) (xy 52.874746 -360.706715)
			(xy 52.847494 -360.707178) (xy 52.819417 -360.706695) (xy 52.763867 -360.698479) (xy 52.710122 -360.682211)
			(xy 52.659341 -360.658241) (xy 52.612621 -360.627088) (xy 52.591462 -360.608626) (xy 52.591208 -360.608372)
			(xy 52.590954 -360.608118) (xy 52.583955 -360.602301) (xy 52.567022 -360.595666) (xy 52.557934 -360.595164)
			(xy 52.481734 -360.593894) (xy 52.464716 -360.59999) (xy 52.45735 -360.606086) (xy 52.43664 -360.622946)
			(xy 52.391398 -360.65132) (xy 52.342638 -360.673099) (xy 52.291315 -360.687857) (xy 52.238434 -360.695304)
			(xy 52.211732 -360.695748) (xy 52.185781 -360.695285) (xy 52.13436 -360.688242) (xy 52.084367 -360.674294)
			(xy 52.036727 -360.6537) (xy 51.992316 -360.626839) (xy 51.951956 -360.594207) (xy 51.933856 -360.575606)
			(xy 51.926998 -360.56824) (xy 51.909472 -360.560112) (xy 51.829716 -360.55554) (xy 51.820153 -360.555399)
			(xy 51.802011 -360.561417) (xy 51.79441 -360.567224) (xy 51.79441 -360.567478) (xy 51.794156 -360.567478)
			(xy 51.773411 -360.584402) (xy 51.728093 -360.612904) (xy 51.679237 -360.634796) (xy 51.627803 -360.64965)
			(xy 51.574798 -360.657174) (xy 51.54803 -360.657648) (xy 51.519137 -360.6571) (xy 51.46201 -360.6484)
			(xy 51.40685 -360.631181) (xy 51.35492 -360.605836) (xy 51.33086 -360.58983) (xy 51.322986 -360.584242)
			(xy 51.304444 -360.579924) (xy 51.227482 -360.590338) (xy 51.218353 -360.591989) (xy 51.202067 -360.600834)
			(xy 51.195732 -360.60761) (xy 51.195478 -360.607864) (xy 51.195224 -360.608118) (xy 51.17592 -360.629454)
			(xy 51.1683 -360.637328) (xy 51.160934 -360.656886) (xy 51.166014 -360.75366) (xy 51.175412 -360.772202)
			(xy 51.183794 -360.77906) (xy 51.205176 -360.797302) (xy 51.242916 -360.838946) (xy 51.274139 -360.885676)
			(xy 51.298169 -360.936481) (xy 51.314486 -360.990261) (xy 51.322737 -361.045853) (xy 51.32324 -361.073954)
			(xy 51.322702 -361.101204) (xy 51.314952 -361.155151) (xy 51.299604 -361.207445) (xy 51.276969 -361.257023)
			(xy 51.247509 -361.302875) (xy 51.211823 -361.344067) (xy 51.170638 -361.379762) (xy 51.124792 -361.409231)
			(xy 51.075219 -361.431876) (xy 51.022927 -361.447236) (xy 50.968982 -361.454996) (xy 50.941732 -361.455462)
			(xy 50.941478 -361.455462) (xy 50.915337 -361.455037) (xy 50.863545 -361.447904) (xy 50.813214 -361.433761)
			(xy 50.789078 -361.423712) (xy 50.779426 -361.419394) (xy 50.745644 -361.419394) (xy 50.740891 -361.419505)
			(xy 50.731555 -361.421287) (xy 50.727102 -361.42295) (xy 50.67046 -361.445302) (xy 50.661127 -361.449534)
			(xy 50.646585 -361.463949) (xy 50.642266 -361.473242) (xy 50.642012 -361.473496) (xy 50.642012 -361.47375)
			(xy 50.631022 -361.499955) (xy 50.602349 -361.549013) (xy 50.566717 -361.593277) (xy 50.524915 -361.631768)
			(xy 50.477868 -361.663634) (xy 50.426614 -361.68817) (xy 50.372289 -361.704835) (xy 50.316094 -361.713259)
			(xy 50.287682 -361.71378) (xy 50.260311 -361.713329) (xy 50.206131 -361.705509) (xy 50.153628 -361.690016)
			(xy 50.103881 -361.667171) (xy 50.057915 -361.637443) (xy 50.036984 -361.6198) (xy 50.029872 -361.613704)
			(xy 50.013108 -361.607354) (xy 49.954434 -361.607354) (xy 49.954434 -361.6198) (xy 49.912778 -361.6198)
			(xy 49.89703 -361.625388) (xy 49.890172 -361.630722) (xy 49.869129 -361.646848) (xy 49.823485 -361.67381)
			(xy 49.774546 -361.694189) (xy 49.723256 -361.707593) (xy 49.670604 -361.713764) (xy 49.617604 -361.712581)
			(xy 49.56528 -361.704069) (xy 49.514639 -361.68839) (xy 49.466657 -361.665848) (xy 49.422261 -361.636877)
			(xy 49.401984 -361.6198) (xy 49.394872 -361.613704) (xy 49.378108 -361.607354) (xy 49.319434 -361.607354)
			(xy 49.319434 -361.6198) (xy 49.277778 -361.6198) (xy 49.26203 -361.625388) (xy 49.255172 -361.630722)
			(xy 49.234129 -361.646848) (xy 49.188485 -361.67381) (xy 49.139546 -361.694189) (xy 49.088256 -361.707593)
			(xy 49.035604 -361.713764) (xy 48.982604 -361.712581) (xy 48.93028 -361.704069) (xy 48.879639 -361.68839)
			(xy 48.831657 -361.665848) (xy 48.787261 -361.636877) (xy 48.766984 -361.6198) (xy 48.759872 -361.613704)
			(xy 48.743108 -361.607354) (xy 48.684434 -361.607354) (xy 48.684434 -361.6198) (xy 48.642778 -361.6198)
			(xy 48.62703 -361.625388) (xy 48.620172 -361.630722) (xy 48.59986 -361.646393) (xy 48.55581 -361.672692)
			(xy 48.50863 -361.692843) (xy 48.459173 -361.706482) (xy 48.408334 -361.713363) (xy 48.382682 -361.71378)
			(xy 48.382174 -361.71378) (xy 48.34904 -361.713036) (xy 48.283773 -361.701545) (xy 48.25238 -361.69092)
			(xy 48.243998 -361.687872) (xy 48.217074 -361.687872) (xy 48.212119 -361.687985) (xy 48.202398 -361.689908)
			(xy 48.19777 -361.691682) (xy 48.132746 -361.718352) (xy 48.118776 -361.731814) (xy 48.114712 -361.740704)
			(xy 48.102724 -361.766129) (xy 48.072367 -361.813437) (xy 48.05426 -361.834938) (xy 48.048164 -361.84205)
			(xy 48.041814 -361.858814) (xy 48.041814 -361.917488) (xy 48.05426 -361.917488) (xy 48.05426 -361.959144)
			(xy 48.059848 -361.974892) (xy 48.065182 -361.98175) (xy 48.080826 -362.002082) (xy 48.107127 -362.046127)
			(xy 48.127283 -362.093302) (xy 48.140929 -362.142754) (xy 48.147818 -362.19359) (xy 48.14824 -362.21924)
			(xy 48.147759 -362.246491) (xy 48.139998 -362.300437) (xy 48.12464 -362.35273) (xy 48.101996 -362.402305)
			(xy 48.072529 -362.448154) (xy 48.036837 -362.489343) (xy 47.995647 -362.525034) (xy 47.949798 -362.5545)
			(xy 47.900222 -362.577143) (xy 47.847929 -362.5925) (xy 47.793983 -362.60026) (xy 47.766732 -362.600748)
			(xy 47.737254 -362.600203) (xy 47.679001 -362.591137) (xy 47.622836 -362.573217) (xy 47.570096 -362.546868)
			(xy 47.522039 -362.512719) (xy 47.50054 -362.492544) (xy 47.493428 -362.485432) (xy 47.47514 -362.478066)
			(xy 47.441358 -362.478066) (xy 47.431352 -362.478553) (xy 47.412866 -362.48622) (xy 47.398715 -362.500372)
			(xy 47.391051 -362.51886) (xy 47.390558 -362.528866) (xy 47.390558 -362.562648) (xy 47.397924 -362.580936)
			(xy 47.405036 -362.588048) (xy 47.42523 -362.609529) (xy 47.459372 -362.657593) (xy 47.485715 -362.710337)
			(xy 47.503632 -362.766506) (xy 47.512694 -362.824762) (xy 47.51324 -362.85424) (xy 47.512759 -362.881491)
			(xy 47.504998 -362.935437) (xy 47.48964 -362.98773) (xy 47.466996 -363.037305) (xy 47.437529 -363.083154)
			(xy 47.401837 -363.124343) (xy 47.360647 -363.160034) (xy 47.314798 -363.1895) (xy 47.265222 -363.212143)
			(xy 47.212929 -363.2275) (xy 47.158983 -363.23526) (xy 47.131732 -363.235748) (xy 47.104362 -363.235276)
			(xy 47.050183 -363.227461) (xy 46.997679 -363.211974) (xy 46.947932 -363.189134) (xy 46.901965 -363.159409)
			(xy 46.881034 -363.141768) (xy 46.873922 -363.135672) (xy 46.857158 -363.129322) (xy 46.798484 -363.129322)
			(xy 46.798484 -363.141768) (xy 46.756828 -363.141768) (xy 46.74108 -363.147356) (xy 46.734222 -363.15269)
			(xy 46.7139 -363.168348) (xy 46.669852 -363.194647) (xy 46.622675 -363.2148) (xy 46.57322 -363.228443)
			(xy 46.522383 -363.235328) (xy 46.496732 -363.235748) (xy 46.469483 -363.235192) (xy 46.41554 -363.227441)
			(xy 46.363249 -363.212092) (xy 46.313675 -363.189457) (xy 46.267826 -363.159998) (xy 46.226637 -363.124314)
			(xy 46.190945 -363.083131) (xy 46.161477 -363.037288) (xy 46.138833 -362.987718) (xy 46.123474 -362.93543)
			(xy 46.115713 -362.881489) (xy 46.115224 -362.85424) (xy 46.115708 -362.82687) (xy 46.12352 -362.772692)
			(xy 46.139005 -362.720189) (xy 46.161843 -362.670441) (xy 46.191564 -362.624474) (xy 46.209204 -362.603542)
			(xy 46.2153 -362.59643) (xy 46.22165 -362.579666) (xy 46.22165 -362.520992) (xy 46.209204 -362.520992)
			(xy 46.209204 -362.479336) (xy 46.203616 -362.463588) (xy 46.198282 -362.45673) (xy 46.182115 -362.435718)
			(xy 46.155154 -362.390069) (xy 46.134777 -362.341124) (xy 46.121377 -362.28983) (xy 46.11521 -362.237173)
			(xy 40.291258 -362.237173) (xy 40.291258 -363.121448) (xy 40.291691 -363.131513) (xy 40.299425 -363.150099)
			(xy 40.306244 -363.157516) (xy 41.316148 -364.16742) (xy 41.35628 -364.16742) (xy 43.94454 -364.16742)
		)
		(stroke
			(width 0)
			(type solid)
		)
		(fill yes)
		(layer "B.Cu")
		(net "GND")
	)
	(gr_poly
		(pts
			(xy 203.347828 -399.31594) (xy 203.357056 -399.315536) (xy 203.374308 -399.30898) (xy 203.388113 -399.296731)
			(xy 203.392786 -399.288762) (xy 203.434696 -399.209514) (xy 203.437723 -399.203224) (xy 203.440567 -399.189564)
			(xy 203.440284 -399.18259) (xy 203.439522 -399.168366) (xy 203.431648 -399.156936) (xy 203.415807 -399.132989)
			(xy 203.390737 -399.081338) (xy 203.373704 -399.026508) (xy 203.365094 -398.969743) (xy 203.364592 -398.941036)
			(xy 203.364592 -398.940274) (xy 203.364592 -398.93494) (xy 203.365538 -398.906676) (xy 203.37474 -398.850878)
			(xy 203.392077 -398.79705) (xy 203.41717 -398.74637) (xy 203.449468 -398.69995) (xy 203.488263 -398.658804)
			(xy 203.532707 -398.623836) (xy 203.581826 -398.595811) (xy 203.634543 -398.575342) (xy 203.689704 -398.562879)
			(xy 203.7461 -398.558694) (xy 203.802496 -398.562879) (xy 203.857657 -398.575342) (xy 203.910374 -398.595811)
			(xy 203.959493 -398.623836) (xy 204.003937 -398.658804) (xy 204.042732 -398.69995) (xy 204.07503 -398.74637)
			(xy 204.100123 -398.79705) (xy 204.11746 -398.850878) (xy 204.126662 -398.906676) (xy 204.127608 -398.93494)
			(xy 204.127608 -398.940274) (xy 204.127608 -398.941036) (xy 204.127068 -398.96974) (xy 204.118434 -399.026495)
			(xy 204.101412 -399.081322) (xy 204.076383 -399.132987) (xy 204.060552 -399.156936) (xy 204.056742 -399.162524)
			(xy 204.05217 -399.175478) (xy 204.051916 -399.18259) (xy 204.051639 -399.189565) (xy 204.054463 -399.203231)
			(xy 204.057504 -399.209514) (xy 204.099414 -399.288762) (xy 204.104062 -399.296745) (xy 204.117884 -399.30898)
			(xy 204.135143 -399.315527) (xy 204.144372 -399.31594) (xy 204.55001 -399.31594) (xy 204.55674 -399.315763)
			(xy 204.569737 -399.312276) (xy 204.575664 -399.309082) (xy 204.60208 -399.293588) (xy 204.61097 -399.284698)
			(xy 204.613764 -399.279872) (xy 204.641571 -399.233109) (xy 204.703666 -399.143762) (xy 204.772768 -399.059716)
			(xy 204.848425 -398.981519) (xy 204.930146 -398.909681) (xy 205.017395 -398.844671) (xy 205.109606 -398.786913)
			(xy 205.206176 -398.736783) (xy 205.25613 -398.71523) (xy 205.261574 -398.712774) (xy 205.271201 -398.705714)
			(xy 205.27518 -398.70126) (xy 205.297786 -398.674336) (xy 205.300326 -398.662398) (xy 205.311877 -398.613285)
			(xy 205.341743 -398.516904) (xy 205.379159 -398.423196) (xy 205.423888 -398.332751) (xy 205.47565 -398.246137)
			(xy 205.534117 -398.163901) (xy 205.598922 -398.086561) (xy 205.669656 -398.014604) (xy 205.745874 -397.948483)
			(xy 205.827096 -397.888615) (xy 205.91281 -397.835377) (xy 206.002476 -397.789105) (xy 206.095529 -397.750088)
			(xy 206.191383 -397.718575) (xy 206.289435 -397.694762) (xy 206.389066 -397.678801) (xy 206.489649 -397.670791)
			(xy 206.5401 -397.670274) (xy 206.589999 -397.670764) (xy 206.689491 -397.678594) (xy 206.788061 -397.694206)
			(xy 206.885102 -397.717503) (xy 206.980017 -397.748342) (xy 207.072219 -397.786533) (xy 207.16114 -397.831841)
			(xy 207.246233 -397.883985) (xy 207.326972 -397.942645) (xy 207.40286 -398.007459) (xy 207.473429 -398.078026)
			(xy 207.538244 -398.153914) (xy 207.596905 -398.234652) (xy 207.64905 -398.319744) (xy 207.694359 -398.408665)
			(xy 207.732551 -398.500867) (xy 207.763392 -398.595781) (xy 207.786691 -398.692822) (xy 207.802304 -398.791392)
			(xy 207.810135 -398.890883) (xy 207.810608 -398.940782) (xy 207.810608 -398.941798) (xy 207.81024 -398.984122)
			(xy 207.804568 -399.068579) (xy 207.793281 -399.152472) (xy 207.785208 -399.19402) (xy 207.782922 -399.20545)
			(xy 207.785462 -399.216118) (xy 207.787004 -399.221582) (xy 207.792129 -399.231709) (xy 207.795622 -399.236184)
			(xy 207.847438 -399.29943) (xy 207.854959 -399.306836) (xy 207.874237 -399.315376) (xy 207.884776 -399.31594)
			(xy 214.015828 -399.31594) (xy 214.025056 -399.315536) (xy 214.042308 -399.30898) (xy 214.056113 -399.296731)
			(xy 214.060786 -399.288762) (xy 214.102696 -399.209514) (xy 214.105723 -399.203224) (xy 214.108567 -399.189564)
			(xy 214.108284 -399.18259) (xy 214.107522 -399.168366) (xy 214.099648 -399.156936) (xy 214.083807 -399.132989)
			(xy 214.058737 -399.081338) (xy 214.041704 -399.026508) (xy 214.033094 -398.969743) (xy 214.032592 -398.941036)
			(xy 214.032592 -398.940274) (xy 214.032592 -398.93494) (xy 214.033538 -398.906676) (xy 214.04274 -398.850878)
			(xy 214.060077 -398.79705) (xy 214.08517 -398.74637) (xy 214.117468 -398.69995) (xy 214.156263 -398.658804)
			(xy 214.200707 -398.623836) (xy 214.249826 -398.595811) (xy 214.302543 -398.575342) (xy 214.357704 -398.562879)
			(xy 214.4141 -398.558694) (xy 214.470496 -398.562879) (xy 214.525657 -398.575342) (xy 214.578374 -398.595811)
			(xy 214.627493 -398.623836) (xy 214.671937 -398.658804) (xy 214.710732 -398.69995) (xy 214.74303 -398.74637)
			(xy 214.768123 -398.79705) (xy 214.78546 -398.850878) (xy 214.794662 -398.906676) (xy 214.795608 -398.93494)
			(xy 214.795608 -398.940274) (xy 214.795608 -398.941036) (xy 214.795068 -398.96974) (xy 214.786434 -399.026495)
			(xy 214.769412 -399.081322) (xy 214.744383 -399.132987) (xy 214.728552 -399.156936) (xy 214.724742 -399.162524)
			(xy 214.72017 -399.175478) (xy 214.719916 -399.18259) (xy 214.719639 -399.189565) (xy 214.722463 -399.203231)
			(xy 214.725504 -399.209514) (xy 214.767414 -399.288762) (xy 214.772062 -399.296745) (xy 214.785884 -399.30898)
			(xy 214.803143 -399.315527) (xy 214.812372 -399.31594) (xy 215.320372 -399.31594) (xy 215.333032 -399.31518)
			(xy 215.355263 -399.303038) (xy 215.36279 -399.292826) (xy 215.381828 -399.262302) (xy 215.422873 -399.203211)
			(xy 215.444832 -399.174716) (xy 215.475958 -399.13564) (xy 215.543453 -399.061974) (xy 215.616529 -398.99384)
			(xy 215.694734 -398.931661) (xy 215.777584 -398.875821) (xy 215.864567 -398.826666) (xy 215.909652 -398.805146)
			(xy 215.9152 -398.802349) (xy 215.924842 -398.794519) (xy 215.928702 -398.789652) (xy 215.950292 -398.76095)
			(xy 215.95207 -398.748504) (xy 215.960139 -398.699073) (xy 215.983067 -398.601566) (xy 216.0136 -398.506168)
			(xy 216.05155 -398.413469) (xy 216.096679 -398.324045) (xy 216.148709 -398.238452) (xy 216.207316 -398.157221)
			(xy 216.272136 -398.080857) (xy 216.342767 -398.009832) (xy 216.41877 -397.944588) (xy 216.499674 -397.885531)
			(xy 216.584977 -397.833026) (xy 216.674148 -397.7874) (xy 216.766634 -397.748936) (xy 216.861862 -397.717873)
			(xy 216.959239 -397.694403) (xy 217.058163 -397.678672) (xy 217.158017 -397.670779) (xy 217.2081 -397.670274)
			(xy 217.257999 -397.670764) (xy 217.357491 -397.678594) (xy 217.456061 -397.694206) (xy 217.553102 -397.717503)
			(xy 217.648017 -397.748342) (xy 217.740219 -397.786533) (xy 217.82914 -397.831841) (xy 217.914233 -397.883985)
			(xy 217.994972 -397.942645) (xy 218.07086 -398.007459) (xy 218.141429 -398.078026) (xy 218.206244 -398.153914)
			(xy 218.264905 -398.234652) (xy 218.31705 -398.319744) (xy 218.362359 -398.408665) (xy 218.400551 -398.500867)
			(xy 218.431392 -398.595781) (xy 218.454691 -398.692822) (xy 218.470304 -398.791392) (xy 218.478135 -398.890883)
			(xy 218.478608 -398.940782) (xy 218.478608 -398.941798) (xy 218.47824 -398.984122) (xy 218.472568 -399.068579)
			(xy 218.461281 -399.152472) (xy 218.453208 -399.19402) (xy 218.450922 -399.20545) (xy 218.453462 -399.216118)
			(xy 218.455004 -399.221582) (xy 218.460129 -399.231709) (xy 218.463622 -399.236184) (xy 218.515438 -399.29943)
			(xy 218.522959 -399.306836) (xy 218.542237 -399.315376) (xy 218.552776 -399.31594) (xy 224.683828 -399.31594)
			(xy 224.693056 -399.315536) (xy 224.710308 -399.30898) (xy 224.724113 -399.296731) (xy 224.728786 -399.288762)
			(xy 224.770696 -399.209514) (xy 224.773723 -399.203224) (xy 224.776567 -399.189564) (xy 224.776284 -399.18259)
			(xy 224.775522 -399.168366) (xy 224.767648 -399.156936) (xy 224.751807 -399.132989) (xy 224.726737 -399.081338)
			(xy 224.709704 -399.026508) (xy 224.701094 -398.969743) (xy 224.700592 -398.941036) (xy 224.700592 -398.940274)
			(xy 224.700592 -398.93494) (xy 224.701538 -398.906676) (xy 224.71074 -398.850878) (xy 224.728077 -398.79705)
			(xy 224.75317 -398.74637) (xy 224.785468 -398.69995) (xy 224.824263 -398.658804) (xy 224.868707 -398.623836)
			(xy 224.917826 -398.595811) (xy 224.970543 -398.575342) (xy 225.025704 -398.562879) (xy 225.0821 -398.558694)
			(xy 225.138496 -398.562879) (xy 225.193657 -398.575342) (xy 225.246374 -398.595811) (xy 225.295493 -398.623836)
			(xy 225.339937 -398.658804) (xy 225.378732 -398.69995) (xy 225.41103 -398.74637) (xy 225.436123 -398.79705)
			(xy 225.45346 -398.850878) (xy 225.462662 -398.906676) (xy 225.463608 -398.93494) (xy 225.463608 -398.940274)
			(xy 225.463608 -398.941036) (xy 225.463068 -398.96974) (xy 225.454434 -399.026495) (xy 225.437412 -399.081322)
			(xy 225.412383 -399.132987) (xy 225.396552 -399.156936) (xy 225.392742 -399.162524) (xy 225.38817 -399.175478)
			(xy 225.387916 -399.18259) (xy 225.387639 -399.189565) (xy 225.390463 -399.203231) (xy 225.393504 -399.209514)
			(xy 225.435414 -399.288762) (xy 225.440062 -399.296745) (xy 225.453884 -399.30898) (xy 225.471143 -399.315527)
			(xy 225.480372 -399.31594) (xy 225.988372 -399.31594) (xy 226.001032 -399.31518) (xy 226.023263 -399.303038)
			(xy 226.03079 -399.292826) (xy 226.049828 -399.262302) (xy 226.090873 -399.203211) (xy 226.112832 -399.174716)
			(xy 226.143958 -399.13564) (xy 226.211453 -399.061974) (xy 226.284529 -398.99384) (xy 226.362734 -398.931661)
			(xy 226.445584 -398.875821) (xy 226.532567 -398.826666) (xy 226.577652 -398.805146) (xy 226.5832 -398.802349)
			(xy 226.592842 -398.794519) (xy 226.596702 -398.789652) (xy 226.618292 -398.76095) (xy 226.62007 -398.748504)
			(xy 226.628139 -398.699073) (xy 226.651067 -398.601566) (xy 226.6816 -398.506168) (xy 226.71955 -398.413469)
			(xy 226.764679 -398.324045) (xy 226.816709 -398.238452) (xy 226.875316 -398.157221) (xy 226.940136 -398.080857)
			(xy 227.010767 -398.009832) (xy 227.08677 -397.944588) (xy 227.167674 -397.885531) (xy 227.252977 -397.833026)
			(xy 227.342148 -397.7874) (xy 227.434634 -397.748936) (xy 227.529862 -397.717873) (xy 227.627239 -397.694403)
			(xy 227.726163 -397.678672) (xy 227.826017 -397.670779) (xy 227.8761 -397.670274) (xy 227.925999 -397.670764)
			(xy 228.025491 -397.678594) (xy 228.124061 -397.694206) (xy 228.221102 -397.717503) (xy 228.316017 -397.748342)
			(xy 228.408219 -397.786533) (xy 228.49714 -397.831841) (xy 228.582233 -397.883985) (xy 228.662972 -397.942645)
			(xy 228.73886 -398.007459) (xy 228.809429 -398.078026) (xy 228.874244 -398.153914) (xy 228.932905 -398.234652)
			(xy 228.98505 -398.319744) (xy 229.030359 -398.408665) (xy 229.068551 -398.500867) (xy 229.099392 -398.595781)
			(xy 229.122691 -398.692822) (xy 229.138304 -398.791392) (xy 229.146135 -398.890883) (xy 229.146608 -398.940782)
			(xy 229.146608 -398.941798) (xy 229.14624 -398.984122) (xy 229.140568 -399.068579) (xy 229.129281 -399.152472)
			(xy 229.121208 -399.19402) (xy 229.118922 -399.20545) (xy 229.121462 -399.216118) (xy 229.123004 -399.221582)
			(xy 229.128129 -399.231709) (xy 229.131622 -399.236184) (xy 229.183438 -399.29943) (xy 229.190959 -399.306836)
			(xy 229.210237 -399.315376) (xy 229.220776 -399.31594) (xy 237.843568 -399.31594) (xy 237.85322 -399.314924)
			(xy 237.860465 -399.313299) (xy 237.873636 -399.306459) (xy 237.879128 -399.301462) (xy 238.35995 -398.82064)
			(xy 238.36493 -398.815137) (xy 238.371758 -398.801968) (xy 238.373412 -398.794732) (xy 238.374428 -398.78508)
			(xy 238.374428 -393.843764) (xy 238.37392 -393.843256) (xy 238.37392 -393.836652) (xy 238.372541 -393.829058)
			(xy 238.365958 -393.815106) (xy 238.360966 -393.80922) (xy 238.310166 -393.758674) (xy 238.277531 -393.725402)
			(xy 238.217558 -393.654054) (xy 238.164037 -393.577746) (xy 238.117378 -393.497059) (xy 238.077937 -393.41261)
			(xy 238.046013 -393.325042) (xy 238.02185 -393.235022) (xy 238.005633 -393.143238) (xy 237.997485 -393.050389)
			(xy 237.996984 -393.003786) (xy 237.996984 -384.211068) (xy 237.997119 -384.206177) (xy 237.999033 -384.196583)
			(xy 238.000794 -384.192018) (xy 238.460026 -383.732786) (xy 238.467422 -383.725934) (xy 238.486021 -383.718196)
			(xy 238.496094 -383.7178) (xy 238.832644 -383.7178) (xy 238.842711 -383.717369) (xy 238.861303 -383.709643)
			(xy 238.868712 -383.702814) (xy 238.881412 -383.690114) (xy 238.888811 -383.683268) (xy 238.907409 -383.675536)
			(xy 238.91748 -383.675128) (xy 242.481608 -383.675128) (xy 242.491636 -383.674681) (xy 242.5102 -383.667096)
			(xy 242.517676 -383.660396) (xy 242.546378 -383.631694) (xy 242.553226 -383.624296) (xy 242.560961 -383.605698)
			(xy 242.561364 -383.595626) (xy 242.561364 -380.359666) (xy 242.561795 -380.3496) (xy 242.569525 -380.33101)
			(xy 242.57635 -380.323598) (xy 242.976146 -379.923802) (xy 242.983547 -379.916963) (xy 243.002145 -379.909245)
			(xy 243.012214 -379.908816) (xy 243.802916 -379.908816) (xy 243.812568 -379.9078) (xy 243.819812 -379.906171)
			(xy 243.832981 -379.89933) (xy 243.838476 -379.894338) (xy 243.912136 -379.820678) (xy 243.919533 -379.813829)
			(xy 243.938132 -379.806095) (xy 243.948204 -379.805692) (xy 245.347236 -379.805692) (xy 245.357304 -379.806121)
			(xy 245.375899 -379.813844) (xy 245.383304 -379.820678) (xy 245.420388 -379.857762) (xy 245.427226 -379.865163)
			(xy 245.434939 -379.883762) (xy 245.435374 -379.89383) (xy 245.435374 -380.147576) (xy 245.436021 -380.160081)
			(xy 245.447747 -380.182174) (xy 245.457726 -380.18974) (xy 245.489552 -380.211552) (xy 245.550931 -380.258317)
			(xy 245.580408 -380.283212) (xy 245.589274 -380.290127) (xy 245.610896 -380.296194) (xy 245.622064 -380.294896)
			(xy 245.637942 -380.292321) (xy 245.669988 -380.289525) (xy 245.686072 -380.289308) (xy 245.713326 -380.289769)
			(xy 245.767279 -380.297523) (xy 245.819579 -380.312877) (xy 245.869162 -380.335518) (xy 245.915017 -380.364986)
			(xy 245.956212 -380.40068) (xy 245.991907 -380.441873) (xy 246.021376 -380.487728) (xy 246.044019 -380.53731)
			(xy 246.059374 -380.589609) (xy 246.06713 -380.643562) (xy 246.06758 -380.670816) (xy 246.067072 -380.69905)
			(xy 246.058763 -380.754903) (xy 246.042328 -380.808926) (xy 246.018125 -380.859944) (xy 246.00281 -380.883668)
			(xy 245.997021 -380.89328) (xy 245.993593 -380.915428) (xy 245.996206 -380.92634) (xy 246.01301 -380.985924)
			(xy 246.036926 -381.107402) (xy 246.043958 -381.16891) (xy 246.046498 -381.180594) (xy 246.054466 -381.204848)
			(xy 246.064631 -381.254877) (xy 246.068038 -381.305815) (xy 246.064627 -381.356753) (xy 246.054458 -381.406781)
			(xy 246.046498 -381.431038) (xy 246.043958 -381.442722) (xy 246.037997 -381.495969) (xy 246.018669 -381.601365)
			(xy 245.991025 -381.704891) (xy 245.955239 -381.805892) (xy 245.911538 -381.903729) (xy 245.860198 -381.997783)
			(xy 245.801545 -382.087458) (xy 245.735949 -382.172187) (xy 245.663825 -382.251434) (xy 245.585631 -382.324697)
			(xy 245.50186 -382.391513) (xy 245.457726 -382.421892) (xy 245.447705 -382.429421) (xy 245.435975 -382.451537)
			(xy 245.435374 -382.464056) (xy 245.435374 -382.798066) (xy 245.435808 -382.808131) (xy 245.443537 -382.826721)
			(xy 245.45036 -382.834134) (xy 245.455694 -382.839468) (xy 245.474236 -382.847088) (xy 245.823486 -382.847088)
			(xy 245.823994 -382.84658) (xy 248.405904 -382.84658) (xy 248.415556 -382.845564) (xy 248.4228 -382.843936)
			(xy 248.435968 -382.837093) (xy 248.441464 -382.832102) (xy 248.536714 -382.736852) (xy 248.541698 -382.731351)
			(xy 248.548535 -382.718183) (xy 248.550176 -382.710944) (xy 248.551192 -382.701292) (xy 248.551192 -382.400556)
			(xy 248.55064 -382.389025) (xy 248.540585 -382.36827) (xy 248.531888 -382.360678) (xy 248.491136 -382.327715)
			(xy 248.414323 -382.256385) (xy 248.343291 -382.179297) (xy 248.27847 -382.096918) (xy 248.220251 -382.009747)
			(xy 248.168989 -381.918312) (xy 248.124993 -381.823167) (xy 248.08853 -381.724889) (xy 248.073672 -381.674624)
			(xy 248.070369 -381.664866) (xy 248.057388 -381.648893) (xy 248.048526 -381.643636) (xy 248.025781 -381.631176)
			(xy 247.983578 -381.601035) (xy 247.945845 -381.565458) (xy 247.913275 -381.5251) (xy 247.886468 -381.480705)
			(xy 247.865918 -381.433089) (xy 247.852004 -381.38313) (xy 247.844981 -381.331746) (xy 247.844564 -381.305816)
			(xy 247.845 -381.279579) (xy 247.852195 -381.2276) (xy 247.86645 -381.177099) (xy 247.887497 -381.129031)
			(xy 247.914938 -381.084303) (xy 247.948254 -381.043761) (xy 247.967246 -381.025654) (xy 247.96877 -381.02413)
			(xy 247.975457 -381.016718) (xy 247.983059 -380.998282) (xy 247.983064 -380.97834) (xy 247.975469 -380.959901)
			(xy 247.96877 -380.952502) (xy 247.967246 -380.950978) (xy 247.948261 -380.932863) (xy 247.914943 -380.892324)
			(xy 247.887499 -380.847598) (xy 247.866449 -380.799531) (xy 247.852189 -380.749031) (xy 247.844991 -380.697053)
			(xy 247.844564 -380.670816) (xy 247.845049 -380.643563) (xy 247.852803 -380.589612) (xy 247.868157 -380.537314)
			(xy 247.890796 -380.487733) (xy 247.920262 -380.441879) (xy 247.955953 -380.400684) (xy 247.997143 -380.364988)
			(xy 248.042994 -380.335518) (xy 248.092573 -380.312872) (xy 248.144869 -380.297513) (xy 248.198819 -380.289752)
			(xy 248.226072 -380.289308) (xy 248.255153 -380.289851) (xy 248.312644 -380.298661) (xy 248.368136 -380.316083)
			(xy 248.394474 -380.328424) (xy 248.403867 -380.332506) (xy 248.424301 -380.333611) (xy 248.443543 -380.326649)
			(xy 248.45137 -380.320042) (xy 248.471073 -380.301874) (xy 248.511726 -380.26694) (xy 248.53265 -380.250192)
			(xy 248.541794 -380.24308) (xy 248.551954 -380.221998) (xy 248.551954 -380.214378) (xy 248.552383 -380.204311)
			(xy 248.560109 -380.185717) (xy 248.56694 -380.17831) (xy 248.821448 -379.923802) (xy 248.828849 -379.916963)
			(xy 248.847447 -379.909246) (xy 248.857516 -379.908816) (xy 251.091954 -379.908816) (xy 251.102019 -379.909249)
			(xy 251.120608 -379.916979) (xy 251.128022 -379.923802) (xy 251.22632 -380.0221) (xy 251.233175 -380.029495)
			(xy 251.240922 -380.048094) (xy 251.241306 -380.058168) (xy 251.241306 -380.157228) (xy 251.241607 -380.16616)
			(xy 251.247672 -380.18296) (xy 251.259154 -380.196641) (xy 251.266706 -380.201424) (xy 251.26696 -380.201424)
			(xy 251.308863 -380.225823) (xy 251.389212 -380.280114) (xy 251.427488 -380.309882) (xy 251.434748 -380.31511)
			(xy 251.451723 -380.320718) (xy 251.469592 -380.320206) (xy 251.478034 -380.317248) (xy 251.500834 -380.308431)
			(xy 251.548115 -380.296005) (xy 251.596594 -380.289711) (xy 251.621036 -380.289308) (xy 251.648285 -380.289797)
			(xy 251.702228 -380.297557) (xy 251.754517 -380.312916) (xy 251.804089 -380.335559) (xy 251.849934 -380.365027)
			(xy 251.891118 -380.400718) (xy 251.926804 -380.441908) (xy 251.956266 -380.487757) (xy 251.978902 -380.537331)
			(xy 251.994254 -380.589623) (xy 252.002007 -380.643567) (xy 252.002544 -380.670816) (xy 252.002128 -380.696455)
			(xy 251.995259 -380.747272) (xy 251.981648 -380.796711) (xy 251.961539 -380.843883) (xy 251.935295 -380.887937)
			(xy 251.903389 -380.92808) (xy 251.885196 -380.946152) (xy 251.878934 -380.952608) (xy 251.871006 -380.968741)
			(xy 251.869144 -380.986619) (xy 251.870972 -380.995428) (xy 251.874528 -381.009144) (xy 251.876389 -381.015999)
			(xy 251.883362 -381.028367) (xy 251.888244 -381.033528) (xy 251.907584 -381.053193) (xy 251.940972 -381.097092)
			(xy 251.96769 -381.145343) (xy 251.987183 -381.196937) (xy 251.999042 -381.250801) (xy 252.003022 -381.305811)
			(xy 251.999039 -381.360821) (xy 251.987176 -381.414684) (xy 251.967681 -381.466278) (xy 251.94096 -381.514526)
			(xy 251.907569 -381.558424) (xy 251.888244 -381.578104) (xy 251.883372 -381.583271) (xy 251.876404 -381.595639)
			(xy 251.874528 -381.602488) (xy 251.861864 -381.652984) (xy 251.829348 -381.751891) (xy 251.788846 -381.847804)
			(xy 251.740627 -381.94008) (xy 251.685017 -382.028099) (xy 251.622388 -382.11127) (xy 251.55316 -382.189035)
			(xy 251.477799 -382.260872) (xy 251.396811 -382.326299) (xy 251.310738 -382.384877) (xy 251.26569 -382.41097)
			(xy 251.255729 -382.417884) (xy 251.243146 -382.438571) (xy 251.24156 -382.450594) (xy 251.241306 -382.454404)
			(xy 251.241306 -382.690878) (xy 251.242322 -382.70053) (xy 251.243946 -382.707776) (xy 251.250783 -382.72095)
			(xy 251.255784 -382.726438) (xy 251.377196 -382.84785) (xy 251.382696 -382.852837) (xy 251.395862 -382.859682)
			(xy 251.403104 -382.861312) (xy 251.412756 -382.862328) (xy 254.129032 -382.862328) (xy 254.1391 -382.8619)
			(xy 254.157699 -382.85418) (xy 254.1651 -382.847342) (xy 254.333248 -382.679194) (xy 254.340099 -382.671798)
			(xy 254.34784 -382.653199) (xy 254.348234 -382.643126) (xy 254.348234 -382.265174) (xy 254.341122 -382.247394)
			(xy 254.33401 -382.240028) (xy 254.296315 -382.20009) (xy 254.226812 -382.115049) (xy 254.164463 -382.024632)
			(xy 254.109681 -381.92944) (xy 254.062831 -381.830104) (xy 254.024222 -381.727284) (xy 254.008636 -381.674624)
			(xy 254.005331 -381.664868) (xy 253.992345 -381.648903) (xy 253.98349 -381.643636) (xy 253.960747 -381.631175)
			(xy 253.918548 -381.601032) (xy 253.880818 -381.565453) (xy 253.848251 -381.525095) (xy 253.821447 -381.4807)
			(xy 253.800899 -381.433085) (xy 253.786986 -381.383127) (xy 253.779964 -381.331746) (xy 253.779528 -381.305816)
			(xy 253.779964 -381.279579) (xy 253.787158 -381.227599) (xy 253.801413 -381.177097) (xy 253.822458 -381.129028)
			(xy 253.849897 -381.084298) (xy 253.883211 -381.043754) (xy 253.90221 -381.025654) (xy 253.903734 -381.02413)
			(xy 253.910425 -381.01672) (xy 253.918033 -380.998284) (xy 253.918038 -380.978339) (xy 253.910438 -380.959899)
			(xy 253.903734 -380.952502) (xy 253.90221 -380.950978) (xy 253.883227 -380.932862) (xy 253.849911 -380.892322)
			(xy 253.82247 -380.847596) (xy 253.801422 -380.799529) (xy 253.787164 -380.74903) (xy 253.779966 -380.697053)
			(xy 253.779528 -380.670816) (xy 253.77999 -380.643563) (xy 253.787746 -380.589613) (xy 253.803101 -380.537315)
			(xy 253.825743 -380.487735) (xy 253.855211 -380.441882) (xy 253.890905 -380.400691) (xy 253.932099 -380.364999)
			(xy 253.977953 -380.335533) (xy 254.027534 -380.312894) (xy 254.079832 -380.297541) (xy 254.133783 -380.289789)
			(xy 254.161036 -380.289308) (xy 254.187237 -380.289745) (xy 254.239145 -380.296926) (xy 254.28958 -380.311148)
			(xy 254.337593 -380.332142) (xy 254.360172 -380.345442) (xy 254.38354 -380.322836) (xy 254.386334 -380.320042)
			(xy 254.411034 -380.297343) (xy 254.462364 -380.25414) (xy 254.48895 -380.233682) (xy 254.489204 -380.233428)
			(xy 254.493741 -380.229765) (xy 254.501175 -380.220784) (xy 254.503936 -380.215648) (xy 254.506476 -380.210568)
			(xy 254.509016 -380.199392) (xy 254.509016 -380.089918) (xy 254.509455 -380.079855) (xy 254.517192 -380.061273)
			(xy 254.524002 -380.05385) (xy 254.65405 -379.923802) (xy 254.661451 -379.916963) (xy 254.680049 -379.909247)
			(xy 254.690118 -379.908816) (xy 257.026918 -379.908816) (xy 257.036986 -379.909243) (xy 257.055585 -379.916964)
			(xy 257.062986 -379.923802) (xy 257.204718 -380.065534) (xy 257.211568 -380.07293) (xy 257.219303 -380.091529)
			(xy 257.219704 -380.101602) (xy 257.219704 -380.182882) (xy 257.219912 -380.189464) (xy 257.223249 -380.202197)
			(xy 257.226308 -380.208028) (xy 257.228594 -380.212092) (xy 257.228594 -380.216664) (xy 257.243834 -380.226062)
			(xy 257.274581 -380.24545) (xy 257.334054 -380.287259) (xy 257.362706 -380.309628) (xy 257.369968 -380.314849)
			(xy 257.38694 -380.320446) (xy 257.404804 -380.319929) (xy 257.413252 -380.316994) (xy 257.435977 -380.308239)
			(xy 257.483093 -380.295918) (xy 257.531396 -380.289703) (xy 257.555746 -380.289308) (xy 257.556 -380.289308)
			(xy 257.583252 -380.289771) (xy 257.637203 -380.297528) (xy 257.689499 -380.312885) (xy 257.739079 -380.335527)
			(xy 257.784931 -380.364996) (xy 257.826122 -380.400689) (xy 257.861814 -380.441882) (xy 257.89128 -380.487736)
			(xy 257.913921 -380.537316) (xy 257.929275 -380.589613) (xy 257.93703 -380.643564) (xy 257.937508 -380.670816)
			(xy 257.937092 -380.696455) (xy 257.930223 -380.747271) (xy 257.91661 -380.79671) (xy 257.8965 -380.84388)
			(xy 257.870255 -380.887932) (xy 257.838346 -380.928073) (xy 257.82016 -380.946152) (xy 257.813891 -380.952605)
			(xy 257.805953 -380.968738) (xy 257.804089 -380.986621) (xy 257.805936 -380.995428) (xy 257.809492 -381.009144)
			(xy 257.811351 -381.016) (xy 257.81832 -381.028372) (xy 257.823208 -381.033528) (xy 257.842549 -381.053192)
			(xy 257.87594 -381.097091) (xy 257.902662 -381.14534) (xy 257.922156 -381.196935) (xy 257.934017 -381.2508)
			(xy 257.937997 -381.305811) (xy 257.934013 -381.360822) (xy 257.922149 -381.414686) (xy 257.902652 -381.46628)
			(xy 257.875928 -381.514528) (xy 257.842535 -381.558425) (xy 257.823208 -381.578104) (xy 257.818339 -381.583272)
			(xy 257.811376 -381.595642) (xy 257.809492 -381.602488) (xy 257.797458 -381.65056) (xy 257.766879 -381.744831)
			(xy 257.72905 -381.836434) (xy 257.684201 -381.924813) (xy 257.632604 -382.009429) (xy 257.574573 -382.089769)
			(xy 257.510461 -382.165346) (xy 257.440657 -382.235699) (xy 257.365585 -382.300401) (xy 257.285702 -382.359059)
			(xy 257.243834 -382.38557) (xy 257.236664 -382.390397) (xy 257.225813 -382.403836) (xy 257.220034 -382.420114)
			(xy 257.219704 -382.42875) (xy 257.219704 -382.773936) (xy 257.22072 -382.783588) (xy 257.222352 -382.79083)
			(xy 257.229199 -382.803993) (xy 257.234182 -382.809496) (xy 257.251962 -382.827276) (xy 257.257462 -382.832262)
			(xy 257.27063 -382.8391) (xy 257.27787 -382.840738) (xy 257.287522 -382.841754) (xy 260.223 -382.841754)
			(xy 260.232652 -382.840738) (xy 260.239895 -382.839109) (xy 260.253062 -382.832265) (xy 260.25856 -382.827276)
			(xy 260.43128 -382.654556) (xy 260.436267 -382.649057) (xy 260.443109 -382.63589) (xy 260.444742 -382.628648)
			(xy 260.445758 -382.618996) (xy 260.445758 -382.407668) (xy 260.435344 -382.386586) (xy 260.425692 -382.37922)
			(xy 260.382719 -382.346015) (xy 260.301691 -382.273693) (xy 260.226754 -382.195077) (xy 260.158397 -382.110677)
			(xy 260.097064 -382.021044) (xy 260.043153 -381.926759) (xy 259.997015 -381.828437) (xy 259.958951 -381.726716)
			(xy 259.9436 -381.674624) (xy 259.940299 -381.664864) (xy 259.927321 -381.648885) (xy 259.918454 -381.643636)
			(xy 259.895713 -381.631173) (xy 259.853517 -381.601028) (xy 259.81579 -381.565449) (xy 259.783227 -381.52509)
			(xy 259.756425 -381.480695) (xy 259.73588 -381.433081) (xy 259.721969 -381.383125) (xy 259.714947 -381.331745)
			(xy 259.714492 -381.305816) (xy 259.714928 -381.279579) (xy 259.722123 -381.227601) (xy 259.73638 -381.1771)
			(xy 259.757428 -381.129033) (xy 259.78487 -381.084307) (xy 259.818187 -381.043767) (xy 259.837174 -381.025654)
			(xy 259.838698 -381.02413) (xy 259.845382 -381.016717) (xy 259.85298 -380.998281) (xy 259.852984 -380.978341)
			(xy 259.845394 -380.959903) (xy 259.838698 -380.952502) (xy 259.837174 -380.950978) (xy 259.818192 -380.932861)
			(xy 259.78488 -380.89232) (xy 259.757441 -380.847593) (xy 259.736395 -380.799527) (xy 259.722139 -380.749028)
			(xy 259.714942 -380.697052) (xy 259.714492 -380.670816) (xy 259.714954 -380.643562) (xy 259.722709 -380.58961)
			(xy 259.738064 -380.53731) (xy 259.760706 -380.487728) (xy 259.790173 -380.441873) (xy 259.825867 -380.400678)
			(xy 259.86706 -380.364983) (xy 259.912914 -380.335513) (xy 259.962495 -380.31287) (xy 260.014794 -380.297513)
			(xy 260.068746 -380.289755) (xy 260.096 -380.289308) (xy 260.125082 -380.289836) (xy 260.182576 -380.298638)
			(xy 260.238062 -380.316084) (xy 260.264402 -380.328424) (xy 260.273828 -380.332594) (xy 260.294385 -380.333784)
			(xy 260.313744 -380.326767) (xy 260.321552 -380.320042) (xy 260.346605 -380.296993) (xy 260.3987 -380.253157)
			(xy 260.425692 -380.232412) (xy 260.428486 -380.230126) (xy 260.431534 -380.226824) (xy 260.434242 -380.223975)
			(xy 260.43884 -380.217599) (xy 260.440678 -380.214124) (xy 260.443218 -380.209298) (xy 260.445758 -380.198122)
			(xy 260.445758 -380.08814) (xy 260.446194 -380.078076) (xy 260.45393 -380.059493) (xy 260.460744 -380.052072)
			(xy 260.589014 -379.923802) (xy 260.596413 -379.916958) (xy 260.615011 -379.909228) (xy 260.625082 -379.908816)
			(xy 262.961882 -379.908816) (xy 262.971945 -379.909255) (xy 262.990527 -379.916992) (xy 262.99795 -379.923802)
			(xy 263.11098 -380.036832) (xy 263.117824 -380.044231) (xy 263.12555 -380.06283) (xy 263.125966 -380.0729)
			(xy 263.125966 -380.16561) (xy 263.126356 -380.174459) (xy 263.132382 -380.191103) (xy 263.143684 -380.204725)
			(xy 263.151112 -380.209552) (xy 263.189255 -380.232296) (xy 263.262601 -380.282382) (xy 263.29767 -380.309628)
			(xy 263.304931 -380.314855) (xy 263.321906 -380.320464) (xy 263.339776 -380.319958) (xy 263.348216 -380.316994)
			(xy 263.370941 -380.308237) (xy 263.418057 -380.295912) (xy 263.466359 -380.289692) (xy 263.49071 -380.289308)
			(xy 263.490964 -380.289308) (xy 263.518218 -380.289769) (xy 263.572172 -380.297522) (xy 263.624473 -380.312875)
			(xy 263.674057 -380.335516) (xy 263.719913 -380.364983) (xy 263.761109 -380.400677) (xy 263.796805 -380.441871)
			(xy 263.826275 -380.487725) (xy 263.848918 -380.537308) (xy 263.864274 -380.589608) (xy 263.87203 -380.643562)
			(xy 263.872472 -380.670816) (xy 263.872056 -380.696456) (xy 263.865188 -380.747273) (xy 263.851577 -380.796713)
			(xy 263.83147 -380.843885) (xy 263.805227 -380.88794) (xy 263.773322 -380.928085) (xy 263.755124 -380.946152)
			(xy 263.748859 -380.952607) (xy 263.740927 -380.96874) (xy 263.739064 -380.98662) (xy 263.7409 -380.995428)
			(xy 263.744456 -381.009144) (xy 263.746314 -381.016001) (xy 263.75328 -381.028376) (xy 263.758172 -381.033528)
			(xy 263.777515 -381.053191) (xy 263.810909 -381.097089) (xy 263.837633 -381.145338) (xy 263.857129 -381.196934)
			(xy 263.868991 -381.250799) (xy 263.872972 -381.305811) (xy 263.868988 -381.360823) (xy 263.857123 -381.414688)
			(xy 263.837623 -381.466282) (xy 263.810897 -381.51453) (xy 263.7775 -381.558426) (xy 263.758172 -381.578104)
			(xy 263.753298 -381.583269) (xy 263.746326 -381.595637) (xy 263.744456 -381.602488) (xy 263.732008 -381.652126)
			(xy 263.700186 -381.749398) (xy 263.660643 -381.843795) (xy 263.613634 -381.934705) (xy 263.559465 -382.021539)
			(xy 263.498487 -382.103735) (xy 263.431094 -382.180759) (xy 263.357725 -382.252112) (xy 263.278853 -382.317333)
			(xy 263.19499 -382.375998) (xy 263.151112 -382.402334) (xy 263.14367 -382.407089) (xy 263.132337 -382.420618)
			(xy 263.126296 -382.437199) (xy 263.125966 -382.446022) (xy 263.125966 -382.72212) (xy 263.126982 -382.731772)
			(xy 263.128611 -382.739016) (xy 263.135451 -382.752186) (xy 263.140444 -382.75768) (xy 263.225026 -382.842262)
			(xy 263.230527 -382.847245) (xy 263.243695 -382.85408) (xy 263.250934 -382.855724) (xy 263.260586 -382.85674)
			(xy 266.22756 -382.85674) (xy 266.237212 -382.855724) (xy 266.244458 -382.8541) (xy 266.25763 -382.847261)
			(xy 266.26312 -382.842262) (xy 266.36853 -382.736852) (xy 266.373513 -382.731351) (xy 266.380347 -382.718182)
			(xy 266.381992 -382.710944) (xy 266.383008 -382.701292) (xy 266.383008 -382.421384) (xy 266.382386 -382.409539)
			(xy 266.371788 -382.388353) (xy 266.362688 -382.380744) (xy 266.319533 -382.347517) (xy 266.238156 -382.275114)
			(xy 266.162897 -382.196372) (xy 266.094247 -382.111805) (xy 266.032656 -382.021966) (xy 265.978527 -381.927445)
			(xy 265.932213 -381.828857) (xy 265.894019 -381.72685) (xy 265.878564 -381.674624) (xy 265.87526 -381.664866)
			(xy 265.862278 -381.648895) (xy 265.853418 -381.643636) (xy 265.830673 -381.631176) (xy 265.788472 -381.601034)
			(xy 265.750739 -381.565457) (xy 265.718169 -381.525099) (xy 265.691363 -381.480704) (xy 265.670814 -381.433088)
			(xy 265.6569 -381.383129) (xy 265.649877 -381.331746) (xy 265.649456 -381.305816) (xy 265.649892 -381.279579)
			(xy 265.657087 -381.2276) (xy 265.671342 -381.177099) (xy 265.692389 -381.12903) (xy 265.719829 -381.084302)
			(xy 265.753144 -381.04376) (xy 265.772138 -381.025654) (xy 265.773662 -381.02413) (xy 265.78035 -381.016718)
			(xy 265.787954 -380.998282) (xy 265.787958 -380.97834) (xy 265.780362 -380.959901) (xy 265.773662 -380.952502)
			(xy 265.772138 -380.950978) (xy 265.753153 -380.932863) (xy 265.719836 -380.892323) (xy 265.692393 -380.847597)
			(xy 265.671343 -380.799531) (xy 265.657084 -380.749031) (xy 265.649885 -380.697053) (xy 265.649456 -380.670816)
			(xy 265.649941 -380.643563) (xy 265.657695 -380.589612) (xy 265.673049 -380.537313) (xy 265.695688 -380.487731)
			(xy 265.725154 -380.441876) (xy 265.760845 -380.400681) (xy 265.802035 -380.364985) (xy 265.847886 -380.335513)
			(xy 265.897464 -380.312867) (xy 265.949761 -380.297506) (xy 266.003711 -380.289744) (xy 266.030964 -380.289308)
			(xy 266.060047 -380.289833) (xy 266.117543 -380.29863) (xy 266.173032 -380.316072) (xy 266.199366 -380.328424)
			(xy 266.208789 -380.332581) (xy 266.229333 -380.333748) (xy 266.24867 -380.326717) (xy 266.256516 -380.320042)
			(xy 266.282037 -380.296564) (xy 266.335151 -380.251965) (xy 266.362688 -380.230888) (xy 266.3718 -380.223288)
			(xy 266.382414 -380.202097) (xy 266.383008 -380.190248) (xy 266.383008 -380.085854) (xy 266.38344 -380.075788)
			(xy 266.391167 -380.057196) (xy 266.397994 -380.049786) (xy 266.523978 -379.923802) (xy 266.531381 -379.916968)
			(xy 266.549979 -379.909262) (xy 266.560046 -379.908816) (xy 268.896846 -379.908816) (xy 268.906912 -379.909248)
			(xy 268.925503 -379.916976) (xy 268.932914 -379.923802) (xy 269.03299 -380.023878) (xy 269.039825 -380.03128)
			(xy 269.047533 -380.049879) (xy 269.047976 -380.059946) (xy 269.047976 -380.15799) (xy 269.048334 -380.16694)
			(xy 269.054495 -380.183747) (xy 269.066041 -380.197428) (xy 269.07363 -380.202186) (xy 269.115117 -380.226385)
			(xy 269.194706 -380.280162) (xy 269.232634 -380.309628) (xy 269.239896 -380.314844) (xy 269.256867 -380.320433)
			(xy 269.274725 -380.319907) (xy 269.28318 -380.316994) (xy 269.305906 -380.308241) (xy 269.353022 -380.295923)
			(xy 269.401324 -380.289712) (xy 269.425674 -380.289308) (xy 269.425928 -380.289308) (xy 269.453177 -380.289796)
			(xy 269.507121 -380.297556) (xy 269.559412 -380.312914) (xy 269.608984 -380.335557) (xy 269.65483 -380.365024)
			(xy 269.696016 -380.400716) (xy 269.731702 -380.441905) (xy 269.761164 -380.487754) (xy 269.783802 -380.53733)
			(xy 269.799153 -380.589622) (xy 269.806907 -380.643566) (xy 269.807436 -380.670816) (xy 269.80702 -380.696455)
			(xy 269.800151 -380.747272) (xy 269.78654 -380.796711) (xy 269.766431 -380.843882) (xy 269.740186 -380.887936)
			(xy 269.708279 -380.928078) (xy 269.690088 -380.946152) (xy 269.683826 -380.952609) (xy 269.6759 -380.968741)
			(xy 269.674039 -380.986619) (xy 269.675864 -380.995428) (xy 269.67942 -381.009144) (xy 269.68128 -381.015999)
			(xy 269.688253 -381.028368) (xy 269.693136 -381.033528) (xy 269.712476 -381.053192) (xy 269.745865 -381.097092)
			(xy 269.772584 -381.145342) (xy 269.792077 -381.196937) (xy 269.803937 -381.250801) (xy 269.807916 -381.305811)
			(xy 269.803933 -381.360821) (xy 269.79207 -381.414685) (xy 269.772575 -381.466278) (xy 269.745853 -381.514527)
			(xy 269.712461 -381.558424) (xy 269.693136 -381.578104) (xy 269.688265 -381.583271) (xy 269.681298 -381.59564)
			(xy 269.67942 -381.602488) (xy 269.667002 -381.652009) (xy 269.635268 -381.749056) (xy 269.595848 -381.843243)
			(xy 269.548998 -381.933964) (xy 269.495019 -382.020632) (xy 269.434259 -382.102689) (xy 269.36711 -382.179606)
			(xy 269.294006 -382.250887) (xy 269.215418 -382.316071) (xy 269.131852 -382.374739) (xy 269.088108 -382.401064)
			(xy 269.08067 -382.405821) (xy 269.069346 -382.419351) (xy 269.063315 -382.435931) (xy 269.062962 -382.444752)
			(xy 269.062962 -382.670304) (xy 269.063978 -382.679956) (xy 269.065608 -382.687199) (xy 269.072455 -382.700363)
			(xy 269.07744 -382.705864) (xy 269.214092 -382.842516) (xy 269.21959 -382.847506) (xy 269.232755 -382.854357)
			(xy 269.24 -382.855978) (xy 269.249652 -382.856994) (xy 272.143982 -382.856994) (xy 272.153634 -382.855978)
			(xy 272.160879 -382.854353) (xy 272.174053 -382.847516) (xy 272.179542 -382.842516) (xy 272.295366 -382.726692)
			(xy 272.30035 -382.721191) (xy 272.30719 -382.708024) (xy 272.308828 -382.700784) (xy 272.309844 -382.691132)
			(xy 272.309844 -382.415034) (xy 272.309844 -382.414526) (xy 272.309479 -382.40646) (xy 272.304303 -382.391176)
			(xy 272.299684 -382.384554) (xy 272.299684 -382.382268) (xy 272.256352 -382.349013) (xy 272.174632 -382.276522)
			(xy 272.099052 -382.19765) (xy 272.030107 -382.112918) (xy 271.96825 -382.02288) (xy 271.913887 -381.928129)
			(xy 271.867376 -381.829286) (xy 271.829022 -381.727002) (xy 271.813528 -381.674624) (xy 271.810228 -381.664862)
			(xy 271.797254 -381.648877) (xy 271.788382 -381.643636) (xy 271.765639 -381.631174) (xy 271.723441 -381.601031)
			(xy 271.685711 -381.565452) (xy 271.653145 -381.525094) (xy 271.626342 -381.480699) (xy 271.605795 -381.433084)
			(xy 271.591882 -381.383127) (xy 271.58486 -381.331745) (xy 271.58442 -381.305816) (xy 271.584856 -381.279579)
			(xy 271.592052 -381.227601) (xy 271.606309 -381.177102) (xy 271.627358 -381.129035) (xy 271.654802 -381.08431)
			(xy 271.688121 -381.043772) (xy 271.707102 -381.025654) (xy 271.708626 -381.02413) (xy 271.715317 -381.01672)
			(xy 271.722927 -380.998284) (xy 271.722931 -380.978339) (xy 271.71533 -380.959899) (xy 271.708626 -380.952502)
			(xy 271.707102 -380.950978) (xy 271.688119 -380.932862) (xy 271.654804 -380.892321) (xy 271.627364 -380.847595)
			(xy 271.606316 -380.799528) (xy 271.592058 -380.749029) (xy 271.584861 -380.697052) (xy 271.58442 -380.670816)
			(xy 271.584882 -380.643563) (xy 271.592638 -380.589612) (xy 271.607992 -380.537314) (xy 271.630634 -380.487733)
			(xy 271.660102 -380.44188) (xy 271.695797 -380.400688) (xy 271.73699 -380.364995) (xy 271.782844 -380.335529)
			(xy 271.832425 -380.312888) (xy 271.884724 -380.297535) (xy 271.938675 -380.289781) (xy 271.965928 -380.289308)
			(xy 271.99501 -380.289838) (xy 272.052502 -380.298644) (xy 272.107986 -380.316093) (xy 272.13433 -380.328424)
			(xy 272.143755 -380.332588) (xy 272.164306 -380.333768) (xy 272.183655 -380.326745) (xy 272.19148 -380.320042)
			(xy 272.21523 -380.298186) (xy 272.264528 -380.256512) (xy 272.290032 -380.23673) (xy 272.29467 -380.232967)
			(xy 272.302229 -380.223724) (xy 272.305018 -380.218442) (xy 272.309844 -380.208536) (xy 272.309844 -380.093982)
			(xy 272.310272 -380.083914) (xy 272.317996 -380.065319) (xy 272.32483 -380.057914) (xy 272.458942 -379.923802)
			(xy 272.466343 -379.916962) (xy 272.484941 -379.909242) (xy 272.49501 -379.908816) (xy 274.83181 -379.908816)
			(xy 274.841879 -379.909241) (xy 274.860479 -379.91696) (xy 274.867878 -379.923802) (xy 274.990814 -380.046738)
			(xy 274.997664 -380.054134) (xy 275.005398 -380.072734) (xy 275.0058 -380.082806) (xy 275.0058 -380.185168)
			(xy 275.018754 -380.208282) (xy 275.030438 -380.21514) (xy 275.065995 -380.236774) (xy 275.134504 -380.284057)
			(xy 275.167344 -380.309628) (xy 275.174607 -380.314843) (xy 275.191576 -380.320428) (xy 275.209433 -380.319899)
			(xy 275.21789 -380.316994) (xy 275.240574 -380.308249) (xy 275.287605 -380.295931) (xy 275.335822 -380.289698)
			(xy 275.36013 -380.289308) (xy 275.360892 -380.289308) (xy 275.388145 -380.289771) (xy 275.442096 -380.297527)
			(xy 275.494394 -380.312882) (xy 275.543974 -380.335525) (xy 275.589827 -380.364993) (xy 275.631019 -380.400687)
			(xy 275.666712 -380.44188) (xy 275.696179 -380.487733) (xy 275.71882 -380.537314) (xy 275.734175 -380.589612)
			(xy 275.74193 -380.643563) (xy 275.7424 -380.670816) (xy 275.741984 -380.696455) (xy 275.735114 -380.747271)
			(xy 275.721502 -380.796709) (xy 275.701392 -380.843879) (xy 275.675146 -380.887931) (xy 275.643236 -380.928072)
			(xy 275.625052 -380.946152) (xy 275.618784 -380.952606) (xy 275.610848 -380.968739) (xy 275.608984 -380.986621)
			(xy 275.610828 -380.995428) (xy 275.614384 -381.009144) (xy 275.616243 -381.016001) (xy 275.623211 -381.028373)
			(xy 275.6281 -381.033528) (xy 275.647442 -381.053192) (xy 275.680834 -381.09709) (xy 275.707555 -381.14534)
			(xy 275.72705 -381.196935) (xy 275.738911 -381.2508) (xy 275.742891 -381.305811) (xy 275.738908 -381.360822)
			(xy 275.727043 -381.414686) (xy 275.707546 -381.46628) (xy 275.680821 -381.514529) (xy 275.647427 -381.558425)
			(xy 275.6281 -381.578104) (xy 275.623231 -381.583273) (xy 275.616269 -381.595642) (xy 275.614384 -381.602488)
			(xy 275.602289 -381.650772) (xy 275.571539 -381.745452) (xy 275.533473 -381.837434) (xy 275.488325 -381.926155)
			(xy 275.436373 -382.01107) (xy 275.377933 -382.091659) (xy 275.313366 -382.167428) (xy 275.243068 -382.23791)
			(xy 275.167469 -382.302675) (xy 275.087033 -382.361325) (xy 275.044916 -382.387856) (xy 275.037747 -382.392684)
			(xy 275.026896 -382.406123) (xy 275.021115 -382.4224) (xy 275.020786 -382.431036) (xy 275.020786 -382.732534)
			(xy 275.021802 -382.742186) (xy 275.023433 -382.749428) (xy 275.030278 -382.762594) (xy 275.035264 -382.768094)
			(xy 275.099272 -382.832102) (xy 275.104773 -382.837085) (xy 275.117942 -382.843917) (xy 275.12518 -382.845564)
			(xy 275.134832 -382.84658) (xy 277.352506 -382.84658) (xy 277.362158 -382.845564) (xy 277.369402 -382.843936)
			(xy 277.382569 -382.837093) (xy 277.388066 -382.832102) (xy 277.942802 -382.277366) (xy 277.949643 -382.269965)
			(xy 277.957365 -382.251367) (xy 277.957788 -382.241298) (xy 277.957788 -381.901954) (xy 277.95762 -381.896436)
			(xy 277.955182 -381.885672) (xy 277.952962 -381.880618) (xy 277.952962 -381.880364) (xy 277.932249 -381.835434)
			(xy 277.896697 -381.743096) (xy 277.868024 -381.648396) (xy 277.846384 -381.551846) (xy 277.831894 -381.453967)
			(xy 277.824632 -381.355289) (xy 277.824184 -381.305816) (xy 277.824646 -381.256345) (xy 277.83193 -381.15767)
			(xy 277.846432 -381.059796) (xy 277.868073 -380.963249) (xy 277.896737 -380.868549) (xy 277.932269 -380.776206)
			(xy 277.952962 -380.731268) (xy 277.955203 -380.726154) (xy 277.957642 -380.71526) (xy 277.957788 -380.709678)
			(xy 277.957788 -378.862844) (xy 277.957354 -378.852779) (xy 277.949624 -378.83419) (xy 277.942802 -378.826776)
			(xy 277.373334 -378.257054) (xy 277.36701 -378.251311) (xy 277.351565 -378.244037) (xy 277.343108 -378.24283)
			(xy 277.337774 -378.242576) (xy 217.536268 -378.242576) (xy 217.536268 -378.24156) (xy 211.539582 -378.24156)
			(xy 211.529515 -378.241988) (xy 211.510921 -378.249714) (xy 211.503514 -378.256546) (xy 211.06638 -378.69368)
			(xy 211.059538 -378.701079) (xy 211.05182 -378.719678) (xy 211.051394 -378.729748) (xy 211.051394 -386.470652)
			(xy 212.630512 -386.470652) (xy 212.631082 -386.4416) (xy 212.639874 -386.384165) (xy 212.657276 -386.328728)
			(xy 212.682887 -386.276573) (xy 212.716113 -386.228907) (xy 212.756186 -386.186832) (xy 212.778848 -386.168646)
			(xy 212.787658 -386.161176) (xy 212.797994 -386.140551) (xy 212.79866 -386.129022) (xy 212.79993 -386.037582)
			(xy 212.790278 -386.016754) (xy 212.781134 -386.009388) (xy 212.75957 -385.991198) (xy 212.721564 -385.949506)
			(xy 212.690115 -385.902669) (xy 212.66591 -385.85171) (xy 212.649478 -385.797741) (xy 212.641176 -385.74194)
			(xy 212.640672 -385.713732) (xy 212.641185 -385.686481) (xy 212.648937 -385.632533) (xy 212.664288 -385.580237)
			(xy 212.686925 -385.530658) (xy 212.716388 -385.484806) (xy 212.752077 -385.443614) (xy 212.793264 -385.407919)
			(xy 212.839113 -385.37845) (xy 212.888688 -385.355806) (xy 212.940982 -385.340448) (xy 212.994929 -385.332689)
			(xy 213.02218 -385.332224) (xy 213.052195 -385.332809) (xy 213.111482 -385.342219) (xy 213.168566 -385.360794)
			(xy 213.222038 -385.388076) (xy 213.270579 -385.423393) (xy 213.292182 -385.444238) (xy 213.299294 -385.45135)
			(xy 213.317074 -385.45897) (xy 213.407752 -385.460494) (xy 213.425786 -385.453636) (xy 213.433152 -385.446778)
			(xy 213.454444 -385.427736) (xy 213.501644 -385.395567) (xy 213.553112 -385.370791) (xy 213.607696 -385.353961)
			(xy 213.66418 -385.345455) (xy 213.69274 -385.344924) (xy 213.719815 -385.345382) (xy 213.77342 -385.353036)
			(xy 213.825402 -385.368199) (xy 213.874716 -385.390566) (xy 213.920368 -385.419687) (xy 213.96144 -385.454975)
			(xy 213.997104 -385.49572) (xy 214.012272 -385.518152) (xy 214.018876 -385.528312) (xy 214.039704 -385.54025)
			(xy 214.145876 -385.5466) (xy 214.167974 -385.536948) (xy 214.175594 -385.52755) (xy 214.193806 -385.50636)
			(xy 214.23537 -385.469019) (xy 214.281936 -385.438141) (xy 214.332508 -385.414386) (xy 214.386005 -385.398262)
			(xy 214.441281 -385.390115) (xy 214.469218 -385.389628) (xy 214.499234 -385.390188) (xy 214.558522 -385.399603)
			(xy 214.615606 -385.418184) (xy 214.669078 -385.445472) (xy 214.717618 -385.480794) (xy 214.73922 -385.501642)
			(xy 214.746332 -385.508754) (xy 214.764112 -385.516374) (xy 214.85479 -385.517898) (xy 214.872824 -385.51104)
			(xy 214.88019 -385.504182) (xy 214.901508 -385.48517) (xy 214.948701 -385.452996) (xy 215.000162 -385.428214)
			(xy 215.054741 -385.411378) (xy 215.11122 -385.402863) (xy 215.139778 -385.402328) (xy 215.168755 -385.402882)
			(xy 215.226044 -385.411639) (xy 215.281351 -385.428954) (xy 215.333406 -385.45443) (xy 215.381011 -385.487481)
			(xy 215.423074 -385.527349) (xy 215.441276 -385.549902) (xy 215.448896 -385.559808) (xy 215.471756 -385.570222)
			(xy 215.580976 -385.563618) (xy 215.602566 -385.55041) (xy 215.608916 -385.539488) (xy 215.623759 -385.515449)
			(xy 215.65937 -385.471594) (xy 215.701063 -385.433474) (xy 215.747926 -385.401925) (xy 215.798932 -385.377637)
			(xy 215.852963 -385.361143) (xy 215.908837 -385.352803) (xy 215.937084 -385.35229) (xy 215.96688 -385.352819)
			(xy 216.025747 -385.362083) (xy 216.082457 -385.380389) (xy 216.135631 -385.407291) (xy 216.183975 -385.442135)
			(xy 216.226312 -385.484072) (xy 216.244424 -385.507738) (xy 216.25179 -385.517644) (xy 216.273126 -385.528566)
			(xy 216.379552 -385.528312) (xy 216.401142 -385.51739) (xy 216.408254 -385.507738) (xy 216.426378 -385.48399)
			(xy 216.468729 -385.441863) (xy 216.517131 -385.406854) (xy 216.570398 -385.37982) (xy 216.62723 -385.361421)
			(xy 216.686234 -385.352108) (xy 216.716102 -385.351528) (xy 216.746117 -385.352098) (xy 216.805406 -385.361511)
			(xy 216.862489 -385.38009) (xy 216.915961 -385.407375) (xy 216.964502 -385.442695) (xy 216.986104 -385.463542)
			(xy 216.993216 -385.470654) (xy 217.010996 -385.478274) (xy 217.101674 -385.479798) (xy 217.119708 -385.47294)
			(xy 217.127074 -385.466082) (xy 217.148399 -385.447078) (xy 217.19559 -385.414903) (xy 217.247049 -385.39012)
			(xy 217.301627 -385.373281) (xy 217.358104 -385.364764) (xy 217.386662 -385.364228) (xy 217.386916 -385.364228)
			(xy 217.41583 -385.364787) (xy 217.472993 -385.373539) (xy 217.528182 -385.39081) (xy 217.580136 -385.416206)
			(xy 217.627668 -385.449144) (xy 217.649044 -385.468622) (xy 217.65641 -385.475734) (xy 217.675714 -385.4831)
			(xy 217.769186 -385.479036) (xy 217.787728 -385.470146) (xy 217.794586 -385.462526) (xy 217.812785 -385.442813)
			(xy 217.853733 -385.408151) (xy 217.899131 -385.379564) (xy 217.948085 -385.357615) (xy 217.999629 -385.342736)
			(xy 218.052749 -385.335221) (xy 218.079574 -385.334764) (xy 218.106823 -385.335302) (xy 218.160768 -385.343055)
			(xy 218.21306 -385.358405) (xy 218.262635 -385.381041) (xy 218.308484 -385.410502) (xy 218.349674 -385.446188)
			(xy 218.385366 -385.487373) (xy 218.414833 -385.533218) (xy 218.437476 -385.58279) (xy 218.452834 -385.63508)
			(xy 218.460594 -385.689023) (xy 218.461082 -385.716272) (xy 218.460594 -385.743332) (xy 218.452933 -385.796908)
			(xy 218.437775 -385.848862) (xy 218.415424 -385.898151) (xy 218.386329 -385.943786) (xy 218.351075 -385.984849)
			(xy 218.331034 -386.003038) (xy 218.33078 -386.003292) (xy 218.323072 -386.010796) (xy 218.314248 -386.030392)
			(xy 218.313762 -386.041138) (xy 218.313254 -386.128006) (xy 218.322144 -386.147818) (xy 218.330272 -386.155184)
			(xy 218.349929 -386.173354) (xy 218.384451 -386.214263) (xy 218.412919 -386.259594) (xy 218.434775 -386.308458)
			(xy 218.449589 -386.359896) (xy 218.457073 -386.4129) (xy 218.457526 -386.439664) (xy 218.457011 -386.466915)
			(xy 218.44926 -386.520863) (xy 218.433909 -386.573159) (xy 218.411272 -386.622738) (xy 218.38181 -386.66859)
			(xy 218.346121 -386.709783) (xy 218.304934 -386.745477) (xy 218.259085 -386.774946) (xy 218.20951 -386.79759)
			(xy 218.157216 -386.812948) (xy 218.103269 -386.820707) (xy 218.076018 -386.821172) (xy 218.049468 -386.820714)
			(xy 217.996882 -386.813336) (xy 217.945828 -386.798735) (xy 217.897294 -386.777192) (xy 217.852218 -386.749124)
			(xy 217.811471 -386.715075) (xy 217.793316 -386.695696) (xy 217.793062 -386.695442) (xy 217.785915 -386.688426)
			(xy 217.767734 -386.680069) (xy 217.757756 -386.679186) (xy 217.674698 -386.675884) (xy 217.655902 -386.682742)
			(xy 217.648282 -386.689854) (xy 217.626916 -386.70924) (xy 217.57946 -386.742042) (xy 217.527606 -386.767324)
			(xy 217.472536 -386.78451) (xy 217.415506 -386.793206) (xy 217.386662 -386.79374) (xy 217.356645 -386.793202)
			(xy 217.297355 -386.783782) (xy 217.240271 -386.765197) (xy 217.1868 -386.737904) (xy 217.138261 -386.702576)
			(xy 217.11666 -386.681726) (xy 217.109548 -386.674614) (xy 217.091768 -386.666994) (xy 217.00109 -386.66547)
			(xy 216.983056 -386.672328) (xy 216.97569 -386.679186) (xy 216.95439 -386.698218) (xy 216.907191 -386.730387)
			(xy 216.855725 -386.755164) (xy 216.801143 -386.771995) (xy 216.744661 -386.780507) (xy 216.716102 -386.78104)
			(xy 216.686306 -386.780509) (xy 216.62744 -386.771244) (xy 216.57073 -386.752937) (xy 216.517557 -386.726035)
			(xy 216.469213 -386.691193) (xy 216.426875 -386.649257) (xy 216.408762 -386.625592) (xy 216.401396 -386.615686)
			(xy 216.38006 -386.604764) (xy 216.273634 -386.605018) (xy 216.252044 -386.61594) (xy 216.244932 -386.625592)
			(xy 216.226824 -386.649353) (xy 216.184469 -386.691478) (xy 216.136064 -386.726484) (xy 216.082793 -386.753516)
			(xy 216.025959 -386.771912) (xy 215.966952 -386.781223) (xy 215.937084 -386.781802) (xy 215.908105 -386.781302)
			(xy 215.850812 -386.772538) (xy 215.795503 -386.755214) (xy 215.743448 -386.729728) (xy 215.695844 -386.696665)
			(xy 215.653785 -386.656787) (xy 215.635586 -386.634228) (xy 215.627966 -386.624322) (xy 215.605106 -386.613908)
			(xy 215.495886 -386.620512) (xy 215.474296 -386.63372) (xy 215.467946 -386.644642) (xy 215.45314 -386.668704)
			(xy 215.417522 -386.712559) (xy 215.375822 -386.750676) (xy 215.328953 -386.782222) (xy 215.277941 -386.806506)
			(xy 215.223905 -386.822995) (xy 215.168026 -386.83133) (xy 215.139778 -386.83184) (xy 215.109762 -386.831292)
			(xy 215.050472 -386.821875) (xy 214.993388 -386.803292) (xy 214.939916 -386.776001) (xy 214.891377 -386.740675)
			(xy 214.869776 -386.719826) (xy 214.862664 -386.712714) (xy 214.844884 -386.705094) (xy 214.754206 -386.70357)
			(xy 214.736172 -386.710428) (xy 214.728806 -386.717286) (xy 214.707499 -386.736311) (xy 214.660302 -386.76848)
			(xy 214.608838 -386.793259) (xy 214.554257 -386.810092) (xy 214.497777 -386.818605) (xy 214.469218 -386.81914)
			(xy 214.440741 -386.818606) (xy 214.384418 -386.810148) (xy 214.329981 -386.793403) (xy 214.278642 -386.768743)
			(xy 214.231544 -386.736718) (xy 214.189737 -386.698041) (xy 214.17153 -386.676138) (xy 214.17153 -386.675884)
			(xy 214.163342 -386.66685) (xy 214.141052 -386.657047) (xy 214.128858 -386.657088) (xy 214.046054 -386.661914)
			(xy 214.033924 -386.663342) (xy 214.012965 -386.675811) (xy 214.005922 -386.68579) (xy 213.990893 -386.708914)
			(xy 213.955204 -386.750959) (xy 213.913833 -386.787427) (xy 213.867642 -386.817557) (xy 213.817593 -386.840721)
			(xy 213.76473 -386.856436) (xy 213.710155 -386.864375) (xy 213.68258 -386.86486) (xy 213.652564 -386.864305)
			(xy 213.593275 -386.854889) (xy 213.536191 -386.836307) (xy 213.48272 -386.809018) (xy 213.43418 -386.773694)
			(xy 213.412578 -386.752846) (xy 213.405466 -386.745734) (xy 213.387686 -386.738114) (xy 213.297008 -386.73659)
			(xy 213.278974 -386.743448) (xy 213.271608 -386.750306) (xy 213.250289 -386.769317) (xy 213.203096 -386.801491)
			(xy 213.151636 -386.826274) (xy 213.097057 -386.84311) (xy 213.040578 -386.851625) (xy 213.01202 -386.85216)
			(xy 212.984765 -386.851726) (xy 212.930811 -386.84397) (xy 212.87851 -386.828615) (xy 212.828926 -386.805971)
			(xy 212.783071 -386.7765) (xy 212.741877 -386.740803) (xy 212.706183 -386.699607) (xy 212.676716 -386.653749)
			(xy 212.654076 -386.604164) (xy 212.638724 -386.551862) (xy 212.630972 -386.497907) (xy 212.630512 -386.470652)
			(xy 211.051394 -386.470652) (xy 211.051394 -388.160514) (xy 221.30132 -388.160514) (xy 221.305305 -387.979173)
			(xy 221.317251 -387.798181) (xy 221.337135 -387.617889) (xy 221.364919 -387.438645) (xy 221.40055 -387.260793)
			(xy 221.443958 -387.084679) (xy 221.49506 -386.910641) (xy 221.553758 -386.739016) (xy 221.619937 -386.570135)
			(xy 221.69347 -386.404323) (xy 221.774215 -386.241902) (xy 221.862017 -386.083183) (xy 221.956706 -385.928475)
			(xy 222.058098 -385.778075) (xy 222.165999 -385.632274) (xy 222.2802 -385.491353) (xy 222.400481 -385.355584)
			(xy 222.526609 -385.22523) (xy 222.658341 -385.100541) (xy 222.795423 -384.981759) (xy 222.93759 -384.869113)
			(xy 223.084567 -384.76282) (xy 223.236072 -384.663086) (xy 223.391811 -384.570102) (xy 223.551484 -384.484049)
			(xy 223.714783 -384.405093) (xy 223.881392 -384.333385) (xy 224.05099 -384.269065) (xy 224.22325 -384.212257)
			(xy 224.397838 -384.163069) (xy 224.574419 -384.121598) (xy 224.752651 -384.087923) (xy 224.93219 -384.062109)
			(xy 225.112689 -384.044207) (xy 225.293801 -384.034249) (xy 225.475175 -384.032257) (xy 225.656462 -384.038233)
			(xy 225.837311 -384.052167) (xy 226.017374 -384.07403) (xy 226.196302 -384.103782) (xy 226.373751 -384.141364)
			(xy 226.549378 -384.186704) (xy 226.722844 -384.239715) (xy 226.893814 -384.300294) (xy 227.061959 -384.368324)
			(xy 227.226952 -384.443674) (xy 227.388477 -384.526199) (xy 227.546221 -384.615739) (xy 227.69988 -384.712121)
			(xy 227.849157 -384.815159) (xy 227.993764 -384.924655) (xy 228.133422 -385.040397) (xy 228.267862 -385.162162)
			(xy 228.396823 -385.289714) (xy 228.520057 -385.422808) (xy 228.637326 -385.561186) (xy 228.748404 -385.704582)
			(xy 228.853076 -385.852718) (xy 228.95114 -386.005309) (xy 229.042407 -386.16206) (xy 229.126701 -386.322669)
			(xy 229.203859 -386.486825) (xy 229.273732 -386.654212) (xy 229.336186 -386.824506) (xy 229.391098 -386.997379)
			(xy 229.438365 -387.172498) (xy 229.477894 -387.349523) (xy 229.509609 -387.528114) (xy 229.53345 -387.707926)
			(xy 229.549369 -387.888611) (xy 229.557336 -388.069821) (xy 229.557834 -388.160514) (xy 229.557336 -388.251207)
			(xy 229.549369 -388.432417) (xy 229.53345 -388.613102) (xy 229.509609 -388.792914) (xy 229.477894 -388.971505)
			(xy 229.438365 -389.14853) (xy 229.391098 -389.323649) (xy 229.336186 -389.496522) (xy 229.273732 -389.666816)
			(xy 229.203859 -389.834203) (xy 229.126701 -389.998359) (xy 229.042407 -390.158968) (xy 228.95114 -390.315719)
			(xy 228.853076 -390.46831) (xy 228.748404 -390.616446) (xy 228.637326 -390.759842) (xy 228.520057 -390.89822)
			(xy 228.396823 -391.031314) (xy 228.267862 -391.158866) (xy 228.133422 -391.280631) (xy 227.993764 -391.396373)
			(xy 227.849157 -391.505869) (xy 227.69988 -391.608907) (xy 227.546221 -391.705289) (xy 227.388477 -391.794829)
			(xy 227.226952 -391.877354) (xy 227.061959 -391.952704) (xy 226.893814 -392.020734) (xy 226.722844 -392.081313)
			(xy 226.549378 -392.134324) (xy 226.373751 -392.179664) (xy 226.196302 -392.217246) (xy 226.017374 -392.246998)
			(xy 225.837311 -392.268861) (xy 225.656462 -392.282795) (xy 225.475175 -392.288771) (xy 225.293801 -392.286779)
			(xy 225.112689 -392.276821) (xy 224.93219 -392.258919) (xy 224.752651 -392.233105) (xy 224.574419 -392.19943)
			(xy 224.397838 -392.157959) (xy 224.22325 -392.108771) (xy 224.05099 -392.051963) (xy 223.881392 -391.987643)
			(xy 223.714783 -391.915935) (xy 223.551484 -391.836979) (xy 223.391811 -391.750926) (xy 223.236072 -391.657942)
			(xy 223.084567 -391.558208) (xy 222.93759 -391.451915) (xy 222.795423 -391.339269) (xy 222.658341 -391.220487)
			(xy 222.526609 -391.095798) (xy 222.400481 -390.965444) (xy 222.2802 -390.829675) (xy 222.165999 -390.688754)
			(xy 222.058098 -390.542953) (xy 221.956706 -390.392553) (xy 221.862017 -390.237845) (xy 221.774215 -390.079126)
			(xy 221.69347 -389.916705) (xy 221.619937 -389.750893) (xy 221.553758 -389.582012) (xy 221.49506 -389.410387)
			(xy 221.443958 -389.236349) (xy 221.40055 -389.060235) (xy 221.364919 -388.882383) (xy 221.337135 -388.703139)
			(xy 221.317251 -388.522847) (xy 221.305305 -388.341855) (xy 221.30132 -388.160514) (xy 211.051394 -388.160514)
			(xy 211.051394 -389.84428) (xy 211.050956 -389.854344) (xy 211.043221 -389.872926) (xy 211.036408 -389.880348)
			(xy 208.841594 -392.075162) (xy 208.834197 -392.082012) (xy 208.815599 -392.08975) (xy 208.805526 -392.090148)
			(xy 185.840878 -392.090148) (xy 185.830811 -392.090577) (xy 185.812217 -392.098302) (xy 185.80481 -392.105134)
			(xy 185.487564 -392.42238) (xy 185.483217 -392.422485) (xy 185.474657 -392.424011) (xy 185.470546 -392.425428)
			(xy 185.46572 -392.427206) (xy 185.461889 -392.429167) (xy 185.45487 -392.434147) (xy 185.45175 -392.437112)
			(xy 184.478676 -393.410186) (xy 184.475968 -393.413035) (xy 184.47137 -393.419411) (xy 184.469532 -393.422886)
			(xy 184.466952 -393.428313) (xy 184.464136 -393.439993) (xy 184.463944 -393.446) (xy 184.463944 -395.437106)
			(xy 184.465214 -395.448028) (xy 184.465214 -395.448282) (xy 184.46877 -395.458696) (xy 184.46877 -396.563088)
			(xy 184.469415 -396.575068) (xy 184.480289 -396.596414) (xy 184.489598 -396.603982) (xy 184.565544 -396.659862)
			(xy 184.588912 -396.663926) (xy 184.592976 -396.662656) (xy 184.628837 -396.651444) (xy 184.702985 -396.639322)
			(xy 184.74055 -396.638526) (xy 184.771003 -396.638999) (xy 184.83139 -396.646943) (xy 184.890223 -396.662702)
			(xy 184.946495 -396.686005) (xy 184.999244 -396.716455) (xy 185.047567 -396.75353) (xy 185.090637 -396.796595)
			(xy 185.127717 -396.844914) (xy 185.158173 -396.89766) (xy 185.181482 -396.95393) (xy 185.197247 -397.012761)
			(xy 185.205197 -397.073147) (xy 185.205197 -397.134053) (xy 185.197247 -397.194439) (xy 185.181482 -397.25327)
			(xy 185.158173 -397.30954) (xy 185.127717 -397.362286) (xy 185.090637 -397.410605) (xy 185.047567 -397.45367)
			(xy 184.999244 -397.490745) (xy 184.946495 -397.521195) (xy 184.890223 -397.544498) (xy 184.83139 -397.560257)
			(xy 184.771003 -397.568201) (xy 184.74055 -397.568674) (xy 184.703183 -397.567914) (xy 184.629418 -397.555921)
			(xy 184.593738 -397.544798) (xy 184.592214 -397.54429) (xy 184.588912 -397.543274) (xy 184.565544 -397.547338)
			(xy 184.489598 -397.603218) (xy 184.480335 -397.610821) (xy 184.469473 -397.632149) (xy 184.46877 -397.644112)
			(xy 184.46877 -398.103344) (xy 184.4692 -398.113411) (xy 184.476923 -398.132007) (xy 184.483756 -398.139412)
			(xy 185.492136 -399.147792) (xy 185.499536 -399.154634) (xy 185.518134 -399.162356) (xy 185.528204 -399.162778)
			(xy 189.128146 -399.162778) (xy 189.134218 -399.162628) (xy 189.146025 -399.159792) (xy 189.151514 -399.15719)
			(xy 189.198563 -399.131815) (xy 189.296143 -399.088146) (xy 189.397048 -399.052835) (xy 189.500565 -399.026132)
			(xy 189.60596 -399.008225) (xy 189.712487 -398.999241) (xy 189.76594 -398.998694) (xy 189.766448 -398.998694)
			(xy 189.816734 -398.999197) (xy 189.91699 -399.007169) (xy 190.016301 -399.023045) (xy 190.114045 -399.046724)
			(xy 190.209611 -399.078059) (xy 190.3024 -399.116853) (xy 190.347346 -399.13941) (xy 190.351664 -399.141696)
			(xy 190.36006 -399.144668) (xy 190.377853 -399.145179) (xy 190.394742 -399.139558) (xy 190.401956 -399.13433)
			(xy 190.406274 -399.13052) (xy 192.281048 -397.255746) (xy 192.288447 -397.248902) (xy 192.307046 -397.241178)
			(xy 192.317116 -397.24076) (xy 193.867786 -397.24076) (xy 193.871593 -397.240696) (xy 193.879121 -397.239553)
			(xy 193.882772 -397.238474) (xy 193.9036 -397.232124) (xy 193.903854 -397.23187) (xy 193.943279 -397.205627)
			(xy 194.025383 -397.1584) (xy 194.110774 -397.117417) (xy 194.198981 -397.082906) (xy 194.289512 -397.05506)
			(xy 194.381866 -397.034031) (xy 194.475529 -397.019938) (xy 194.569981 -397.012859) (xy 194.61734 -397.012414)
			(xy 194.807078 -397.012414) (xy 194.816476 -397.027908) (xy 194.86238 -397.035586) (xy 194.953009 -397.056807)
			(xy 195.041841 -397.084608) (xy 195.128398 -397.11884) (xy 195.212216 -397.159319) (xy 195.292844 -397.205827)
			(xy 195.331588 -397.231616) (xy 195.331842 -397.23187) (xy 195.338192 -397.236188) (xy 195.345304 -397.238474)
			(xy 195.349024 -397.239539) (xy 195.356676 -397.240682) (xy 195.360544 -397.24076) (xy 195.461128 -397.24076)
			(xy 195.471195 -397.24119) (xy 195.489786 -397.248918) (xy 195.497196 -397.255746) (xy 197.54342 -399.302224)
			(xy 197.549616 -399.307605) (xy 197.564515 -399.31446) (xy 197.57263 -399.315686) (xy 197.578218 -399.31594)
		)
		(stroke
			(width 0)
			(type solid)
		)
		(fill yes)
		(layer "B.Cu")
		(net "P12V_AUX")
	)
	(gr_poly
		(pts
			(xy 265.162538 -198.152766) (xy 265.174121 -198.152187) (xy 265.194948 -198.142036) (xy 265.209271 -198.123825)
			(xy 265.212322 -198.112634) (xy 265.218251 -198.087379) (xy 265.236684 -198.038889) (xy 265.262199 -197.993722)
			(xy 265.294216 -197.952905) (xy 265.332006 -197.917367) (xy 265.37471 -197.887915) (xy 265.421357 -197.865219)
			(xy 265.470887 -197.849796) (xy 265.522172 -197.841995) (xy 265.574048 -197.841995) (xy 265.625333 -197.849796)
			(xy 265.674863 -197.865219) (xy 265.72151 -197.887915) (xy 265.764214 -197.917367) (xy 265.802004 -197.952905)
			(xy 265.834021 -197.993722) (xy 265.859536 -198.038889) (xy 265.877969 -198.087379) (xy 265.883898 -198.112634)
			(xy 265.886865 -198.123872) (xy 265.901179 -198.142153) (xy 265.922071 -198.152282) (xy 265.933682 -198.152766)
			(xy 269.25524 -198.152766) (xy 269.28318 -198.129906) (xy 269.286736 -198.112126) (xy 269.292461 -198.086111)
			(xy 269.310397 -198.035954) (xy 269.335363 -197.9889) (xy 269.36684 -197.945928) (xy 269.404173 -197.907932)
			(xy 269.446585 -197.875705) (xy 269.493193 -197.849915) (xy 269.543027 -197.831101) (xy 269.59505 -197.819653)
			(xy 269.648178 -197.815811) (xy 269.701306 -197.819653) (xy 269.753329 -197.831101) (xy 269.803163 -197.849915)
			(xy 269.849771 -197.875705) (xy 269.892183 -197.907932) (xy 269.929516 -197.945928) (xy 269.960993 -197.9889)
			(xy 269.985959 -198.035954) (xy 270.003895 -198.086111) (xy 270.00962 -198.112126) (xy 270.013176 -198.129906)
			(xy 270.041116 -198.152766) (xy 272.706592 -198.152766) (xy 272.718181 -198.152197) (xy 272.739026 -198.142054)
			(xy 272.753364 -198.123839) (xy 272.756376 -198.112634) (xy 272.762305 -198.087379) (xy 272.780738 -198.038889)
			(xy 272.806253 -197.993722) (xy 272.83827 -197.952905) (xy 272.87606 -197.917367) (xy 272.918764 -197.887915)
			(xy 272.965411 -197.865219) (xy 273.014941 -197.849796) (xy 273.066226 -197.841995) (xy 273.118102 -197.841995)
			(xy 273.169387 -197.849796) (xy 273.218917 -197.865219) (xy 273.265564 -197.887915) (xy 273.308268 -197.917367)
			(xy 273.346058 -197.952905) (xy 273.378075 -197.993722) (xy 273.40359 -198.038889) (xy 273.422023 -198.087379)
			(xy 273.427952 -198.112634) (xy 273.430921 -198.123866) (xy 273.445239 -198.142132) (xy 273.466129 -198.15224)
			(xy 273.477736 -198.152766) (xy 276.799294 -198.152766) (xy 276.827234 -198.129906) (xy 276.83079 -198.112126)
			(xy 276.836515 -198.086111) (xy 276.854451 -198.035954) (xy 276.879417 -197.9889) (xy 276.910894 -197.945928)
			(xy 276.948227 -197.907932) (xy 276.990639 -197.875705) (xy 277.037247 -197.849915) (xy 277.087081 -197.831101)
			(xy 277.139104 -197.819653) (xy 277.192232 -197.815811) (xy 277.24536 -197.819653) (xy 277.297383 -197.831101)
			(xy 277.347217 -197.849915) (xy 277.393825 -197.875705) (xy 277.436237 -197.907932) (xy 277.47357 -197.945928)
			(xy 277.505047 -197.9889) (xy 277.530013 -198.035954) (xy 277.547949 -198.086111) (xy 277.553674 -198.112126)
			(xy 277.55723 -198.129906) (xy 277.58517 -198.152766) (xy 280.250392 -198.152766) (xy 280.261981 -198.152197)
			(xy 280.282826 -198.142054) (xy 280.297164 -198.123839) (xy 280.300176 -198.112634) (xy 280.306105 -198.087379)
			(xy 280.324538 -198.038889) (xy 280.350053 -197.993722) (xy 280.38207 -197.952905) (xy 280.41986 -197.917367)
			(xy 280.462564 -197.887915) (xy 280.509211 -197.865219) (xy 280.558741 -197.849796) (xy 280.610026 -197.841995)
			(xy 280.661902 -197.841995) (xy 280.713187 -197.849796) (xy 280.762717 -197.865219) (xy 280.809364 -197.887915)
			(xy 280.852068 -197.917367) (xy 280.889858 -197.952905) (xy 280.921875 -197.993722) (xy 280.94739 -198.038889)
			(xy 280.965823 -198.087379) (xy 280.971752 -198.112634) (xy 280.974721 -198.123866) (xy 280.989039 -198.142132)
			(xy 281.009929 -198.15224) (xy 281.021536 -198.152766) (xy 284.343094 -198.152766) (xy 284.371034 -198.129906)
			(xy 284.37459 -198.112126) (xy 284.380315 -198.086111) (xy 284.398251 -198.035954) (xy 284.423217 -197.9889)
			(xy 284.454694 -197.945928) (xy 284.492027 -197.907932) (xy 284.534439 -197.875705) (xy 284.581047 -197.849915)
			(xy 284.630881 -197.831101) (xy 284.682904 -197.819653) (xy 284.736032 -197.815811) (xy 284.78916 -197.819653)
			(xy 284.841183 -197.831101) (xy 284.891017 -197.849915) (xy 284.937625 -197.875705) (xy 284.980037 -197.907932)
			(xy 285.01737 -197.945928) (xy 285.048847 -197.9889) (xy 285.073813 -198.035954) (xy 285.091749 -198.086111)
			(xy 285.097474 -198.112126) (xy 285.10103 -198.129906) (xy 285.12897 -198.152766) (xy 287.794446 -198.152766)
			(xy 287.806042 -198.152206) (xy 287.826904 -198.142072) (xy 287.841257 -198.123854) (xy 287.84423 -198.112634)
			(xy 287.850159 -198.087379) (xy 287.868592 -198.038889) (xy 287.894107 -197.993722) (xy 287.926124 -197.952905)
			(xy 287.963914 -197.917367) (xy 288.006618 -197.887915) (xy 288.053265 -197.865219) (xy 288.102795 -197.849796)
			(xy 288.15408 -197.841995) (xy 288.205956 -197.841995) (xy 288.257241 -197.849796) (xy 288.306771 -197.865219)
			(xy 288.353418 -197.887915) (xy 288.396122 -197.917367) (xy 288.433912 -197.952905) (xy 288.465929 -197.993722)
			(xy 288.491444 -198.038889) (xy 288.509877 -198.087379) (xy 288.515806 -198.112634) (xy 288.518773 -198.123871)
			(xy 288.533088 -198.142149) (xy 288.55398 -198.152276) (xy 288.56559 -198.152766) (xy 291.887148 -198.152766)
			(xy 291.915088 -198.129906) (xy 291.918644 -198.112126) (xy 291.924369 -198.086111) (xy 291.942305 -198.035954)
			(xy 291.967271 -197.9889) (xy 291.998748 -197.945928) (xy 292.036081 -197.907932) (xy 292.078493 -197.875705)
			(xy 292.125101 -197.849915) (xy 292.174935 -197.831101) (xy 292.226958 -197.819653) (xy 292.280086 -197.815811)
			(xy 292.333214 -197.819653) (xy 292.385237 -197.831101) (xy 292.435071 -197.849915) (xy 292.481679 -197.875705)
			(xy 292.524091 -197.907932) (xy 292.561424 -197.945928) (xy 292.592901 -197.9889) (xy 292.617867 -198.035954)
			(xy 292.635803 -198.086111) (xy 292.641528 -198.112126) (xy 292.645084 -198.129906) (xy 292.673024 -198.152766)
			(xy 295.3385 -198.152766) (xy 295.350088 -198.152195) (xy 295.370929 -198.142051) (xy 295.385265 -198.123837)
			(xy 295.388284 -198.112634) (xy 295.394213 -198.087379) (xy 295.412646 -198.038889) (xy 295.438161 -197.993722)
			(xy 295.470178 -197.952905) (xy 295.507968 -197.917367) (xy 295.550672 -197.887915) (xy 295.597319 -197.865219)
			(xy 295.646849 -197.849796) (xy 295.698134 -197.841995) (xy 295.75001 -197.841995) (xy 295.801295 -197.849796)
			(xy 295.850825 -197.865219) (xy 295.897472 -197.887915) (xy 295.940176 -197.917367) (xy 295.977966 -197.952905)
			(xy 296.009983 -197.993722) (xy 296.035498 -198.038889) (xy 296.053931 -198.087379) (xy 296.05986 -198.112634)
			(xy 296.06283 -198.123865) (xy 296.077147 -198.142129) (xy 296.098038 -198.152234) (xy 296.109644 -198.152766)
			(xy 299.431202 -198.152766) (xy 299.459142 -198.129906) (xy 299.462698 -198.112126) (xy 299.468423 -198.086111)
			(xy 299.486359 -198.035954) (xy 299.511325 -197.9889) (xy 299.542802 -197.945928) (xy 299.580135 -197.907932)
			(xy 299.622547 -197.875705) (xy 299.669155 -197.849915) (xy 299.718989 -197.831101) (xy 299.771012 -197.819653)
			(xy 299.82414 -197.815811) (xy 299.877268 -197.819653) (xy 299.929291 -197.831101) (xy 299.979125 -197.849915)
			(xy 300.025733 -197.875705) (xy 300.068145 -197.907932) (xy 300.105478 -197.945928) (xy 300.136955 -197.9889)
			(xy 300.161921 -198.035954) (xy 300.179857 -198.086111) (xy 300.185582 -198.112126) (xy 300.189138 -198.129906)
			(xy 300.217078 -198.152766) (xy 305.497992 -198.152766) (xy 305.507865 -198.152294) (xy 305.52615 -198.144839)
			(xy 305.533552 -198.138288) (xy 305.533806 -198.138034) (xy 305.841146 -197.830694) (xy 305.841654 -197.830186)
			(xy 305.848242 -197.822807) (xy 305.855706 -197.804508) (xy 305.856132 -197.794626) (xy 305.856132 -196.04609)
			(xy 305.855708 -196.03602) (xy 305.847995 -196.017415) (xy 305.841146 -196.010022) (xy 305.786536 -195.955412)
			(xy 305.764537 -195.932824) (xy 305.725211 -195.883534) (xy 305.691655 -195.830148) (xy 305.664293 -195.773338)
			(xy 305.643467 -195.713821) (xy 305.629442 -195.652345) (xy 305.622393 -195.589684) (xy 305.621944 -195.558156)
			(xy 305.622391 -195.526191) (xy 305.629643 -195.462673) (xy 305.644059 -195.400388) (xy 305.665452 -195.340144)
			(xy 305.693547 -195.282717) (xy 305.72798 -195.228851) (xy 305.768305 -195.179243) (xy 305.790854 -195.156582)
			(xy 305.797966 -195.14947) (xy 305.80584 -195.131436) (xy 305.809262 -195.122389) (xy 305.809771 -195.103068)
			(xy 305.806856 -195.093844) (xy 305.801776 -195.080128) (xy 305.796442 -195.073524) (xy 305.776305 -195.048347)
			(xy 305.741305 -194.994201) (xy 305.712733 -194.936404) (xy 305.690964 -194.875718) (xy 305.676284 -194.812938)
			(xy 305.668887 -194.74889) (xy 305.668426 -194.716654) (xy 305.668426 -194.7164) (xy 305.668955 -194.681865)
			(xy 305.677427 -194.613315) (xy 305.694245 -194.546323) (xy 305.719154 -194.4819) (xy 305.751777 -194.421018)
			(xy 305.791621 -194.364598) (xy 305.814476 -194.338702) (xy 305.820572 -194.331844) (xy 305.827176 -194.315588)
			(xy 305.827938 -194.297808) (xy 305.823112 -194.28206) (xy 305.818286 -194.275202) (xy 305.801472 -194.250658)
			(xy 305.773316 -194.198248) (xy 305.751799 -194.14278) (xy 305.737246 -194.085093) (xy 305.729876 -194.026057)
			(xy 305.729386 -193.99631) (xy 305.729806 -193.967531) (xy 305.73669 -193.910388) (xy 305.750372 -193.85448)
			(xy 305.76012 -193.8274) (xy 305.764692 -193.815462) (xy 305.761644 -193.791078) (xy 305.70805 -193.713354)
			(xy 305.70044 -193.703681) (xy 305.678678 -193.692264) (xy 305.666394 -193.69151) (xy 304.25517 -193.69151)
			(xy 304.243193 -193.692161) (xy 304.221852 -193.703038) (xy 304.214276 -193.712338) (xy 304.168048 -193.77533)
			(xy 304.163546 -193.782057) (xy 304.158612 -193.797465) (xy 304.158396 -193.805556) (xy 304.158396 -193.824098)
			(xy 304.160682 -193.831464) (xy 304.171123 -193.867574) (xy 304.183355 -193.941741) (xy 304.185066 -193.979292)
			(xy 304.185066 -194.013582) (xy 304.18368 -194.044878) (xy 304.174822 -194.106895) (xy 304.159127 -194.167544)
			(xy 304.136791 -194.226074) (xy 304.122836 -194.25412) (xy 304.122836 -194.254374) (xy 304.119218 -194.262235)
			(xy 304.116933 -194.279378) (xy 304.120464 -194.296309) (xy 304.124614 -194.303904) (xy 304.169572 -194.378072)
			(xy 304.17439 -194.38533) (xy 304.187892 -194.396319) (xy 304.204301 -194.402133) (xy 304.213006 -194.402456)
			(xy 304.423826 -194.402456) (xy 304.455438 -194.402975) (xy 304.518122 -194.41123) (xy 304.579191 -194.427597)
			(xy 304.637602 -194.451794) (xy 304.692355 -194.483408) (xy 304.742513 -194.521899) (xy 304.787219 -194.566606)
			(xy 304.825706 -194.616767) (xy 304.857318 -194.671521) (xy 304.881512 -194.729934) (xy 304.897875 -194.791004)
			(xy 304.906127 -194.853688) (xy 304.906127 -194.916912) (xy 304.897875 -194.979596) (xy 304.881512 -195.040666)
			(xy 304.857318 -195.099079) (xy 304.825706 -195.153833) (xy 304.787219 -195.203994) (xy 304.742513 -195.248701)
			(xy 304.692355 -195.287192) (xy 304.637602 -195.318806) (xy 304.579191 -195.343003) (xy 304.518122 -195.35937)
			(xy 304.455438 -195.367625) (xy 304.423826 -195.368164) (xy 303.676812 -195.368164) (xy 303.645465 -195.367622)
			(xy 303.583307 -195.359431) (xy 303.522728 -195.343275) (xy 303.464746 -195.319425) (xy 303.410333 -195.288281)
			(xy 303.360401 -195.250366) (xy 303.337722 -195.228718) (xy 303.33442 -195.225416) (xy 303.323498 -195.21805)
			(xy 303.314862 -195.213224) (xy 303.299622 -195.20662) (xy 303.294822 -195.204728) (xy 303.284713 -195.202677)
			(xy 303.279556 -195.202556) (xy 303.059592 -195.202556) (xy 303.048214 -195.204331) (xy 303.028737 -195.216572)
			(xy 303.016624 -195.236128) (xy 303.014888 -195.247514) (xy 303.014888 -195.2625) (xy 302.970692 -195.2625)
			(xy 302.967022 -195.262543) (xy 302.959753 -195.263558) (xy 302.956214 -195.264532) (xy 302.948848 -195.266818)
			(xy 302.942752 -195.270628) (xy 302.914932 -195.287795) (xy 302.855462 -195.314935) (xy 302.792742 -195.333357)
			(xy 302.728041 -195.342688) (xy 302.695356 -195.343272) (xy 302.664682 -195.342785) (xy 302.603882 -195.334606)
			(xy 302.544717 -195.318387) (xy 302.488246 -195.294418) (xy 302.435478 -195.263128) (xy 302.41113 -195.244466)
			(xy 302.405542 -195.240148) (xy 302.38827 -195.233798) (xy 302.380874 -195.231412) (xy 302.365357 -195.23076)
			(xy 302.35779 -195.232528) (xy 302.35017 -195.23456) (xy 302.344836 -195.237354) (xy 302.317843 -195.250713)
			(xy 302.261389 -195.271698) (xy 302.20285 -195.285867) (xy 302.143048 -195.293022) (xy 302.112934 -195.293488)
			(xy 302.112426 -195.293488) (xy 302.082072 -195.293048) (xy 302.021797 -195.285823) (xy 301.962811 -195.271473)
			(xy 301.905952 -195.250201) (xy 301.852031 -195.222311) (xy 301.801815 -195.188199) (xy 301.756017 -195.148351)
			(xy 301.715289 -195.103333) (xy 301.680212 -195.053786) (xy 301.665386 -195.027296) (xy 301.658528 -195.014596)
			(xy 301.634144 -195.000372) (xy 301.543466 -195.002404) (xy 301.536546 -195.002778) (xy 301.523283 -195.006773)
			(xy 301.517304 -195.010278) (xy 301.490888 -195.027296) (xy 301.481998 -195.036948) (xy 301.478696 -195.043044)
			(xy 301.459374 -195.078884) (xy 301.411945 -195.145063) (xy 301.384208 -195.17487) (xy 301.377724 -195.182225)
			(xy 301.370384 -195.200388) (xy 301.370377 -195.219978) (xy 301.377705 -195.238145) (xy 301.384208 -195.245482)
			(xy 301.408714 -195.271722) (xy 301.451548 -195.329343) (xy 301.486683 -195.391956) (xy 301.513545 -195.45854)
			(xy 301.531696 -195.528006) (xy 301.540838 -195.599219) (xy 301.541434 -195.635118) (xy 301.540975 -195.666626)
			(xy 301.533888 -195.729243) (xy 301.519839 -195.790674) (xy 301.499004 -195.850146) (xy 301.471645 -195.906914)
			(xy 301.438106 -195.960264) (xy 301.398808 -196.009526) (xy 301.376842 -196.03212) (xy 301.003208 -196.405754)
			(xy 300.995865 -196.412571) (xy 300.977403 -196.420313) (xy 300.967394 -196.42074) (xy 300.293278 -196.42074)
			(xy 300.278097 -196.421301) (xy 300.249072 -196.430216) (xy 300.223941 -196.447255) (xy 300.204916 -196.470918)
			(xy 300.193672 -196.499122) (xy 300.191932 -196.514212) (xy 300.189239 -196.541615) (xy 300.176764 -196.595245)
			(xy 300.156463 -196.646427) (xy 300.128786 -196.694026) (xy 300.094346 -196.736987) (xy 300.053908 -196.774357)
			(xy 300.008368 -196.805307) (xy 299.958737 -196.82915) (xy 299.906116 -196.845358) (xy 299.85167 -196.853571)
			(xy 299.82414 -196.854064) (xy 299.797774 -196.853619) (xy 299.745579 -196.846119) (xy 299.694982 -196.831268)
			(xy 299.647014 -196.809366) (xy 299.602652 -196.780861) (xy 299.562798 -196.746331) (xy 299.528265 -196.706482)
			(xy 299.499754 -196.662122) (xy 299.477847 -196.614157) (xy 299.46299 -196.563562) (xy 299.455484 -196.511368)
			(xy 299.455078 -196.485002) (xy 299.455332 -196.47027) (xy 299.455314 -196.460656) (xy 299.448977 -196.44252)
			(xy 299.43641 -196.427989) (xy 299.419377 -196.419104) (xy 299.409866 -196.417692) (xy 299.377179 -196.41378)
			(xy 299.312961 -196.399288) (xy 299.250876 -196.377393) (xy 299.191773 -196.348395) (xy 299.136462 -196.312691)
			(xy 299.085702 -196.27077) (xy 299.040186 -196.223207) (xy 299.019976 -196.19722) (xy 299.012425 -196.18815)
			(xy 298.991373 -196.177543) (xy 298.97959 -196.1769) (xy 298.887642 -196.1769) (xy 298.874434 -196.18071)
			(xy 298.868338 -196.18452) (xy 298.834302 -196.203062) (xy 298.827952 -196.20611) (xy 298.817538 -196.215508)
			(xy 298.812204 -196.223636) (xy 298.800012 -196.230494) (xy 298.794289 -196.233454) (xy 298.781815 -196.236672)
			(xy 298.775374 -196.236844) (xy 298.724066 -196.236844) (xy 298.720764 -196.237352) (xy 298.707749 -196.239035)
			(xy 298.681563 -196.240817) (xy 298.66844 -196.240908) (xy 298.655317 -196.240803) (xy 298.629133 -196.239021)
			(xy 298.616116 -196.237352) (xy 298.612814 -196.236844) (xy 298.538392 -196.236844) (xy 298.516046 -196.236306)
			(xy 298.472228 -196.227514) (xy 298.430979 -196.210312) (xy 298.393897 -196.185366) (xy 298.362417 -196.153642)
			(xy 298.33776 -196.116368) (xy 298.320878 -196.074987) (xy 298.312426 -196.031101) (xy 298.312078 -196.008752)
			(xy 298.312078 -195.996306) (xy 298.30903 -195.987924) (xy 298.298586 -195.956759) (xy 298.28734 -195.892007)
			(xy 298.286678 -195.859146) (xy 298.287363 -195.826287) (xy 298.2986 -195.761536) (xy 298.30903 -195.730368)
			(xy 298.312078 -195.721986) (xy 298.312078 -195.70954) (xy 298.312465 -195.68667) (xy 298.321278 -195.641796)
			(xy 298.338917 -195.599603) (xy 298.364665 -195.561809) (xy 298.380658 -195.545456) (xy 298.388278 -195.53809)
			(xy 298.396152 -195.51904) (xy 298.395136 -195.424552) (xy 298.386754 -195.405756) (xy 298.379134 -195.398644)
			(xy 298.364148 -195.384166) (xy 298.271184 -195.291202) (xy 298.249184 -195.268614) (xy 298.209855 -195.219325)
			(xy 298.176298 -195.16594) (xy 298.148934 -195.10913) (xy 298.128108 -195.049612) (xy 298.114082 -194.988136)
			(xy 298.107033 -194.925474) (xy 298.106592 -194.893946) (xy 298.107133 -194.859743) (xy 298.115503 -194.791849)
			(xy 298.132052 -194.725474) (xy 298.156535 -194.661597) (xy 298.188591 -194.601165) (xy 298.227745 -194.545071)
			(xy 298.273418 -194.494144) (xy 298.29887 -194.47129) (xy 298.30014 -194.470274) (xy 298.305728 -194.464686)
			(xy 298.311926 -194.457871) (xy 298.319466 -194.441079) (xy 298.32046 -194.43192) (xy 298.325032 -194.360038)
			(xy 298.325794 -194.34937) (xy 298.318428 -194.329304) (xy 298.31157 -194.321684) (xy 298.291867 -194.299379)
			(xy 298.257495 -194.250794) (xy 298.229352 -194.198354) (xy 298.207867 -194.142853) (xy 298.193363 -194.085132)
			(xy 298.186061 -194.026067) (xy 298.185586 -193.99631) (xy 298.185586 -193.995802) (xy 298.185586 -193.995548)
			(xy 298.185983 -193.967545) (xy 298.192461 -193.911914) (xy 298.205347 -193.85741) (xy 298.214542 -193.830956)
			(xy 298.21632 -193.82613) (xy 298.217844 -193.815462) (xy 298.218835 -193.805992) (xy 298.214522 -193.78746)
			(xy 298.209462 -193.779394) (xy 298.163996 -193.713354) (xy 298.156341 -193.70363) (xy 298.13444 -193.692191)
			(xy 298.122086 -193.69151) (xy 296.740072 -193.69151) (xy 296.730004 -193.691939) (xy 296.711408 -193.699661)
			(xy 296.704004 -193.706496) (xy 296.656252 -193.754248) (xy 296.648886 -193.76136) (xy 296.641266 -193.780156)
			(xy 296.641266 -193.986404) (xy 296.641266 -193.987166) (xy 296.64152 -193.995548) (xy 296.64152 -193.997072)
			(xy 296.641266 -194.005454) (xy 296.641266 -194.006216) (xy 296.641266 -194.29984) (xy 296.641729 -194.309716)
			(xy 296.649174 -194.328012) (xy 296.655744 -194.3354) (xy 296.655998 -194.335654) (xy 296.707814 -194.38747)
			(xy 296.708322 -194.387978) (xy 296.715703 -194.394563) (xy 296.734001 -194.40202) (xy 296.743882 -194.402456)
			(xy 296.879772 -194.402456) (xy 296.911388 -194.402949) (xy 296.97408 -194.411199) (xy 297.035158 -194.427562)
			(xy 297.093578 -194.451757) (xy 297.148339 -194.483371) (xy 297.198506 -194.521862) (xy 297.243219 -194.566573)
			(xy 297.281714 -194.616737) (xy 297.313331 -194.671497) (xy 297.337529 -194.729916) (xy 297.353896 -194.790993)
			(xy 297.362149 -194.853684) (xy 297.362149 -194.916916) (xy 297.353896 -194.979607) (xy 297.337529 -195.040684)
			(xy 297.313331 -195.099103) (xy 297.281714 -195.153863) (xy 297.243219 -195.204027) (xy 297.198506 -195.248738)
			(xy 297.148339 -195.287229) (xy 297.093578 -195.318843) (xy 297.035158 -195.343038) (xy 296.97408 -195.359401)
			(xy 296.911388 -195.367651) (xy 296.879772 -195.368164) (xy 296.132758 -195.368164) (xy 296.10141 -195.367625)
			(xy 296.039249 -195.359439) (xy 295.978667 -195.343288) (xy 295.920681 -195.319442) (xy 295.866263 -195.288301)
			(xy 295.816326 -195.250388) (xy 295.793668 -195.228718) (xy 295.790366 -195.225416) (xy 295.779444 -195.21805)
			(xy 295.770808 -195.213224) (xy 295.755568 -195.20662) (xy 295.750767 -195.204733) (xy 295.740658 -195.202693)
			(xy 295.735502 -195.202556) (xy 295.515792 -195.202556) (xy 295.506594 -195.203873) (xy 295.490056 -195.21232)
			(xy 295.477689 -195.226172) (xy 295.471167 -195.243559) (xy 295.470834 -195.252848) (xy 295.470834 -195.2625)
			(xy 295.203118 -195.2625) (xy 295.183587 -195.262089) (xy 295.145106 -195.255379) (xy 295.108351 -195.242155)
			(xy 295.074416 -195.22281) (xy 295.0591 -195.210684) (xy 295.052496 -195.20535) (xy 295.029128 -195.19646)
			(xy 295.020238 -195.192904) (xy 294.88892 -195.192904) (xy 294.880792 -195.192904) (xy 294.865552 -195.19773)
			(xy 294.858948 -195.202302) (xy 294.833323 -195.219606) (xy 294.77868 -195.248545) (xy 294.720926 -195.270633)
			(xy 294.660918 -195.285543) (xy 294.599543 -195.293056) (xy 294.568626 -195.293488) (xy 294.568372 -195.293488)
			(xy 294.53802 -195.293045) (xy 294.477748 -195.285814) (xy 294.418766 -195.271459) (xy 294.361913 -195.250184)
			(xy 294.307997 -195.22229) (xy 294.257785 -195.188176) (xy 294.211993 -195.148327) (xy 294.17127 -195.103309)
			(xy 294.136197 -195.053763) (xy 294.121332 -195.027296) (xy 294.114474 -195.014596) (xy 294.09009 -195.000372)
			(xy 293.999412 -195.002404) (xy 293.992414 -195.002827) (xy 293.979021 -195.006948) (xy 293.972996 -195.010532)
			(xy 293.952168 -195.02374) (xy 293.942516 -195.032122) (xy 293.937944 -195.036948) (xy 293.934642 -195.043044)
			(xy 293.934388 -195.043552) (xy 293.915104 -195.079251) (xy 293.867801 -195.145172) (xy 293.840154 -195.17487)
			(xy 293.833685 -195.182188) (xy 293.826365 -195.200278) (xy 293.826378 -195.219792) (xy 293.833724 -195.237871)
			(xy 293.840154 -195.245228) (xy 293.864666 -195.271491) (xy 293.907511 -195.329156) (xy 293.942656 -195.391813)
			(xy 293.969528 -195.458437) (xy 293.987689 -195.527944) (xy 293.996844 -195.599198) (xy 293.99738 -195.635118)
			(xy 293.996921 -195.666626) (xy 293.989834 -195.729242) (xy 293.975784 -195.790672) (xy 293.954947 -195.850143)
			(xy 293.927586 -195.90691) (xy 293.894045 -195.960258) (xy 293.854744 -196.009517) (xy 293.832788 -196.03212)
			(xy 293.459154 -196.405754) (xy 293.451808 -196.412562) (xy 293.433345 -196.420285) (xy 293.42334 -196.42074)
			(xy 292.749224 -196.42074) (xy 292.734048 -196.421308) (xy 292.705037 -196.430233) (xy 292.67992 -196.447275)
			(xy 292.660906 -196.470935) (xy 292.649669 -196.499131) (xy 292.647878 -196.514212) (xy 292.645185 -196.541614)
			(xy 292.632709 -196.59524) (xy 292.612407 -196.646418) (xy 292.584729 -196.694014) (xy 292.550289 -196.73697)
			(xy 292.50985 -196.774335) (xy 292.46431 -196.805278) (xy 292.414679 -196.829115) (xy 292.362058 -196.845316)
			(xy 292.307615 -196.853521) (xy 292.280086 -196.854064) (xy 292.253724 -196.853593) (xy 292.201538 -196.846088)
			(xy 292.150951 -196.831233) (xy 292.102993 -196.809329) (xy 292.05864 -196.780824) (xy 292.018795 -196.746297)
			(xy 291.984269 -196.706451) (xy 291.955765 -196.662097) (xy 291.933863 -196.614138) (xy 291.91901 -196.56355)
			(xy 291.911506 -196.511364) (xy 291.911024 -196.485002) (xy 291.911278 -196.47027) (xy 291.91126 -196.460653)
			(xy 291.904925 -196.44251) (xy 291.892361 -196.42797) (xy 291.875328 -196.419071) (xy 291.865812 -196.417692)
			(xy 291.833141 -196.413773) (xy 291.768956 -196.399271) (xy 291.706904 -196.377372) (xy 291.647834 -196.348377)
			(xy 291.592554 -196.312682) (xy 291.541821 -196.270775) (xy 291.49633 -196.22323) (xy 291.476176 -196.19722)
			(xy 291.468625 -196.18815) (xy 291.447573 -196.177543) (xy 291.43579 -196.1769) (xy 291.343842 -196.1769)
			(xy 291.330634 -196.18071) (xy 291.324538 -196.18452) (xy 291.290502 -196.203062) (xy 291.284152 -196.20611)
			(xy 291.273738 -196.215508) (xy 291.268404 -196.223636) (xy 291.256212 -196.230494) (xy 291.250489 -196.233454)
			(xy 291.238015 -196.236672) (xy 291.231574 -196.236844) (xy 291.180266 -196.236844) (xy 291.176964 -196.237352)
			(xy 291.163949 -196.239035) (xy 291.137763 -196.240817) (xy 291.12464 -196.240908) (xy 291.111517 -196.240803)
			(xy 291.085333 -196.239021) (xy 291.072316 -196.237352) (xy 291.069014 -196.236844) (xy 290.994592 -196.236844)
			(xy 290.972246 -196.236306) (xy 290.928428 -196.227514) (xy 290.887179 -196.210312) (xy 290.850097 -196.185366)
			(xy 290.818617 -196.153642) (xy 290.79396 -196.116368) (xy 290.777078 -196.074987) (xy 290.768626 -196.031101)
			(xy 290.768278 -196.008752) (xy 290.768278 -195.996306) (xy 290.76523 -195.987924) (xy 290.754786 -195.956759)
			(xy 290.74354 -195.892007) (xy 290.742878 -195.859146) (xy 290.743563 -195.826287) (xy 290.7548 -195.761536)
			(xy 290.76523 -195.730368) (xy 290.768278 -195.721986) (xy 290.768278 -195.70954) (xy 290.768665 -195.68667)
			(xy 290.777478 -195.641796) (xy 290.795117 -195.599603) (xy 290.820865 -195.561809) (xy 290.836858 -195.545456)
			(xy 290.844478 -195.53809) (xy 290.852352 -195.51904) (xy 290.851336 -195.424552) (xy 290.842954 -195.405756)
			(xy 290.835334 -195.398644) (xy 290.820348 -195.384166) (xy 290.727384 -195.291202) (xy 290.705384 -195.268614)
			(xy 290.666055 -195.219325) (xy 290.632498 -195.16594) (xy 290.605134 -195.10913) (xy 290.584308 -195.049612)
			(xy 290.570282 -194.988136) (xy 290.563233 -194.925474) (xy 290.562792 -194.893946) (xy 290.563333 -194.859743)
			(xy 290.571703 -194.791849) (xy 290.588252 -194.725474) (xy 290.612735 -194.661597) (xy 290.644791 -194.601165)
			(xy 290.683945 -194.545071) (xy 290.729618 -194.494144) (xy 290.75507 -194.47129) (xy 290.75634 -194.470274)
			(xy 290.761928 -194.464686) (xy 290.768126 -194.457871) (xy 290.775666 -194.441079) (xy 290.77666 -194.43192)
			(xy 290.781232 -194.360038) (xy 290.781994 -194.34937) (xy 290.774628 -194.329304) (xy 290.76777 -194.321684)
			(xy 290.748067 -194.299379) (xy 290.713695 -194.250794) (xy 290.685552 -194.198354) (xy 290.664067 -194.142853)
			(xy 290.649563 -194.085132) (xy 290.642261 -194.026067) (xy 290.641786 -193.99631) (xy 290.641786 -193.995802)
			(xy 290.641786 -193.995548) (xy 290.642183 -193.967545) (xy 290.648661 -193.911914) (xy 290.661547 -193.85741)
			(xy 290.670742 -193.830956) (xy 290.67252 -193.82613) (xy 290.674044 -193.815462) (xy 290.675035 -193.805992)
			(xy 290.670722 -193.78746) (xy 290.665662 -193.779394) (xy 290.620196 -193.713354) (xy 290.612541 -193.70363)
			(xy 290.59064 -193.692191) (xy 290.578286 -193.69151) (xy 289.175952 -193.69151) (xy 289.157156 -193.69913)
			(xy 289.150044 -193.706496) (xy 289.111944 -193.744596) (xy 289.105092 -193.751992) (xy 289.097349 -193.770591)
			(xy 289.096958 -193.780664) (xy 289.096958 -194.312032) (xy 289.097419 -194.321909) (xy 289.104862 -194.340208)
			(xy 289.111436 -194.347592) (xy 289.11169 -194.347846) (xy 289.151314 -194.38747) (xy 289.151822 -194.387978)
			(xy 289.159203 -194.394563) (xy 289.177501 -194.40202) (xy 289.187382 -194.402456) (xy 289.324542 -194.402456)
			(xy 289.32505 -194.402202) (xy 289.335718 -194.402202) (xy 289.367347 -194.40272) (xy 289.430064 -194.410979)
			(xy 289.491167 -194.427354) (xy 289.54961 -194.451563) (xy 289.604392 -194.483194) (xy 289.654578 -194.521704)
			(xy 289.699308 -194.566436) (xy 289.737816 -194.616623) (xy 289.769445 -194.671407) (xy 289.793652 -194.72985)
			(xy 289.810024 -194.790953) (xy 289.818281 -194.853671) (xy 289.818281 -194.916929) (xy 289.810024 -194.979647)
			(xy 289.793652 -195.04075) (xy 289.769445 -195.099193) (xy 289.737816 -195.153977) (xy 289.699308 -195.204164)
			(xy 289.654578 -195.248896) (xy 289.604392 -195.287406) (xy 289.54961 -195.319037) (xy 289.491167 -195.343246)
			(xy 289.430064 -195.359621) (xy 289.367347 -195.36788) (xy 289.335718 -195.368418) (xy 289.32505 -195.368418)
			(xy 289.324542 -195.368164) (xy 288.588958 -195.368164) (xy 288.55761 -195.367625) (xy 288.495449 -195.359439)
			(xy 288.434867 -195.343288) (xy 288.376881 -195.319442) (xy 288.322463 -195.288301) (xy 288.272526 -195.250388)
			(xy 288.249868 -195.228718) (xy 288.246566 -195.225416) (xy 288.235644 -195.21805) (xy 288.227008 -195.213224)
			(xy 288.211768 -195.20662) (xy 288.206967 -195.204733) (xy 288.196858 -195.202693) (xy 288.191702 -195.202556)
			(xy 287.971992 -195.202556) (xy 287.962794 -195.203873) (xy 287.946256 -195.21232) (xy 287.933889 -195.226172)
			(xy 287.927367 -195.243559) (xy 287.927034 -195.252848) (xy 287.927034 -195.2625) (xy 287.659318 -195.2625)
			(xy 287.639787 -195.262089) (xy 287.601306 -195.255379) (xy 287.564551 -195.242155) (xy 287.530616 -195.22281)
			(xy 287.5153 -195.210684) (xy 287.508696 -195.20535) (xy 287.485328 -195.19646) (xy 287.476438 -195.192904)
			(xy 287.344866 -195.192904) (xy 287.336738 -195.192904) (xy 287.321498 -195.19773) (xy 287.314894 -195.202302)
			(xy 287.289269 -195.219603) (xy 287.234624 -195.248536) (xy 287.17687 -195.270618) (xy 287.116862 -195.285522)
			(xy 287.055488 -195.293028) (xy 287.024572 -195.293488) (xy 287.024318 -195.293488) (xy 286.993965 -195.293048)
			(xy 286.93369 -195.285822) (xy 286.874704 -195.271471) (xy 286.817846 -195.250198) (xy 286.763926 -195.222308)
			(xy 286.71371 -195.188196) (xy 286.667913 -195.148347) (xy 286.627186 -195.103329) (xy 286.592109 -195.053782)
			(xy 286.577278 -195.027296) (xy 286.57042 -195.014596) (xy 286.546036 -195.000372) (xy 286.455358 -195.002404)
			(xy 286.448438 -195.002779) (xy 286.435176 -195.006776) (xy 286.429196 -195.010278) (xy 286.40278 -195.027296)
			(xy 286.39389 -195.036948) (xy 286.390588 -195.043044) (xy 286.371266 -195.078884) (xy 286.323836 -195.145062)
			(xy 286.2961 -195.17487) (xy 286.289617 -195.182225) (xy 286.282277 -195.200388) (xy 286.282271 -195.219978)
			(xy 286.289598 -195.238145) (xy 286.2961 -195.245482) (xy 286.320606 -195.271722) (xy 286.363441 -195.329342)
			(xy 286.398576 -195.391956) (xy 286.425439 -195.458539) (xy 286.44359 -195.528005) (xy 286.452732 -195.599219)
			(xy 286.453326 -195.635118) (xy 286.452867 -195.666626) (xy 286.44578 -195.729243) (xy 286.431731 -195.790673)
			(xy 286.410896 -195.850146) (xy 286.383537 -195.906914) (xy 286.349997 -195.960263) (xy 286.310698 -196.009525)
			(xy 286.288734 -196.03212) (xy 285.9151 -196.405754) (xy 285.907757 -196.41257) (xy 285.889294 -196.420309)
			(xy 285.879286 -196.42074) (xy 285.20517 -196.42074) (xy 285.18999 -196.421302) (xy 285.160967 -196.430219)
			(xy 285.135838 -196.447258) (xy 285.116815 -196.470921) (xy 285.105571 -196.499124) (xy 285.103824 -196.514212)
			(xy 285.101131 -196.541615) (xy 285.088656 -196.595244) (xy 285.068355 -196.646426) (xy 285.040677 -196.694024)
			(xy 285.006238 -196.736985) (xy 284.965799 -196.774354) (xy 284.92026 -196.805303) (xy 284.870629 -196.829145)
			(xy 284.818007 -196.845351) (xy 284.763562 -196.853563) (xy 284.736032 -196.854064) (xy 284.709667 -196.853618)
			(xy 284.657472 -196.846118) (xy 284.606877 -196.831266) (xy 284.55891 -196.809364) (xy 284.514548 -196.780858)
			(xy 284.474695 -196.746329) (xy 284.440163 -196.706479) (xy 284.411653 -196.66212) (xy 284.389746 -196.614155)
			(xy 284.374889 -196.563561) (xy 284.367384 -196.511367) (xy 284.36697 -196.485002) (xy 284.367224 -196.47027)
			(xy 284.367207 -196.46065) (xy 284.360873 -196.442501) (xy 284.348312 -196.427951) (xy 284.33128 -196.419038)
			(xy 284.321758 -196.417692) (xy 284.289089 -196.41377) (xy 284.224908 -196.399263) (xy 284.16286 -196.37736)
			(xy 284.103794 -196.348361) (xy 284.048519 -196.312663) (xy 283.99779 -196.270754) (xy 283.952303 -196.223208)
			(xy 283.932122 -196.19722) (xy 283.924567 -196.188159) (xy 283.903515 -196.177574) (xy 283.891736 -196.1769)
			(xy 283.799788 -196.1769) (xy 283.78658 -196.18071) (xy 283.780484 -196.18452) (xy 283.746448 -196.203062)
			(xy 283.73959 -196.206364) (xy 283.728668 -196.21627) (xy 283.724096 -196.22389) (xy 283.711904 -196.230494)
			(xy 283.70624 -196.23343) (xy 283.693897 -196.236644) (xy 283.68752 -196.236844) (xy 283.636212 -196.236844)
			(xy 283.63291 -196.237352) (xy 283.619895 -196.239033) (xy 283.593709 -196.240811) (xy 283.580586 -196.240908)
			(xy 283.567463 -196.240805) (xy 283.541278 -196.239026) (xy 283.528262 -196.237352) (xy 283.52496 -196.236844)
			(xy 283.450538 -196.236844) (xy 283.428196 -196.236301) (xy 283.384386 -196.227501) (xy 283.343146 -196.210295)
			(xy 283.306073 -196.185347) (xy 283.274603 -196.153624) (xy 283.249952 -196.116353) (xy 283.233075 -196.074977)
			(xy 283.224626 -196.031098) (xy 283.224224 -196.008752) (xy 283.224224 -196.003418) (xy 283.221684 -195.989448)
			(xy 283.220414 -195.985638) (xy 283.21036 -195.954985) (xy 283.199501 -195.891399) (xy 283.198824 -195.859146)
			(xy 283.199497 -195.826892) (xy 283.210353 -195.763306) (xy 283.220414 -195.732654) (xy 283.221684 -195.728844)
			(xy 283.224224 -195.714874) (xy 283.224224 -195.70954) (xy 283.224611 -195.686671) (xy 283.233425 -195.641798)
			(xy 283.251067 -195.599607) (xy 283.276819 -195.561816) (xy 283.292804 -195.545456) (xy 283.300424 -195.53809)
			(xy 283.308298 -195.51904) (xy 283.307282 -195.424552) (xy 283.2989 -195.405756) (xy 283.29128 -195.398644)
			(xy 283.276294 -195.384166) (xy 283.18333 -195.291202) (xy 283.161383 -195.268623) (xy 283.12213 -195.219386)
			(xy 283.088632 -195.166066) (xy 283.061311 -195.109333) (xy 283.040509 -195.049899) (xy 283.026489 -194.98851)
			(xy 283.019426 -194.925938) (xy 283.018992 -194.894454) (xy 283.018992 -194.893946) (xy 283.018992 -194.893692)
			(xy 283.019536 -194.85911) (xy 283.028053 -194.790473) (xy 283.044933 -194.723401) (xy 283.069921 -194.658909)
			(xy 283.102638 -194.597973) (xy 283.14259 -194.541516) (xy 283.18917 -194.49039) (xy 283.21508 -194.46748)
			(xy 283.2227 -194.460622) (xy 283.232098 -194.442334) (xy 283.237178 -194.359784) (xy 283.237347 -194.354885)
			(xy 283.236064 -194.34517) (xy 283.234638 -194.34048) (xy 283.230828 -194.329304) (xy 283.223462 -194.321176)
			(xy 283.203787 -194.298904) (xy 283.169456 -194.250393) (xy 283.141336 -194.198037) (xy 283.119853 -194.142627)
			(xy 283.105331 -194.084999) (xy 283.097989 -194.026024) (xy 283.097478 -193.99631) (xy 283.097898 -193.967531)
			(xy 283.104782 -193.910388) (xy 283.118463 -193.85448) (xy 283.128212 -193.8274) (xy 283.132784 -193.815462)
			(xy 283.129736 -193.791078) (xy 283.076142 -193.713354) (xy 283.068531 -193.703682) (xy 283.04677 -193.692269)
			(xy 283.034486 -193.69151) (xy 281.675332 -193.69151) (xy 281.665268 -193.691946) (xy 281.646682 -193.699679)
			(xy 281.639264 -193.706496) (xy 281.568144 -193.777616) (xy 281.560778 -193.784728) (xy 281.553158 -193.803524)
			(xy 281.553158 -193.986404) (xy 281.553158 -193.987166) (xy 281.553412 -193.995548) (xy 281.553412 -193.997072)
			(xy 281.553158 -194.005454) (xy 281.553158 -194.006216) (xy 281.553158 -194.329812) (xy 281.553616 -194.33969)
			(xy 281.561053 -194.357994) (xy 281.567636 -194.365372) (xy 281.56789 -194.365626) (xy 281.589734 -194.38747)
			(xy 281.590242 -194.387978) (xy 281.597624 -194.394559) (xy 281.615922 -194.40201) (xy 281.625802 -194.402456)
			(xy 281.780488 -194.402456) (xy 281.780996 -194.402202) (xy 281.791664 -194.402202) (xy 281.823297 -194.402695)
			(xy 281.886022 -194.410948) (xy 281.947133 -194.427319) (xy 282.005585 -194.451527) (xy 282.060376 -194.483157)
			(xy 282.11057 -194.521668) (xy 282.155308 -194.566403) (xy 282.193823 -194.616594) (xy 282.225458 -194.671383)
			(xy 282.249669 -194.729832) (xy 282.266045 -194.790942) (xy 282.274303 -194.853667) (xy 282.274303 -194.916933)
			(xy 282.266045 -194.979658) (xy 282.249669 -195.040768) (xy 282.225458 -195.099217) (xy 282.193823 -195.154006)
			(xy 282.155308 -195.204197) (xy 282.11057 -195.248932) (xy 282.060376 -195.287443) (xy 282.005585 -195.319073)
			(xy 281.947133 -195.343281) (xy 281.886022 -195.359652) (xy 281.823297 -195.367905) (xy 281.791664 -195.368418)
			(xy 281.780996 -195.368418) (xy 281.780488 -195.368164) (xy 281.044904 -195.368164) (xy 281.013557 -195.367622)
			(xy 280.951399 -195.35943) (xy 280.890822 -195.343273) (xy 280.83284 -195.319422) (xy 280.778427 -195.288278)
			(xy 280.728496 -195.250362) (xy 280.705814 -195.228718) (xy 280.702512 -195.225416) (xy 280.69159 -195.21805)
			(xy 280.682954 -195.213224) (xy 280.667714 -195.20662) (xy 280.662914 -195.204729) (xy 280.652805 -195.202679)
			(xy 280.647648 -195.202556) (xy 280.427684 -195.202556) (xy 280.416307 -195.204333) (xy 280.396833 -195.216574)
			(xy 280.384722 -195.23613) (xy 280.38298 -195.247514) (xy 280.38298 -195.2625) (xy 280.115264 -195.2625)
			(xy 280.095735 -195.262085) (xy 280.057258 -195.255366) (xy 280.020509 -195.242135) (xy 279.98658 -195.222786)
			(xy 279.971246 -195.210684) (xy 279.964642 -195.20535) (xy 279.941274 -195.19646) (xy 279.932384 -195.192904)
			(xy 279.800812 -195.192904) (xy 279.792684 -195.192904) (xy 279.777444 -195.19773) (xy 279.77084 -195.202302)
			(xy 279.745215 -195.219606) (xy 279.690572 -195.248543) (xy 279.632818 -195.270631) (xy 279.57281 -195.28554)
			(xy 279.511434 -195.293052) (xy 279.480518 -195.293488) (xy 279.480264 -195.293488) (xy 279.44992 -195.293052)
			(xy 279.389661 -195.285838) (xy 279.330689 -195.271506) (xy 279.273841 -195.25026) (xy 279.219924 -195.2224)
			(xy 279.169706 -195.188322) (xy 279.123899 -195.148512) (xy 279.083155 -195.103534) (xy 279.048051 -195.054028)
			(xy 279.033224 -195.02755) (xy 279.02844 -195.019556) (xy 279.014331 -195.007415) (xy 278.996817 -195.001111)
			(xy 278.987504 -195.00088) (xy 278.911304 -195.002658) (xy 278.904383 -195.003028) (xy 278.891116 -195.007018)
			(xy 278.885142 -195.010532) (xy 278.858726 -195.02755) (xy 278.849836 -195.037202) (xy 278.846788 -195.043298)
			(xy 278.834106 -195.067031) (xy 278.804846 -195.112194) (xy 278.788368 -195.133468) (xy 278.787606 -195.13423)
			(xy 278.786844 -195.135246) (xy 278.778621 -195.145505) (xy 278.761342 -195.165325) (xy 278.7523 -195.17487)
			(xy 278.745837 -195.182191) (xy 278.738524 -195.200279) (xy 278.738538 -195.21979) (xy 278.745875 -195.237869)
			(xy 278.7523 -195.245228) (xy 278.77681 -195.271491) (xy 278.819651 -195.329158) (xy 278.854793 -195.391815)
			(xy 278.881664 -195.45844) (xy 278.899823 -195.527945) (xy 278.908977 -195.599199) (xy 278.909526 -195.635118)
			(xy 278.909067 -195.666626) (xy 278.90198 -195.729243) (xy 278.887931 -195.790673) (xy 278.867096 -195.850146)
			(xy 278.839737 -195.906914) (xy 278.806197 -195.960263) (xy 278.766898 -196.009525) (xy 278.744934 -196.03212)
			(xy 278.3713 -196.405754) (xy 278.363957 -196.41257) (xy 278.345494 -196.420309) (xy 278.335486 -196.42074)
			(xy 277.66137 -196.42074) (xy 277.64619 -196.421302) (xy 277.617167 -196.430219) (xy 277.592038 -196.447258)
			(xy 277.573015 -196.470921) (xy 277.561771 -196.499124) (xy 277.560024 -196.514212) (xy 277.557331 -196.541615)
			(xy 277.544856 -196.595244) (xy 277.524555 -196.646426) (xy 277.496877 -196.694024) (xy 277.462438 -196.736985)
			(xy 277.421999 -196.774354) (xy 277.37646 -196.805303) (xy 277.326829 -196.829145) (xy 277.274207 -196.845351)
			(xy 277.219762 -196.853563) (xy 277.192232 -196.854064) (xy 277.165867 -196.853618) (xy 277.113672 -196.846118)
			(xy 277.063077 -196.831266) (xy 277.01511 -196.809364) (xy 276.970748 -196.780858) (xy 276.930895 -196.746329)
			(xy 276.896363 -196.706479) (xy 276.867853 -196.66212) (xy 276.845946 -196.614155) (xy 276.831089 -196.563561)
			(xy 276.823584 -196.511367) (xy 276.82317 -196.485002) (xy 276.823424 -196.47027) (xy 276.823407 -196.46065)
			(xy 276.817073 -196.442501) (xy 276.804512 -196.427951) (xy 276.78748 -196.419038) (xy 276.777958 -196.417692)
			(xy 276.745272 -196.413779) (xy 276.681054 -196.399286) (xy 276.618969 -196.377391) (xy 276.559867 -196.348392)
			(xy 276.504557 -196.312688) (xy 276.453797 -196.270767) (xy 276.408282 -196.223203) (xy 276.388068 -196.19722)
			(xy 276.380516 -196.188151) (xy 276.359464 -196.177548) (xy 276.347682 -196.1769) (xy 276.255734 -196.1769)
			(xy 276.242526 -196.18071) (xy 276.23643 -196.18452) (xy 276.202394 -196.203062) (xy 276.196044 -196.20611)
			(xy 276.18563 -196.215508) (xy 276.180296 -196.223636) (xy 276.168104 -196.230494) (xy 276.16238 -196.233453)
			(xy 276.149907 -196.236669) (xy 276.143466 -196.236844) (xy 276.092158 -196.236844) (xy 276.088856 -196.237352)
			(xy 276.075841 -196.239035) (xy 276.049655 -196.240816) (xy 276.036532 -196.240908) (xy 276.023409 -196.240803)
			(xy 275.997225 -196.23902) (xy 275.984208 -196.237352) (xy 275.980906 -196.236844) (xy 275.906484 -196.236844)
			(xy 275.884139 -196.236305) (xy 275.840321 -196.227512) (xy 275.799074 -196.21031) (xy 275.761993 -196.185363)
			(xy 275.730515 -196.153639) (xy 275.705858 -196.116365) (xy 275.688978 -196.074985) (xy 275.680526 -196.0311)
			(xy 275.68017 -196.008752) (xy 275.68017 -195.996306) (xy 275.677122 -195.987924) (xy 275.666678 -195.956759)
			(xy 275.655432 -195.892007) (xy 275.65477 -195.859146) (xy 275.655455 -195.826287) (xy 275.666692 -195.761536)
			(xy 275.677122 -195.730368) (xy 275.68017 -195.721986) (xy 275.68017 -195.70954) (xy 275.680557 -195.68667)
			(xy 275.68937 -195.641796) (xy 275.707008 -195.599603) (xy 275.732756 -195.561808) (xy 275.74875 -195.545456)
			(xy 275.75637 -195.53809) (xy 275.764244 -195.51904) (xy 275.763228 -195.424552) (xy 275.754846 -195.405756)
			(xy 275.747226 -195.398644) (xy 275.73224 -195.384166) (xy 275.639276 -195.291202) (xy 275.617276 -195.268614)
			(xy 275.577948 -195.219325) (xy 275.544391 -195.165939) (xy 275.517027 -195.10913) (xy 275.496202 -195.049612)
			(xy 275.482176 -194.988135) (xy 275.475128 -194.925474) (xy 275.474684 -194.893946) (xy 275.475225 -194.859743)
			(xy 275.483596 -194.791851) (xy 275.500147 -194.725478) (xy 275.524633 -194.661604) (xy 275.556693 -194.601175)
			(xy 275.595851 -194.545086) (xy 275.641528 -194.494164) (xy 275.666962 -194.47129) (xy 275.668232 -194.470274)
			(xy 275.67382 -194.464686) (xy 275.680019 -194.457872) (xy 275.68756 -194.441079) (xy 275.688552 -194.43192)
			(xy 275.693124 -194.360038) (xy 275.693886 -194.34937) (xy 275.68652 -194.329304) (xy 275.679662 -194.321684)
			(xy 275.65996 -194.299379) (xy 275.625588 -194.250794) (xy 275.597446 -194.198353) (xy 275.57596 -194.142852)
			(xy 275.561457 -194.085132) (xy 275.554155 -194.026067) (xy 275.553678 -193.99631) (xy 275.553678 -193.995802)
			(xy 275.553678 -193.995548) (xy 275.554075 -193.967545) (xy 275.560553 -193.911914) (xy 275.573439 -193.85741)
			(xy 275.582634 -193.830956) (xy 275.584412 -193.82613) (xy 275.585936 -193.815462) (xy 275.586927 -193.805992)
			(xy 275.582614 -193.787461) (xy 275.577554 -193.779394) (xy 275.532088 -193.713354) (xy 275.524432 -193.703632)
			(xy 275.502532 -193.692196) (xy 275.490178 -193.69151) (xy 274.079208 -193.69151) (xy 274.067226 -193.692153)
			(xy 274.045872 -193.70302) (xy 274.038314 -193.712338) (xy 273.992086 -193.77533) (xy 273.987581 -193.782056)
			(xy 273.982643 -193.797465) (xy 273.982434 -193.805556) (xy 273.982434 -193.816478) (xy 273.98472 -193.831464)
			(xy 273.994805 -193.866096) (xy 274.007038 -193.937184) (xy 274.009104 -193.973196) (xy 274.009104 -194.019932)
			(xy 274.007404 -194.050425) (xy 273.99821 -194.110803) (xy 273.98253 -194.169831) (xy 273.960547 -194.226812)
			(xy 273.946874 -194.25412) (xy 273.946874 -194.254374) (xy 273.943254 -194.262235) (xy 273.940967 -194.279378)
			(xy 273.944501 -194.296309) (xy 273.948652 -194.303904) (xy 273.99361 -194.378072) (xy 273.99843 -194.385326)
			(xy 274.011933 -194.396304) (xy 274.028341 -194.402106) (xy 274.037044 -194.402456) (xy 274.247864 -194.402456)
			(xy 274.27948 -194.402948) (xy 274.342173 -194.411197) (xy 274.403252 -194.427559) (xy 274.461673 -194.451754)
			(xy 274.516435 -194.483368) (xy 274.566603 -194.521859) (xy 274.611317 -194.56657) (xy 274.649812 -194.616735)
			(xy 274.68143 -194.671495) (xy 274.705629 -194.729914) (xy 274.721996 -194.790992) (xy 274.730249 -194.853684)
			(xy 274.730249 -194.916916) (xy 274.721996 -194.979608) (xy 274.705629 -195.040686) (xy 274.68143 -195.099105)
			(xy 274.649812 -195.153865) (xy 274.611317 -195.20403) (xy 274.566603 -195.248741) (xy 274.516435 -195.287232)
			(xy 274.461673 -195.318846) (xy 274.403252 -195.343041) (xy 274.342173 -195.359403) (xy 274.27948 -195.367652)
			(xy 274.247864 -195.368164) (xy 273.50085 -195.368164) (xy 273.469502 -195.367625) (xy 273.407341 -195.359438)
			(xy 273.34676 -195.343285) (xy 273.288775 -195.319439) (xy 273.234358 -195.288298) (xy 273.184422 -195.250384)
			(xy 273.16176 -195.228718) (xy 273.158458 -195.225416) (xy 273.147536 -195.21805) (xy 273.1389 -195.213224)
			(xy 273.12366 -195.20662) (xy 273.118859 -195.204734) (xy 273.10875 -195.202695) (xy 273.103594 -195.202556)
			(xy 272.883884 -195.202556) (xy 272.874687 -195.203875) (xy 272.858151 -195.212322) (xy 272.845787 -195.226175)
			(xy 272.839266 -195.24356) (xy 272.838926 -195.252848) (xy 272.838926 -195.2625) (xy 272.57121 -195.2625)
			(xy 272.551679 -195.262088) (xy 272.513199 -195.255377) (xy 272.476445 -195.242152) (xy 272.44251 -195.222807)
			(xy 272.427192 -195.210684) (xy 272.420588 -195.20535) (xy 272.39722 -195.19646) (xy 272.38833 -195.192904)
			(xy 272.257012 -195.192904) (xy 272.248884 -195.192904) (xy 272.233644 -195.19773) (xy 272.22704 -195.202302)
			(xy 272.201415 -195.219606) (xy 272.146772 -195.248543) (xy 272.089018 -195.270631) (xy 272.02901 -195.28554)
			(xy 271.967634 -195.293052) (xy 271.936718 -195.293488) (xy 271.936464 -195.293488) (xy 271.906109 -195.29305)
			(xy 271.845831 -195.285829) (xy 271.786842 -195.271482) (xy 271.72998 -195.250213) (xy 271.676055 -195.222325)
			(xy 271.625835 -195.188215) (xy 271.580034 -195.148367) (xy 271.539303 -195.103349) (xy 271.504222 -195.053802)
			(xy 271.489424 -195.027296) (xy 271.482566 -195.014596) (xy 271.458182 -195.000372) (xy 271.367504 -195.002404)
			(xy 271.360582 -195.002773) (xy 271.347314 -195.00676) (xy 271.341342 -195.010278) (xy 271.314926 -195.027296)
			(xy 271.306036 -195.036948) (xy 271.302734 -195.043044) (xy 271.283413 -195.078885) (xy 271.235987 -195.145066)
			(xy 271.208246 -195.17487) (xy 271.201758 -195.182223) (xy 271.194412 -195.200387) (xy 271.194405 -195.219979)
			(xy 271.201739 -195.238147) (xy 271.208246 -195.245482) (xy 271.23275 -195.271722) (xy 271.275582 -195.329344)
			(xy 271.310714 -195.391958) (xy 271.337575 -195.458542) (xy 271.355724 -195.528007) (xy 271.364865 -195.599219)
			(xy 271.365472 -195.635118) (xy 271.365013 -195.666626) (xy 271.357926 -195.729242) (xy 271.343875 -195.790672)
			(xy 271.323039 -195.850143) (xy 271.295678 -195.906909) (xy 271.262136 -195.960257) (xy 271.222834 -196.009515)
			(xy 271.20088 -196.03212) (xy 270.827246 -196.405754) (xy 270.8199 -196.412561) (xy 270.801437 -196.420281)
			(xy 270.791432 -196.42074) (xy 270.117316 -196.42074) (xy 270.102141 -196.42131) (xy 270.073132 -196.430236)
			(xy 270.048017 -196.447278) (xy 270.029005 -196.470938) (xy 270.017769 -196.499133) (xy 270.01597 -196.514212)
			(xy 270.013277 -196.541614) (xy 270.000801 -196.595239) (xy 269.980499 -196.646417) (xy 269.952821 -196.694012)
			(xy 269.91838 -196.736968) (xy 269.877941 -196.774331) (xy 269.832401 -196.805274) (xy 269.78277 -196.82911)
			(xy 269.73015 -196.845309) (xy 269.675707 -196.853513) (xy 269.648178 -196.854064) (xy 269.621817 -196.853592)
			(xy 269.569631 -196.846086) (xy 269.519045 -196.83123) (xy 269.471088 -196.809327) (xy 269.426736 -196.780821)
			(xy 269.386892 -196.746294) (xy 269.352367 -196.706448) (xy 269.323864 -196.662095) (xy 269.301963 -196.614136)
			(xy 269.287109 -196.563549) (xy 269.279606 -196.511363) (xy 269.279116 -196.485002) (xy 269.27937 -196.47027)
			(xy 269.279352 -196.460653) (xy 269.273016 -196.442512) (xy 269.260451 -196.427974) (xy 269.243419 -196.419077)
			(xy 269.233904 -196.417692) (xy 269.201216 -196.413782) (xy 269.136995 -196.399293) (xy 269.074907 -196.377402)
			(xy 269.015801 -196.348406) (xy 268.960488 -196.312704) (xy 268.909723 -196.270785) (xy 268.864204 -196.223222)
			(xy 268.844014 -196.19722) (xy 268.836459 -196.18816) (xy 268.815406 -196.177579) (xy 268.803628 -196.1769)
			(xy 268.71168 -196.1769) (xy 268.698472 -196.18071) (xy 268.692376 -196.18452) (xy 268.65834 -196.203062)
			(xy 268.651482 -196.206364) (xy 268.64056 -196.21627) (xy 268.635988 -196.22389) (xy 268.623796 -196.230494)
			(xy 268.618131 -196.233429) (xy 268.605789 -196.236642) (xy 268.599412 -196.236844) (xy 268.548104 -196.236844)
			(xy 268.544802 -196.237352) (xy 268.531787 -196.239033) (xy 268.505601 -196.24081) (xy 268.492478 -196.240908)
			(xy 268.479355 -196.240804) (xy 268.45317 -196.239025) (xy 268.440154 -196.237352) (xy 268.436852 -196.236844)
			(xy 268.36243 -196.236844) (xy 268.340089 -196.2363) (xy 268.296279 -196.227499) (xy 268.255041 -196.210292)
			(xy 268.21797 -196.185344) (xy 268.1865 -196.153621) (xy 268.161851 -196.116351) (xy 268.144975 -196.074976)
			(xy 268.136526 -196.031097) (xy 268.136116 -196.008752) (xy 268.136116 -196.003418) (xy 268.133576 -195.989448)
			(xy 268.132306 -195.985638) (xy 268.122252 -195.954985) (xy 268.111393 -195.891399) (xy 268.110716 -195.859146)
			(xy 268.111389 -195.826892) (xy 268.122245 -195.763306) (xy 268.132306 -195.732654) (xy 268.133576 -195.728844)
			(xy 268.136116 -195.714874) (xy 268.136116 -195.70954) (xy 268.136503 -195.686671) (xy 268.145317 -195.641797)
			(xy 268.162959 -195.599607) (xy 268.18871 -195.561815) (xy 268.204696 -195.545456) (xy 268.212316 -195.53809)
			(xy 268.22019 -195.51904) (xy 268.219174 -195.424552) (xy 268.210792 -195.405756) (xy 268.203172 -195.398644)
			(xy 268.188186 -195.384166) (xy 268.095222 -195.291202) (xy 268.073275 -195.268623) (xy 268.034022 -195.219386)
			(xy 268.000525 -195.166066) (xy 267.973204 -195.109332) (xy 267.952403 -195.049898) (xy 267.938383 -194.98851)
			(xy 267.93132 -194.925938) (xy 267.930884 -194.894454) (xy 267.930884 -194.893946) (xy 267.930884 -194.893692)
			(xy 267.931428 -194.85911) (xy 267.939945 -194.790473) (xy 267.956825 -194.723401) (xy 267.981813 -194.658909)
			(xy 268.014529 -194.597973) (xy 268.05448 -194.541514) (xy 268.101061 -194.490388) (xy 268.126972 -194.46748)
			(xy 268.134592 -194.460622) (xy 268.14399 -194.442334) (xy 268.14907 -194.359784) (xy 268.149239 -194.354885)
			(xy 268.147956 -194.34517) (xy 268.14653 -194.34048) (xy 268.14272 -194.329304) (xy 268.135354 -194.321176)
			(xy 268.115679 -194.298904) (xy 268.081349 -194.250393) (xy 268.05323 -194.198037) (xy 268.031747 -194.142626)
			(xy 268.017225 -194.084998) (xy 268.009883 -194.026024) (xy 268.00937 -193.99631) (xy 268.00979 -193.967531)
			(xy 268.016674 -193.910388) (xy 268.030355 -193.85448) (xy 268.040104 -193.8274) (xy 268.044676 -193.815462)
			(xy 268.041628 -193.791078) (xy 267.988034 -193.713354) (xy 267.980423 -193.703683) (xy 267.958661 -193.692274)
			(xy 267.946378 -193.69151) (xy 266.535154 -193.69151) (xy 266.523167 -193.692143) (xy 266.501797 -193.702999)
			(xy 266.49426 -193.712338) (xy 266.448032 -193.77533) (xy 266.443531 -193.782057) (xy 266.438598 -193.797466)
			(xy 266.43838 -193.805556) (xy 266.43838 -193.824098) (xy 266.440666 -193.831464) (xy 266.451105 -193.867575)
			(xy 266.463335 -193.941742) (xy 266.46505 -193.979292) (xy 266.46505 -194.013582) (xy 266.463664 -194.044878)
			(xy 266.454805 -194.106895) (xy 266.43911 -194.167544) (xy 266.416774 -194.226073) (xy 266.40282 -194.25412)
			(xy 266.40282 -194.254374) (xy 266.399203 -194.262235) (xy 266.396919 -194.279378) (xy 266.400448 -194.296308)
			(xy 266.404598 -194.303904) (xy 266.449556 -194.378072) (xy 266.454373 -194.385332) (xy 266.467875 -194.396325)
			(xy 266.484284 -194.402144) (xy 266.49299 -194.402456) (xy 266.70381 -194.402456) (xy 266.735423 -194.402974)
			(xy 266.798108 -194.411227) (xy 266.859179 -194.427593) (xy 266.917592 -194.451789) (xy 266.972347 -194.483403)
			(xy 267.022507 -194.521893) (xy 267.067214 -194.566601) (xy 267.105703 -194.616762) (xy 267.137315 -194.671517)
			(xy 267.161511 -194.72993) (xy 267.177875 -194.791002) (xy 267.186127 -194.853687) (xy 267.186127 -194.916913)
			(xy 267.177875 -194.979598) (xy 267.161511 -195.04067) (xy 267.137315 -195.099083) (xy 267.105703 -195.153838)
			(xy 267.067214 -195.203999) (xy 267.022507 -195.248707) (xy 266.972347 -195.287197) (xy 266.917592 -195.318811)
			(xy 266.859179 -195.343007) (xy 266.798108 -195.359373) (xy 266.735423 -195.367626) (xy 266.70381 -195.368164)
			(xy 265.956796 -195.368164) (xy 265.925449 -195.367621) (xy 265.863292 -195.359428) (xy 265.802715 -195.34327)
			(xy 265.744734 -195.319419) (xy 265.690322 -195.288274) (xy 265.640392 -195.250358) (xy 265.617706 -195.228718)
			(xy 265.614404 -195.225416) (xy 265.603482 -195.21805) (xy 265.594846 -195.213224) (xy 265.579606 -195.20662)
			(xy 265.574806 -195.20473) (xy 265.564697 -195.202682) (xy 265.55954 -195.202556) (xy 265.339576 -195.202556)
			(xy 265.3282 -195.204334) (xy 265.308729 -195.216577) (xy 265.296621 -195.236131) (xy 265.294872 -195.247514)
			(xy 265.294872 -195.2625) (xy 265.027156 -195.2625) (xy 265.007627 -195.262084) (xy 264.969151 -195.255364)
			(xy 264.932403 -195.242132) (xy 264.898475 -195.222782) (xy 264.883138 -195.210684) (xy 264.876534 -195.20535)
			(xy 264.853166 -195.19646) (xy 264.844276 -195.192904) (xy 264.712958 -195.192904) (xy 264.70483 -195.192904)
			(xy 264.68959 -195.19773) (xy 264.682986 -195.202302) (xy 264.65736 -195.219603) (xy 264.602716 -195.248535)
			(xy 264.544962 -195.270616) (xy 264.484954 -195.285519) (xy 264.42358 -195.293024) (xy 264.392664 -195.293488)
			(xy 264.39241 -195.293488) (xy 264.361552 -195.293005) (xy 264.300295 -195.285495) (xy 264.270236 -195.278502)
			(xy 264.258806 -195.275708) (xy 264.235946 -195.280534) (xy 264.16381 -195.336668) (xy 264.162032 -195.337938)
			(xy 264.157439 -195.342134) (xy 264.150247 -195.352281) (xy 264.147808 -195.358004) (xy 264.143998 -195.367656)
			(xy 264.143998 -196.446648) (xy 264.144611 -196.457932) (xy 264.154241 -196.478346) (xy 264.16254 -196.486018)
			(xy 264.184753 -196.504838) (xy 264.224712 -196.547181) (xy 264.258984 -196.594246) (xy 264.287015 -196.645274)
			(xy 264.308356 -196.699443) (xy 264.32266 -196.755879) (xy 264.326624 -196.784722) (xy 264.326624 -196.785484)
			(xy 264.328402 -196.79666) (xy 264.328402 -196.802502) (xy 264.328656 -196.804534) (xy 264.329926 -196.83984)
			(xy 264.328656 -196.875146) (xy 264.328402 -196.877178) (xy 264.328402 -197.33514) (xy 265.178809 -197.33514)
			(xy 265.182744 -197.281369) (xy 265.194467 -197.228745) (xy 265.213727 -197.178388) (xy 265.240113 -197.131371)
			(xy 265.273065 -197.088698) (xy 265.311878 -197.051277) (xy 265.355726 -197.019907) (xy 265.403674 -196.995255)
			(xy 265.454701 -196.977847) (xy 265.507719 -196.968054) (xy 265.561598 -196.966085) (xy 265.615189 -196.971982)
			(xy 265.66735 -196.985618) (xy 265.71697 -197.006705) (xy 265.762991 -197.034791) (xy 265.804433 -197.069279)
			(xy 265.840411 -197.109433) (xy 265.870159 -197.154397) (xy 265.893044 -197.203214) (xy 265.908576 -197.254843)
			(xy 265.916426 -197.308183) (xy 265.916918 -197.33514) (xy 269.304265 -197.33514) (xy 269.308295 -197.282642)
			(xy 269.320292 -197.231374) (xy 269.339975 -197.182539) (xy 269.366881 -197.13728) (xy 269.400381 -197.096659)
			(xy 269.439689 -197.061628) (xy 269.483884 -197.033008) (xy 269.531929 -197.011469) (xy 269.5827 -196.997517)
			(xy 269.635005 -196.991479) (xy 269.687619 -196.993496) (xy 269.739309 -197.00352) (xy 269.788862 -197.021318)
			(xy 269.835118 -197.046471) (xy 269.876992 -197.07839) (xy 269.913504 -197.116328) (xy 269.943796 -197.159394)
			(xy 269.967159 -197.206579) (xy 269.983045 -197.256778) (xy 269.991082 -197.308814) (xy 269.991586 -197.33514)
			(xy 272.722863 -197.33514) (xy 272.726798 -197.281369) (xy 272.738521 -197.228745) (xy 272.757781 -197.178388)
			(xy 272.784167 -197.131371) (xy 272.817119 -197.088698) (xy 272.855932 -197.051277) (xy 272.89978 -197.019907)
			(xy 272.947728 -196.995255) (xy 272.998755 -196.977847) (xy 273.051773 -196.968054) (xy 273.105652 -196.966085)
			(xy 273.159243 -196.971982) (xy 273.211404 -196.985618) (xy 273.261024 -197.006705) (xy 273.307045 -197.034791)
			(xy 273.348487 -197.069279) (xy 273.384465 -197.109433) (xy 273.414213 -197.154397) (xy 273.437098 -197.203214)
			(xy 273.45263 -197.254843) (xy 273.46048 -197.308183) (xy 273.460972 -197.33514) (xy 276.848319 -197.33514)
			(xy 276.852349 -197.282642) (xy 276.864346 -197.231374) (xy 276.884029 -197.182539) (xy 276.910935 -197.13728)
			(xy 276.944435 -197.096659) (xy 276.983743 -197.061628) (xy 277.027938 -197.033008) (xy 277.075983 -197.011469)
			(xy 277.126754 -196.997517) (xy 277.179059 -196.991479) (xy 277.231673 -196.993496) (xy 277.283363 -197.00352)
			(xy 277.332916 -197.021318) (xy 277.379172 -197.046471) (xy 277.421046 -197.07839) (xy 277.457558 -197.116328)
			(xy 277.48785 -197.159394) (xy 277.511213 -197.206579) (xy 277.527099 -197.256778) (xy 277.535136 -197.308814)
			(xy 277.53564 -197.33514) (xy 280.266663 -197.33514) (xy 280.270598 -197.281369) (xy 280.282321 -197.228745)
			(xy 280.301581 -197.178388) (xy 280.327967 -197.131371) (xy 280.360919 -197.088698) (xy 280.399732 -197.051277)
			(xy 280.44358 -197.019907) (xy 280.491528 -196.995255) (xy 280.542555 -196.977847) (xy 280.595573 -196.968054)
			(xy 280.649452 -196.966085) (xy 280.703043 -196.971982) (xy 280.755204 -196.985618) (xy 280.804824 -197.006705)
			(xy 280.850845 -197.034791) (xy 280.892287 -197.069279) (xy 280.928265 -197.109433) (xy 280.958013 -197.154397)
			(xy 280.980898 -197.203214) (xy 280.99643 -197.254843) (xy 281.00428 -197.308183) (xy 281.004772 -197.33514)
			(xy 284.392119 -197.33514) (xy 284.396149 -197.282642) (xy 284.408146 -197.231374) (xy 284.427829 -197.182539)
			(xy 284.454735 -197.13728) (xy 284.488235 -197.096659) (xy 284.527543 -197.061628) (xy 284.571738 -197.033008)
			(xy 284.619783 -197.011469) (xy 284.670554 -196.997517) (xy 284.722859 -196.991479) (xy 284.775473 -196.993496)
			(xy 284.827163 -197.00352) (xy 284.876716 -197.021318) (xy 284.922972 -197.046471) (xy 284.964846 -197.07839)
			(xy 285.001358 -197.116328) (xy 285.03165 -197.159394) (xy 285.055013 -197.206579) (xy 285.070899 -197.256778)
			(xy 285.078936 -197.308814) (xy 285.07944 -197.33514) (xy 287.810717 -197.33514) (xy 287.814652 -197.281369)
			(xy 287.826375 -197.228745) (xy 287.845635 -197.178388) (xy 287.872021 -197.131371) (xy 287.904973 -197.088698)
			(xy 287.943786 -197.051277) (xy 287.987634 -197.019907) (xy 288.035582 -196.995255) (xy 288.086609 -196.977847)
			(xy 288.139627 -196.968054) (xy 288.193506 -196.966085) (xy 288.247097 -196.971982) (xy 288.299258 -196.985618)
			(xy 288.348878 -197.006705) (xy 288.394899 -197.034791) (xy 288.436341 -197.069279) (xy 288.472319 -197.109433)
			(xy 288.502067 -197.154397) (xy 288.524952 -197.203214) (xy 288.540484 -197.254843) (xy 288.548334 -197.308183)
			(xy 288.548826 -197.33514) (xy 291.936173 -197.33514) (xy 291.940203 -197.282642) (xy 291.9522 -197.231374)
			(xy 291.971883 -197.182539) (xy 291.998789 -197.13728) (xy 292.032289 -197.096659) (xy 292.071597 -197.061628)
			(xy 292.115792 -197.033008) (xy 292.163837 -197.011469) (xy 292.214608 -196.997517) (xy 292.266913 -196.991479)
			(xy 292.319527 -196.993496) (xy 292.371217 -197.00352) (xy 292.42077 -197.021318) (xy 292.467026 -197.046471)
			(xy 292.5089 -197.07839) (xy 292.545412 -197.116328) (xy 292.575704 -197.159394) (xy 292.599067 -197.206579)
			(xy 292.614953 -197.256778) (xy 292.62299 -197.308814) (xy 292.623494 -197.33514) (xy 295.354771 -197.33514)
			(xy 295.358706 -197.281369) (xy 295.370429 -197.228745) (xy 295.389689 -197.178388) (xy 295.416075 -197.131371)
			(xy 295.449027 -197.088698) (xy 295.48784 -197.051277) (xy 295.531688 -197.019907) (xy 295.579636 -196.995255)
			(xy 295.630663 -196.977847) (xy 295.683681 -196.968054) (xy 295.73756 -196.966085) (xy 295.791151 -196.971982)
			(xy 295.843312 -196.985618) (xy 295.892932 -197.006705) (xy 295.938953 -197.034791) (xy 295.980395 -197.069279)
			(xy 296.016373 -197.109433) (xy 296.046121 -197.154397) (xy 296.069006 -197.203214) (xy 296.084538 -197.254843)
			(xy 296.092388 -197.308183) (xy 296.09288 -197.33514) (xy 299.480227 -197.33514) (xy 299.484257 -197.282642)
			(xy 299.496254 -197.231374) (xy 299.515937 -197.182539) (xy 299.542843 -197.13728) (xy 299.576343 -197.096659)
			(xy 299.615651 -197.061628) (xy 299.659846 -197.033008) (xy 299.707891 -197.011469) (xy 299.758662 -196.997517)
			(xy 299.810967 -196.991479) (xy 299.863581 -196.993496) (xy 299.915271 -197.00352) (xy 299.964824 -197.021318)
			(xy 300.01108 -197.046471) (xy 300.052954 -197.07839) (xy 300.089466 -197.116328) (xy 300.119758 -197.159394)
			(xy 300.143121 -197.206579) (xy 300.159007 -197.256778) (xy 300.167044 -197.308814) (xy 300.167548 -197.33514)
			(xy 302.898825 -197.33514) (xy 302.90276 -197.281369) (xy 302.914483 -197.228745) (xy 302.933743 -197.178388)
			(xy 302.960129 -197.131371) (xy 302.993081 -197.088698) (xy 303.031894 -197.051277) (xy 303.075742 -197.019907)
			(xy 303.12369 -196.995255) (xy 303.174717 -196.977847) (xy 303.227735 -196.968054) (xy 303.281614 -196.966085)
			(xy 303.335205 -196.971982) (xy 303.387366 -196.985618) (xy 303.436986 -197.006705) (xy 303.483007 -197.034791)
			(xy 303.524449 -197.069279) (xy 303.560427 -197.109433) (xy 303.590175 -197.154397) (xy 303.61306 -197.203214)
			(xy 303.628592 -197.254843) (xy 303.636442 -197.308183) (xy 303.636934 -197.33514) (xy 303.636442 -197.362097)
			(xy 303.628592 -197.415437) (xy 303.61306 -197.467066) (xy 303.590175 -197.515883) (xy 303.560427 -197.560847)
			(xy 303.524449 -197.601001) (xy 303.483007 -197.635489) (xy 303.436986 -197.663575) (xy 303.387366 -197.684662)
			(xy 303.335205 -197.698298) (xy 303.281614 -197.704195) (xy 303.227735 -197.702226) (xy 303.174717 -197.692433)
			(xy 303.12369 -197.675025) (xy 303.075742 -197.650373) (xy 303.031894 -197.619003) (xy 302.993081 -197.581582)
			(xy 302.960129 -197.538909) (xy 302.933743 -197.491892) (xy 302.914483 -197.441535) (xy 302.90276 -197.388911)
			(xy 302.898825 -197.33514) (xy 300.167548 -197.33514) (xy 300.167044 -197.361466) (xy 300.159007 -197.413502)
			(xy 300.143121 -197.463701) (xy 300.119758 -197.510886) (xy 300.089466 -197.553952) (xy 300.052954 -197.59189)
			(xy 300.01108 -197.623809) (xy 299.964824 -197.648962) (xy 299.915271 -197.66676) (xy 299.863581 -197.676784)
			(xy 299.810967 -197.678801) (xy 299.758662 -197.672763) (xy 299.707891 -197.658811) (xy 299.659846 -197.637272)
			(xy 299.615651 -197.608652) (xy 299.576343 -197.573621) (xy 299.542843 -197.533) (xy 299.515937 -197.487741)
			(xy 299.496254 -197.438906) (xy 299.484257 -197.387638) (xy 299.480227 -197.33514) (xy 296.09288 -197.33514)
			(xy 296.092388 -197.362097) (xy 296.084538 -197.415437) (xy 296.069006 -197.467066) (xy 296.046121 -197.515883)
			(xy 296.016373 -197.560847) (xy 295.980395 -197.601001) (xy 295.938953 -197.635489) (xy 295.892932 -197.663575)
			(xy 295.843312 -197.684662) (xy 295.791151 -197.698298) (xy 295.73756 -197.704195) (xy 295.683681 -197.702226)
			(xy 295.630663 -197.692433) (xy 295.579636 -197.675025) (xy 295.531688 -197.650373) (xy 295.48784 -197.619003)
			(xy 295.449027 -197.581582) (xy 295.416075 -197.538909) (xy 295.389689 -197.491892) (xy 295.370429 -197.441535)
			(xy 295.358706 -197.388911) (xy 295.354771 -197.33514) (xy 292.623494 -197.33514) (xy 292.62299 -197.361466)
			(xy 292.614953 -197.413502) (xy 292.599067 -197.463701) (xy 292.575704 -197.510886) (xy 292.545412 -197.553952)
			(xy 292.5089 -197.59189) (xy 292.467026 -197.623809) (xy 292.42077 -197.648962) (xy 292.371217 -197.66676)
			(xy 292.319527 -197.676784) (xy 292.266913 -197.678801) (xy 292.214608 -197.672763) (xy 292.163837 -197.658811)
			(xy 292.115792 -197.637272) (xy 292.071597 -197.608652) (xy 292.032289 -197.573621) (xy 291.998789 -197.533)
			(xy 291.971883 -197.487741) (xy 291.9522 -197.438906) (xy 291.940203 -197.387638) (xy 291.936173 -197.33514)
			(xy 288.548826 -197.33514) (xy 288.548334 -197.362097) (xy 288.540484 -197.415437) (xy 288.524952 -197.467066)
			(xy 288.502067 -197.515883) (xy 288.472319 -197.560847) (xy 288.436341 -197.601001) (xy 288.394899 -197.635489)
			(xy 288.348878 -197.663575) (xy 288.299258 -197.684662) (xy 288.247097 -197.698298) (xy 288.193506 -197.704195)
			(xy 288.139627 -197.702226) (xy 288.086609 -197.692433) (xy 288.035582 -197.675025) (xy 287.987634 -197.650373)
			(xy 287.943786 -197.619003) (xy 287.904973 -197.581582) (xy 287.872021 -197.538909) (xy 287.845635 -197.491892)
			(xy 287.826375 -197.441535) (xy 287.814652 -197.388911) (xy 287.810717 -197.33514) (xy 285.07944 -197.33514)
			(xy 285.078936 -197.361466) (xy 285.070899 -197.413502) (xy 285.055013 -197.463701) (xy 285.03165 -197.510886)
			(xy 285.001358 -197.553952) (xy 284.964846 -197.59189) (xy 284.922972 -197.623809) (xy 284.876716 -197.648962)
			(xy 284.827163 -197.66676) (xy 284.775473 -197.676784) (xy 284.722859 -197.678801) (xy 284.670554 -197.672763)
			(xy 284.619783 -197.658811) (xy 284.571738 -197.637272) (xy 284.527543 -197.608652) (xy 284.488235 -197.573621)
			(xy 284.454735 -197.533) (xy 284.427829 -197.487741) (xy 284.408146 -197.438906) (xy 284.396149 -197.387638)
			(xy 284.392119 -197.33514) (xy 281.004772 -197.33514) (xy 281.00428 -197.362097) (xy 280.99643 -197.415437)
			(xy 280.980898 -197.467066) (xy 280.958013 -197.515883) (xy 280.928265 -197.560847) (xy 280.892287 -197.601001)
			(xy 280.850845 -197.635489) (xy 280.804824 -197.663575) (xy 280.755204 -197.684662) (xy 280.703043 -197.698298)
			(xy 280.649452 -197.704195) (xy 280.595573 -197.702226) (xy 280.542555 -197.692433) (xy 280.491528 -197.675025)
			(xy 280.44358 -197.650373) (xy 280.399732 -197.619003) (xy 280.360919 -197.581582) (xy 280.327967 -197.538909)
			(xy 280.301581 -197.491892) (xy 280.282321 -197.441535) (xy 280.270598 -197.388911) (xy 280.266663 -197.33514)
			(xy 277.53564 -197.33514) (xy 277.535136 -197.361466) (xy 277.527099 -197.413502) (xy 277.511213 -197.463701)
			(xy 277.48785 -197.510886) (xy 277.457558 -197.553952) (xy 277.421046 -197.59189) (xy 277.379172 -197.623809)
			(xy 277.332916 -197.648962) (xy 277.283363 -197.66676) (xy 277.231673 -197.676784) (xy 277.179059 -197.678801)
			(xy 277.126754 -197.672763) (xy 277.075983 -197.658811) (xy 277.027938 -197.637272) (xy 276.983743 -197.608652)
			(xy 276.944435 -197.573621) (xy 276.910935 -197.533) (xy 276.884029 -197.487741) (xy 276.864346 -197.438906)
			(xy 276.852349 -197.387638) (xy 276.848319 -197.33514) (xy 273.460972 -197.33514) (xy 273.46048 -197.362097)
			(xy 273.45263 -197.415437) (xy 273.437098 -197.467066) (xy 273.414213 -197.515883) (xy 273.384465 -197.560847)
			(xy 273.348487 -197.601001) (xy 273.307045 -197.635489) (xy 273.261024 -197.663575) (xy 273.211404 -197.684662)
			(xy 273.159243 -197.698298) (xy 273.105652 -197.704195) (xy 273.051773 -197.702226) (xy 272.998755 -197.692433)
			(xy 272.947728 -197.675025) (xy 272.89978 -197.650373) (xy 272.855932 -197.619003) (xy 272.817119 -197.581582)
			(xy 272.784167 -197.538909) (xy 272.757781 -197.491892) (xy 272.738521 -197.441535) (xy 272.726798 -197.388911)
			(xy 272.722863 -197.33514) (xy 269.991586 -197.33514) (xy 269.991082 -197.361466) (xy 269.983045 -197.413502)
			(xy 269.967159 -197.463701) (xy 269.943796 -197.510886) (xy 269.913504 -197.553952) (xy 269.876992 -197.59189)
			(xy 269.835118 -197.623809) (xy 269.788862 -197.648962) (xy 269.739309 -197.66676) (xy 269.687619 -197.676784)
			(xy 269.635005 -197.678801) (xy 269.5827 -197.672763) (xy 269.531929 -197.658811) (xy 269.483884 -197.637272)
			(xy 269.439689 -197.608652) (xy 269.400381 -197.573621) (xy 269.366881 -197.533) (xy 269.339975 -197.487741)
			(xy 269.320292 -197.438906) (xy 269.308295 -197.387638) (xy 269.304265 -197.33514) (xy 265.916918 -197.33514)
			(xy 265.916426 -197.362097) (xy 265.908576 -197.415437) (xy 265.893044 -197.467066) (xy 265.870159 -197.515883)
			(xy 265.840411 -197.560847) (xy 265.804433 -197.601001) (xy 265.762991 -197.635489) (xy 265.71697 -197.663575)
			(xy 265.66735 -197.684662) (xy 265.615189 -197.698298) (xy 265.561598 -197.704195) (xy 265.507719 -197.702226)
			(xy 265.454701 -197.692433) (xy 265.403674 -197.675025) (xy 265.355726 -197.650373) (xy 265.311878 -197.619003)
			(xy 265.273065 -197.581582) (xy 265.240113 -197.538909) (xy 265.213727 -197.491892) (xy 265.194467 -197.441535)
			(xy 265.182744 -197.388911) (xy 265.178809 -197.33514) (xy 264.328402 -197.33514) (xy 264.328402 -197.53834)
			(xy 264.328866 -197.548215) (xy 264.336315 -197.566508) (xy 264.34288 -197.5739) (xy 264.343134 -197.574154)
			(xy 264.90676 -198.13778) (xy 264.907268 -198.138288) (xy 264.914652 -198.144864) (xy 264.93295 -198.152304)
			(xy 264.942828 -198.152766)
		)
		(stroke
			(width 0)
			(type solid)
		)
		(fill yes)
		(layer "B.Cu")
		(net "P3V3")
	)
	(gr_poly
		(pts
			(xy 415.999676 -198.328534) (xy 416.01021 -198.327946) (xy 416.029479 -198.31941) (xy 416.037014 -198.312024)
			(xy 416.094926 -198.248778) (xy 416.101784 -198.228458) (xy 416.100768 -198.21779) (xy 416.099244 -198.185024)
			(xy 416.09976 -198.157424) (xy 416.107987 -198.102841) (xy 416.124257 -198.050094) (xy 416.148207 -198.000362)
			(xy 416.179302 -197.954754) (xy 416.216847 -197.91429) (xy 416.260004 -197.879873) (xy 416.307808 -197.852274)
			(xy 416.359192 -197.832107) (xy 416.413007 -197.819824) (xy 416.468052 -197.815699) (xy 416.523097 -197.819824)
			(xy 416.576912 -197.832107) (xy 416.628296 -197.852274) (xy 416.6761 -197.879873) (xy 416.719257 -197.91429)
			(xy 416.756802 -197.954754) (xy 416.787897 -198.000362) (xy 416.811847 -198.050094) (xy 416.828117 -198.102841)
			(xy 416.836344 -198.157424) (xy 416.83686 -198.185024) (xy 416.835336 -198.21779) (xy 416.83432 -198.228458)
			(xy 416.841178 -198.248778) (xy 416.89909 -198.312024) (xy 416.906585 -198.319465) (xy 416.92588 -198.327993)
			(xy 416.936428 -198.328534) (xy 419.469316 -198.328534) (xy 419.479855 -198.327958) (xy 419.499141 -198.319437)
			(xy 419.506654 -198.312024) (xy 419.564312 -198.24827) (xy 419.57117 -198.228204) (xy 419.570154 -198.217282)
			(xy 419.56863 -198.185024) (xy 419.56911 -198.159325) (xy 419.576771 -198.108501) (xy 419.59192 -198.059387)
			(xy 419.614221 -198.013079) (xy 419.643174 -197.970612) (xy 419.678134 -197.932935) (xy 419.718318 -197.900889)
			(xy 419.76283 -197.87519) (xy 419.810675 -197.856413) (xy 419.860784 -197.844975) (xy 419.912038 -197.841135)
			(xy 419.963292 -197.844975) (xy 420.013401 -197.856413) (xy 420.061246 -197.87519) (xy 420.105758 -197.900889)
			(xy 420.145942 -197.932935) (xy 420.180902 -197.970612) (xy 420.209855 -198.013079) (xy 420.232156 -198.059387)
			(xy 420.247305 -198.108501) (xy 420.254966 -198.159325) (xy 420.255446 -198.185024) (xy 420.253922 -198.217282)
			(xy 420.252906 -198.228204) (xy 420.259764 -198.24827) (xy 420.317422 -198.312024) (xy 420.324919 -198.31946)
			(xy 420.344214 -198.327976) (xy 420.35476 -198.328534) (xy 423.54373 -198.328534) (xy 423.554268 -198.327955)
			(xy 423.57355 -198.319431) (xy 423.581068 -198.312024) (xy 423.63898 -198.248778) (xy 423.645838 -198.228458)
			(xy 423.644822 -198.21779) (xy 423.643298 -198.185024) (xy 423.643814 -198.157424) (xy 423.652041 -198.102841)
			(xy 423.668311 -198.050094) (xy 423.692261 -198.000362) (xy 423.723356 -197.954754) (xy 423.760901 -197.91429)
			(xy 423.804058 -197.879873) (xy 423.851862 -197.852274) (xy 423.903246 -197.832107) (xy 423.957061 -197.819824)
			(xy 424.012106 -197.815699) (xy 424.067151 -197.819824) (xy 424.120966 -197.832107) (xy 424.17235 -197.852274)
			(xy 424.220154 -197.879873) (xy 424.263311 -197.91429) (xy 424.300856 -197.954754) (xy 424.331951 -198.000362)
			(xy 424.355901 -198.050094) (xy 424.372171 -198.102841) (xy 424.380398 -198.157424) (xy 424.380914 -198.185024)
			(xy 424.37939 -198.21779) (xy 424.378374 -198.228458) (xy 424.385232 -198.248778) (xy 424.443144 -198.312024)
			(xy 424.450642 -198.319457) (xy 424.469937 -198.327964) (xy 424.480482 -198.328534) (xy 427.01337 -198.328534)
			(xy 427.023904 -198.327947) (xy 427.043175 -198.319413) (xy 427.050708 -198.312024) (xy 427.108366 -198.24827)
			(xy 427.115224 -198.228204) (xy 427.114208 -198.217282) (xy 427.112684 -198.185024) (xy 427.113164 -198.159325)
			(xy 427.120825 -198.108501) (xy 427.135974 -198.059387) (xy 427.158275 -198.013079) (xy 427.187228 -197.970612)
			(xy 427.222188 -197.932935) (xy 427.262372 -197.900889) (xy 427.306884 -197.87519) (xy 427.354729 -197.856413)
			(xy 427.404838 -197.844975) (xy 427.456092 -197.841135) (xy 427.507346 -197.844975) (xy 427.557455 -197.856413)
			(xy 427.6053 -197.87519) (xy 427.649812 -197.900889) (xy 427.689996 -197.932935) (xy 427.724956 -197.970612)
			(xy 427.753909 -198.013079) (xy 427.77621 -198.059387) (xy 427.791359 -198.108501) (xy 427.79902 -198.159325)
			(xy 427.7995 -198.185024) (xy 427.797976 -198.217282) (xy 427.79696 -198.228204) (xy 427.803818 -198.24827)
			(xy 427.861476 -198.312024) (xy 427.86897 -198.319467) (xy 427.888265 -198.328001) (xy 427.898814 -198.328534)
			(xy 431.087784 -198.328534) (xy 431.098317 -198.327945) (xy 431.117584 -198.319407) (xy 431.125122 -198.312024)
			(xy 431.183034 -198.248778) (xy 431.189892 -198.228458) (xy 431.188876 -198.21779) (xy 431.187352 -198.185024)
			(xy 431.187868 -198.157424) (xy 431.196095 -198.102841) (xy 431.212365 -198.050094) (xy 431.236315 -198.000362)
			(xy 431.26741 -197.954754) (xy 431.304955 -197.91429) (xy 431.348112 -197.879873) (xy 431.395916 -197.852274)
			(xy 431.4473 -197.832107) (xy 431.501115 -197.819824) (xy 431.55616 -197.815699) (xy 431.611205 -197.819824)
			(xy 431.66502 -197.832107) (xy 431.716404 -197.852274) (xy 431.764208 -197.879873) (xy 431.807365 -197.91429)
			(xy 431.84491 -197.954754) (xy 431.876005 -198.000362) (xy 431.899955 -198.050094) (xy 431.916225 -198.102841)
			(xy 431.924452 -198.157424) (xy 431.924968 -198.185024) (xy 431.923444 -198.21779) (xy 431.922428 -198.228458)
			(xy 431.929286 -198.248778) (xy 431.987198 -198.312024) (xy 431.994694 -198.319464) (xy 432.013988 -198.327989)
			(xy 432.024536 -198.328534) (xy 434.557424 -198.328534) (xy 434.567962 -198.327956) (xy 434.587246 -198.319433)
			(xy 434.594762 -198.312024) (xy 434.65242 -198.24827) (xy 434.659278 -198.228204) (xy 434.658262 -198.217282)
			(xy 434.656738 -198.185024) (xy 434.657218 -198.159325) (xy 434.664879 -198.108501) (xy 434.680028 -198.059387)
			(xy 434.702329 -198.013079) (xy 434.731282 -197.970612) (xy 434.766242 -197.932935) (xy 434.806426 -197.900889)
			(xy 434.850938 -197.87519) (xy 434.898783 -197.856413) (xy 434.948892 -197.844975) (xy 435.000146 -197.841135)
			(xy 435.0514 -197.844975) (xy 435.101509 -197.856413) (xy 435.149354 -197.87519) (xy 435.193866 -197.900889)
			(xy 435.23405 -197.932935) (xy 435.26901 -197.970612) (xy 435.297963 -198.013079) (xy 435.320264 -198.059387)
			(xy 435.335413 -198.108501) (xy 435.343074 -198.159325) (xy 435.343554 -198.185024) (xy 435.34203 -198.217282)
			(xy 435.341014 -198.228204) (xy 435.347872 -198.24827) (xy 435.40553 -198.312024) (xy 435.413027 -198.319459)
			(xy 435.432322 -198.327972) (xy 435.442868 -198.328534) (xy 438.631838 -198.328534) (xy 438.642375 -198.327953)
			(xy 438.661655 -198.319427) (xy 438.669176 -198.312024) (xy 438.727088 -198.248778) (xy 438.733946 -198.228458)
			(xy 438.73293 -198.21779) (xy 438.731406 -198.185024) (xy 438.731922 -198.157424) (xy 438.740149 -198.102841)
			(xy 438.756419 -198.050094) (xy 438.780369 -198.000362) (xy 438.811464 -197.954754) (xy 438.849009 -197.91429)
			(xy 438.892166 -197.879873) (xy 438.93997 -197.852274) (xy 438.991354 -197.832107) (xy 439.045169 -197.819824)
			(xy 439.100214 -197.815699) (xy 439.155259 -197.819824) (xy 439.209074 -197.832107) (xy 439.260458 -197.852274)
			(xy 439.308262 -197.879873) (xy 439.351419 -197.91429) (xy 439.388964 -197.954754) (xy 439.420059 -198.000362)
			(xy 439.444009 -198.050094) (xy 439.460279 -198.102841) (xy 439.468506 -198.157424) (xy 439.469022 -198.185024)
			(xy 439.467498 -198.21779) (xy 439.466482 -198.228458) (xy 439.47334 -198.248778) (xy 439.531252 -198.312024)
			(xy 439.538745 -198.319471) (xy 439.55804 -198.328014) (xy 439.56859 -198.328534) (xy 442.101478 -198.328534)
			(xy 442.112011 -198.327946) (xy 442.13128 -198.319409) (xy 442.138816 -198.312024) (xy 442.196474 -198.24827)
			(xy 442.203332 -198.228204) (xy 442.202316 -198.217282) (xy 442.200792 -198.185024) (xy 442.201272 -198.159325)
			(xy 442.208933 -198.108501) (xy 442.224082 -198.059387) (xy 442.246383 -198.013079) (xy 442.275336 -197.970612)
			(xy 442.310296 -197.932935) (xy 442.35048 -197.900889) (xy 442.394992 -197.87519) (xy 442.442837 -197.856413)
			(xy 442.492946 -197.844975) (xy 442.5442 -197.841135) (xy 442.595454 -197.844975) (xy 442.645563 -197.856413)
			(xy 442.693408 -197.87519) (xy 442.73792 -197.900889) (xy 442.778104 -197.932935) (xy 442.813064 -197.970612)
			(xy 442.842017 -198.013079) (xy 442.864318 -198.059387) (xy 442.879467 -198.108501) (xy 442.887128 -198.159325)
			(xy 442.887608 -198.185024) (xy 442.886084 -198.217282) (xy 442.885068 -198.228204) (xy 442.891926 -198.24827)
			(xy 442.949584 -198.312024) (xy 442.957079 -198.319466) (xy 442.976374 -198.327997) (xy 442.986922 -198.328534)
			(xy 446.175892 -198.328534) (xy 446.186424 -198.327943) (xy 446.205689 -198.319403) (xy 446.21323 -198.312024)
			(xy 446.271142 -198.248778) (xy 446.278 -198.228458) (xy 446.276984 -198.21779) (xy 446.27546 -198.185024)
			(xy 446.275976 -198.157424) (xy 446.284203 -198.102841) (xy 446.300473 -198.050094) (xy 446.324423 -198.000362)
			(xy 446.355518 -197.954754) (xy 446.393063 -197.91429) (xy 446.43622 -197.879873) (xy 446.484024 -197.852274)
			(xy 446.535408 -197.832107) (xy 446.589223 -197.819824) (xy 446.644268 -197.815699) (xy 446.699313 -197.819824)
			(xy 446.753128 -197.832107) (xy 446.804512 -197.852274) (xy 446.852316 -197.879873) (xy 446.895473 -197.91429)
			(xy 446.933018 -197.954754) (xy 446.964113 -198.000362) (xy 446.988063 -198.050094) (xy 447.004333 -198.102841)
			(xy 447.01256 -198.157424) (xy 447.013076 -198.185024) (xy 447.011552 -198.21779) (xy 447.010536 -198.228458)
			(xy 447.017394 -198.248778) (xy 447.075306 -198.312024) (xy 447.082802 -198.319462) (xy 447.102097 -198.327984)
			(xy 447.112644 -198.328534) (xy 449.645278 -198.328534) (xy 449.655811 -198.327946) (xy 449.67508 -198.319409)
			(xy 449.682616 -198.312024) (xy 449.740274 -198.24827) (xy 449.747132 -198.228204) (xy 449.746116 -198.217282)
			(xy 449.744592 -198.185024) (xy 449.745072 -198.159325) (xy 449.752733 -198.108501) (xy 449.767882 -198.059387)
			(xy 449.790183 -198.013079) (xy 449.819136 -197.970612) (xy 449.854096 -197.932935) (xy 449.89428 -197.900889)
			(xy 449.938792 -197.87519) (xy 449.986637 -197.856413) (xy 450.036746 -197.844975) (xy 450.088 -197.841135)
			(xy 450.139254 -197.844975) (xy 450.189363 -197.856413) (xy 450.237208 -197.87519) (xy 450.28172 -197.900889)
			(xy 450.321904 -197.932935) (xy 450.356864 -197.970612) (xy 450.385817 -198.013079) (xy 450.408118 -198.059387)
			(xy 450.423267 -198.108501) (xy 450.430928 -198.159325) (xy 450.431408 -198.185024) (xy 450.429884 -198.217282)
			(xy 450.428868 -198.228204) (xy 450.435726 -198.24827) (xy 450.493384 -198.312024) (xy 450.500879 -198.319466)
			(xy 450.520174 -198.327997) (xy 450.530722 -198.328534) (xy 452.337678 -198.328534) (xy 452.34774 -198.328095)
			(xy 452.366318 -198.320353) (xy 452.373746 -198.313548) (xy 452.706994 -197.9803) (xy 452.713841 -197.972902)
			(xy 452.721577 -197.954304) (xy 452.72198 -197.944232) (xy 452.72198 -196.22262) (xy 452.717916 -196.20865)
			(xy 452.713598 -196.2023) (xy 452.701775 -196.183452) (xy 452.685001 -196.142248) (xy 452.676598 -196.098562)
			(xy 452.67626 -196.076316) (xy 452.67626 -196.064124) (xy 452.673466 -196.055742) (xy 452.662957 -196.024522)
			(xy 452.65159 -195.959643) (xy 452.65086 -195.92671) (xy 452.651575 -195.893776) (xy 452.662944 -195.828895)
			(xy 452.673466 -195.797678) (xy 452.67626 -195.789296) (xy 452.67626 -195.777104) (xy 452.676458 -195.760947)
			(xy 452.680915 -195.728943) (xy 452.68515 -195.71335) (xy 452.687414 -195.703888) (xy 452.6854 -195.684554)
			(xy 452.676286 -195.667385) (xy 452.669148 -195.660772) (xy 452.64377 -195.638594) (xy 452.597958 -195.58916)
			(xy 452.55839 -195.534599) (xy 452.525635 -195.475695) (xy 452.500164 -195.413295) (xy 452.482343 -195.348296)
			(xy 452.472428 -195.281631) (xy 452.470561 -195.214259) (xy 452.47677 -195.147147) (xy 452.490964 -195.08126)
			(xy 452.512941 -195.017546) (xy 452.542383 -194.956919) (xy 452.578869 -194.90025) (xy 452.621874 -194.848355)
			(xy 452.646034 -194.824858) (xy 452.65319 -194.817381) (xy 452.661313 -194.798368) (xy 452.661782 -194.788028)
			(xy 452.661782 -194.257168) (xy 452.661556 -194.25013) (xy 452.657685 -194.236596) (xy 452.654162 -194.230498)
			(xy 452.638361 -194.204001) (xy 452.613417 -194.147577) (xy 452.596498 -194.08825) (xy 452.587928 -194.027156)
			(xy 452.58736 -193.99631) (xy 452.587816 -193.967165) (xy 452.595428 -193.909375) (xy 452.610522 -193.853074)
			(xy 452.632841 -193.799227) (xy 452.662001 -193.748755) (xy 452.697503 -193.702525) (xy 452.738739 -193.661328)
			(xy 452.761604 -193.64325) (xy 452.774558 -193.633344) (xy 452.783956 -193.602102) (xy 452.747888 -193.495676)
			(xy 452.743992 -193.485846) (xy 452.729744 -193.470252) (xy 452.71044 -193.461678) (xy 452.699882 -193.461132)
			(xy 451.348094 -193.461132) (xy 451.34149 -193.46291) (xy 451.317517 -193.469092) (xy 451.268454 -193.475719)
			(xy 451.218946 -193.475719) (xy 451.169883 -193.469092) (xy 451.14591 -193.46291) (xy 451.139306 -193.461132)
			(xy 450.945504 -193.461132) (xy 450.934392 -193.461686) (xy 450.914226 -193.471028) (xy 450.906642 -193.479166)
			(xy 450.90207 -193.4845) (xy 450.860922 -193.574416) (xy 450.857213 -193.58346) (xy 450.856242 -193.602965)
			(xy 450.862676 -193.621404) (xy 450.868796 -193.629026) (xy 450.888977 -193.653054) (xy 450.924447 -193.704818)
			(xy 450.953926 -193.760213) (xy 450.977049 -193.818549) (xy 450.993525 -193.879098) (xy 451.003151 -193.941106)
			(xy 451.00494 -193.972434) (xy 451.00494 -194.019932) (xy 451.002896 -194.055037) (xy 450.991159 -194.124371)
			(xy 450.970872 -194.191701) (xy 450.942351 -194.255978) (xy 450.924676 -194.286378) (xy 450.917564 -194.298316)
			(xy 450.917056 -194.325494) (xy 450.967348 -194.414648) (xy 450.972061 -194.422303) (xy 450.985723 -194.43397)
			(xy 451.002563 -194.44023) (xy 451.011544 -194.440556) (xy 451.2437 -194.440556) (xy 451.274086 -194.441075)
			(xy 451.334292 -194.44935) (xy 451.39281 -194.465746) (xy 451.44855 -194.489957) (xy 451.500475 -194.521533)
			(xy 451.547616 -194.559885) (xy 451.589096 -194.6043) (xy 451.624142 -194.653948) (xy 451.652101 -194.707907)
			(xy 451.672452 -194.765169) (xy 451.684816 -194.82467) (xy 451.688964 -194.8853) (xy 451.684816 -194.94593)
			(xy 451.672452 -195.005431) (xy 451.652101 -195.062693) (xy 451.624142 -195.116652) (xy 451.589096 -195.1663)
			(xy 451.547616 -195.210715) (xy 451.500475 -195.249067) (xy 451.44855 -195.280643) (xy 451.39281 -195.304854)
			(xy 451.334292 -195.32125) (xy 451.274086 -195.329525) (xy 451.2437 -195.330064) (xy 450.496686 -195.330064)
			(xy 450.464136 -195.329479) (xy 450.399735 -195.319952) (xy 450.337414 -195.301132) (xy 450.278504 -195.273422)
			(xy 450.251068 -195.255896) (xy 450.242178 -195.25107) (xy 450.2404 -195.250308) (xy 450.222276 -195.243694)
			(xy 450.188437 -195.22517) (xy 450.17309 -195.213478) (xy 450.166206 -195.208453) (xy 450.150111 -195.20288)
			(xy 450.141594 -195.202556) (xy 449.885308 -195.202556) (xy 449.876672 -195.2029) (xy 449.860389 -195.208658)
			(xy 449.846959 -195.219518) (xy 449.842128 -195.226686) (xy 449.838601 -195.232783) (xy 449.834723 -195.246317)
			(xy 449.834508 -195.253356) (xy 449.834508 -195.2625) (xy 449.566792 -195.2625) (xy 449.547304 -195.262092)
			(xy 449.508906 -195.255416) (xy 449.472217 -195.242262) (xy 449.438324 -195.223019) (xy 449.423028 -195.210938)
			(xy 449.416678 -195.205604) (xy 449.383912 -195.192904) (xy 449.032122 -195.192904) (xy 449.002333 -195.192187)
			(xy 448.943876 -195.180684) (xy 448.916044 -195.170044) (xy 448.912488 -195.168774) (xy 448.897502 -195.164964)
			(xy 448.893946 -195.16471) (xy 448.866079 -195.161377) (xy 448.811678 -195.147585) (xy 448.759881 -195.125979)
			(xy 448.711804 -195.097025) (xy 448.668483 -195.061345) (xy 448.630851 -195.01971) (xy 448.599718 -194.973014)
			(xy 448.575755 -194.922265) (xy 448.559478 -194.868555) (xy 448.551237 -194.813041) (xy 448.550792 -194.78498)
			(xy 448.551229 -194.758747) (xy 448.55842 -194.706775) (xy 448.572662 -194.656279) (xy 448.593688 -194.608209)
			(xy 448.621102 -194.563474) (xy 448.637406 -194.542918) (xy 448.643756 -194.535044) (xy 448.649598 -194.51574)
			(xy 448.643502 -194.455034) (xy 448.642282 -194.446431) (xy 448.634878 -194.430722) (xy 448.629024 -194.4243)
			(xy 448.625976 -194.421252) (xy 448.624706 -194.420236) (xy 448.596258 -194.393566) (xy 448.54495 -194.342004)
			(xy 448.544442 -194.341496) (xy 448.524376 -194.32143) (xy 448.501008 -194.298062) (xy 448.488054 -194.29095)
			(xy 448.480942 -194.289426) (xy 448.455898 -194.283914) (xy 448.406345 -194.270698) (xy 448.381882 -194.26301)
			(xy 448.374277 -194.260889) (xy 448.358499 -194.260889) (xy 448.350894 -194.26301) (xy 448.2973 -194.278504)
			(xy 448.2846 -194.281806) (xy 448.266058 -194.299078) (xy 448.230498 -194.40398) (xy 448.234816 -194.429126)
			(xy 448.24269 -194.439286) (xy 448.261453 -194.463969) (xy 448.294017 -194.516732) (xy 448.320574 -194.57276)
			(xy 448.3408 -194.631371) (xy 448.35445 -194.691854) (xy 448.361357 -194.753471) (xy 448.361816 -194.784472)
			(xy 448.361816 -194.799204) (xy 448.361562 -194.801236) (xy 448.361562 -194.802506) (xy 448.3608 -194.818254)
			(xy 448.358424 -194.850253) (xy 448.347315 -194.913453) (xy 448.329082 -194.974977) (xy 448.303963 -195.034024)
			(xy 448.272284 -195.089828) (xy 448.234458 -195.141662) (xy 448.190975 -195.188852) (xy 448.166998 -195.210176)
			(xy 448.192728 -195.233077) (xy 448.238972 -195.284131) (xy 448.278622 -195.340459) (xy 448.31108 -195.401216)
			(xy 448.335861 -195.465488) (xy 448.35259 -195.53231) (xy 448.361017 -195.600676) (xy 448.361562 -195.635118)
			(xy 448.361103 -195.666626) (xy 448.354015 -195.729242) (xy 448.339965 -195.790671) (xy 448.319128 -195.850142)
			(xy 448.291767 -195.906908) (xy 448.258224 -195.960255) (xy 448.218923 -196.009514) (xy 448.19697 -196.03212)
			(xy 447.80708 -196.422264) (xy 447.007742 -196.422264) (xy 447.010228 -196.437702) (xy 447.012898 -196.468859)
			(xy 447.013076 -196.484494) (xy 447.013076 -196.485002) (xy 447.01256 -196.512602) (xy 447.004333 -196.567185)
			(xy 446.988063 -196.619932) (xy 446.964113 -196.669665) (xy 446.933018 -196.715272) (xy 446.895473 -196.755736)
			(xy 446.852316 -196.790153) (xy 446.804512 -196.817752) (xy 446.753128 -196.837919) (xy 446.699313 -196.850202)
			(xy 446.644268 -196.854327) (xy 446.589223 -196.850202) (xy 446.535408 -196.837919) (xy 446.484024 -196.817752)
			(xy 446.43622 -196.790153) (xy 446.393063 -196.755736) (xy 446.355518 -196.715272) (xy 446.324423 -196.669665)
			(xy 446.300473 -196.619932) (xy 446.284203 -196.567185) (xy 446.275976 -196.512602) (xy 446.27546 -196.485002)
			(xy 446.27546 -196.484748) (xy 446.275622 -196.469049) (xy 446.278291 -196.437763) (xy 446.280794 -196.422264)
			(xy 446.247212 -196.421301) (xy 446.180626 -196.412352) (xy 446.115583 -196.395527) (xy 446.053009 -196.371067)
			(xy 445.993799 -196.33932) (xy 445.938797 -196.300739) (xy 445.888787 -196.255875) (xy 445.844484 -196.205368)
			(xy 445.825118 -196.177916) (xy 445.714882 -196.177916) (xy 445.707843 -196.17814) (xy 445.694307 -196.182008)
			(xy 445.688212 -196.185536) (xy 445.65443 -196.204078) (xy 445.641222 -196.210428) (xy 445.625728 -196.235066)
			(xy 445.625728 -196.23786) (xy 445.544702 -196.23786) (xy 445.5414 -196.238368) (xy 445.528199 -196.240137)
			(xy 445.501632 -196.242047) (xy 445.488314 -196.242178) (xy 445.474996 -196.242036) (xy 445.448429 -196.240131)
			(xy 445.435228 -196.238368) (xy 445.431926 -196.23786) (xy 445.358266 -196.23786) (xy 445.335958 -196.237339)
			(xy 445.292208 -196.228592) (xy 445.25102 -196.211445) (xy 445.213988 -196.18656) (xy 445.182549 -196.154904)
			(xy 445.157921 -196.117702) (xy 445.141057 -196.076396) (xy 445.132612 -196.032587) (xy 445.132206 -196.010276)
			(xy 445.13246 -196.010276) (xy 445.13246 -195.998084) (xy 445.129412 -195.989702) (xy 445.118908 -195.958481)
			(xy 445.107549 -195.893602) (xy 445.106806 -195.86067) (xy 445.107516 -195.827735) (xy 445.118878 -195.762851)
			(xy 445.129412 -195.731638) (xy 445.13246 -195.723256) (xy 445.13246 -195.711064) (xy 445.132206 -195.711064)
			(xy 445.132651 -195.688261) (xy 445.141529 -195.643532) (xy 445.159161 -195.601477) (xy 445.184836 -195.563791)
			(xy 445.200786 -195.547488) (xy 445.208406 -195.539868) (xy 445.21628 -195.521072) (xy 445.21501 -195.426076)
			(xy 445.206882 -195.40728) (xy 445.199008 -195.400168) (xy 445.184022 -195.38569) (xy 445.091058 -195.292726)
			(xy 445.069109 -195.270148) (xy 445.029852 -195.220912) (xy 444.99635 -195.167593) (xy 444.969025 -195.11086)
			(xy 444.94822 -195.051425) (xy 444.934196 -194.990036) (xy 444.92713 -194.927463) (xy 444.92672 -194.895978)
			(xy 444.92672 -194.89547) (xy 444.927152 -194.86375) (xy 444.934289 -194.800712) (xy 444.948479 -194.73888)
			(xy 444.969542 -194.679038) (xy 444.99721 -194.621949) (xy 445.031131 -194.56834) (xy 445.070874 -194.518891)
			(xy 445.115932 -194.474233) (xy 445.140588 -194.454272) (xy 445.148462 -194.447922) (xy 445.163194 -194.42176)
			(xy 445.165701 -194.417013) (xy 445.168904 -194.40677) (xy 445.169544 -194.40144) (xy 445.175132 -194.337686)
			(xy 445.175132 -194.337178) (xy 445.176148 -194.32651) (xy 445.16929 -194.306444) (xy 445.161924 -194.298316)
			(xy 445.143435 -194.277715) (xy 445.11117 -194.232736) (xy 445.084735 -194.1841) (xy 445.06454 -194.132561)
			(xy 445.050895 -194.078913) (xy 445.044013 -194.023988) (xy 445.04356 -193.99631) (xy 445.044016 -193.967165)
			(xy 445.051628 -193.909375) (xy 445.066722 -193.853074) (xy 445.089041 -193.799227) (xy 445.118201 -193.748755)
			(xy 445.153703 -193.702525) (xy 445.194939 -193.661328) (xy 445.217804 -193.64325) (xy 445.230758 -193.633344)
			(xy 445.240156 -193.602102) (xy 445.204088 -193.495676) (xy 445.200192 -193.485846) (xy 445.185944 -193.470252)
			(xy 445.16664 -193.461678) (xy 445.156082 -193.461132) (xy 443.804294 -193.461132) (xy 443.79769 -193.46291)
			(xy 443.773717 -193.469092) (xy 443.724654 -193.475719) (xy 443.675146 -193.475719) (xy 443.626083 -193.469092)
			(xy 443.60211 -193.46291) (xy 443.595506 -193.461132) (xy 443.401704 -193.461132) (xy 443.390592 -193.461686)
			(xy 443.370426 -193.471028) (xy 443.362842 -193.479166) (xy 443.35827 -193.4845) (xy 443.317122 -193.574416)
			(xy 443.313413 -193.58346) (xy 443.312442 -193.602965) (xy 443.318876 -193.621404) (xy 443.324996 -193.629026)
			(xy 443.345177 -193.653054) (xy 443.380647 -193.704818) (xy 443.410126 -193.760213) (xy 443.433249 -193.818549)
			(xy 443.449725 -193.879098) (xy 443.459351 -193.941106) (xy 443.46114 -193.972434) (xy 443.46114 -194.019932)
			(xy 443.459096 -194.055037) (xy 443.447359 -194.124371) (xy 443.427072 -194.191701) (xy 443.398551 -194.255978)
			(xy 443.380876 -194.286378) (xy 443.373764 -194.298316) (xy 443.373256 -194.325494) (xy 443.423548 -194.414648)
			(xy 443.428261 -194.422303) (xy 443.441923 -194.43397) (xy 443.458763 -194.44023) (xy 443.467744 -194.440556)
			(xy 443.6999 -194.440556) (xy 443.730286 -194.441075) (xy 443.790492 -194.44935) (xy 443.84901 -194.465746)
			(xy 443.90475 -194.489957) (xy 443.956675 -194.521533) (xy 444.003816 -194.559885) (xy 444.045296 -194.6043)
			(xy 444.080342 -194.653948) (xy 444.108301 -194.707907) (xy 444.128652 -194.765169) (xy 444.141016 -194.82467)
			(xy 444.145164 -194.8853) (xy 444.141016 -194.94593) (xy 444.128652 -195.005431) (xy 444.108301 -195.062693)
			(xy 444.080342 -195.116652) (xy 444.045296 -195.1663) (xy 444.003816 -195.210715) (xy 443.956675 -195.249067)
			(xy 443.90475 -195.280643) (xy 443.84901 -195.304854) (xy 443.790492 -195.32125) (xy 443.730286 -195.329525)
			(xy 443.6999 -195.330064) (xy 442.952632 -195.330064) (xy 442.920048 -195.329502) (xy 442.855578 -195.320001)
			(xy 442.793187 -195.301184) (xy 442.734214 -195.273454) (xy 442.70676 -195.255896) (xy 442.706252 -195.255642)
			(xy 442.697108 -195.250562) (xy 442.678845 -195.24391) (xy 442.644745 -195.225265) (xy 442.62929 -195.213478)
			(xy 442.622406 -195.208453) (xy 442.606311 -195.20288) (xy 442.597794 -195.202556) (xy 442.341508 -195.202556)
			(xy 442.331496 -195.203042) (xy 442.312994 -195.210699) (xy 442.298828 -195.22485) (xy 442.291152 -195.243345)
			(xy 442.290708 -195.253356) (xy 442.290708 -195.2625) (xy 442.022738 -195.2625) (xy 442.003252 -195.262088)
			(xy 441.964858 -195.255403) (xy 441.928175 -195.242243) (xy 441.894288 -195.222994) (xy 441.878974 -195.210938)
			(xy 441.872624 -195.205604) (xy 441.839858 -195.192904) (xy 441.488322 -195.192904) (xy 441.458533 -195.192187)
			(xy 441.400076 -195.180684) (xy 441.372244 -195.170044) (xy 441.368688 -195.168774) (xy 441.353702 -195.164964)
			(xy 441.350146 -195.16471) (xy 441.3206 -195.16114) (xy 441.263043 -195.146011) (xy 441.208536 -195.122122)
			(xy 441.158404 -195.090054) (xy 441.13577 -195.07073) (xy 441.102242 -195.05803) (xy 441.071254 -195.05803)
			(xy 441.061332 -195.058603) (xy 441.043035 -195.066315) (xy 441.035694 -195.073016) (xy 440.746642 -195.362068)
			(xy 440.763494 -195.393495) (xy 440.789998 -195.459699) (xy 440.807912 -195.528724) (xy 440.816947 -195.599462)
			(xy 440.817508 -195.635118) (xy 440.817049 -195.666626) (xy 440.809962 -195.729243) (xy 440.795912 -195.790673)
			(xy 440.775077 -195.850145) (xy 440.747717 -195.906912) (xy 440.714177 -195.960261) (xy 440.674877 -196.009522)
			(xy 440.652916 -196.03212) (xy 440.26455 -196.42074) (xy 439.463434 -196.42074) (xy 439.466046 -196.436549)
			(xy 439.468844 -196.468472) (xy 439.469022 -196.484494) (xy 439.469022 -196.485002) (xy 439.468506 -196.512602)
			(xy 439.460279 -196.567185) (xy 439.444009 -196.619932) (xy 439.420059 -196.669665) (xy 439.388964 -196.715272)
			(xy 439.351419 -196.755736) (xy 439.308262 -196.790153) (xy 439.260458 -196.817752) (xy 439.209074 -196.837919)
			(xy 439.155259 -196.850202) (xy 439.100214 -196.854327) (xy 439.045169 -196.850202) (xy 438.991354 -196.837919)
			(xy 438.93997 -196.817752) (xy 438.892166 -196.790153) (xy 438.849009 -196.755736) (xy 438.811464 -196.715272)
			(xy 438.780369 -196.669665) (xy 438.756419 -196.619932) (xy 438.740149 -196.567185) (xy 438.731922 -196.512602)
			(xy 438.731406 -196.485002) (xy 438.731406 -196.484494) (xy 438.73159 -196.468472) (xy 438.734388 -196.43655)
			(xy 438.736994 -196.42074) (xy 438.703412 -196.419777) (xy 438.636827 -196.410828) (xy 438.571784 -196.394003)
			(xy 438.509211 -196.369542) (xy 438.450002 -196.337794) (xy 438.395001 -196.299212) (xy 438.344993 -196.254347)
			(xy 438.300691 -196.203839) (xy 438.281318 -196.176392) (xy 438.171082 -196.176392) (xy 438.164043 -196.176616)
			(xy 438.150506 -196.180482) (xy 438.144412 -196.184012) (xy 438.11063 -196.202554) (xy 438.097422 -196.208904)
			(xy 438.081928 -196.233542) (xy 438.081928 -196.236336) (xy 438.000902 -196.236336) (xy 437.9976 -196.236844)
			(xy 437.984399 -196.238613) (xy 437.957832 -196.240522) (xy 437.944514 -196.240654) (xy 437.931196 -196.240512)
			(xy 437.904629 -196.238607) (xy 437.891428 -196.236844) (xy 437.888126 -196.236336) (xy 437.814466 -196.236336)
			(xy 437.792159 -196.235815) (xy 437.748411 -196.227068) (xy 437.707225 -196.20992) (xy 437.670196 -196.185035)
			(xy 437.638759 -196.153378) (xy 437.614134 -196.116176) (xy 437.597275 -196.074871) (xy 437.588834 -196.031062)
			(xy 437.588406 -196.008752) (xy 437.58866 -196.008752) (xy 437.58866 -195.99656) (xy 437.585612 -195.988178)
			(xy 437.575102 -195.956958) (xy 437.56373 -195.892079) (xy 437.563006 -195.859146) (xy 437.563718 -195.826211)
			(xy 437.575083 -195.761329) (xy 437.585612 -195.730114) (xy 437.58866 -195.721732) (xy 437.58866 -195.70954)
			(xy 437.588406 -195.70954) (xy 437.588854 -195.686738) (xy 437.597735 -195.642012) (xy 437.61537 -195.59996)
			(xy 437.641047 -195.562277) (xy 437.656986 -195.545964) (xy 437.664606 -195.538344) (xy 437.67248 -195.519548)
			(xy 437.67121 -195.424552) (xy 437.663082 -195.405756) (xy 437.655208 -195.398644) (xy 437.640222 -195.384166)
			(xy 437.547258 -195.291202) (xy 437.525286 -195.268621) (xy 437.48601 -195.219352) (xy 437.452497 -195.165996)
			(xy 437.425169 -195.109223) (xy 437.40437 -195.049747) (xy 437.39036 -194.988317) (xy 437.383317 -194.925704)
			(xy 437.38292 -194.8942) (xy 437.38292 -194.893692) (xy 437.383372 -194.861624) (xy 437.390671 -194.797904)
			(xy 437.405185 -194.735432) (xy 437.426723 -194.675021) (xy 437.455007 -194.617458) (xy 437.489666 -194.563493)
			(xy 437.53025 -194.51383) (xy 437.576229 -194.469116) (xy 437.60136 -194.449192) (xy 437.6039 -194.44716)
			(xy 437.609234 -194.441826) (xy 437.615321 -194.435237) (xy 437.622872 -194.418978) (xy 437.623966 -194.410076)
			(xy 437.631332 -194.325494) (xy 437.624474 -194.305682) (xy 437.617108 -194.297554) (xy 437.59876 -194.276984)
			(xy 437.566756 -194.232105) (xy 437.540541 -194.183616) (xy 437.520518 -194.13226) (xy 437.506994 -194.078823)
			(xy 437.500176 -194.024125) (xy 437.49976 -193.996564) (xy 437.49976 -193.996056) (xy 437.500212 -193.966937)
			(xy 437.507808 -193.909197) (xy 437.522877 -193.852943) (xy 437.54516 -193.799137) (xy 437.574278 -193.748701)
			(xy 437.60973 -193.702498) (xy 437.650911 -193.661319) (xy 437.67375 -193.64325) (xy 437.686704 -193.633344)
			(xy 437.696102 -193.602356) (xy 437.660034 -193.495676) (xy 437.656135 -193.485852) (xy 437.641885 -193.470273)
			(xy 437.622582 -193.461718) (xy 437.612028 -193.461132) (xy 436.26024 -193.461132) (xy 436.253636 -193.46291)
			(xy 436.229663 -193.469092) (xy 436.1806 -193.475719) (xy 436.131092 -193.475719) (xy 436.082029 -193.469092)
			(xy 436.058056 -193.46291) (xy 436.051452 -193.461132) (xy 435.85765 -193.461132) (xy 435.846543 -193.461697)
			(xy 435.826394 -193.471052) (xy 435.818788 -193.479166) (xy 435.814216 -193.4845) (xy 435.773068 -193.574416)
			(xy 435.769362 -193.583461) (xy 435.768392 -193.602966) (xy 435.77482 -193.621407) (xy 435.780942 -193.629026)
			(xy 435.801457 -193.653486) (xy 435.837415 -193.706237) (xy 435.867158 -193.762726) (xy 435.890303 -193.822223)
			(xy 435.906552 -193.883962) (xy 435.915693 -193.947145) (xy 435.917086 -193.979038) (xy 435.917086 -194.013582)
			(xy 435.915423 -194.049496) (xy 435.904091 -194.120493) (xy 435.883798 -194.189465) (xy 435.854875 -194.255287)
			(xy 435.836822 -194.286378) (xy 435.82971 -194.298316) (xy 435.829202 -194.325494) (xy 435.879494 -194.414648)
			(xy 435.884209 -194.422298) (xy 435.897873 -194.433952) (xy 435.914712 -194.440197) (xy 435.92369 -194.440556)
			(xy 436.155846 -194.440556) (xy 436.18623 -194.441078) (xy 436.246431 -194.449358) (xy 436.304944 -194.465758)
			(xy 436.360679 -194.489972) (xy 436.412598 -194.521549) (xy 436.459734 -194.559902) (xy 436.501209 -194.604315)
			(xy 436.53625 -194.653962) (xy 436.564206 -194.707918) (xy 436.584554 -194.765177) (xy 436.596917 -194.824674)
			(xy 436.601064 -194.8853) (xy 436.596917 -194.945926) (xy 436.584554 -195.005423) (xy 436.564206 -195.062682)
			(xy 436.53625 -195.116638) (xy 436.501209 -195.166285) (xy 436.459734 -195.210698) (xy 436.412598 -195.249051)
			(xy 436.360679 -195.280628) (xy 436.304944 -195.304842) (xy 436.246431 -195.321242) (xy 436.18623 -195.329522)
			(xy 436.155846 -195.330064) (xy 435.408832 -195.330064) (xy 435.376281 -195.329483) (xy 435.311877 -195.319961)
			(xy 435.249552 -195.301146) (xy 435.190638 -195.273441) (xy 435.163214 -195.255896) (xy 435.154324 -195.25107)
			(xy 435.152546 -195.250308) (xy 435.13442 -195.243697) (xy 435.100577 -195.225178) (xy 435.085236 -195.213478)
			(xy 435.078354 -195.208447) (xy 435.062259 -195.202859) (xy 435.05374 -195.202556) (xy 434.797708 -195.202556)
			(xy 434.787696 -195.203042) (xy 434.769194 -195.210699) (xy 434.755028 -195.22485) (xy 434.747352 -195.243345)
			(xy 434.746908 -195.253356) (xy 434.746908 -195.2625) (xy 434.478938 -195.2625) (xy 434.459452 -195.262088)
			(xy 434.421058 -195.255403) (xy 434.384375 -195.242243) (xy 434.350488 -195.222994) (xy 434.335174 -195.210938)
			(xy 434.328824 -195.205604) (xy 434.296058 -195.192904) (xy 433.944268 -195.192904) (xy 433.914481 -195.192181)
			(xy 433.856027 -195.180669) (xy 433.82819 -195.170044) (xy 433.824634 -195.168774) (xy 433.809648 -195.164964)
			(xy 433.806092 -195.16471) (xy 433.778228 -195.161373) (xy 433.723833 -195.147576) (xy 433.672043 -195.125966)
			(xy 433.623973 -195.097009) (xy 433.580658 -195.061329) (xy 433.543032 -195.019694) (xy 433.511904 -194.973001)
			(xy 433.487945 -194.922255) (xy 433.471671 -194.868548) (xy 433.463432 -194.813039) (xy 433.462938 -194.78498)
			(xy 433.463375 -194.758747) (xy 433.470566 -194.706776) (xy 433.48481 -194.65628) (xy 433.505839 -194.608213)
			(xy 433.533254 -194.563479) (xy 433.549552 -194.542918) (xy 433.555902 -194.535044) (xy 433.561744 -194.51574)
			(xy 433.555648 -194.455034) (xy 433.554426 -194.446432) (xy 433.547016 -194.430729) (xy 433.54117 -194.4243)
			(xy 433.538122 -194.421252) (xy 433.536852 -194.420236) (xy 433.508404 -194.393566) (xy 433.457096 -194.342004)
			(xy 433.456588 -194.341496) (xy 433.436522 -194.32143) (xy 433.413154 -194.298062) (xy 433.4002 -194.29095)
			(xy 433.393088 -194.289426) (xy 433.367979 -194.283923) (xy 433.318299 -194.270709) (xy 433.293774 -194.26301)
			(xy 433.285138 -194.260216) (xy 433.267358 -194.260978) (xy 433.260246 -194.263772) (xy 433.209192 -194.278504)
			(xy 433.207668 -194.279012) (xy 433.186078 -194.28587) (xy 433.167028 -194.323462) (xy 433.168552 -194.327526)
			(xy 433.14239 -194.403726) (xy 433.146708 -194.428872) (xy 433.154582 -194.439032) (xy 433.173367 -194.46375)
			(xy 433.205964 -194.516591) (xy 433.232536 -194.572704) (xy 433.252759 -194.631404) (xy 433.266386 -194.691977)
			(xy 433.273251 -194.753683) (xy 433.273708 -194.784726) (xy 433.273708 -194.79895) (xy 433.273454 -194.800982)
			(xy 433.273454 -194.802252) (xy 433.272692 -194.818508) (xy 433.27032 -194.850482) (xy 433.259227 -194.913631)
			(xy 433.241019 -194.975108) (xy 433.215933 -195.034113) (xy 433.184294 -195.089879) (xy 433.146515 -195.141683)
			(xy 433.103085 -195.18885) (xy 433.079144 -195.210176) (xy 433.104849 -195.233093) (xy 433.151044 -195.284169)
			(xy 433.190651 -195.340507) (xy 433.223076 -195.401263) (xy 433.247833 -195.465527) (xy 433.264549 -195.532335)
			(xy 433.272976 -195.600684) (xy 433.273454 -195.635118) (xy 433.272995 -195.666626) (xy 433.265907 -195.729242)
			(xy 433.251857 -195.790671) (xy 433.23102 -195.850142) (xy 433.203658 -195.906907) (xy 433.170115 -195.960254)
			(xy 433.130813 -196.009512) (xy 433.108862 -196.03212) (xy 432.729132 -196.412104) (xy 431.917602 -196.412104)
			(xy 431.92103 -196.430134) (xy 431.92472 -196.466651) (xy 431.924968 -196.485002) (xy 431.924452 -196.512602)
			(xy 431.916225 -196.567185) (xy 431.899955 -196.619932) (xy 431.876005 -196.669665) (xy 431.84491 -196.715272)
			(xy 431.807365 -196.755736) (xy 431.764208 -196.790153) (xy 431.716404 -196.817752) (xy 431.66502 -196.837919)
			(xy 431.611205 -196.850202) (xy 431.55616 -196.854327) (xy 431.501115 -196.850202) (xy 431.4473 -196.837919)
			(xy 431.395916 -196.817752) (xy 431.348112 -196.790153) (xy 431.304955 -196.755736) (xy 431.26741 -196.715272)
			(xy 431.236315 -196.669665) (xy 431.212365 -196.619932) (xy 431.196095 -196.567185) (xy 431.187868 -196.512602)
			(xy 431.187352 -196.485002) (xy 431.187607 -196.466651) (xy 431.1913 -196.430135) (xy 431.194718 -196.412104)
			(xy 431.161018 -196.411263) (xy 431.094175 -196.402509) (xy 431.028863 -196.385809) (xy 430.966022 -196.361405)
			(xy 430.906557 -196.329647) (xy 430.851326 -196.290993) (xy 430.801124 -196.246) (xy 430.756675 -196.195317)
			(xy 430.737264 -196.167756) (xy 430.627028 -196.167756) (xy 430.619987 -196.167974) (xy 430.606446 -196.171834)
			(xy 430.600358 -196.175376) (xy 430.566576 -196.193918) (xy 430.553368 -196.200268) (xy 430.538128 -196.224906)
			(xy 430.538128 -196.2277) (xy 430.456848 -196.2277) (xy 430.453546 -196.228208) (xy 430.440345 -196.229975)
			(xy 430.413778 -196.231881) (xy 430.40046 -196.232018) (xy 430.387143 -196.231874) (xy 430.360576 -196.229966)
			(xy 430.347374 -196.228208) (xy 430.344072 -196.2277) (xy 430.270412 -196.2277) (xy 430.2481 -196.227183)
			(xy 430.20434 -196.218444) (xy 430.16314 -196.201301) (xy 430.126096 -196.176419) (xy 430.094645 -196.144762)
			(xy 430.070005 -196.107558) (xy 430.053131 -196.066247) (xy 430.044676 -196.022431) (xy 430.044352 -196.000116)
			(xy 430.044352 -195.987924) (xy 430.041558 -195.979542) (xy 430.03105 -195.948322) (xy 430.019682 -195.883443)
			(xy 430.018952 -195.85051) (xy 430.019667 -195.817576) (xy 430.031036 -195.752695) (xy 430.041558 -195.721478)
			(xy 430.044352 -195.713096) (xy 430.044352 -195.700904) (xy 430.044647 -195.681201) (xy 430.051212 -195.642349)
			(xy 430.064405 -195.605221) (xy 430.083828 -195.570939) (xy 430.108894 -195.540538) (xy 430.1236 -195.527422)
			(xy 430.132236 -195.520056) (xy 430.141126 -195.500498) (xy 430.141634 -195.40093) (xy 430.132744 -195.381118)
			(xy 430.124108 -195.373752) (xy 430.096168 -195.34759) (xy 430.003204 -195.254626) (xy 429.981202 -195.232039)
			(xy 429.94187 -195.182751) (xy 429.908309 -195.129366) (xy 429.880942 -195.072557) (xy 429.860112 -195.013039)
			(xy 429.846083 -194.951561) (xy 429.839032 -194.888899) (xy 429.838612 -194.85737) (xy 429.839136 -194.822577)
			(xy 429.847732 -194.753523) (xy 429.86479 -194.686059) (xy 429.890048 -194.621219) (xy 429.92312 -194.559993)
			(xy 429.963499 -194.50332) (xy 430.010567 -194.452067) (xy 430.036732 -194.429126) (xy 430.044098 -194.422776)
			(xy 430.05756 -194.39763) (xy 430.059839 -194.393157) (xy 430.062778 -194.383561) (xy 430.063402 -194.37858)
			(xy 430.069244 -194.31762) (xy 430.069244 -194.317366) (xy 430.070514 -194.305428) (xy 430.061624 -194.282568)
			(xy 430.055274 -194.276726) (xy 430.036506 -194.252853) (xy 430.004932 -194.20098) (xy 429.980712 -194.145293)
			(xy 429.964297 -194.086828) (xy 429.95599 -194.026673) (xy 429.955452 -193.99631) (xy 429.955908 -193.967165)
			(xy 429.96352 -193.909375) (xy 429.978614 -193.853074) (xy 430.000932 -193.799226) (xy 430.030092 -193.748754)
			(xy 430.065594 -193.702523) (xy 430.106829 -193.661325) (xy 430.129696 -193.64325) (xy 430.14265 -193.633344)
			(xy 430.152048 -193.602102) (xy 430.11598 -193.495676) (xy 430.112083 -193.485847) (xy 430.097835 -193.470255)
			(xy 430.078532 -193.461684) (xy 430.067974 -193.461132) (xy 428.716186 -193.461132) (xy 428.709582 -193.46291)
			(xy 428.685609 -193.469092) (xy 428.636546 -193.475719) (xy 428.587038 -193.475719) (xy 428.537975 -193.469092)
			(xy 428.514002 -193.46291) (xy 428.507398 -193.461132) (xy 428.313596 -193.461132) (xy 428.302485 -193.461687)
			(xy 428.282322 -193.471031) (xy 428.274734 -193.479166) (xy 428.270162 -193.4845) (xy 428.229014 -193.574416)
			(xy 428.225305 -193.58346) (xy 428.224335 -193.602965) (xy 428.230768 -193.621405) (xy 428.236888 -193.629026)
			(xy 428.257069 -193.653054) (xy 428.292539 -193.704818) (xy 428.32202 -193.760213) (xy 428.345142 -193.818549)
			(xy 428.361619 -193.879098) (xy 428.371245 -193.941106) (xy 428.373032 -193.972434) (xy 428.373032 -194.019932)
			(xy 428.370988 -194.055037) (xy 428.359251 -194.124371) (xy 428.338963 -194.191701) (xy 428.310443 -194.255978)
			(xy 428.292768 -194.286378) (xy 428.285656 -194.298316) (xy 428.285148 -194.325494) (xy 428.33544 -194.414648)
			(xy 428.340158 -194.422293) (xy 428.353824 -194.433935) (xy 428.370661 -194.440165) (xy 428.379636 -194.440556)
			(xy 428.611792 -194.440556) (xy 428.64218 -194.441051) (xy 428.702389 -194.449325) (xy 428.760912 -194.465721)
			(xy 428.816656 -194.489934) (xy 428.868584 -194.521511) (xy 428.915729 -194.559865) (xy 428.957212 -194.604282)
			(xy 428.99226 -194.653934) (xy 429.020221 -194.707895) (xy 429.040574 -194.765162) (xy 429.052939 -194.824666)
			(xy 429.057087 -194.8853) (xy 429.052939 -194.945934) (xy 429.040574 -195.005438) (xy 429.020221 -195.062705)
			(xy 428.99226 -195.116666) (xy 428.957212 -195.166318) (xy 428.915729 -195.210735) (xy 428.868584 -195.249089)
			(xy 428.816656 -195.280666) (xy 428.760912 -195.304879) (xy 428.702389 -195.321275) (xy 428.64218 -195.329549)
			(xy 428.611792 -195.330064) (xy 427.864778 -195.330064) (xy 427.832228 -195.329479) (xy 427.767828 -195.31995)
			(xy 427.705507 -195.301129) (xy 427.646598 -195.273418) (xy 427.61916 -195.255896) (xy 427.61027 -195.25107)
			(xy 427.608492 -195.250308) (xy 427.590368 -195.243694) (xy 427.55653 -195.225168) (xy 427.541182 -195.213478)
			(xy 427.534298 -195.208454) (xy 427.518203 -195.202884) (xy 427.509686 -195.202556) (xy 427.2534 -195.202556)
			(xy 427.244765 -195.202901) (xy 427.228483 -195.208661) (xy 427.215055 -195.219522) (xy 427.21022 -195.226686)
			(xy 427.206693 -195.232783) (xy 427.202816 -195.246317) (xy 427.2026 -195.253356) (xy 427.2026 -195.2625)
			(xy 426.934884 -195.2625) (xy 426.915397 -195.262092) (xy 426.876998 -195.255414) (xy 426.840311 -195.242259)
			(xy 426.806419 -195.223015) (xy 426.79112 -195.210938) (xy 426.78477 -195.205604) (xy 426.752004 -195.192904)
			(xy 426.400214 -195.192904) (xy 426.370426 -195.192186) (xy 426.311969 -195.180682) (xy 426.284136 -195.170044)
			(xy 426.28058 -195.168774) (xy 426.265594 -195.164964) (xy 426.262038 -195.16471) (xy 426.234172 -195.161376)
			(xy 426.179771 -195.147583) (xy 426.127975 -195.125977) (xy 426.0799 -195.097022) (xy 426.03658 -195.061343)
			(xy 425.998948 -195.019707) (xy 425.967816 -194.973012) (xy 425.943854 -194.922264) (xy 425.927577 -194.868554)
			(xy 425.919337 -194.813041) (xy 425.918884 -194.78498) (xy 425.919321 -194.758747) (xy 425.926511 -194.706775)
			(xy 425.940754 -194.656278) (xy 425.96178 -194.608209) (xy 425.989192 -194.563473) (xy 426.005498 -194.542918)
			(xy 426.011848 -194.535044) (xy 426.01769 -194.51574) (xy 426.011594 -194.455034) (xy 426.010373 -194.446431)
			(xy 426.002969 -194.430723) (xy 425.997116 -194.4243) (xy 425.994068 -194.421252) (xy 425.992798 -194.420236)
			(xy 425.96435 -194.393566) (xy 425.913042 -194.342004) (xy 425.912534 -194.341496) (xy 425.892468 -194.32143)
			(xy 425.8691 -194.298062) (xy 425.856146 -194.29095) (xy 425.849034 -194.289426) (xy 425.823925 -194.283924)
			(xy 425.774244 -194.270712) (xy 425.74972 -194.26301) (xy 425.741084 -194.260216) (xy 425.723304 -194.260978)
			(xy 425.716192 -194.263772) (xy 425.665138 -194.278504) (xy 425.663614 -194.279012) (xy 425.642024 -194.28587)
			(xy 425.622974 -194.323462) (xy 425.624498 -194.327526) (xy 425.598336 -194.40398) (xy 425.602654 -194.429126)
			(xy 425.610528 -194.439286) (xy 425.629293 -194.464012) (xy 425.661851 -194.516863) (xy 425.688386 -194.57298)
			(xy 425.708576 -194.63168) (xy 425.722175 -194.692246) (xy 425.729017 -194.753943) (xy 425.7294 -194.78498)
			(xy 425.728897 -194.819432) (xy 425.720509 -194.887824) (xy 425.703819 -194.954677) (xy 425.679079 -195.018986)
			(xy 425.646659 -195.079787) (xy 425.607046 -195.136166) (xy 425.560835 -195.187277) (xy 425.53509 -195.210176)
			(xy 425.560793 -195.233095) (xy 425.606985 -195.284171) (xy 425.646589 -195.34051) (xy 425.679011 -195.401267)
			(xy 425.703765 -195.46553) (xy 425.72048 -195.532336) (xy 425.728906 -195.600685) (xy 425.7294 -195.635118)
			(xy 425.728941 -195.666626) (xy 425.721854 -195.729242) (xy 425.707804 -195.790672) (xy 425.686968 -195.850145)
			(xy 425.659608 -195.906911) (xy 425.626068 -195.96026) (xy 425.586768 -196.00952) (xy 425.564808 -196.03212)
			(xy 425.185078 -196.412104) (xy 424.373548 -196.412104) (xy 424.376976 -196.430134) (xy 424.380665 -196.466651)
			(xy 424.380914 -196.485002) (xy 424.380398 -196.512602) (xy 424.372171 -196.567185) (xy 424.355901 -196.619932)
			(xy 424.331951 -196.669665) (xy 424.300856 -196.715272) (xy 424.263311 -196.755736) (xy 424.220154 -196.790153)
			(xy 424.17235 -196.817752) (xy 424.120966 -196.837919) (xy 424.067151 -196.850202) (xy 424.012106 -196.854327)
			(xy 423.957061 -196.850202) (xy 423.903246 -196.837919) (xy 423.851862 -196.817752) (xy 423.804058 -196.790153)
			(xy 423.760901 -196.755736) (xy 423.723356 -196.715272) (xy 423.692261 -196.669665) (xy 423.668311 -196.619932)
			(xy 423.652041 -196.567185) (xy 423.643814 -196.512602) (xy 423.643298 -196.485002) (xy 423.643552 -196.466651)
			(xy 423.647245 -196.430135) (xy 423.650664 -196.412104) (xy 423.616966 -196.41126) (xy 423.550126 -196.4025)
			(xy 423.484818 -196.385796) (xy 423.421982 -196.361387) (xy 423.362522 -196.329626) (xy 423.307296 -196.29097)
			(xy 423.257099 -196.245976) (xy 423.212655 -196.195292) (xy 423.19321 -196.167756) (xy 423.082974 -196.167756)
			(xy 423.075936 -196.167981) (xy 423.062403 -196.171854) (xy 423.056304 -196.175376) (xy 423.022522 -196.193918)
			(xy 423.009314 -196.200268) (xy 422.99382 -196.224906) (xy 422.99382 -196.2277) (xy 422.912794 -196.2277)
			(xy 422.909492 -196.228208) (xy 422.896291 -196.229977) (xy 422.869724 -196.231885) (xy 422.856406 -196.232018)
			(xy 422.843088 -196.231876) (xy 422.816521 -196.229971) (xy 422.80332 -196.228208) (xy 422.800018 -196.2277)
			(xy 422.726358 -196.2277) (xy 422.704049 -196.227178) (xy 422.660298 -196.218431) (xy 422.619107 -196.201283)
			(xy 422.582073 -196.1764) (xy 422.55063 -196.144744) (xy 422.525997 -196.107543) (xy 422.509128 -196.066237)
			(xy 422.500676 -196.022428) (xy 422.500298 -196.000116) (xy 422.500552 -196.000116) (xy 422.500552 -195.987924)
			(xy 422.497504 -195.979542) (xy 422.486997 -195.948322) (xy 422.475631 -195.883443) (xy 422.474898 -195.85051)
			(xy 422.475613 -195.817576) (xy 422.486984 -195.752695) (xy 422.497504 -195.721478) (xy 422.500552 -195.713096)
			(xy 422.500552 -195.700904) (xy 422.500298 -195.700904) (xy 422.50074 -195.678099) (xy 422.50961 -195.633366)
			(xy 422.527236 -195.591305) (xy 422.552907 -195.553612) (xy 422.568878 -195.537328) (xy 422.576498 -195.529708)
			(xy 422.584372 -195.510912) (xy 422.583102 -195.415916) (xy 422.574974 -195.39712) (xy 422.5671 -195.390008)
			(xy 422.552114 -195.37553) (xy 422.45915 -195.282566) (xy 422.437204 -195.259987) (xy 422.397952 -195.21075)
			(xy 422.364457 -195.157429) (xy 422.337138 -195.100696) (xy 422.31634 -195.041262) (xy 422.302323 -194.979873)
			(xy 422.295264 -194.917302) (xy 422.294812 -194.885818) (xy 422.294812 -194.885056) (xy 422.295282 -194.853072)
			(xy 422.302582 -194.789521) (xy 422.317049 -194.72721) (xy 422.338494 -194.666943) (xy 422.366642 -194.6095)
			(xy 422.401128 -194.555623) (xy 422.441507 -194.506009) (xy 422.487257 -194.461299) (xy 422.512236 -194.441318)
			(xy 422.520618 -194.434714) (xy 422.530524 -194.416426) (xy 422.53916 -194.32143) (xy 422.532556 -194.301618)
			(xy 422.525444 -194.293744) (xy 422.504113 -194.269138) (xy 422.468138 -194.214857) (xy 422.44047 -194.155908)
			(xy 422.421701 -194.093552) (xy 422.412232 -194.029124) (xy 422.411652 -193.996564) (xy 422.411652 -193.996056)
			(xy 422.412104 -193.966937) (xy 422.4197 -193.909197) (xy 422.434768 -193.852942) (xy 422.457052 -193.799136)
			(xy 422.486169 -193.7487) (xy 422.521621 -193.702496) (xy 422.562801 -193.661316) (xy 422.585642 -193.64325)
			(xy 422.598596 -193.633344) (xy 422.607994 -193.602356) (xy 422.571926 -193.495676) (xy 422.568027 -193.485853)
			(xy 422.553776 -193.470276) (xy 422.534474 -193.461724) (xy 422.52392 -193.461132) (xy 421.172132 -193.461132)
			(xy 421.165528 -193.46291) (xy 421.141555 -193.469092) (xy 421.092492 -193.475719) (xy 421.042984 -193.475719)
			(xy 420.993921 -193.469092) (xy 420.969948 -193.46291) (xy 420.963344 -193.461132) (xy 420.769542 -193.461132)
			(xy 420.758436 -193.461698) (xy 420.73829 -193.471056) (xy 420.73068 -193.479166) (xy 420.726108 -193.4845)
			(xy 420.68496 -193.574416) (xy 420.681249 -193.583459) (xy 420.680277 -193.602965) (xy 420.686716 -193.621403)
			(xy 420.692834 -193.629026) (xy 420.713349 -193.653485) (xy 420.749307 -193.706236) (xy 420.779051 -193.762725)
			(xy 420.802197 -193.822223) (xy 420.818445 -193.883962) (xy 420.827587 -193.947145) (xy 420.828978 -193.979038)
			(xy 420.828978 -194.013582) (xy 420.827315 -194.049496) (xy 420.815983 -194.120493) (xy 420.79569 -194.189465)
			(xy 420.766766 -194.255286) (xy 420.748714 -194.286378) (xy 420.741602 -194.298316) (xy 420.741094 -194.325494)
			(xy 420.791386 -194.414648) (xy 420.796101 -194.422299) (xy 420.809765 -194.433955) (xy 420.826603 -194.440203)
			(xy 420.835582 -194.440556) (xy 421.067738 -194.440556) (xy 421.098122 -194.441077) (xy 421.158324 -194.449356)
			(xy 421.216838 -194.465756) (xy 421.272574 -194.489969) (xy 421.324494 -194.521546) (xy 421.371631 -194.559899)
			(xy 421.413106 -194.604312) (xy 421.448149 -194.65396) (xy 421.476105 -194.707916) (xy 421.496454 -194.765176)
			(xy 421.508817 -194.824673) (xy 421.512964 -194.8853) (xy 421.508817 -194.945927) (xy 421.496454 -195.005424)
			(xy 421.476105 -195.062684) (xy 421.448149 -195.11664) (xy 421.413106 -195.166288) (xy 421.371631 -195.210701)
			(xy 421.324494 -195.249054) (xy 421.272574 -195.280631) (xy 421.216838 -195.304844) (xy 421.158324 -195.321244)
			(xy 421.098122 -195.329523) (xy 421.067738 -195.330064) (xy 420.320724 -195.330064) (xy 420.288173 -195.329482)
			(xy 420.22377 -195.31996) (xy 420.161445 -195.301144) (xy 420.102532 -195.273438) (xy 420.075106 -195.255896)
			(xy 420.066216 -195.25107) (xy 420.064438 -195.250308) (xy 420.046313 -195.243697) (xy 420.01247 -195.225177)
			(xy 419.997128 -195.213478) (xy 419.990246 -195.208448) (xy 419.974151 -195.202863) (xy 419.965632 -195.202556)
			(xy 419.7096 -195.202556) (xy 419.699589 -195.203043) (xy 419.68109 -195.210701) (xy 419.666926 -195.224853)
			(xy 419.659252 -195.243346) (xy 419.6588 -195.253356) (xy 419.6588 -195.2625) (xy 419.39083 -195.2625)
			(xy 419.371344 -195.262087) (xy 419.332951 -195.255401) (xy 419.296269 -195.24224) (xy 419.262383 -195.222991)
			(xy 419.247066 -195.210938) (xy 419.240716 -195.205604) (xy 419.20795 -195.192904) (xy 418.85616 -195.192904)
			(xy 418.826373 -195.192181) (xy 418.76792 -195.180667) (xy 418.740082 -195.170044) (xy 418.736526 -195.168774)
			(xy 418.72154 -195.164964) (xy 418.717984 -195.16471) (xy 418.69012 -195.161373) (xy 418.635726 -195.147574)
			(xy 418.583937 -195.125964) (xy 418.535868 -195.097007) (xy 418.492554 -195.061327) (xy 418.454929 -195.019692)
			(xy 418.423802 -194.972999) (xy 418.399844 -194.922253) (xy 418.38357 -194.868547) (xy 418.375331 -194.813038)
			(xy 418.37483 -194.78498) (xy 418.375267 -194.758747) (xy 418.382458 -194.706776) (xy 418.396702 -194.65628)
			(xy 418.41773 -194.608212) (xy 418.445145 -194.563478) (xy 418.461444 -194.542918) (xy 418.467794 -194.535044)
			(xy 418.473636 -194.51574) (xy 418.46754 -194.455034) (xy 418.466317 -194.446432) (xy 418.458907 -194.43073)
			(xy 418.453062 -194.4243) (xy 418.450014 -194.421252) (xy 418.448744 -194.420236) (xy 418.420296 -194.393566)
			(xy 418.368988 -194.342004) (xy 418.36848 -194.341496) (xy 418.348414 -194.32143) (xy 418.325046 -194.298062)
			(xy 418.312092 -194.29095) (xy 418.30498 -194.289426) (xy 418.279871 -194.283923) (xy 418.230191 -194.270708)
			(xy 418.205666 -194.26301) (xy 418.19703 -194.260216) (xy 418.17925 -194.260978) (xy 418.172138 -194.263772)
			(xy 418.121084 -194.278504) (xy 418.11956 -194.279012) (xy 418.09797 -194.28587) (xy 418.07892 -194.323462)
			(xy 418.080444 -194.327526) (xy 418.054282 -194.403726) (xy 418.0586 -194.428872) (xy 418.066474 -194.439032)
			(xy 418.085259 -194.46375) (xy 418.117857 -194.516591) (xy 418.144429 -194.572703) (xy 418.164652 -194.631404)
			(xy 418.17828 -194.691977) (xy 418.185145 -194.753683) (xy 418.1856 -194.784726) (xy 418.1856 -194.79895)
			(xy 418.185346 -194.800982) (xy 418.185346 -194.802252) (xy 418.184584 -194.818508) (xy 418.182212 -194.850482)
			(xy 418.171119 -194.913631) (xy 418.152911 -194.975107) (xy 418.127824 -195.034112) (xy 418.096185 -195.089878)
			(xy 418.058405 -195.141681) (xy 418.014975 -195.188848) (xy 417.991036 -195.210176) (xy 418.016737 -195.233096)
			(xy 418.062926 -195.284174) (xy 418.102526 -195.340513) (xy 418.134945 -195.40127) (xy 418.159698 -195.465533)
			(xy 418.176411 -195.532338) (xy 418.184836 -195.600686) (xy 418.185346 -195.635118) (xy 418.184887 -195.666626)
			(xy 418.1778 -195.729243) (xy 418.163752 -195.790674) (xy 418.142917 -195.850147) (xy 418.115559 -195.906915)
			(xy 418.08202 -195.960266) (xy 418.042722 -196.009528) (xy 418.020754 -196.03212) (xy 417.641024 -196.412104)
			(xy 416.829494 -196.412104) (xy 416.832922 -196.430134) (xy 416.836612 -196.466651) (xy 416.83686 -196.485002)
			(xy 416.836344 -196.512602) (xy 416.828117 -196.567185) (xy 416.811847 -196.619932) (xy 416.787897 -196.669665)
			(xy 416.756802 -196.715272) (xy 416.719257 -196.755736) (xy 416.6761 -196.790153) (xy 416.628296 -196.817752)
			(xy 416.576912 -196.837919) (xy 416.523097 -196.850202) (xy 416.468052 -196.854327) (xy 416.413007 -196.850202)
			(xy 416.359192 -196.837919) (xy 416.307808 -196.817752) (xy 416.260004 -196.790153) (xy 416.216847 -196.755736)
			(xy 416.179302 -196.715272) (xy 416.148207 -196.669665) (xy 416.124257 -196.619932) (xy 416.107987 -196.567185)
			(xy 416.09976 -196.512602) (xy 416.099244 -196.485002) (xy 416.099499 -196.466651) (xy 416.103192 -196.430135)
			(xy 416.10661 -196.412104) (xy 416.07291 -196.411263) (xy 416.006068 -196.402508) (xy 415.940756 -196.385807)
			(xy 415.877916 -196.361402) (xy 415.818452 -196.329643) (xy 415.763222 -196.290989) (xy 415.713021 -196.245996)
			(xy 415.668572 -196.195313) (xy 415.649156 -196.167756) (xy 415.505646 -196.167756) (xy 415.494216 -196.170804)
			(xy 415.488628 -196.173598) (xy 415.478468 -196.178678) (xy 415.46526 -196.185028) (xy 415.45002 -196.209666)
			(xy 415.431732 -196.2277) (xy 415.182304 -196.2277) (xy 415.159992 -196.227183) (xy 415.116234 -196.218442)
			(xy 415.075035 -196.201298) (xy 415.037993 -196.176416) (xy 415.006543 -196.14476) (xy 414.981904 -196.107555)
			(xy 414.96503 -196.066245) (xy 414.956576 -196.02243) (xy 414.956244 -196.000116) (xy 414.956244 -195.972684)
			(xy 414.95345 -195.964302) (xy 414.942945 -195.933082) (xy 414.931585 -195.868202) (xy 414.930844 -195.83527)
			(xy 414.930844 -195.834508) (xy 414.931559 -195.801574) (xy 414.942928 -195.736693) (xy 414.95345 -195.705476)
			(xy 414.956498 -195.690236) (xy 414.957935 -195.667839) (xy 414.968542 -195.624237) (xy 414.987523 -195.583575)
			(xy 415.014136 -195.547445) (xy 415.030412 -195.531994) (xy 415.03854 -195.524628) (xy 415.047176 -195.50507)
			(xy 415.046922 -195.407788) (xy 415.038032 -195.38823) (xy 415.029904 -195.381118) (xy 415.00806 -195.36029)
			(xy 414.915096 -195.267326) (xy 414.893094 -195.244739) (xy 414.853763 -195.195451) (xy 414.820203 -195.142066)
			(xy 414.792835 -195.085257) (xy 414.772006 -195.025738) (xy 414.757978 -194.964261) (xy 414.750926 -194.901599)
			(xy 414.750504 -194.87007) (xy 414.750939 -194.838601) (xy 414.757967 -194.776056) (xy 414.771943 -194.714688)
			(xy 414.792691 -194.655268) (xy 414.819951 -194.598539) (xy 414.853383 -194.545213) (xy 414.892566 -194.495959)
			(xy 414.937009 -194.451394) (xy 414.961324 -194.431412) (xy 414.969452 -194.425062) (xy 414.979104 -194.406774)
			(xy 414.986724 -194.32397) (xy 414.987057 -194.318828) (xy 414.985905 -194.30859) (xy 414.984438 -194.30365)
			(xy 414.98139 -194.293998) (xy 414.974786 -194.286124) (xy 414.974532 -194.28587) (xy 414.954426 -194.261558)
			(xy 414.920551 -194.208337) (xy 414.894522 -194.150869) (xy 414.876859 -194.090304) (xy 414.867917 -194.027853)
			(xy 414.867344 -193.99631) (xy 414.8678 -193.967165) (xy 414.875412 -193.909375) (xy 414.890506 -193.853073)
			(xy 414.912823 -193.799225) (xy 414.941983 -193.748753) (xy 414.977484 -193.702522) (xy 415.01872 -193.661323)
			(xy 415.041588 -193.64325) (xy 415.054542 -193.633344) (xy 415.06394 -193.602102) (xy 415.027872 -193.495676)
			(xy 415.023975 -193.485848) (xy 415.009727 -193.470258) (xy 414.990423 -193.46169) (xy 414.979866 -193.461132)
			(xy 413.628078 -193.461132) (xy 413.621474 -193.46291) (xy 413.597501 -193.469092) (xy 413.548438 -193.475719)
			(xy 413.49893 -193.475719) (xy 413.449867 -193.469092) (xy 413.425894 -193.46291) (xy 413.41929 -193.461132)
			(xy 413.225488 -193.461132) (xy 413.214377 -193.461689) (xy 413.194217 -193.471035) (xy 413.186626 -193.479166)
			(xy 413.182054 -193.4845) (xy 413.140906 -193.574416) (xy 413.137198 -193.58346) (xy 413.136227 -193.602965)
			(xy 413.14266 -193.621405) (xy 413.14878 -193.629026) (xy 413.168961 -193.653054) (xy 413.204432 -193.704818)
			(xy 413.233913 -193.760213) (xy 413.257036 -193.818548) (xy 413.273513 -193.879097) (xy 413.283139 -193.941106)
			(xy 413.284924 -193.972434) (xy 413.284924 -194.019932) (xy 413.283289 -194.049328) (xy 413.274622 -194.107565)
			(xy 413.259905 -194.164575) (xy 413.239299 -194.21973) (xy 413.226504 -194.246246) (xy 413.225996 -194.24777)
			(xy 413.225234 -194.24904) (xy 413.220924 -194.260554) (xy 413.222797 -194.28504) (xy 413.22879 -194.295776)
			(xy 413.274256 -194.369182) (xy 413.279084 -194.376351) (xy 413.292523 -194.387203) (xy 413.3088 -194.392984)
			(xy 413.317436 -194.393312) (xy 413.3342 -194.393312) (xy 413.352742 -194.400932) (xy 413.354266 -194.402456)
			(xy 413.512508 -194.402456) (xy 413.513016 -194.402202) (xy 413.523684 -194.402202) (xy 413.558864 -194.40284)
			(xy 413.628481 -194.413047) (xy 413.662368 -194.422522) (xy 413.732218 -194.492372) (xy 413.760421 -194.507987)
			(xy 413.812407 -194.546109) (xy 413.858345 -194.591336) (xy 413.897273 -194.64272) (xy 413.91332 -194.67068)
			(xy 413.916876 -194.67703) (xy 414.004252 -194.764406) (xy 414.011103 -194.771802) (xy 414.018843 -194.790401)
			(xy 414.019238 -194.800474) (xy 414.019238 -197.33514) (xy 419.542737 -197.33514) (xy 419.546672 -197.281369)
			(xy 419.558395 -197.228745) (xy 419.577655 -197.178388) (xy 419.604041 -197.131371) (xy 419.636993 -197.088698)
			(xy 419.675806 -197.051277) (xy 419.719654 -197.019907) (xy 419.767602 -196.995255) (xy 419.818629 -196.977847)
			(xy 419.871647 -196.968054) (xy 419.925526 -196.966085) (xy 419.979117 -196.971982) (xy 420.031278 -196.985618)
			(xy 420.080898 -197.006705) (xy 420.126919 -197.034791) (xy 420.168361 -197.069279) (xy 420.204339 -197.109433)
			(xy 420.234087 -197.154397) (xy 420.256972 -197.203214) (xy 420.272504 -197.254843) (xy 420.280354 -197.308183)
			(xy 420.280846 -197.33514) (xy 423.668193 -197.33514) (xy 423.672223 -197.282642) (xy 423.68422 -197.231374)
			(xy 423.703903 -197.182539) (xy 423.730809 -197.13728) (xy 423.764309 -197.096659) (xy 423.803617 -197.061628)
			(xy 423.847812 -197.033008) (xy 423.895857 -197.011469) (xy 423.946628 -196.997517) (xy 423.998933 -196.991479)
			(xy 424.051547 -196.993496) (xy 424.103237 -197.00352) (xy 424.15279 -197.021318) (xy 424.199046 -197.046471)
			(xy 424.24092 -197.07839) (xy 424.277432 -197.116328) (xy 424.307724 -197.159394) (xy 424.331087 -197.206579)
			(xy 424.346973 -197.256778) (xy 424.35501 -197.308814) (xy 424.355514 -197.33514) (xy 427.086791 -197.33514)
			(xy 427.090726 -197.281369) (xy 427.102449 -197.228745) (xy 427.121709 -197.178388) (xy 427.148095 -197.131371)
			(xy 427.181047 -197.088698) (xy 427.21986 -197.051277) (xy 427.263708 -197.019907) (xy 427.311656 -196.995255)
			(xy 427.362683 -196.977847) (xy 427.415701 -196.968054) (xy 427.46958 -196.966085) (xy 427.523171 -196.971982)
			(xy 427.575332 -196.985618) (xy 427.624952 -197.006705) (xy 427.670973 -197.034791) (xy 427.712415 -197.069279)
			(xy 427.748393 -197.109433) (xy 427.778141 -197.154397) (xy 427.801026 -197.203214) (xy 427.816558 -197.254843)
			(xy 427.824408 -197.308183) (xy 427.8249 -197.33514) (xy 431.212247 -197.33514) (xy 431.216277 -197.282642)
			(xy 431.228274 -197.231374) (xy 431.247957 -197.182539) (xy 431.274863 -197.13728) (xy 431.308363 -197.096659)
			(xy 431.347671 -197.061628) (xy 431.391866 -197.033008) (xy 431.439911 -197.011469) (xy 431.490682 -196.997517)
			(xy 431.542987 -196.991479) (xy 431.595601 -196.993496) (xy 431.647291 -197.00352) (xy 431.696844 -197.021318)
			(xy 431.7431 -197.046471) (xy 431.784974 -197.07839) (xy 431.821486 -197.116328) (xy 431.851778 -197.159394)
			(xy 431.875141 -197.206579) (xy 431.891027 -197.256778) (xy 431.899064 -197.308814) (xy 431.899568 -197.33514)
			(xy 434.630845 -197.33514) (xy 434.63478 -197.281369) (xy 434.646503 -197.228745) (xy 434.665763 -197.178388)
			(xy 434.692149 -197.131371) (xy 434.725101 -197.088698) (xy 434.763914 -197.051277) (xy 434.807762 -197.019907)
			(xy 434.85571 -196.995255) (xy 434.906737 -196.977847) (xy 434.959755 -196.968054) (xy 435.013634 -196.966085)
			(xy 435.067225 -196.971982) (xy 435.119386 -196.985618) (xy 435.169006 -197.006705) (xy 435.215027 -197.034791)
			(xy 435.256469 -197.069279) (xy 435.292447 -197.109433) (xy 435.322195 -197.154397) (xy 435.34508 -197.203214)
			(xy 435.360612 -197.254843) (xy 435.368462 -197.308183) (xy 435.368954 -197.33514) (xy 438.756301 -197.33514)
			(xy 438.760331 -197.282642) (xy 438.772328 -197.231374) (xy 438.792011 -197.182539) (xy 438.818917 -197.13728)
			(xy 438.852417 -197.096659) (xy 438.891725 -197.061628) (xy 438.93592 -197.033008) (xy 438.983965 -197.011469)
			(xy 439.034736 -196.997517) (xy 439.087041 -196.991479) (xy 439.139655 -196.993496) (xy 439.191345 -197.00352)
			(xy 439.240898 -197.021318) (xy 439.287154 -197.046471) (xy 439.329028 -197.07839) (xy 439.36554 -197.116328)
			(xy 439.395832 -197.159394) (xy 439.419195 -197.206579) (xy 439.435081 -197.256778) (xy 439.443118 -197.308814)
			(xy 439.443622 -197.33514) (xy 442.174899 -197.33514) (xy 442.178834 -197.281369) (xy 442.190557 -197.228745)
			(xy 442.209817 -197.178388) (xy 442.236203 -197.131371) (xy 442.269155 -197.088698) (xy 442.307968 -197.051277)
			(xy 442.351816 -197.019907) (xy 442.399764 -196.995255) (xy 442.450791 -196.977847) (xy 442.503809 -196.968054)
			(xy 442.557688 -196.966085) (xy 442.611279 -196.971982) (xy 442.66344 -196.985618) (xy 442.71306 -197.006705)
			(xy 442.759081 -197.034791) (xy 442.800523 -197.069279) (xy 442.836501 -197.109433) (xy 442.866249 -197.154397)
			(xy 442.889134 -197.203214) (xy 442.904666 -197.254843) (xy 442.912516 -197.308183) (xy 442.913008 -197.33514)
			(xy 446.300355 -197.33514) (xy 446.304385 -197.282642) (xy 446.316382 -197.231374) (xy 446.336065 -197.182539)
			(xy 446.362971 -197.13728) (xy 446.396471 -197.096659) (xy 446.435779 -197.061628) (xy 446.479974 -197.033008)
			(xy 446.528019 -197.011469) (xy 446.57879 -196.997517) (xy 446.631095 -196.991479) (xy 446.683709 -196.993496)
			(xy 446.735399 -197.00352) (xy 446.784952 -197.021318) (xy 446.831208 -197.046471) (xy 446.873082 -197.07839)
			(xy 446.909594 -197.116328) (xy 446.939886 -197.159394) (xy 446.963249 -197.206579) (xy 446.979135 -197.256778)
			(xy 446.987172 -197.308814) (xy 446.987676 -197.33514) (xy 449.718699 -197.33514) (xy 449.722634 -197.281369)
			(xy 449.734357 -197.228745) (xy 449.753617 -197.178388) (xy 449.780003 -197.131371) (xy 449.812955 -197.088698)
			(xy 449.851768 -197.051277) (xy 449.895616 -197.019907) (xy 449.943564 -196.995255) (xy 449.994591 -196.977847)
			(xy 450.047609 -196.968054) (xy 450.101488 -196.966085) (xy 450.155079 -196.971982) (xy 450.20724 -196.985618)
			(xy 450.25686 -197.006705) (xy 450.302881 -197.034791) (xy 450.344323 -197.069279) (xy 450.380301 -197.109433)
			(xy 450.410049 -197.154397) (xy 450.432934 -197.203214) (xy 450.448466 -197.254843) (xy 450.456316 -197.308183)
			(xy 450.456808 -197.33514) (xy 450.456316 -197.362097) (xy 450.448466 -197.415437) (xy 450.432934 -197.467066)
			(xy 450.410049 -197.515883) (xy 450.380301 -197.560847) (xy 450.344323 -197.601001) (xy 450.302881 -197.635489)
			(xy 450.25686 -197.663575) (xy 450.20724 -197.684662) (xy 450.155079 -197.698298) (xy 450.101488 -197.704195)
			(xy 450.047609 -197.702226) (xy 449.994591 -197.692433) (xy 449.943564 -197.675025) (xy 449.895616 -197.650373)
			(xy 449.851768 -197.619003) (xy 449.812955 -197.581582) (xy 449.780003 -197.538909) (xy 449.753617 -197.491892)
			(xy 449.734357 -197.441535) (xy 449.722634 -197.388911) (xy 449.718699 -197.33514) (xy 446.987676 -197.33514)
			(xy 446.987172 -197.361466) (xy 446.979135 -197.413502) (xy 446.963249 -197.463701) (xy 446.939886 -197.510886)
			(xy 446.909594 -197.553952) (xy 446.873082 -197.59189) (xy 446.831208 -197.623809) (xy 446.784952 -197.648962)
			(xy 446.735399 -197.66676) (xy 446.683709 -197.676784) (xy 446.631095 -197.678801) (xy 446.57879 -197.672763)
			(xy 446.528019 -197.658811) (xy 446.479974 -197.637272) (xy 446.435779 -197.608652) (xy 446.396471 -197.573621)
			(xy 446.362971 -197.533) (xy 446.336065 -197.487741) (xy 446.316382 -197.438906) (xy 446.304385 -197.387638)
			(xy 446.300355 -197.33514) (xy 442.913008 -197.33514) (xy 442.912516 -197.362097) (xy 442.904666 -197.415437)
			(xy 442.889134 -197.467066) (xy 442.866249 -197.515883) (xy 442.836501 -197.560847) (xy 442.800523 -197.601001)
			(xy 442.759081 -197.635489) (xy 442.71306 -197.663575) (xy 442.66344 -197.684662) (xy 442.611279 -197.698298)
			(xy 442.557688 -197.704195) (xy 442.503809 -197.702226) (xy 442.450791 -197.692433) (xy 442.399764 -197.675025)
			(xy 442.351816 -197.650373) (xy 442.307968 -197.619003) (xy 442.269155 -197.581582) (xy 442.236203 -197.538909)
			(xy 442.209817 -197.491892) (xy 442.190557 -197.441535) (xy 442.178834 -197.388911) (xy 442.174899 -197.33514)
			(xy 439.443622 -197.33514) (xy 439.443118 -197.361466) (xy 439.435081 -197.413502) (xy 439.419195 -197.463701)
			(xy 439.395832 -197.510886) (xy 439.36554 -197.553952) (xy 439.329028 -197.59189) (xy 439.287154 -197.623809)
			(xy 439.240898 -197.648962) (xy 439.191345 -197.66676) (xy 439.139655 -197.676784) (xy 439.087041 -197.678801)
			(xy 439.034736 -197.672763) (xy 438.983965 -197.658811) (xy 438.93592 -197.637272) (xy 438.891725 -197.608652)
			(xy 438.852417 -197.573621) (xy 438.818917 -197.533) (xy 438.792011 -197.487741) (xy 438.772328 -197.438906)
			(xy 438.760331 -197.387638) (xy 438.756301 -197.33514) (xy 435.368954 -197.33514) (xy 435.368462 -197.362097)
			(xy 435.360612 -197.415437) (xy 435.34508 -197.467066) (xy 435.322195 -197.515883) (xy 435.292447 -197.560847)
			(xy 435.256469 -197.601001) (xy 435.215027 -197.635489) (xy 435.169006 -197.663575) (xy 435.119386 -197.684662)
			(xy 435.067225 -197.698298) (xy 435.013634 -197.704195) (xy 434.959755 -197.702226) (xy 434.906737 -197.692433)
			(xy 434.85571 -197.675025) (xy 434.807762 -197.650373) (xy 434.763914 -197.619003) (xy 434.725101 -197.581582)
			(xy 434.692149 -197.538909) (xy 434.665763 -197.491892) (xy 434.646503 -197.441535) (xy 434.63478 -197.388911)
			(xy 434.630845 -197.33514) (xy 431.899568 -197.33514) (xy 431.899064 -197.361466) (xy 431.891027 -197.413502)
			(xy 431.875141 -197.463701) (xy 431.851778 -197.510886) (xy 431.821486 -197.553952) (xy 431.784974 -197.59189)
			(xy 431.7431 -197.623809) (xy 431.696844 -197.648962) (xy 431.647291 -197.66676) (xy 431.595601 -197.676784)
			(xy 431.542987 -197.678801) (xy 431.490682 -197.672763) (xy 431.439911 -197.658811) (xy 431.391866 -197.637272)
			(xy 431.347671 -197.608652) (xy 431.308363 -197.573621) (xy 431.274863 -197.533) (xy 431.247957 -197.487741)
			(xy 431.228274 -197.438906) (xy 431.216277 -197.387638) (xy 431.212247 -197.33514) (xy 427.8249 -197.33514)
			(xy 427.824408 -197.362097) (xy 427.816558 -197.415437) (xy 427.801026 -197.467066) (xy 427.778141 -197.515883)
			(xy 427.748393 -197.560847) (xy 427.712415 -197.601001) (xy 427.670973 -197.635489) (xy 427.624952 -197.663575)
			(xy 427.575332 -197.684662) (xy 427.523171 -197.698298) (xy 427.46958 -197.704195) (xy 427.415701 -197.702226)
			(xy 427.362683 -197.692433) (xy 427.311656 -197.675025) (xy 427.263708 -197.650373) (xy 427.21986 -197.619003)
			(xy 427.181047 -197.581582) (xy 427.148095 -197.538909) (xy 427.121709 -197.491892) (xy 427.102449 -197.441535)
			(xy 427.090726 -197.388911) (xy 427.086791 -197.33514) (xy 424.355514 -197.33514) (xy 424.35501 -197.361466)
			(xy 424.346973 -197.413502) (xy 424.331087 -197.463701) (xy 424.307724 -197.510886) (xy 424.277432 -197.553952)
			(xy 424.24092 -197.59189) (xy 424.199046 -197.623809) (xy 424.15279 -197.648962) (xy 424.103237 -197.66676)
			(xy 424.051547 -197.676784) (xy 423.998933 -197.678801) (xy 423.946628 -197.672763) (xy 423.895857 -197.658811)
			(xy 423.847812 -197.637272) (xy 423.803617 -197.608652) (xy 423.764309 -197.573621) (xy 423.730809 -197.533)
			(xy 423.703903 -197.487741) (xy 423.68422 -197.438906) (xy 423.672223 -197.387638) (xy 423.668193 -197.33514)
			(xy 420.280846 -197.33514) (xy 420.280354 -197.362097) (xy 420.272504 -197.415437) (xy 420.256972 -197.467066)
			(xy 420.234087 -197.515883) (xy 420.204339 -197.560847) (xy 420.168361 -197.601001) (xy 420.126919 -197.635489)
			(xy 420.080898 -197.663575) (xy 420.031278 -197.684662) (xy 419.979117 -197.698298) (xy 419.925526 -197.704195)
			(xy 419.871647 -197.702226) (xy 419.818629 -197.692433) (xy 419.767602 -197.675025) (xy 419.719654 -197.650373)
			(xy 419.675806 -197.619003) (xy 419.636993 -197.581582) (xy 419.604041 -197.538909) (xy 419.577655 -197.491892)
			(xy 419.558395 -197.441535) (xy 419.546672 -197.388911) (xy 419.542737 -197.33514) (xy 414.019238 -197.33514)
			(xy 414.019238 -197.537578) (xy 414.019676 -197.547641) (xy 414.027415 -197.566221) (xy 414.034224 -197.573646)
			(xy 414.774126 -198.313548) (xy 414.781524 -198.320396) (xy 414.800122 -198.328129) (xy 414.810194 -198.328534)
		)
		(stroke
			(width 0)
			(type solid)
		)
		(fill yes)
		(layer "B.Cu")
		(net "P3V3")
	)
	(gr_poly
		(pts
			(xy 168.13911 -198.551546) (xy 168.148268 -198.551114) (xy 168.165395 -198.544607) (xy 168.179168 -198.532524)
			(xy 168.183814 -198.524622) (xy 168.225978 -198.44512) (xy 168.229892 -198.436836) (xy 168.232185 -198.418672)
			(xy 168.227986 -198.400851) (xy 168.223184 -198.39305) (xy 168.223184 -198.392796) (xy 168.208098 -198.369719)
			(xy 168.184198 -198.320037) (xy 168.167944 -198.267355) (xy 168.159697 -198.212843) (xy 168.159176 -198.185278)
			(xy 168.159692 -198.157678) (xy 168.167919 -198.103095) (xy 168.184189 -198.050348) (xy 168.208139 -198.000616)
			(xy 168.239234 -197.955008) (xy 168.276779 -197.914544) (xy 168.319936 -197.880127) (xy 168.36774 -197.852528)
			(xy 168.419124 -197.832361) (xy 168.472939 -197.820078) (xy 168.527984 -197.815953) (xy 168.583029 -197.820078)
			(xy 168.636844 -197.832361) (xy 168.688228 -197.852528) (xy 168.736032 -197.880127) (xy 168.779189 -197.914544)
			(xy 168.816734 -197.955008) (xy 168.847829 -198.000616) (xy 168.871779 -198.050348) (xy 168.888049 -198.103095)
			(xy 168.896276 -198.157678) (xy 168.896792 -198.185278) (xy 168.896264 -198.212814) (xy 168.888031 -198.267267)
			(xy 168.871774 -198.319884) (xy 168.847858 -198.369492) (xy 168.832784 -198.392542) (xy 168.832784 -198.39305)
			(xy 168.827976 -198.400855) (xy 168.823731 -198.418673) (xy 168.82605 -198.436842) (xy 168.82999 -198.44512)
			(xy 168.872154 -198.524622) (xy 168.876788 -198.532539) (xy 168.890541 -198.544659) (xy 168.907692 -198.551127)
			(xy 168.916858 -198.551546) (xy 171.614338 -198.551546) (xy 171.623681 -198.551074) (xy 171.641102 -198.544298)
			(xy 171.654965 -198.531759) (xy 171.65955 -198.523606) (xy 171.700444 -198.44258) (xy 171.704289 -198.434013)
			(xy 171.706144 -198.415343) (xy 171.701152 -198.397257) (xy 171.695872 -198.389494) (xy 171.680031 -198.367188)
			(xy 171.654882 -198.318604) (xy 171.637755 -198.266647) (xy 171.629083 -198.212632) (xy 171.628562 -198.185278)
			(xy 171.629042 -198.159579) (xy 171.636703 -198.108755) (xy 171.651852 -198.059641) (xy 171.674153 -198.013333)
			(xy 171.703106 -197.970866) (xy 171.738066 -197.933189) (xy 171.77825 -197.901143) (xy 171.822762 -197.875444)
			(xy 171.870607 -197.856667) (xy 171.920716 -197.845229) (xy 171.97197 -197.841389) (xy 172.023224 -197.845229)
			(xy 172.073333 -197.856667) (xy 172.121178 -197.875444) (xy 172.16569 -197.901143) (xy 172.205874 -197.933189)
			(xy 172.240834 -197.970866) (xy 172.269787 -198.013333) (xy 172.292088 -198.059641) (xy 172.307237 -198.108755)
			(xy 172.314898 -198.159579) (xy 172.315378 -198.185278) (xy 172.314849 -198.212632) (xy 172.306181 -198.266648)
			(xy 172.28906 -198.318607) (xy 172.263919 -198.367195) (xy 172.248068 -198.389494) (xy 172.242835 -198.397285)
			(xy 172.23784 -198.415357) (xy 172.239652 -198.43402) (xy 172.243496 -198.44258) (xy 172.28439 -198.523606)
			(xy 172.288956 -198.531782) (xy 172.302797 -198.544371) (xy 172.320247 -198.55112) (xy 172.329602 -198.551546)
			(xy 175.683164 -198.551546) (xy 175.692317 -198.551105) (xy 175.70943 -198.544586) (xy 175.723187 -198.532501)
			(xy 175.727868 -198.524622) (xy 175.770032 -198.44512) (xy 175.773949 -198.436837) (xy 175.776244 -198.418672)
			(xy 175.772041 -198.400851) (xy 175.767238 -198.39305) (xy 175.767238 -198.392796) (xy 175.752153 -198.369718)
			(xy 175.728256 -198.320036) (xy 175.712005 -198.267354) (xy 175.703759 -198.212843) (xy 175.70323 -198.185278)
			(xy 175.703746 -198.157678) (xy 175.711973 -198.103095) (xy 175.728243 -198.050348) (xy 175.752193 -198.000616)
			(xy 175.783288 -197.955008) (xy 175.820833 -197.914544) (xy 175.86399 -197.880127) (xy 175.911794 -197.852528)
			(xy 175.963178 -197.832361) (xy 176.016993 -197.820078) (xy 176.072038 -197.815953) (xy 176.127083 -197.820078)
			(xy 176.180898 -197.832361) (xy 176.232282 -197.852528) (xy 176.280086 -197.880127) (xy 176.323243 -197.914544)
			(xy 176.360788 -197.955008) (xy 176.391883 -198.000616) (xy 176.415833 -198.050348) (xy 176.432103 -198.103095)
			(xy 176.44033 -198.157678) (xy 176.440846 -198.185278) (xy 176.440319 -198.212814) (xy 176.432086 -198.267267)
			(xy 176.415831 -198.319886) (xy 176.391918 -198.369496) (xy 176.376838 -198.392542) (xy 176.376838 -198.39305)
			(xy 176.372026 -198.400853) (xy 176.367777 -198.418673) (xy 176.370098 -198.436844) (xy 176.374044 -198.44512)
			(xy 176.416208 -198.524622) (xy 176.42084 -198.532544) (xy 176.43459 -198.544677) (xy 176.451743 -198.55116)
			(xy 176.460912 -198.551546) (xy 179.158392 -198.551546) (xy 179.16774 -198.551081) (xy 179.185173 -198.544315)
			(xy 179.199049 -198.531779) (xy 179.203604 -198.523606) (xy 179.244498 -198.44258) (xy 179.248346 -198.434014)
			(xy 179.250202 -198.415343) (xy 179.245206 -198.397258) (xy 179.239926 -198.389494) (xy 179.224087 -198.367187)
			(xy 179.198941 -198.318603) (xy 179.181816 -198.266646) (xy 179.173146 -198.212631) (xy 179.172616 -198.185278)
			(xy 179.173096 -198.159579) (xy 179.180757 -198.108755) (xy 179.195906 -198.059641) (xy 179.218207 -198.013333)
			(xy 179.24716 -197.970866) (xy 179.28212 -197.933189) (xy 179.322304 -197.901143) (xy 179.366816 -197.875444)
			(xy 179.414661 -197.856667) (xy 179.46477 -197.845229) (xy 179.516024 -197.841389) (xy 179.567278 -197.845229)
			(xy 179.617387 -197.856667) (xy 179.665232 -197.875444) (xy 179.709744 -197.901143) (xy 179.749928 -197.933189)
			(xy 179.784888 -197.970866) (xy 179.813841 -198.013333) (xy 179.836142 -198.059641) (xy 179.851291 -198.108755)
			(xy 179.858952 -198.159579) (xy 179.859432 -198.185278) (xy 179.858904 -198.212632) (xy 179.850237 -198.266649)
			(xy 179.833118 -198.31861) (xy 179.80798 -198.3672) (xy 179.792122 -198.389494) (xy 179.786885 -198.397283)
			(xy 179.781884 -198.415357) (xy 179.783698 -198.434023) (xy 179.78755 -198.44258) (xy 179.828444 -198.523606)
			(xy 179.833008 -198.531787) (xy 179.846847 -198.544388) (xy 179.864298 -198.551152) (xy 179.873656 -198.551546)
			(xy 183.227218 -198.551546) (xy 183.236375 -198.551112) (xy 183.2535 -198.544604) (xy 183.26727 -198.532521)
			(xy 183.271922 -198.524622) (xy 183.314086 -198.44512) (xy 183.318006 -198.436838) (xy 183.320303 -198.418672)
			(xy 183.316096 -198.400851) (xy 183.311292 -198.39305) (xy 183.311292 -198.392796) (xy 183.296205 -198.369719)
			(xy 183.272305 -198.320037) (xy 183.256051 -198.267355) (xy 183.247804 -198.212844) (xy 183.247284 -198.185278)
			(xy 183.2478 -198.157678) (xy 183.256027 -198.103095) (xy 183.272297 -198.050348) (xy 183.296247 -198.000616)
			(xy 183.327342 -197.955008) (xy 183.364887 -197.914544) (xy 183.408044 -197.880127) (xy 183.455848 -197.852528)
			(xy 183.507232 -197.832361) (xy 183.561047 -197.820078) (xy 183.616092 -197.815953) (xy 183.671137 -197.820078)
			(xy 183.724952 -197.832361) (xy 183.776336 -197.852528) (xy 183.82414 -197.880127) (xy 183.867297 -197.914544)
			(xy 183.904842 -197.955008) (xy 183.935937 -198.000616) (xy 183.959887 -198.050348) (xy 183.976157 -198.103095)
			(xy 183.984384 -198.157678) (xy 183.9849 -198.185278) (xy 183.984372 -198.212814) (xy 183.976139 -198.267267)
			(xy 183.959883 -198.319885) (xy 183.935967 -198.369493) (xy 183.920892 -198.392542) (xy 183.920892 -198.39305)
			(xy 183.916084 -198.400855) (xy 183.911838 -198.418673) (xy 183.914158 -198.436843) (xy 183.918098 -198.44512)
			(xy 183.960262 -198.524622) (xy 183.964897 -198.532538) (xy 183.978649 -198.544656) (xy 183.995801 -198.551121)
			(xy 184.004966 -198.551546) (xy 186.702446 -198.551546) (xy 186.711788 -198.551072) (xy 186.729207 -198.544295)
			(xy 186.743068 -198.531756) (xy 186.747658 -198.523606) (xy 186.788552 -198.44258) (xy 186.792397 -198.434013)
			(xy 186.794251 -198.415343) (xy 186.78926 -198.397257) (xy 186.78398 -198.389494) (xy 186.768139 -198.367188)
			(xy 186.742989 -198.318604) (xy 186.725861 -198.266647) (xy 186.71719 -198.212632) (xy 186.71667 -198.185278)
			(xy 186.71715 -198.159579) (xy 186.724811 -198.108755) (xy 186.73996 -198.059641) (xy 186.762261 -198.013333)
			(xy 186.791214 -197.970866) (xy 186.826174 -197.933189) (xy 186.866358 -197.901143) (xy 186.91087 -197.875444)
			(xy 186.958715 -197.856667) (xy 187.008824 -197.845229) (xy 187.060078 -197.841389) (xy 187.111332 -197.845229)
			(xy 187.161441 -197.856667) (xy 187.209286 -197.875444) (xy 187.253798 -197.901143) (xy 187.293982 -197.933189)
			(xy 187.328942 -197.970866) (xy 187.357895 -198.013333) (xy 187.380196 -198.059641) (xy 187.395345 -198.108755)
			(xy 187.403006 -198.159579) (xy 187.403486 -198.185278) (xy 187.402957 -198.212632) (xy 187.394289 -198.266648)
			(xy 187.377168 -198.318607) (xy 187.352028 -198.367196) (xy 187.336176 -198.389494) (xy 187.330943 -198.397285)
			(xy 187.325947 -198.415357) (xy 187.327759 -198.434021) (xy 187.331604 -198.44258) (xy 187.372498 -198.523606)
			(xy 187.377065 -198.531781) (xy 187.390906 -198.544368) (xy 187.408356 -198.551113) (xy 187.41771 -198.551546)
			(xy 190.771272 -198.551546) (xy 190.780424 -198.551104) (xy 190.797535 -198.544583) (xy 190.81129 -198.532497)
			(xy 190.815976 -198.524622) (xy 190.85814 -198.44512) (xy 190.862057 -198.436837) (xy 190.864351 -198.418672)
			(xy 190.860149 -198.400851) (xy 190.855346 -198.39305) (xy 190.855346 -198.392796) (xy 190.840261 -198.369718)
			(xy 190.816363 -198.320036) (xy 190.800111 -198.267354) (xy 190.791866 -198.212843) (xy 190.791338 -198.185278)
			(xy 190.791854 -198.157678) (xy 190.800081 -198.103095) (xy 190.816351 -198.050348) (xy 190.840301 -198.000616)
			(xy 190.871396 -197.955008) (xy 190.908941 -197.914544) (xy 190.952098 -197.880127) (xy 190.999902 -197.852528)
			(xy 191.051286 -197.832361) (xy 191.105101 -197.820078) (xy 191.160146 -197.815953) (xy 191.215191 -197.820078)
			(xy 191.269006 -197.832361) (xy 191.32039 -197.852528) (xy 191.368194 -197.880127) (xy 191.411351 -197.914544)
			(xy 191.448896 -197.955008) (xy 191.479991 -198.000616) (xy 191.503941 -198.050348) (xy 191.520211 -198.103095)
			(xy 191.528438 -198.157678) (xy 191.528954 -198.185278) (xy 191.528426 -198.212814) (xy 191.520192 -198.267266)
			(xy 191.503934 -198.319883) (xy 191.480015 -198.369489) (xy 191.464946 -198.392542) (xy 191.464946 -198.39305)
			(xy 191.460133 -198.400853) (xy 191.455883 -198.418673) (xy 191.458206 -198.436845) (xy 191.462152 -198.44512)
			(xy 191.504316 -198.524622) (xy 191.508949 -198.532543) (xy 191.522699 -198.544673) (xy 191.539852 -198.551154)
			(xy 191.54902 -198.551546) (xy 194.2465 -198.551546) (xy 194.255847 -198.55108) (xy 194.273278 -198.544312)
			(xy 194.287152 -198.531776) (xy 194.291712 -198.523606) (xy 194.332606 -198.44258) (xy 194.336453 -198.434013)
			(xy 194.338309 -198.415343) (xy 194.333314 -198.397258) (xy 194.328034 -198.389494) (xy 194.312195 -198.367187)
			(xy 194.287048 -198.318603) (xy 194.269923 -198.266646) (xy 194.261252 -198.212631) (xy 194.260724 -198.185278)
			(xy 194.261204 -198.159579) (xy 194.268865 -198.108755) (xy 194.284014 -198.059641) (xy 194.306315 -198.013333)
			(xy 194.335268 -197.970866) (xy 194.370228 -197.933189) (xy 194.410412 -197.901143) (xy 194.454924 -197.875444)
			(xy 194.502769 -197.856667) (xy 194.552878 -197.845229) (xy 194.604132 -197.841389) (xy 194.655386 -197.845229)
			(xy 194.705495 -197.856667) (xy 194.75334 -197.875444) (xy 194.797852 -197.901143) (xy 194.838036 -197.933189)
			(xy 194.872996 -197.970866) (xy 194.901949 -198.013333) (xy 194.92425 -198.059641) (xy 194.939399 -198.108755)
			(xy 194.94706 -198.159579) (xy 194.94754 -198.185278) (xy 194.947011 -198.212631) (xy 194.938342 -198.266647)
			(xy 194.921219 -198.318605) (xy 194.896076 -198.367192) (xy 194.88023 -198.389494) (xy 194.874992 -198.397283)
			(xy 194.86999 -198.415357) (xy 194.871805 -198.434023) (xy 194.875658 -198.44258) (xy 194.916552 -198.523606)
			(xy 194.921117 -198.531786) (xy 194.934955 -198.544385) (xy 194.952407 -198.551147) (xy 194.961764 -198.551546)
			(xy 198.315326 -198.551546) (xy 198.324483 -198.551111) (xy 198.341605 -198.544601) (xy 198.355373 -198.532517)
			(xy 198.36003 -198.524622) (xy 198.402194 -198.44512) (xy 198.406113 -198.436838) (xy 198.40841 -198.418672)
			(xy 198.404204 -198.400851) (xy 198.3994 -198.39305) (xy 198.3994 -198.392796) (xy 198.384313 -198.369719)
			(xy 198.360412 -198.320037) (xy 198.344157 -198.267356) (xy 198.335911 -198.212844) (xy 198.335392 -198.185278)
			(xy 198.335908 -198.157678) (xy 198.344135 -198.103095) (xy 198.360405 -198.050348) (xy 198.384355 -198.000616)
			(xy 198.41545 -197.955008) (xy 198.452995 -197.914544) (xy 198.496152 -197.880127) (xy 198.543956 -197.852528)
			(xy 198.59534 -197.832361) (xy 198.649155 -197.820078) (xy 198.7042 -197.815953) (xy 198.759245 -197.820078)
			(xy 198.81306 -197.832361) (xy 198.864444 -197.852528) (xy 198.912248 -197.880127) (xy 198.955405 -197.914544)
			(xy 198.99295 -197.955008) (xy 199.024045 -198.000616) (xy 199.047995 -198.050348) (xy 199.064265 -198.103095)
			(xy 199.072492 -198.157678) (xy 199.073008 -198.185278) (xy 199.072481 -198.212814) (xy 199.064247 -198.267267)
			(xy 199.047991 -198.319885) (xy 199.024075 -198.369493) (xy 199.009 -198.392542) (xy 199.009 -198.39305)
			(xy 199.004191 -198.400854) (xy 198.999945 -198.418673) (xy 199.002265 -198.436843) (xy 199.006206 -198.44512)
			(xy 199.04837 -198.524622) (xy 199.053 -198.532548) (xy 199.066749 -198.544691) (xy 199.083903 -198.551187)
			(xy 199.093074 -198.551546) (xy 201.7903 -198.551546) (xy 201.799647 -198.55108) (xy 201.817078 -198.544312)
			(xy 201.830952 -198.531776) (xy 201.835512 -198.523606) (xy 201.876406 -198.44258) (xy 201.880253 -198.434013)
			(xy 201.882109 -198.415343) (xy 201.877114 -198.397258) (xy 201.871834 -198.389494) (xy 201.855995 -198.367187)
			(xy 201.830848 -198.318603) (xy 201.813723 -198.266646) (xy 201.805052 -198.212631) (xy 201.804524 -198.185278)
			(xy 201.805004 -198.159579) (xy 201.812665 -198.108755) (xy 201.827814 -198.059641) (xy 201.850115 -198.013333)
			(xy 201.879068 -197.970866) (xy 201.914028 -197.933189) (xy 201.954212 -197.901143) (xy 201.998724 -197.875444)
			(xy 202.046569 -197.856667) (xy 202.096678 -197.845229) (xy 202.147932 -197.841389) (xy 202.199186 -197.845229)
			(xy 202.249295 -197.856667) (xy 202.29714 -197.875444) (xy 202.341652 -197.901143) (xy 202.381836 -197.933189)
			(xy 202.416796 -197.970866) (xy 202.445749 -198.013333) (xy 202.46805 -198.059641) (xy 202.483199 -198.108755)
			(xy 202.49086 -198.159579) (xy 202.49134 -198.185278) (xy 202.490811 -198.212631) (xy 202.482142 -198.266647)
			(xy 202.465019 -198.318605) (xy 202.439876 -198.367192) (xy 202.42403 -198.389494) (xy 202.418792 -198.397283)
			(xy 202.41379 -198.415357) (xy 202.415605 -198.434023) (xy 202.419458 -198.44258) (xy 202.460352 -198.523606)
			(xy 202.464917 -198.531786) (xy 202.478755 -198.544385) (xy 202.496207 -198.551147) (xy 202.505564 -198.551546)
			(xy 205.43647 -198.551546) (xy 205.446533 -198.551109) (xy 205.465114 -198.54337) (xy 205.472538 -198.53656)
			(xy 205.555088 -198.45401) (xy 205.561937 -198.446613) (xy 205.569677 -198.428015) (xy 205.570074 -198.417942)
			(xy 205.570074 -197.11289) (xy 205.570498 -197.10282) (xy 205.578212 -197.084216) (xy 205.58506 -197.076822)
			(xy 205.9051 -196.756528) (xy 205.912974 -196.746368) (xy 205.931008 -196.715634) (xy 205.935326 -196.708014)
			(xy 205.935326 -196.694806) (xy 205.935101 -196.688204) (xy 205.931619 -196.675466) (xy 205.928468 -196.66966)
			(xy 205.928468 -196.669406) (xy 205.915083 -196.64519) (xy 205.89493 -196.593662) (xy 205.888336 -196.56679)
			(xy 205.886107 -196.556467) (xy 205.882678 -196.535626) (xy 205.881478 -196.525134) (xy 205.880208 -196.515736)
			(xy 205.8797 -196.510656) (xy 205.865137 -196.512085) (xy 205.835912 -196.51361) (xy 205.82128 -196.513704)
			(xy 205.139036 -196.513704) (xy 205.107527 -196.513248) (xy 205.044907 -196.506166) (xy 204.983474 -196.492122)
			(xy 204.923998 -196.47129) (xy 204.867227 -196.443934) (xy 204.813873 -196.410396) (xy 204.764608 -196.371099)
			(xy 204.742034 -196.349112) (xy 204.613256 -196.220334) (xy 204.591268 -196.19776) (xy 204.551958 -196.148502)
			(xy 204.518411 -196.095152) (xy 204.49105 -196.03838) (xy 204.470218 -195.978902) (xy 204.456178 -195.917465)
			(xy 204.449106 -195.854842) (xy 204.448664 -195.823332) (xy 204.449147 -195.790176) (xy 204.456955 -195.724324)
			(xy 204.472467 -195.659851) (xy 204.495465 -195.597654) (xy 204.52563 -195.538599) (xy 204.562542 -195.483509)
			(xy 204.605687 -195.433152) (xy 204.654464 -195.388227) (xy 204.708194 -195.349361) (xy 204.736954 -195.332858)
			(xy 204.695298 -195.291202) (xy 204.673352 -195.268622) (xy 204.634101 -195.219385) (xy 204.600605 -195.166064)
			(xy 204.573285 -195.109331) (xy 204.552485 -195.049897) (xy 204.538466 -194.988509) (xy 204.531403 -194.925938)
			(xy 204.53096 -194.894454) (xy 204.53096 -194.893946) (xy 204.531442 -194.860555) (xy 204.539363 -194.794246)
			(xy 204.555088 -194.729342) (xy 204.578394 -194.66676) (xy 204.608954 -194.607381) (xy 204.646336 -194.552043)
			(xy 204.690013 -194.501525) (xy 204.714348 -194.478656) (xy 204.721603 -194.471435) (xy 204.730161 -194.452862)
			(xy 204.730788 -194.432421) (xy 204.723384 -194.413358) (xy 204.709124 -194.398699) (xy 204.69987 -194.394328)
			(xy 204.695503 -194.392357) (xy 204.68757 -194.386987) (xy 204.684122 -194.38366) (xy 204.006704 -193.706242)
			(xy 204.003853 -193.703536) (xy 203.997475 -193.698942) (xy 203.994004 -193.697098) (xy 203.988576 -193.694521)
			(xy 203.976896 -193.691709) (xy 203.97089 -193.69151) (xy 203.209652 -193.69151) (xy 203.199586 -193.691942)
			(xy 203.180995 -193.69967) (xy 203.173584 -193.706496) (xy 203.100686 -193.779394) (xy 203.093829 -193.786788)
			(xy 203.086079 -193.805387) (xy 203.0857 -193.815462) (xy 203.0857 -194.182492) (xy 203.086122 -194.192563)
			(xy 203.093834 -194.211169) (xy 203.100686 -194.21856) (xy 203.269342 -194.387216) (xy 203.276623 -194.393889)
			(xy 203.29479 -194.401587) (xy 203.304648 -194.402202) (xy 203.306934 -194.402202) (xy 203.32192 -194.40271)
			(xy 203.686156 -194.40271) (xy 203.695994 -194.403244) (xy 203.714158 -194.410828) (xy 203.721462 -194.417442)
			(xy 203.844398 -194.540378) (xy 203.851118 -194.547614) (xy 203.858726 -194.565819) (xy 203.85913 -194.575684)
			(xy 203.85913 -195.259452) (xy 203.858719 -195.269482) (xy 203.851059 -195.288021) (xy 203.836886 -195.302215)
			(xy 203.818359 -195.309904) (xy 203.80833 -195.310252) (xy 203.491084 -195.310252) (xy 203.480162 -195.311522)
			(xy 203.464668 -195.314824) (xy 203.464414 -195.314824) (xy 203.43516 -195.327653) (xy 203.373897 -195.345742)
			(xy 203.310678 -195.35489) (xy 203.27874 -195.355464) (xy 202.557126 -195.355464) (xy 202.525186 -195.354912)
			(xy 202.461965 -195.345764) (xy 202.400707 -195.327654) (xy 202.371452 -195.314824) (xy 202.361292 -195.310252)
			(xy 200.55586 -195.310252) (xy 200.545848 -195.309825) (xy 200.527353 -195.302146) (xy 200.513205 -195.287974)
			(xy 200.505558 -195.269465) (xy 200.50506 -195.259452) (xy 200.50506 -194.932046) (xy 200.503028 -194.925188)
			(xy 200.50252 -194.922648) (xy 200.499776 -194.914115) (xy 200.489315 -194.899573) (xy 200.474487 -194.889522)
			(xy 200.457105 -194.885191) (xy 200.448164 -194.885818) (xy 200.43902 -194.887596) (xy 200.430726 -194.890433)
			(xy 200.416588 -194.900776) (xy 200.406754 -194.915272) (xy 200.404222 -194.923664) (xy 200.404222 -194.923918)
			(xy 200.394357 -194.960256) (xy 200.366214 -195.030097) (xy 200.328987 -195.095548) (xy 200.283344 -195.155435)
			(xy 200.257156 -195.18249) (xy 200.232772 -195.20662) (xy 200.2282 -195.211446) (xy 200.253777 -195.234349)
			(xy 200.299732 -195.285357) (xy 200.339127 -195.341586) (xy 200.371376 -195.402198) (xy 200.395997 -195.466288)
			(xy 200.412623 -195.532901) (xy 200.421007 -195.601044) (xy 200.421494 -195.635372) (xy 200.421038 -195.666881)
			(xy 200.413955 -195.7295) (xy 200.399909 -195.790933) (xy 200.379077 -195.850408) (xy 200.35172 -195.907178)
			(xy 200.318181 -195.96053) (xy 200.278883 -196.009794) (xy 200.256902 -196.032374) (xy 199.868536 -196.420994)
			(xy 199.06742 -196.420994) (xy 199.07003 -196.436803) (xy 199.072823 -196.468726) (xy 199.073008 -196.484748)
			(xy 199.073008 -196.485256) (xy 199.072492 -196.512856) (xy 199.064265 -196.567439) (xy 199.047995 -196.620186)
			(xy 199.024045 -196.669919) (xy 198.99295 -196.715526) (xy 198.955405 -196.75599) (xy 198.912248 -196.790407)
			(xy 198.864444 -196.818006) (xy 198.81306 -196.838173) (xy 198.759245 -196.850456) (xy 198.7042 -196.854581)
			(xy 198.649155 -196.850456) (xy 198.59534 -196.838173) (xy 198.543956 -196.818006) (xy 198.496152 -196.790407)
			(xy 198.452995 -196.75599) (xy 198.41545 -196.715526) (xy 198.384355 -196.669919) (xy 198.360405 -196.620186)
			(xy 198.344135 -196.567439) (xy 198.335908 -196.512856) (xy 198.335392 -196.485256) (xy 198.335392 -196.484748)
			(xy 198.335578 -196.468726) (xy 198.338379 -196.436805) (xy 198.34098 -196.420994) (xy 198.307406 -196.420048)
			(xy 198.240831 -196.411133) (xy 198.175796 -196.394341) (xy 198.113227 -196.369912) (xy 198.054019 -196.338195)
			(xy 197.999016 -196.299643) (xy 197.949004 -196.254806) (xy 197.904696 -196.204324) (xy 197.885304 -196.1769)
			(xy 197.774814 -196.1769) (xy 197.767925 -196.17716) (xy 197.754659 -196.180885) (xy 197.748652 -196.184266)
			(xy 197.71487 -196.202808) (xy 197.714362 -196.202808) (xy 197.701408 -196.209158) (xy 197.686168 -196.233796)
			(xy 197.686168 -196.236844) (xy 197.604888 -196.236844) (xy 197.601586 -196.237098) (xy 197.588385 -196.238867)
			(xy 197.561818 -196.240775) (xy 197.5485 -196.240908) (xy 197.535182 -196.240766) (xy 197.508615 -196.23886)
			(xy 197.495414 -196.237098) (xy 197.492112 -196.236844) (xy 197.418452 -196.236844) (xy 197.39613 -196.23632)
			(xy 197.352354 -196.227559) (xy 197.311144 -196.210386) (xy 197.274101 -196.185468) (xy 197.242662 -196.153771)
			(xy 197.218046 -196.116526) (xy 197.201209 -196.075178) (xy 197.192805 -196.031332) (xy 197.192392 -196.009006)
			(xy 197.192392 -195.996814) (xy 197.189598 -195.988432) (xy 197.179092 -195.957212) (xy 197.167728 -195.892333)
			(xy 197.166992 -195.8594) (xy 197.167708 -195.826466) (xy 197.17908 -195.761586) (xy 197.189598 -195.730368)
			(xy 197.192392 -195.721986) (xy 197.192392 -195.709794) (xy 197.192834 -195.686989) (xy 197.201707 -195.642257)
			(xy 197.219334 -195.600197) (xy 197.245005 -195.562505) (xy 197.260972 -195.546218) (xy 197.268592 -195.538852)
			(xy 197.276466 -195.519802) (xy 197.275196 -195.42506) (xy 197.266814 -195.40601) (xy 197.259194 -195.398898)
			(xy 197.244208 -195.38442) (xy 197.151244 -195.291456) (xy 197.129243 -195.268868) (xy 197.089912 -195.21958)
			(xy 197.056352 -195.166195) (xy 197.028985 -195.109385) (xy 197.008154 -195.049868) (xy 196.994124 -194.988391)
			(xy 196.98707 -194.925729) (xy 196.986652 -194.8942) (xy 196.987108 -194.862419) (xy 196.994313 -194.799266)
			(xy 197.008597 -194.737329) (xy 197.029777 -194.677399) (xy 197.057582 -194.620241) (xy 197.091659 -194.566585)
			(xy 197.131572 -194.517117) (xy 197.176811 -194.472466) (xy 197.201536 -194.452494) (xy 197.209664 -194.44589)
			(xy 197.214744 -194.437) (xy 197.217139 -194.432425) (xy 197.220207 -194.422567) (xy 197.22084 -194.417442)
			(xy 197.22846 -194.345306) (xy 197.228845 -194.340175) (xy 197.227827 -194.329937) (xy 197.226428 -194.324986)
			(xy 197.22338 -194.31508) (xy 197.216776 -194.307206) (xy 197.195513 -194.281016) (xy 197.159742 -194.22382)
			(xy 197.132289 -194.162198) (xy 197.113688 -194.097353) (xy 197.104301 -194.030548) (xy 197.103746 -193.996818)
			(xy 197.103746 -193.99631) (xy 197.104142 -193.968173) (xy 197.110689 -193.91228) (xy 197.123696 -193.857529)
			(xy 197.132956 -193.830956) (xy 197.13448 -193.826638) (xy 197.136258 -193.815716) (xy 197.137205 -193.806308)
			(xy 197.132904 -193.787909) (xy 197.127876 -193.779902) (xy 197.082156 -193.713608) (xy 197.077584 -193.70802)
			(xy 197.070947 -193.701511) (xy 197.054278 -193.693315) (xy 197.045072 -193.692018) (xy 197.0405 -193.691764)
			(xy 195.670678 -193.691764) (xy 195.660611 -193.692193) (xy 195.642018 -193.69992) (xy 195.63461 -193.70675)
			(xy 195.485766 -193.855594) (xy 195.478911 -193.862989) (xy 195.471164 -193.881588) (xy 195.47078 -193.891662)
			(xy 195.47078 -194.312794) (xy 195.471201 -194.322865) (xy 195.478912 -194.341473) (xy 195.485766 -194.348862)
			(xy 195.524374 -194.38747) (xy 195.531775 -194.394308) (xy 195.550374 -194.40202) (xy 195.560442 -194.402456)
			(xy 195.759832 -194.402456) (xy 195.791464 -194.402975) (xy 195.854185 -194.411236) (xy 195.915292 -194.427614)
			(xy 195.973739 -194.451826) (xy 196.028525 -194.48346) (xy 196.078714 -194.521975) (xy 196.123446 -194.56671)
			(xy 196.161957 -194.616901) (xy 196.193588 -194.67169) (xy 196.217797 -194.730138) (xy 196.23417 -194.791246)
			(xy 196.242427 -194.853968) (xy 196.242427 -194.917232) (xy 196.23417 -194.979954) (xy 196.217797 -195.041062)
			(xy 196.193588 -195.09951) (xy 196.161957 -195.154298) (xy 196.123446 -195.20449) (xy 196.078714 -195.249225)
			(xy 196.028525 -195.28774) (xy 195.973739 -195.319374) (xy 195.915292 -195.343586) (xy 195.854185 -195.359964)
			(xy 195.791464 -195.368225) (xy 195.759832 -195.368672) (xy 195.013326 -195.368672) (xy 194.981515 -195.368161)
			(xy 194.918443 -195.359805) (xy 194.857012 -195.343246) (xy 194.798285 -195.318771) (xy 194.743277 -195.286804)
			(xy 194.692937 -195.247896) (xy 194.670172 -195.22567) (xy 194.66306 -195.218558) (xy 194.635628 -195.20662)
			(xy 194.622674 -195.203318) (xy 194.616832 -195.203064) (xy 194.400678 -195.203064) (xy 194.390882 -195.203577)
			(xy 194.372792 -195.211114) (xy 194.358931 -195.224967) (xy 194.351383 -195.243052) (xy 194.350894 -195.252848)
			(xy 194.350894 -195.263008) (xy 194.08267 -195.263008) (xy 194.063235 -195.262541) (xy 194.024957 -195.255769)
			(xy 193.988401 -195.24255) (xy 193.954645 -195.223273) (xy 193.939414 -195.211192) (xy 193.938144 -195.210176)
			(xy 193.932556 -195.205604) (xy 193.90868 -195.196714) (xy 193.904392 -195.195195) (xy 193.895448 -195.193537)
			(xy 193.8909 -195.193412) (xy 193.76771 -195.193412) (xy 193.763765 -195.193496) (xy 193.755978 -195.194765)
			(xy 193.752216 -195.195952) (xy 193.745612 -195.197984) (xy 193.738754 -195.202556) (xy 193.7385 -195.20281)
			(xy 193.712882 -195.220059) (xy 193.658268 -195.248901) (xy 193.600564 -195.270917) (xy 193.540618 -195.285783)
			(xy 193.479313 -195.293279) (xy 193.448432 -195.293742) (xy 193.418079 -195.293302) (xy 193.357804 -195.286078)
			(xy 193.298818 -195.271727) (xy 193.241961 -195.250455) (xy 193.188041 -195.222563) (xy 193.137826 -195.18845)
			(xy 193.092031 -195.1486) (xy 193.051306 -195.10358) (xy 193.016232 -195.054032) (xy 193.001392 -195.02755)
			(xy 193.001392 -195.027296) (xy 192.997804 -195.02132) (xy 192.988016 -195.011404) (xy 192.982088 -195.007738)
			(xy 192.976246 -195.004182) (xy 192.963038 -195.00088) (xy 192.865248 -195.002912) (xy 192.858183 -195.003289)
			(xy 192.844653 -195.007413) (xy 192.838578 -195.01104) (xy 192.833244 -195.014596) (xy 192.8241 -195.024756)
			(xy 192.820798 -195.03136) (xy 192.806815 -195.059121) (xy 192.773594 -195.111659) (xy 192.734772 -195.160205)
			(xy 192.713102 -195.18249) (xy 192.684146 -195.211446) (xy 192.709721 -195.23435) (xy 192.755672 -195.28536)
			(xy 192.795065 -195.34159) (xy 192.827311 -195.402201) (xy 192.85193 -195.466291) (xy 192.868554 -195.532903)
			(xy 192.876937 -195.601044) (xy 192.87744 -195.635372) (xy 192.876984 -195.666881) (xy 192.869902 -195.729501)
			(xy 192.855857 -195.790934) (xy 192.835026 -195.85041) (xy 192.80767 -195.907182) (xy 192.774134 -195.960536)
			(xy 192.734837 -196.009802) (xy 192.712848 -196.032374) (xy 192.324482 -196.420994) (xy 191.523366 -196.420994)
			(xy 191.525975 -196.436803) (xy 191.528769 -196.468726) (xy 191.528954 -196.484748) (xy 191.528954 -196.485256)
			(xy 191.528438 -196.512856) (xy 191.520211 -196.567439) (xy 191.503941 -196.620186) (xy 191.479991 -196.669919)
			(xy 191.448896 -196.715526) (xy 191.411351 -196.75599) (xy 191.368194 -196.790407) (xy 191.32039 -196.818006)
			(xy 191.269006 -196.838173) (xy 191.215191 -196.850456) (xy 191.160146 -196.854581) (xy 191.105101 -196.850456)
			(xy 191.051286 -196.838173) (xy 190.999902 -196.818006) (xy 190.952098 -196.790407) (xy 190.908941 -196.75599)
			(xy 190.871396 -196.715526) (xy 190.840301 -196.669919) (xy 190.816351 -196.620186) (xy 190.800081 -196.567439)
			(xy 190.791854 -196.512856) (xy 190.791338 -196.485256) (xy 190.791338 -196.484748) (xy 190.791524 -196.468726)
			(xy 190.794326 -196.436805) (xy 190.796926 -196.420994) (xy 190.763353 -196.420045) (xy 190.696783 -196.411124)
			(xy 190.631751 -196.394327) (xy 190.569187 -196.369895) (xy 190.509984 -196.338175) (xy 190.454986 -196.29962)
			(xy 190.404979 -196.254782) (xy 190.360676 -196.204299) (xy 190.34125 -196.1769) (xy 190.23076 -196.1769)
			(xy 190.223874 -196.177167) (xy 190.210614 -196.180904) (xy 190.204598 -196.184266) (xy 190.170816 -196.202808)
			(xy 190.170308 -196.202808) (xy 190.1571 -196.209412) (xy 190.14186 -196.233796) (xy 190.14186 -196.236844)
			(xy 190.060834 -196.236844) (xy 190.057532 -196.237098) (xy 190.044331 -196.238865) (xy 190.017764 -196.240769)
			(xy 190.004446 -196.240908) (xy 189.991129 -196.240764) (xy 189.964562 -196.238855) (xy 189.95136 -196.237098)
			(xy 189.948058 -196.236844) (xy 189.874398 -196.236844) (xy 189.852073 -196.236324) (xy 189.808289 -196.22757)
			(xy 189.767072 -196.210401) (xy 189.730021 -196.185484) (xy 189.698574 -196.153787) (xy 189.673953 -196.116539)
			(xy 189.657112 -196.075186) (xy 189.648705 -196.031335) (xy 189.648338 -196.009006) (xy 189.648592 -196.009006)
			(xy 189.648592 -195.996814) (xy 189.645544 -195.988432) (xy 189.635037 -195.957212) (xy 189.623672 -195.892333)
			(xy 189.622938 -195.8594) (xy 189.623653 -195.826466) (xy 189.635024 -195.761585) (xy 189.645544 -195.730368)
			(xy 189.648592 -195.721986) (xy 189.648592 -195.709794) (xy 189.648338 -195.709794) (xy 189.648781 -195.68699)
			(xy 189.657655 -195.642259) (xy 189.675284 -195.600201) (xy 189.700959 -195.562513) (xy 189.716918 -195.546218)
			(xy 189.724538 -195.538852) (xy 189.732412 -195.519802) (xy 189.731142 -195.42506) (xy 189.72276 -195.40601)
			(xy 189.71514 -195.398898) (xy 189.700154 -195.38442) (xy 189.60719 -195.291456) (xy 189.58521 -195.268859)
			(xy 189.545924 -195.219557) (xy 189.512407 -195.166164) (xy 189.485082 -195.109353) (xy 189.464293 -195.049839)
			(xy 189.450302 -194.98837) (xy 189.443285 -194.925721) (xy 189.442852 -194.8942) (xy 189.443371 -194.859609)
			(xy 189.45184 -194.790947) (xy 189.468677 -194.723845) (xy 189.493625 -194.659318) (xy 189.526307 -194.598342)
			(xy 189.566228 -194.541841) (xy 189.612785 -194.490668) (xy 189.638686 -194.467734) (xy 189.646814 -194.460876)
			(xy 189.651386 -194.451732) (xy 189.653436 -194.447156) (xy 189.655868 -194.43743) (xy 189.656212 -194.432428)
			(xy 189.658498 -194.39636) (xy 189.658498 -194.395852) (xy 189.660784 -194.359784) (xy 189.660988 -194.354619)
			(xy 189.659585 -194.34438) (xy 189.65799 -194.339464) (xy 189.654688 -194.330066) (xy 189.648846 -194.323716)
			(xy 189.647576 -194.322192) (xy 189.627827 -194.299889) (xy 189.593395 -194.251274) (xy 189.565201 -194.198794)
			(xy 189.543673 -194.143246) (xy 189.529139 -194.085473) (xy 189.521819 -194.026351) (xy 189.521338 -193.996564)
			(xy 189.521761 -193.967786) (xy 189.528651 -193.910644) (xy 189.542339 -193.85474) (xy 189.552072 -193.827654)
			(xy 189.554149 -193.821729) (xy 189.555685 -193.80927) (xy 189.55512 -193.803016) (xy 189.553596 -193.791332)
			(xy 189.500002 -193.713608) (xy 189.49543 -193.707766) (xy 189.488801 -193.701275) (xy 189.472122 -193.693186)
			(xy 189.462918 -193.692018) (xy 189.458346 -193.691764) (xy 188.058298 -193.691764) (xy 188.048229 -193.692189)
			(xy 188.029631 -193.699911) (xy 188.02223 -193.70675) (xy 187.974986 -193.753994) (xy 187.968129 -193.761388)
			(xy 187.960379 -193.779987) (xy 187.96 -193.790062) (xy 187.96 -194.307714) (xy 187.960426 -194.317783)
			(xy 187.968144 -194.336384) (xy 187.974986 -194.343782) (xy 188.018674 -194.38747) (xy 188.026075 -194.394308)
			(xy 188.044674 -194.40202) (xy 188.054742 -194.402456) (xy 188.215778 -194.402456) (xy 188.247413 -194.40295)
			(xy 188.310143 -194.411206) (xy 188.371259 -194.427579) (xy 188.429714 -194.45179) (xy 188.484509 -194.483423)
			(xy 188.534706 -194.521939) (xy 188.579447 -194.566677) (xy 188.617964 -194.616872) (xy 188.649601 -194.671666)
			(xy 188.673814 -194.73012) (xy 188.69019 -194.791235) (xy 188.698449 -194.853965) (xy 188.698449 -194.917235)
			(xy 188.69019 -194.979965) (xy 188.673814 -195.04108) (xy 188.649601 -195.099534) (xy 188.617964 -195.154328)
			(xy 188.579447 -195.204523) (xy 188.534706 -195.249261) (xy 188.484509 -195.287777) (xy 188.429714 -195.31941)
			(xy 188.371259 -195.343621) (xy 188.310143 -195.359994) (xy 188.247413 -195.36825) (xy 188.215778 -195.368672)
			(xy 187.469272 -195.368672) (xy 187.437459 -195.368164) (xy 187.374385 -195.359813) (xy 187.312951 -195.343259)
			(xy 187.254219 -195.318788) (xy 187.199206 -195.286824) (xy 187.148863 -195.247918) (xy 187.126118 -195.22567)
			(xy 187.119006 -195.218558) (xy 187.091574 -195.20662) (xy 187.07862 -195.203318) (xy 187.072778 -195.203064)
			(xy 186.85764 -195.203064) (xy 186.850274 -195.203572) (xy 186.840586 -195.212314) (xy 186.82038 -195.228832)
			(xy 186.809888 -195.236592) (xy 186.80684 -195.253864) (xy 186.80684 -195.263008) (xy 186.783726 -195.263008)
			(xy 186.777288 -195.263202) (xy 186.764823 -195.266426) (xy 186.759088 -195.269358) (xy 186.732766 -195.283434)
			(xy 186.677331 -195.305571) (xy 186.619545 -195.320537) (xy 186.560334 -195.328092) (xy 186.530488 -195.32854)
			(xy 186.530234 -195.32854) (xy 186.500159 -195.328069) (xy 186.440495 -195.320429) (xy 186.382286 -195.305268)
			(xy 186.326476 -195.282831) (xy 186.27397 -195.253484) (xy 186.22562 -195.217702) (xy 186.20359 -195.197222)
			(xy 186.201558 -195.197984) (xy 186.198764 -195.199762) (xy 186.172887 -195.217571) (xy 186.117585 -195.247368)
			(xy 186.059034 -195.270127) (xy 185.998125 -195.285502) (xy 185.935787 -195.29326) (xy 185.904378 -195.293742)
			(xy 185.874026 -195.293299) (xy 185.813755 -195.286069) (xy 185.754774 -195.271713) (xy 185.697922 -195.250437)
			(xy 185.644007 -195.222543) (xy 185.593797 -195.188427) (xy 185.548007 -195.148576) (xy 185.507287 -195.103556)
			(xy 185.472218 -195.054008) (xy 185.457338 -195.02755) (xy 185.457338 -195.027296) (xy 185.453747 -195.021324)
			(xy 185.443954 -195.011416) (xy 185.438034 -195.007738) (xy 185.432192 -195.004182) (xy 185.418984 -195.00088)
			(xy 185.321194 -195.002912) (xy 185.314127 -195.003283) (xy 185.300591 -195.007397) (xy 185.294524 -195.01104)
			(xy 185.28919 -195.014596) (xy 185.280046 -195.024756) (xy 185.276744 -195.03136) (xy 185.262762 -195.059121)
			(xy 185.229543 -195.111661) (xy 185.190723 -195.16021) (xy 185.169048 -195.18249) (xy 185.140092 -195.211446)
			(xy 185.165669 -195.234348) (xy 185.211625 -195.285357) (xy 185.251021 -195.341586) (xy 185.28327 -195.402197)
			(xy 185.307891 -195.466287) (xy 185.324518 -195.532901) (xy 185.332901 -195.601044) (xy 185.333386 -195.635372)
			(xy 185.33293 -195.666881) (xy 185.325847 -195.7295) (xy 185.311801 -195.790932) (xy 185.290969 -195.850407)
			(xy 185.263611 -195.907178) (xy 185.230072 -195.960529) (xy 185.190773 -196.009793) (xy 185.168794 -196.032374)
			(xy 184.780428 -196.420994) (xy 183.979312 -196.420994) (xy 183.981922 -196.436803) (xy 183.984716 -196.468726)
			(xy 183.9849 -196.484748) (xy 183.9849 -196.485256) (xy 183.984384 -196.512856) (xy 183.976157 -196.567439)
			(xy 183.959887 -196.620186) (xy 183.935937 -196.669919) (xy 183.904842 -196.715526) (xy 183.867297 -196.75599)
			(xy 183.82414 -196.790407) (xy 183.776336 -196.818006) (xy 183.724952 -196.838173) (xy 183.671137 -196.850456)
			(xy 183.616092 -196.854581) (xy 183.561047 -196.850456) (xy 183.507232 -196.838173) (xy 183.455848 -196.818006)
			(xy 183.408044 -196.790407) (xy 183.364887 -196.75599) (xy 183.327342 -196.715526) (xy 183.296247 -196.669919)
			(xy 183.272297 -196.620186) (xy 183.256027 -196.567439) (xy 183.2478 -196.512856) (xy 183.247284 -196.485256)
			(xy 183.247284 -196.484748) (xy 183.24747 -196.468726) (xy 183.250271 -196.436805) (xy 183.252872 -196.420994)
			(xy 183.219312 -196.420036) (xy 183.15277 -196.411104) (xy 183.087767 -196.394302) (xy 183.02523 -196.36987)
			(xy 182.966052 -196.338158) (xy 182.911077 -196.299616) (xy 182.861089 -196.254795) (xy 182.816801 -196.204335)
			(xy 182.79745 -196.1769) (xy 182.68696 -196.1769) (xy 182.680074 -196.177167) (xy 182.666814 -196.180904)
			(xy 182.660798 -196.184266) (xy 182.627016 -196.202808) (xy 182.626508 -196.202808) (xy 182.6133 -196.209412)
			(xy 182.59806 -196.233796) (xy 182.59806 -196.236844) (xy 182.517034 -196.236844) (xy 182.513732 -196.237098)
			(xy 182.500531 -196.238865) (xy 182.473964 -196.240769) (xy 182.460646 -196.240908) (xy 182.447329 -196.240764)
			(xy 182.420762 -196.238855) (xy 182.40756 -196.237098) (xy 182.404258 -196.236844) (xy 182.330598 -196.236844)
			(xy 182.308273 -196.236324) (xy 182.264489 -196.22757) (xy 182.223272 -196.210401) (xy 182.186221 -196.185484)
			(xy 182.154774 -196.153787) (xy 182.130153 -196.116539) (xy 182.113312 -196.075186) (xy 182.104905 -196.031335)
			(xy 182.104538 -196.009006) (xy 182.104792 -196.009006) (xy 182.104792 -195.996814) (xy 182.101744 -195.988432)
			(xy 182.091237 -195.957212) (xy 182.079872 -195.892333) (xy 182.079138 -195.8594) (xy 182.079853 -195.826466)
			(xy 182.091224 -195.761585) (xy 182.101744 -195.730368) (xy 182.104792 -195.721986) (xy 182.104792 -195.709794)
			(xy 182.104538 -195.709794) (xy 182.104981 -195.68699) (xy 182.113855 -195.642259) (xy 182.131484 -195.600201)
			(xy 182.157159 -195.562513) (xy 182.173118 -195.546218) (xy 182.180738 -195.538852) (xy 182.188612 -195.519802)
			(xy 182.187342 -195.42506) (xy 182.17896 -195.40601) (xy 182.17134 -195.398898) (xy 182.156354 -195.38442)
			(xy 182.06339 -195.291456) (xy 182.041446 -195.268876) (xy 182.0022 -195.219637) (xy 181.968709 -195.166316)
			(xy 181.941394 -195.109582) (xy 181.920599 -195.050148) (xy 181.906585 -194.988761) (xy 181.899528 -194.926191)
			(xy 181.899052 -194.894708) (xy 181.899052 -194.8942) (xy 181.899564 -194.859635) (xy 181.908015 -194.791023)
			(xy 181.924826 -194.723968) (xy 181.949743 -194.659485) (xy 181.982388 -194.598549) (xy 182.022268 -194.542082)
			(xy 182.068779 -194.490938) (xy 182.094632 -194.467988) (xy 182.094886 -194.467988) (xy 182.10276 -194.46113)
			(xy 182.107078 -194.452494) (xy 182.109305 -194.447825) (xy 182.112002 -194.437839) (xy 182.112412 -194.432682)
			(xy 182.116984 -194.359784) (xy 182.117108 -194.354672) (xy 182.115563 -194.344566) (xy 182.113936 -194.339718)
			(xy 182.110634 -194.330066) (xy 182.103776 -194.322192) (xy 182.084025 -194.299915) (xy 182.049584 -194.251349)
			(xy 182.021382 -194.198914) (xy 181.999845 -194.143407) (xy 181.985303 -194.085673) (xy 181.977974 -194.026587)
			(xy 181.977538 -193.996818) (xy 181.977538 -193.99631) (xy 181.977934 -193.968173) (xy 181.984481 -193.91228)
			(xy 181.997487 -193.857529) (xy 182.006748 -193.830956) (xy 182.008272 -193.826638) (xy 182.01005 -193.815716)
			(xy 182.010997 -193.806308) (xy 182.006695 -193.787909) (xy 182.001668 -193.779902) (xy 181.955948 -193.713608)
			(xy 181.951376 -193.70802) (xy 181.944739 -193.701512) (xy 181.928069 -193.693319) (xy 181.918864 -193.692018)
			(xy 181.914292 -193.691764) (xy 180.527198 -193.691764) (xy 180.517129 -193.692189) (xy 180.498531 -193.699911)
			(xy 180.49113 -193.70675) (xy 180.446426 -193.751454) (xy 180.439585 -193.758854) (xy 180.431867 -193.777453)
			(xy 180.43144 -193.787522) (xy 180.43144 -194.254374) (xy 180.431878 -194.264437) (xy 180.439616 -194.283018)
			(xy 180.446426 -194.290442) (xy 180.543454 -194.38747) (xy 180.550854 -194.394311) (xy 180.569453 -194.402031)
			(xy 180.579522 -194.402456) (xy 180.671724 -194.402456) (xy 180.703356 -194.402975) (xy 180.766078 -194.411235)
			(xy 180.827186 -194.427612) (xy 180.885634 -194.451824) (xy 180.940421 -194.483458) (xy 180.990611 -194.521972)
			(xy 181.035344 -194.566707) (xy 181.073856 -194.616899) (xy 181.105487 -194.671688) (xy 181.129696 -194.730137)
			(xy 181.14607 -194.791245) (xy 181.154327 -194.853968) (xy 181.154327 -194.917232) (xy 181.14607 -194.979955)
			(xy 181.129696 -195.041063) (xy 181.105487 -195.099512) (xy 181.073856 -195.154301) (xy 181.035344 -195.204493)
			(xy 180.990611 -195.249228) (xy 180.940421 -195.287742) (xy 180.885634 -195.319376) (xy 180.827186 -195.343588)
			(xy 180.766078 -195.359965) (xy 180.703356 -195.368225) (xy 180.671724 -195.368672) (xy 179.925472 -195.368672)
			(xy 179.893659 -195.368164) (xy 179.830585 -195.359813) (xy 179.769151 -195.343259) (xy 179.710419 -195.318788)
			(xy 179.655406 -195.286824) (xy 179.605063 -195.247918) (xy 179.582318 -195.22567) (xy 179.575206 -195.218558)
			(xy 179.547774 -195.20662) (xy 179.53482 -195.203318) (xy 179.528978 -195.203064) (xy 179.31384 -195.203064)
			(xy 179.303811 -195.203476) (xy 179.285274 -195.211137) (xy 179.27108 -195.22531) (xy 179.263391 -195.243835)
			(xy 179.26304 -195.253864) (xy 179.26304 -195.263008) (xy 178.997864 -195.263008) (xy 178.987704 -195.262754)
			(xy 178.987196 -195.262754) (xy 178.962591 -195.261207) (xy 178.91489 -195.248783) (xy 178.870989 -195.226369)
			(xy 178.85156 -195.211192) (xy 178.85029 -195.210176) (xy 178.844702 -195.205604) (xy 178.820826 -195.196714)
			(xy 178.816538 -195.195192) (xy 178.807594 -195.193525) (xy 178.803046 -195.193412) (xy 178.679602 -195.193412)
			(xy 178.675657 -195.193497) (xy 178.667871 -195.194767) (xy 178.664108 -195.195952) (xy 178.657504 -195.197984)
			(xy 178.650646 -195.202556) (xy 178.650392 -195.20281) (xy 178.624773 -195.220058) (xy 178.57016 -195.2489)
			(xy 178.512455 -195.270915) (xy 178.45251 -195.28578) (xy 178.391205 -195.293275) (xy 178.360324 -195.293742)
			(xy 178.329971 -195.293302) (xy 178.269697 -195.286076) (xy 178.210712 -195.271725) (xy 178.153855 -195.250452)
			(xy 178.099936 -195.22256) (xy 178.049722 -195.188447) (xy 178.003927 -195.148596) (xy 177.963203 -195.103577)
			(xy 177.92813 -195.054028) (xy 177.913284 -195.02755) (xy 177.913284 -195.027296) (xy 177.909695 -195.021321)
			(xy 177.899907 -195.011406) (xy 177.89398 -195.007738) (xy 177.888138 -195.004182) (xy 177.87493 -195.00088)
			(xy 177.77714 -195.002912) (xy 177.770075 -195.00329) (xy 177.756547 -195.007416) (xy 177.75047 -195.01104)
			(xy 177.745136 -195.014596) (xy 177.735992 -195.024756) (xy 177.73269 -195.03136) (xy 177.718709 -195.059122)
			(xy 177.685492 -195.111664) (xy 177.646674 -195.160215) (xy 177.624994 -195.18249) (xy 177.596038 -195.211446)
			(xy 177.621613 -195.23435) (xy 177.667565 -195.285359) (xy 177.706958 -195.341589) (xy 177.739205 -195.4022)
			(xy 177.763824 -195.46629) (xy 177.780449 -195.532902) (xy 177.788832 -195.601044) (xy 177.789332 -195.635372)
			(xy 177.788876 -195.666881) (xy 177.781793 -195.7295) (xy 177.767749 -195.790934) (xy 177.746917 -195.85041)
			(xy 177.719561 -195.907181) (xy 177.686024 -195.960535) (xy 177.646728 -196.009801) (xy 177.62474 -196.032374)
			(xy 177.236374 -196.420994) (xy 176.435258 -196.420994) (xy 176.437867 -196.436803) (xy 176.440661 -196.468726)
			(xy 176.440846 -196.484748) (xy 176.440846 -196.485256) (xy 176.44033 -196.512856) (xy 176.432103 -196.567439)
			(xy 176.415833 -196.620186) (xy 176.391883 -196.669919) (xy 176.360788 -196.715526) (xy 176.323243 -196.75599)
			(xy 176.280086 -196.790407) (xy 176.232282 -196.818006) (xy 176.180898 -196.838173) (xy 176.127083 -196.850456)
			(xy 176.072038 -196.854581) (xy 176.016993 -196.850456) (xy 175.963178 -196.838173) (xy 175.911794 -196.818006)
			(xy 175.86399 -196.790407) (xy 175.820833 -196.75599) (xy 175.783288 -196.715526) (xy 175.752193 -196.669919)
			(xy 175.728243 -196.620186) (xy 175.711973 -196.567439) (xy 175.703746 -196.512856) (xy 175.70323 -196.485256)
			(xy 175.70323 -196.484748) (xy 175.703416 -196.468726) (xy 175.706218 -196.436805) (xy 175.708818 -196.420994)
			(xy 175.67526 -196.420033) (xy 175.608721 -196.411095) (xy 175.543722 -196.394288) (xy 175.48119 -196.369853)
			(xy 175.422017 -196.338137) (xy 175.367047 -196.299593) (xy 175.317064 -196.254771) (xy 175.272781 -196.20431)
			(xy 175.253396 -196.1769) (xy 175.142906 -196.1769) (xy 175.136018 -196.177161) (xy 175.122752 -196.180888)
			(xy 175.116744 -196.184266) (xy 175.082962 -196.202808) (xy 175.082454 -196.202808) (xy 175.0695 -196.209158)
			(xy 175.05426 -196.233796) (xy 175.05426 -196.236844) (xy 174.97298 -196.236844) (xy 174.969678 -196.237098)
			(xy 174.956477 -196.238866) (xy 174.92991 -196.240774) (xy 174.916592 -196.240908) (xy 174.903275 -196.240765)
			(xy 174.876707 -196.238859) (xy 174.863506 -196.237098) (xy 174.860204 -196.236844) (xy 174.786544 -196.236844)
			(xy 174.764216 -196.236329) (xy 174.720425 -196.227581) (xy 174.6792 -196.210416) (xy 174.642141 -196.185501)
			(xy 174.610687 -196.153802) (xy 174.586059 -196.116551) (xy 174.569214 -196.075194) (xy 174.560805 -196.031337)
			(xy 174.560484 -196.009006) (xy 174.560484 -195.996814) (xy 174.55769 -195.988432) (xy 174.547184 -195.957212)
			(xy 174.535821 -195.892332) (xy 174.535084 -195.8594) (xy 174.5358 -195.826466) (xy 174.547172 -195.761586)
			(xy 174.55769 -195.730368) (xy 174.560484 -195.721986) (xy 174.560484 -195.709794) (xy 174.560926 -195.686989)
			(xy 174.569798 -195.642257) (xy 174.587425 -195.600197) (xy 174.613096 -195.562504) (xy 174.629064 -195.546218)
			(xy 174.636684 -195.538852) (xy 174.644558 -195.519802) (xy 174.643288 -195.42506) (xy 174.634906 -195.40601)
			(xy 174.627286 -195.398898) (xy 174.6123 -195.38442) (xy 174.519336 -195.291456) (xy 174.497335 -195.268868)
			(xy 174.458005 -195.219579) (xy 174.424445 -195.166194) (xy 174.397078 -195.109385) (xy 174.376248 -195.049867)
			(xy 174.362218 -194.98839) (xy 174.355164 -194.925729) (xy 174.354744 -194.8942) (xy 174.355269 -194.859625)
			(xy 174.363746 -194.790996) (xy 174.380585 -194.723927) (xy 174.40553 -194.659432) (xy 174.438205 -194.598488)
			(xy 174.478114 -194.542017) (xy 174.524655 -194.490872) (xy 174.550578 -194.467988) (xy 174.550832 -194.467988)
			(xy 174.558706 -194.46113) (xy 174.563024 -194.452494) (xy 174.565253 -194.447825) (xy 174.567953 -194.437839)
			(xy 174.568358 -194.432682) (xy 174.57293 -194.359784) (xy 174.573054 -194.354672) (xy 174.571511 -194.344566)
			(xy 174.569882 -194.339718) (xy 174.56658 -194.330066) (xy 174.56023 -194.322954) (xy 174.559468 -194.322192)
			(xy 174.539719 -194.299889) (xy 174.505287 -194.251274) (xy 174.477094 -194.198794) (xy 174.455567 -194.143246)
			(xy 174.441033 -194.085473) (xy 174.433713 -194.026351) (xy 174.43323 -193.996564) (xy 174.433653 -193.967786)
			(xy 174.440543 -193.910644) (xy 174.454231 -193.85474) (xy 174.463964 -193.827654) (xy 174.466042 -193.821729)
			(xy 174.467577 -193.80927) (xy 174.467012 -193.803016) (xy 174.465488 -193.791332) (xy 174.411894 -193.713608)
			(xy 174.407322 -193.707766) (xy 174.400692 -193.701276) (xy 174.384013 -193.69319) (xy 174.37481 -193.692018)
			(xy 174.370238 -193.691764) (xy 173.051978 -193.691764) (xy 173.041911 -193.692193) (xy 173.023318 -193.69992)
			(xy 173.01591 -193.70675) (xy 172.889926 -193.832734) (xy 172.883082 -193.840133) (xy 172.875356 -193.858731)
			(xy 172.87494 -193.868802) (xy 172.87494 -194.277234) (xy 172.875371 -194.287301) (xy 172.883098 -194.305892)
			(xy 172.889926 -194.313302) (xy 172.964094 -194.38747) (xy 172.971491 -194.39432) (xy 172.990089 -194.402062)
			(xy 173.000162 -194.402456) (xy 173.12767 -194.402456) (xy 173.159306 -194.402949) (xy 173.222036 -194.411204)
			(xy 173.283153 -194.427577) (xy 173.341609 -194.451787) (xy 173.396405 -194.483421) (xy 173.446603 -194.521936)
			(xy 173.491344 -194.566674) (xy 173.529863 -194.61687) (xy 173.5615 -194.671664) (xy 173.585713 -194.730119)
			(xy 173.60209 -194.791234) (xy 173.610349 -194.853964) (xy 173.610349 -194.917236) (xy 173.60209 -194.979966)
			(xy 173.585713 -195.041081) (xy 173.5615 -195.099536) (xy 173.529863 -195.15433) (xy 173.491344 -195.204526)
			(xy 173.446603 -195.249264) (xy 173.396405 -195.287779) (xy 173.341609 -195.319413) (xy 173.283153 -195.343623)
			(xy 173.222036 -195.359996) (xy 173.159306 -195.368251) (xy 173.12767 -195.368672) (xy 172.381418 -195.368672)
			(xy 172.349607 -195.368161) (xy 172.286535 -195.359803) (xy 172.225106 -195.343244) (xy 172.166379 -195.318768)
			(xy 172.111371 -195.2868) (xy 172.061033 -195.247892) (xy 172.038264 -195.22567) (xy 172.031152 -195.218558)
			(xy 172.00372 -195.20662) (xy 171.990766 -195.203318) (xy 171.984924 -195.203064) (xy 171.76877 -195.203064)
			(xy 171.758975 -195.203578) (xy 171.740888 -195.211116) (xy 171.727029 -195.224969) (xy 171.719482 -195.243053)
			(xy 171.718986 -195.252848) (xy 171.718986 -195.263008) (xy 171.450762 -195.263008) (xy 171.431327 -195.26254)
			(xy 171.39305 -195.255767) (xy 171.356495 -195.242547) (xy 171.32274 -195.223269) (xy 171.307506 -195.211192)
			(xy 171.306236 -195.210176) (xy 171.300648 -195.205604) (xy 171.276772 -195.196714) (xy 171.272484 -195.195196)
			(xy 171.26354 -195.19354) (xy 171.258992 -195.193412) (xy 171.135548 -195.193412) (xy 171.131604 -195.193501)
			(xy 171.12382 -195.194779) (xy 171.120054 -195.195952) (xy 171.11345 -195.197984) (xy 171.106592 -195.202556)
			(xy 171.106338 -195.20281) (xy 171.08072 -195.220061) (xy 171.026107 -195.248907) (xy 170.968403 -195.270928)
			(xy 170.908457 -195.285798) (xy 170.847151 -195.293298) (xy 170.81627 -195.293742) (xy 170.785919 -195.293299)
			(xy 170.725648 -195.286067) (xy 170.666667 -195.271711) (xy 170.609816 -195.250434) (xy 170.555902 -195.22254)
			(xy 170.505693 -195.188424) (xy 170.459903 -195.148573) (xy 170.419184 -195.103553) (xy 170.384115 -195.054005)
			(xy 170.36923 -195.02755) (xy 170.36923 -195.027296) (xy 170.365638 -195.021324) (xy 170.355845 -195.011418)
			(xy 170.349926 -195.007738) (xy 170.344084 -195.004182) (xy 170.330876 -195.00088) (xy 170.233086 -195.002912)
			(xy 170.226019 -195.003284) (xy 170.212484 -195.0074) (xy 170.206416 -195.01104) (xy 170.201082 -195.014596)
			(xy 170.191938 -195.024756) (xy 170.188636 -195.03136) (xy 170.174654 -195.059121) (xy 170.141434 -195.111661)
			(xy 170.102614 -195.160209) (xy 170.08094 -195.18249) (xy 170.051984 -195.211446) (xy 170.077561 -195.234348)
			(xy 170.123518 -195.285356) (xy 170.162914 -195.341585) (xy 170.195164 -195.402197) (xy 170.219786 -195.466287)
			(xy 170.236412 -195.5329) (xy 170.244796 -195.601044) (xy 170.245278 -195.635372) (xy 170.244822 -195.666881)
			(xy 170.237739 -195.729499) (xy 170.223693 -195.790932) (xy 170.20286 -195.850407) (xy 170.175502 -195.907177)
			(xy 170.141963 -195.960528) (xy 170.102664 -196.009791) (xy 170.080686 -196.032374) (xy 169.69232 -196.420994)
			(xy 168.891204 -196.420994) (xy 168.893814 -196.436803) (xy 168.896608 -196.468726) (xy 168.896792 -196.484748)
			(xy 168.896792 -196.485256) (xy 168.896276 -196.512856) (xy 168.888049 -196.567439) (xy 168.871779 -196.620186)
			(xy 168.847829 -196.669919) (xy 168.816734 -196.715526) (xy 168.779189 -196.75599) (xy 168.736032 -196.790407)
			(xy 168.688228 -196.818006) (xy 168.636844 -196.838173) (xy 168.583029 -196.850456) (xy 168.527984 -196.854581)
			(xy 168.472939 -196.850456) (xy 168.419124 -196.838173) (xy 168.36774 -196.818006) (xy 168.319936 -196.790407)
			(xy 168.276779 -196.75599) (xy 168.239234 -196.715526) (xy 168.208139 -196.669919) (xy 168.184189 -196.620186)
			(xy 168.167919 -196.567439) (xy 168.159692 -196.512856) (xy 168.159176 -196.485256) (xy 168.159176 -196.484748)
			(xy 168.159362 -196.468726) (xy 168.162163 -196.436805) (xy 168.164764 -196.420994) (xy 168.131205 -196.420036)
			(xy 168.064662 -196.411103) (xy 167.99966 -196.3943) (xy 167.937124 -196.369868) (xy 167.877947 -196.338155)
			(xy 167.822973 -196.299613) (xy 167.772986 -196.254792) (xy 167.728698 -196.204331) (xy 167.709342 -196.1769)
			(xy 167.598852 -196.1769) (xy 167.591966 -196.177168) (xy 167.578708 -196.180907) (xy 167.57269 -196.184266)
			(xy 167.538908 -196.202808) (xy 167.5384 -196.202808) (xy 167.525192 -196.209412) (xy 167.509952 -196.233796)
			(xy 167.509952 -196.236844) (xy 167.428926 -196.236844) (xy 167.425624 -196.237098) (xy 167.412423 -196.238864)
			(xy 167.385856 -196.240768) (xy 167.372538 -196.240908) (xy 167.359221 -196.240764) (xy 167.332654 -196.238854)
			(xy 167.319452 -196.237098) (xy 167.31615 -196.236844) (xy 167.24249 -196.236844) (xy 167.220165 -196.236324)
			(xy 167.176383 -196.227568) (xy 167.135167 -196.210398) (xy 167.098118 -196.185481) (xy 167.066672 -196.153784)
			(xy 167.042052 -196.116536) (xy 167.025211 -196.075185) (xy 167.016805 -196.031334) (xy 167.01643 -196.009006)
			(xy 167.016684 -196.009006) (xy 167.016684 -195.996814) (xy 167.013636 -195.988432) (xy 167.003129 -195.957212)
			(xy 166.991764 -195.892333) (xy 166.99103 -195.8594) (xy 166.991745 -195.826466) (xy 167.003116 -195.761585)
			(xy 167.013636 -195.730368) (xy 167.016684 -195.721986) (xy 167.016684 -195.709794) (xy 167.01643 -195.709794)
			(xy 167.016873 -195.68699) (xy 167.025746 -195.642258) (xy 167.043375 -195.600201) (xy 167.06905 -195.562512)
			(xy 167.08501 -195.546218) (xy 167.09263 -195.538852) (xy 167.100504 -195.519802) (xy 167.099234 -195.42506)
			(xy 167.090852 -195.40601) (xy 167.083232 -195.398898) (xy 167.068246 -195.38442) (xy 166.975282 -195.291456)
			(xy 166.953339 -195.268875) (xy 166.914092 -195.219636) (xy 166.880602 -195.166315) (xy 166.853288 -195.109581)
			(xy 166.832493 -195.050148) (xy 166.818479 -194.988761) (xy 166.811422 -194.926191) (xy 166.810944 -194.894708)
			(xy 166.810944 -194.8942) (xy 166.811456 -194.859635) (xy 166.819907 -194.791023) (xy 166.836718 -194.723968)
			(xy 166.861634 -194.659484) (xy 166.894279 -194.598548) (xy 166.934159 -194.54208) (xy 166.98067 -194.490936)
			(xy 167.006524 -194.467988) (xy 167.006778 -194.467988) (xy 167.014652 -194.46113) (xy 167.01897 -194.452494)
			(xy 167.021198 -194.447825) (xy 167.023895 -194.437839) (xy 167.024304 -194.432682) (xy 167.028876 -194.359784)
			(xy 167.029 -194.354672) (xy 167.027455 -194.344566) (xy 167.025828 -194.339718) (xy 167.022526 -194.330066)
			(xy 167.015668 -194.322192) (xy 166.99593 -194.299931) (xy 166.961511 -194.251402) (xy 166.933319 -194.19901)
			(xy 166.911784 -194.143548) (xy 166.897232 -194.08586) (xy 166.889883 -194.02682) (xy 166.88943 -193.997072)
			(xy 166.88943 -193.996564) (xy 166.889923 -193.965364) (xy 166.897969 -193.903486) (xy 166.913922 -193.843161)
			(xy 166.937516 -193.785395) (xy 166.968358 -193.731151) (xy 167.005934 -193.681334) (xy 167.049616 -193.636774)
			(xy 167.098676 -193.598216) (xy 167.152296 -193.566301) (xy 167.209582 -193.541563) (xy 167.239442 -193.532506)
			(xy 167.245538 -193.530728) (xy 167.256714 -193.524124) (xy 167.261286 -193.519552) (xy 167.267858 -193.512443)
			(xy 167.275561 -193.494699) (xy 167.276113 -193.475364) (xy 167.269435 -193.457209) (xy 167.263318 -193.449702)
			(xy 167.249602 -193.435986) (xy 167.243393 -193.430659) (xy 167.228492 -193.423929) (xy 167.220392 -193.422778)
			(xy 167.215058 -193.422524) (xy 167.12565 -193.422524) (xy 167.109466 -193.421327) (xy 167.078455 -193.411801)
			(xy 167.050827 -193.394796) (xy 167.028353 -193.3714) (xy 167.012471 -193.343112) (xy 167.004198 -193.311743)
			(xy 167.00373 -193.295524) (xy 167.00373 -192.322958) (xy 167.002714 -192.312798) (xy 167.001952 -192.309242)
			(xy 167.001698 -192.30848) (xy 166.996617 -192.286348) (xy 166.991138 -192.241269) (xy 166.990776 -192.218564)
			(xy 166.991156 -192.195272) (xy 166.996887 -192.149041) (xy 167.002206 -192.126362) (xy 167.00373 -192.120266)
			(xy 167.00373 -192.08115) (xy 167.003563 -192.07514) (xy 167.000741 -192.063457) (xy 166.998142 -192.058036)
			(xy 166.996304 -192.054561) (xy 166.991711 -192.048181) (xy 166.988998 -192.045336) (xy 166.777924 -191.834262)
			(xy 166.775075 -191.831554) (xy 166.768699 -191.826956) (xy 166.765224 -191.825118) (xy 166.759797 -191.822538)
			(xy 166.748117 -191.81972) (xy 166.74211 -191.81953) (xy 166.167562 -191.81953) (xy 166.161552 -191.819696)
			(xy 166.149869 -191.822519) (xy 166.144448 -191.825118) (xy 166.140976 -191.82696) (xy 166.134601 -191.831558)
			(xy 166.131748 -191.834262) (xy 165.95217 -192.01384) (xy 165.952678 -192.02527) (xy 165.952678 -192.121536)
			(xy 165.954202 -192.127378) (xy 165.959315 -192.149698) (xy 165.964789 -192.19516) (xy 165.965124 -192.218056)
			(xy 165.965124 -192.218564) (xy 165.965124 -192.219072) (xy 165.964783 -192.241967) (xy 165.959304 -192.287428)
			(xy 165.954202 -192.30975) (xy 165.952678 -192.315592) (xy 165.952678 -193.010536) (xy 165.954202 -193.016378)
			(xy 165.959315 -193.038698) (xy 165.964789 -193.08416) (xy 165.965124 -193.107056) (xy 165.965124 -193.107564)
			(xy 165.965124 -193.108072) (xy 165.964783 -193.130967) (xy 165.959304 -193.176428) (xy 165.954202 -193.19875)
			(xy 165.952678 -193.204592) (xy 165.952678 -193.24955) (xy 165.952424 -193.249804) (xy 165.952424 -193.29527)
			(xy 165.951932 -193.311959) (xy 165.943298 -193.344201) (xy 165.926611 -193.373109) (xy 165.903009 -193.396711)
			(xy 165.874101 -193.413398) (xy 165.841859 -193.422032) (xy 165.82517 -193.422524) (xy 165.814248 -193.422524)
			(xy 165.810505 -193.422603) (xy 165.803107 -193.42375) (xy 165.799516 -193.42481) (xy 165.793166 -193.426588)
			(xy 165.78707 -193.430398) (xy 165.760433 -193.446491) (xy 165.703122 -193.470743) (xy 165.673024 -193.478658)
			(xy 165.672516 -193.478658) (xy 165.665658 -193.480436) (xy 165.66007 -193.483484) (xy 165.6588 -193.484246)
			(xy 165.64864 -193.49212) (xy 165.358826 -193.781934) (xy 165.351982 -193.789333) (xy 165.344256 -193.807931)
			(xy 165.34384 -193.818002) (xy 165.34384 -194.267074) (xy 165.344278 -194.277137) (xy 165.352016 -194.295718)
			(xy 165.358826 -194.303142) (xy 165.443154 -194.38747) (xy 165.450554 -194.394311) (xy 165.469153 -194.402031)
			(xy 165.479222 -194.402456) (xy 165.583616 -194.402456) (xy 165.615248 -194.402974) (xy 165.677972 -194.411234)
			(xy 165.73908 -194.427609) (xy 165.797529 -194.451821) (xy 165.852317 -194.483455) (xy 165.902507 -194.521969)
			(xy 165.947242 -194.566705) (xy 165.985754 -194.616897) (xy 166.017386 -194.671686) (xy 166.041596 -194.730135)
			(xy 166.057969 -194.791244) (xy 166.066227 -194.853968) (xy 166.066227 -194.917232) (xy 166.057969 -194.979956)
			(xy 166.041596 -195.041065) (xy 166.017386 -195.099514) (xy 165.985754 -195.154303) (xy 165.947242 -195.204495)
			(xy 165.902507 -195.249231) (xy 165.852317 -195.287745) (xy 165.797529 -195.319379) (xy 165.73908 -195.343591)
			(xy 165.677972 -195.359966) (xy 165.615248 -195.368226) (xy 165.583616 -195.368672) (xy 165.268148 -195.368672)
			(xy 165.258081 -195.369104) (xy 165.239488 -195.376828) (xy 165.23208 -195.383658) (xy 165.154356 -195.461382)
			(xy 165.147517 -195.468782) (xy 165.139803 -195.487381) (xy 165.13937 -195.49745) (xy 165.13937 -197.335394)
			(xy 171.602669 -197.335394) (xy 171.606604 -197.281623) (xy 171.618327 -197.228999) (xy 171.637587 -197.178642)
			(xy 171.663973 -197.131625) (xy 171.696925 -197.088952) (xy 171.735738 -197.051531) (xy 171.779586 -197.020161)
			(xy 171.827534 -196.995509) (xy 171.878561 -196.978101) (xy 171.931579 -196.968308) (xy 171.985458 -196.966339)
			(xy 172.039049 -196.972236) (xy 172.09121 -196.985872) (xy 172.14083 -197.006959) (xy 172.186851 -197.035045)
			(xy 172.228293 -197.069533) (xy 172.264271 -197.109687) (xy 172.294019 -197.154651) (xy 172.316904 -197.203468)
			(xy 172.332436 -197.255097) (xy 172.340286 -197.308437) (xy 172.340778 -197.335394) (xy 175.728125 -197.335394)
			(xy 175.732155 -197.282896) (xy 175.744152 -197.231628) (xy 175.763835 -197.182793) (xy 175.790741 -197.137534)
			(xy 175.824241 -197.096913) (xy 175.863549 -197.061882) (xy 175.907744 -197.033262) (xy 175.955789 -197.011723)
			(xy 176.00656 -196.997771) (xy 176.058865 -196.991733) (xy 176.111479 -196.99375) (xy 176.163169 -197.003774)
			(xy 176.212722 -197.021572) (xy 176.258978 -197.046725) (xy 176.300852 -197.078644) (xy 176.337364 -197.116582)
			(xy 176.367656 -197.159648) (xy 176.391019 -197.206833) (xy 176.406905 -197.257032) (xy 176.414942 -197.309068)
			(xy 176.415446 -197.335394) (xy 179.146723 -197.335394) (xy 179.150658 -197.281623) (xy 179.162381 -197.228999)
			(xy 179.181641 -197.178642) (xy 179.208027 -197.131625) (xy 179.240979 -197.088952) (xy 179.279792 -197.051531)
			(xy 179.32364 -197.020161) (xy 179.371588 -196.995509) (xy 179.422615 -196.978101) (xy 179.475633 -196.968308)
			(xy 179.529512 -196.966339) (xy 179.583103 -196.972236) (xy 179.635264 -196.985872) (xy 179.684884 -197.006959)
			(xy 179.730905 -197.035045) (xy 179.772347 -197.069533) (xy 179.808325 -197.109687) (xy 179.838073 -197.154651)
			(xy 179.860958 -197.203468) (xy 179.87649 -197.255097) (xy 179.88434 -197.308437) (xy 179.884832 -197.335394)
			(xy 183.272179 -197.335394) (xy 183.276209 -197.282896) (xy 183.288206 -197.231628) (xy 183.307889 -197.182793)
			(xy 183.334795 -197.137534) (xy 183.368295 -197.096913) (xy 183.407603 -197.061882) (xy 183.451798 -197.033262)
			(xy 183.499843 -197.011723) (xy 183.550614 -196.997771) (xy 183.602919 -196.991733) (xy 183.655533 -196.99375)
			(xy 183.707223 -197.003774) (xy 183.756776 -197.021572) (xy 183.803032 -197.046725) (xy 183.844906 -197.078644)
			(xy 183.881418 -197.116582) (xy 183.91171 -197.159648) (xy 183.935073 -197.206833) (xy 183.950959 -197.257032)
			(xy 183.958996 -197.309068) (xy 183.9595 -197.335394) (xy 186.690777 -197.335394) (xy 186.694712 -197.281623)
			(xy 186.706435 -197.228999) (xy 186.725695 -197.178642) (xy 186.752081 -197.131625) (xy 186.785033 -197.088952)
			(xy 186.823846 -197.051531) (xy 186.867694 -197.020161) (xy 186.915642 -196.995509) (xy 186.966669 -196.978101)
			(xy 187.019687 -196.968308) (xy 187.073566 -196.966339) (xy 187.127157 -196.972236) (xy 187.179318 -196.985872)
			(xy 187.228938 -197.006959) (xy 187.274959 -197.035045) (xy 187.316401 -197.069533) (xy 187.352379 -197.109687)
			(xy 187.382127 -197.154651) (xy 187.405012 -197.203468) (xy 187.420544 -197.255097) (xy 187.428394 -197.308437)
			(xy 187.428886 -197.335394) (xy 190.816233 -197.335394) (xy 190.820263 -197.282896) (xy 190.83226 -197.231628)
			(xy 190.851943 -197.182793) (xy 190.878849 -197.137534) (xy 190.912349 -197.096913) (xy 190.951657 -197.061882)
			(xy 190.995852 -197.033262) (xy 191.043897 -197.011723) (xy 191.094668 -196.997771) (xy 191.146973 -196.991733)
			(xy 191.199587 -196.99375) (xy 191.251277 -197.003774) (xy 191.30083 -197.021572) (xy 191.347086 -197.046725)
			(xy 191.38896 -197.078644) (xy 191.425472 -197.116582) (xy 191.455764 -197.159648) (xy 191.479127 -197.206833)
			(xy 191.495013 -197.257032) (xy 191.50305 -197.309068) (xy 191.503554 -197.335394) (xy 194.234831 -197.335394)
			(xy 194.238766 -197.281623) (xy 194.250489 -197.228999) (xy 194.269749 -197.178642) (xy 194.296135 -197.131625)
			(xy 194.329087 -197.088952) (xy 194.3679 -197.051531) (xy 194.411748 -197.020161) (xy 194.459696 -196.995509)
			(xy 194.510723 -196.978101) (xy 194.563741 -196.968308) (xy 194.61762 -196.966339) (xy 194.671211 -196.972236)
			(xy 194.723372 -196.985872) (xy 194.772992 -197.006959) (xy 194.819013 -197.035045) (xy 194.860455 -197.069533)
			(xy 194.896433 -197.109687) (xy 194.926181 -197.154651) (xy 194.949066 -197.203468) (xy 194.964598 -197.255097)
			(xy 194.972448 -197.308437) (xy 194.97294 -197.335394) (xy 198.360287 -197.335394) (xy 198.364317 -197.282896)
			(xy 198.376314 -197.231628) (xy 198.395997 -197.182793) (xy 198.422903 -197.137534) (xy 198.456403 -197.096913)
			(xy 198.495711 -197.061882) (xy 198.539906 -197.033262) (xy 198.587951 -197.011723) (xy 198.638722 -196.997771)
			(xy 198.691027 -196.991733) (xy 198.743641 -196.99375) (xy 198.795331 -197.003774) (xy 198.844884 -197.021572)
			(xy 198.89114 -197.046725) (xy 198.933014 -197.078644) (xy 198.969526 -197.116582) (xy 198.999818 -197.159648)
			(xy 199.023181 -197.206833) (xy 199.039067 -197.257032) (xy 199.047104 -197.309068) (xy 199.047608 -197.335394)
			(xy 201.778631 -197.335394) (xy 201.782566 -197.281623) (xy 201.794289 -197.228999) (xy 201.813549 -197.178642)
			(xy 201.839935 -197.131625) (xy 201.872887 -197.088952) (xy 201.9117 -197.051531) (xy 201.955548 -197.020161)
			(xy 202.003496 -196.995509) (xy 202.054523 -196.978101) (xy 202.107541 -196.968308) (xy 202.16142 -196.966339)
			(xy 202.215011 -196.972236) (xy 202.267172 -196.985872) (xy 202.316792 -197.006959) (xy 202.362813 -197.035045)
			(xy 202.404255 -197.069533) (xy 202.440233 -197.109687) (xy 202.469981 -197.154651) (xy 202.492866 -197.203468)
			(xy 202.508398 -197.255097) (xy 202.516248 -197.308437) (xy 202.51674 -197.335394) (xy 202.516248 -197.362351)
			(xy 202.508398 -197.415691) (xy 202.492866 -197.46732) (xy 202.469981 -197.516137) (xy 202.440233 -197.561101)
			(xy 202.404255 -197.601255) (xy 202.362813 -197.635743) (xy 202.316792 -197.663829) (xy 202.267172 -197.684916)
			(xy 202.215011 -197.698552) (xy 202.16142 -197.704449) (xy 202.107541 -197.70248) (xy 202.054523 -197.692687)
			(xy 202.003496 -197.675279) (xy 201.955548 -197.650627) (xy 201.9117 -197.619257) (xy 201.872887 -197.581836)
			(xy 201.839935 -197.539163) (xy 201.813549 -197.492146) (xy 201.794289 -197.441789) (xy 201.782566 -197.389165)
			(xy 201.778631 -197.335394) (xy 199.047608 -197.335394) (xy 199.047104 -197.36172) (xy 199.039067 -197.413756)
			(xy 199.023181 -197.463955) (xy 198.999818 -197.51114) (xy 198.969526 -197.554206) (xy 198.933014 -197.592144)
			(xy 198.89114 -197.624063) (xy 198.844884 -197.649216) (xy 198.795331 -197.667014) (xy 198.743641 -197.677038)
			(xy 198.691027 -197.679055) (xy 198.638722 -197.673017) (xy 198.587951 -197.659065) (xy 198.539906 -197.637526)
			(xy 198.495711 -197.608906) (xy 198.456403 -197.573875) (xy 198.422903 -197.533254) (xy 198.395997 -197.487995)
			(xy 198.376314 -197.43916) (xy 198.364317 -197.387892) (xy 198.360287 -197.335394) (xy 194.97294 -197.335394)
			(xy 194.972448 -197.362351) (xy 194.964598 -197.415691) (xy 194.949066 -197.46732) (xy 194.926181 -197.516137)
			(xy 194.896433 -197.561101) (xy 194.860455 -197.601255) (xy 194.819013 -197.635743) (xy 194.772992 -197.663829)
			(xy 194.723372 -197.684916) (xy 194.671211 -197.698552) (xy 194.61762 -197.704449) (xy 194.563741 -197.70248)
			(xy 194.510723 -197.692687) (xy 194.459696 -197.675279) (xy 194.411748 -197.650627) (xy 194.3679 -197.619257)
			(xy 194.329087 -197.581836) (xy 194.296135 -197.539163) (xy 194.269749 -197.492146) (xy 194.250489 -197.441789)
			(xy 194.238766 -197.389165) (xy 194.234831 -197.335394) (xy 191.503554 -197.335394) (xy 191.50305 -197.36172)
			(xy 191.495013 -197.413756) (xy 191.479127 -197.463955) (xy 191.455764 -197.51114) (xy 191.425472 -197.554206)
			(xy 191.38896 -197.592144) (xy 191.347086 -197.624063) (xy 191.30083 -197.649216) (xy 191.251277 -197.667014)
			(xy 191.199587 -197.677038) (xy 191.146973 -197.679055) (xy 191.094668 -197.673017) (xy 191.043897 -197.659065)
			(xy 190.995852 -197.637526) (xy 190.951657 -197.608906) (xy 190.912349 -197.573875) (xy 190.878849 -197.533254)
			(xy 190.851943 -197.487995) (xy 190.83226 -197.43916) (xy 190.820263 -197.387892) (xy 190.816233 -197.335394)
			(xy 187.428886 -197.335394) (xy 187.428394 -197.362351) (xy 187.420544 -197.415691) (xy 187.405012 -197.46732)
			(xy 187.382127 -197.516137) (xy 187.352379 -197.561101) (xy 187.316401 -197.601255) (xy 187.274959 -197.635743)
			(xy 187.228938 -197.663829) (xy 187.179318 -197.684916) (xy 187.127157 -197.698552) (xy 187.073566 -197.704449)
			(xy 187.019687 -197.70248) (xy 186.966669 -197.692687) (xy 186.915642 -197.675279) (xy 186.867694 -197.650627)
			(xy 186.823846 -197.619257) (xy 186.785033 -197.581836) (xy 186.752081 -197.539163) (xy 186.725695 -197.492146)
			(xy 186.706435 -197.441789) (xy 186.694712 -197.389165) (xy 186.690777 -197.335394) (xy 183.9595 -197.335394)
			(xy 183.958996 -197.36172) (xy 183.950959 -197.413756) (xy 183.935073 -197.463955) (xy 183.91171 -197.51114)
			(xy 183.881418 -197.554206) (xy 183.844906 -197.592144) (xy 183.803032 -197.624063) (xy 183.756776 -197.649216)
			(xy 183.707223 -197.667014) (xy 183.655533 -197.677038) (xy 183.602919 -197.679055) (xy 183.550614 -197.673017)
			(xy 183.499843 -197.659065) (xy 183.451798 -197.637526) (xy 183.407603 -197.608906) (xy 183.368295 -197.573875)
			(xy 183.334795 -197.533254) (xy 183.307889 -197.487995) (xy 183.288206 -197.43916) (xy 183.276209 -197.387892)
			(xy 183.272179 -197.335394) (xy 179.884832 -197.335394) (xy 179.88434 -197.362351) (xy 179.87649 -197.415691)
			(xy 179.860958 -197.46732) (xy 179.838073 -197.516137) (xy 179.808325 -197.561101) (xy 179.772347 -197.601255)
			(xy 179.730905 -197.635743) (xy 179.684884 -197.663829) (xy 179.635264 -197.684916) (xy 179.583103 -197.698552)
			(xy 179.529512 -197.704449) (xy 179.475633 -197.70248) (xy 179.422615 -197.692687) (xy 179.371588 -197.675279)
			(xy 179.32364 -197.650627) (xy 179.279792 -197.619257) (xy 179.240979 -197.581836) (xy 179.208027 -197.539163)
			(xy 179.181641 -197.492146) (xy 179.162381 -197.441789) (xy 179.150658 -197.389165) (xy 179.146723 -197.335394)
			(xy 176.415446 -197.335394) (xy 176.414942 -197.36172) (xy 176.406905 -197.413756) (xy 176.391019 -197.463955)
			(xy 176.367656 -197.51114) (xy 176.337364 -197.554206) (xy 176.300852 -197.592144) (xy 176.258978 -197.624063)
			(xy 176.212722 -197.649216) (xy 176.163169 -197.667014) (xy 176.111479 -197.677038) (xy 176.058865 -197.679055)
			(xy 176.00656 -197.673017) (xy 175.955789 -197.659065) (xy 175.907744 -197.637526) (xy 175.863549 -197.608906)
			(xy 175.824241 -197.573875) (xy 175.790741 -197.533254) (xy 175.763835 -197.487995) (xy 175.744152 -197.43916)
			(xy 175.732155 -197.387892) (xy 175.728125 -197.335394) (xy 172.340778 -197.335394) (xy 172.340286 -197.362351)
			(xy 172.332436 -197.415691) (xy 172.316904 -197.46732) (xy 172.294019 -197.516137) (xy 172.264271 -197.561101)
			(xy 172.228293 -197.601255) (xy 172.186851 -197.635743) (xy 172.14083 -197.663829) (xy 172.09121 -197.684916)
			(xy 172.039049 -197.698552) (xy 171.985458 -197.704449) (xy 171.931579 -197.70248) (xy 171.878561 -197.692687)
			(xy 171.827534 -197.675279) (xy 171.779586 -197.650627) (xy 171.735738 -197.619257) (xy 171.696925 -197.581836)
			(xy 171.663973 -197.539163) (xy 171.637587 -197.492146) (xy 171.618327 -197.441789) (xy 171.606604 -197.389165)
			(xy 171.602669 -197.335394) (xy 165.13937 -197.335394) (xy 165.13937 -197.752716) (xy 165.139795 -197.762786)
			(xy 165.14751 -197.781389) (xy 165.154356 -197.788784) (xy 165.902132 -198.53656) (xy 165.90953 -198.543406)
			(xy 165.928129 -198.551135) (xy 165.9382 -198.551546)
		)
		(stroke
			(width 0)
			(type solid)
		)
		(fill yes)
		(layer "B.Cu")
		(net "P3V3")
	)
	(gr_poly
		(pts
			(xy 285.957518 -385.592574) (xy 285.967586 -385.592147) (xy 285.986184 -385.584425) (xy 285.993586 -385.577588)
			(xy 286.779462 -384.791712) (xy 286.786314 -384.784316) (xy 286.794059 -384.765718) (xy 286.794448 -384.755644)
			(xy 286.794448 -383.16662) (xy 286.794887 -383.156557) (xy 286.802627 -383.137979) (xy 286.809434 -383.130552)
			(xy 287.765236 -382.17475) (xy 287.76676 -382.172718) (xy 287.820505 -382.107814) (xy 287.932413 -381.981798)
			(xy 288.049208 -381.860298) (xy 288.170709 -381.743503) (xy 288.296725 -381.631595) (xy 288.361628 -381.57785)
			(xy 288.36366 -381.576326) (xy 289.24758 -380.692406) (xy 289.254983 -380.685572) (xy 289.273581 -380.677865)
			(xy 289.283648 -380.67742) (xy 290.315396 -380.67742) (xy 290.319714 -380.676658) (xy 290.412311 -380.6607)
			(xy 290.598596 -380.635948) (xy 290.78579 -380.619414) (xy 290.973529 -380.61113) (xy 291.06749 -380.610618)
			(xy 291.161451 -380.611129) (xy 291.349192 -380.6194) (xy 291.536385 -380.635933) (xy 291.72267 -380.660693)
			(xy 291.815266 -380.676658) (xy 291.824156 -380.67742) (xy 296.90568 -380.67742) (xy 296.915744 -380.676983)
			(xy 296.934329 -380.66925) (xy 296.941748 -380.662434) (xy 298.462446 -379.141736) (xy 298.468796 -379.130306)
			(xy 298.470574 -379.123702) (xy 298.478168 -379.096897) (xy 298.500054 -379.045666) (xy 298.529153 -378.998159)
			(xy 298.564846 -378.955385) (xy 298.606376 -378.918251) (xy 298.652861 -378.887546) (xy 298.703315 -378.863922)
			(xy 298.756665 -378.84788) (xy 298.811781 -378.839761) (xy 298.839636 -378.839222) (xy 298.86969 -378.839781)
			(xy 298.929056 -378.849199) (xy 298.986209 -378.867814) (xy 299.039735 -378.895163) (xy 299.088307 -378.93057)
			(xy 299.109892 -378.95149) (xy 299.11729 -378.958339) (xy 299.135888 -378.966078) (xy 299.14596 -378.966476)
			(xy 299.747432 -378.966476) (xy 299.757499 -378.966046) (xy 299.776093 -378.958321) (xy 299.7835 -378.95149)
			(xy 299.803111 -378.932468) (xy 299.846796 -378.899661) (xy 299.894714 -378.873421) (xy 299.945885 -378.854285)
			(xy 299.999263 -378.842645) (xy 300.053756 -378.838738) (xy 300.108249 -378.842645) (xy 300.161627 -378.854285)
			(xy 300.212798 -378.873421) (xy 300.260716 -378.899661) (xy 300.304401 -378.932468) (xy 300.324012 -378.95149)
			(xy 300.331411 -378.958335) (xy 300.350009 -378.966067) (xy 300.36008 -378.966476) (xy 302.933354 -378.966476)
			(xy 302.943419 -378.966042) (xy 302.962007 -378.958312) (xy 302.969422 -378.95149) (xy 303.286668 -378.634244)
			(xy 303.293509 -378.626844) (xy 303.301228 -378.608245) (xy 303.301654 -378.598176) (xy 303.301654 -377.007628)
			(xy 303.302092 -376.997565) (xy 303.309831 -376.978985) (xy 303.31664 -376.97156) (xy 303.943766 -376.344434)
			(xy 303.951166 -376.337594) (xy 303.969765 -376.329879) (xy 303.979834 -376.329448) (xy 392.391392 -376.329448)
			(xy 392.402434 -376.328844) (xy 392.422447 -376.319492) (xy 392.43 -376.311414) (xy 392.487404 -376.243596)
			(xy 392.493246 -376.22226) (xy 392.491468 -376.21083) (xy 392.488136 -376.189844) (xy 392.484579 -376.147496)
			(xy 392.484356 -376.126248) (xy 392.484869 -376.093836) (xy 392.493117 -376.029538) (xy 392.509472 -375.966811)
			(xy 392.533669 -375.906672) (xy 392.565315 -375.850097) (xy 392.584178 -375.823734) (xy 392.590272 -375.814612)
			(xy 392.594773 -375.793165) (xy 392.589909 -375.771798) (xy 392.58367 -375.762774) (xy 392.563932 -375.736064)
			(xy 392.530806 -375.678501) (xy 392.505447 -375.61712) (xy 392.488283 -375.552962) (xy 392.479608 -375.487117)
			(xy 392.479022 -375.45391) (xy 392.479524 -375.421949) (xy 392.487535 -375.358531) (xy 392.503432 -375.296617)
			(xy 392.526964 -375.237184) (xy 392.557758 -375.181169) (xy 392.595331 -375.129454) (xy 392.639088 -375.082857)
			(xy 392.688341 -375.042112) (xy 392.742312 -375.007861) (xy 392.800151 -374.980644) (xy 392.860944 -374.960891)
			(xy 392.923734 -374.948913) (xy 392.98753 -374.9449) (xy 393.051326 -374.948913) (xy 393.114116 -374.960891)
			(xy 393.174909 -374.980644) (xy 393.232748 -375.007861) (xy 393.286719 -375.042112) (xy 393.335972 -375.082857)
			(xy 393.379729 -375.129454) (xy 393.417302 -375.181169) (xy 393.448096 -375.237184) (xy 393.471628 -375.296617)
			(xy 393.487525 -375.358531) (xy 393.495536 -375.421949) (xy 393.496038 -375.45391) (xy 393.495528 -375.486323)
			(xy 393.487285 -375.550623) (xy 393.470934 -375.613353) (xy 393.44674 -375.673495) (xy 393.415097 -375.730073)
			(xy 393.396216 -375.756424) (xy 393.390114 -375.765547) (xy 393.385597 -375.787001) (xy 393.390448 -375.808382)
			(xy 393.396724 -375.817384) (xy 393.416465 -375.844093) (xy 393.449596 -375.901655) (xy 393.474961 -375.963036)
			(xy 393.49213 -376.027194) (xy 393.500811 -376.09304) (xy 393.501372 -376.126248) (xy 393.501139 -376.147496)
			(xy 393.497577 -376.189842) (xy 393.49426 -376.21083) (xy 393.492482 -376.22226) (xy 393.498324 -376.243596)
			(xy 393.555728 -376.311414) (xy 393.563265 -376.319515) (xy 393.583287 -376.328876) (xy 393.594336 -376.329448)
			(xy 425.315126 -376.329448) (xy 425.325193 -376.329877) (xy 425.343786 -376.337604) (xy 425.351194 -376.344434)
			(xy 428.030386 -379.023626) (xy 428.037786 -379.030467) (xy 428.056385 -379.038182) (xy 428.066454 -379.038612)
			(xy 440.219084 -379.038612) (xy 440.229148 -379.038174) (xy 440.247731 -379.03044) (xy 440.255152 -379.023626)
			(xy 440.69381 -378.584968) (xy 440.700661 -378.577572) (xy 440.708398 -378.558973) (xy 440.708796 -378.5489)
			(xy 440.708796 -374.715786) (xy 440.709222 -374.705717) (xy 440.716939 -374.687116) (xy 440.723782 -374.679718)
			(xy 441.322206 -374.081294) (xy 441.329605 -374.074449) (xy 441.348203 -374.066718) (xy 441.358274 -374.066308)
			(xy 455.075544 -374.066308) (xy 455.085611 -374.065877) (xy 455.104205 -374.058153) (xy 455.111612 -374.051322)
			(xy 455.48423 -373.678704) (xy 455.491085 -373.671309) (xy 455.498832 -373.65271) (xy 455.499216 -373.642636)
			(xy 455.499216 -364.446312) (xy 455.495406 -364.433104) (xy 455.49185 -364.427008) (xy 455.48835 -364.420902)
			(xy 455.484488 -364.407372) (xy 455.48423 -364.400338) (xy 455.48423 -344.286078) (xy 455.484658 -344.27601)
			(xy 455.492381 -344.257414) (xy 455.499216 -344.25001) (xy 459.1685 -340.580726) (xy 459.175897 -340.573877)
			(xy 459.194496 -340.566138) (xy 459.204568 -340.56574) (xy 464.054952 -340.56574) (xy 464.064827 -340.565275)
			(xy 464.083121 -340.557827) (xy 464.090512 -340.551262) (xy 464.090766 -340.551008) (xy 465.94903 -338.692744)
			(xy 465.949538 -338.692236) (xy 465.95612 -338.684855) (xy 465.963569 -338.666556) (xy 465.964016 -338.656676)
			(xy 465.964016 -174.356268) (xy 465.963588 -174.3462) (xy 465.955867 -174.327602) (xy 465.94903 -174.3202)
			(xy 455.874374 -164.245798) (xy 455.86752 -164.238403) (xy 455.859775 -164.219804) (xy 455.859388 -164.20973)
			(xy 455.859388 -156.788866) (xy 455.859817 -156.778798) (xy 455.867539 -156.760202) (xy 455.874374 -156.752798)
			(xy 465.971128 -146.656044) (xy 465.977974 -146.648646) (xy 465.985699 -146.630047) (xy 465.986114 -146.619976)
			(xy 465.986114 -143.963898) (xy 465.986202 -143.958878) (xy 465.988113 -143.949023) (xy 465.989924 -143.94434)
			(xy 465.99729 -143.927068) (xy 465.999086 -143.922381) (xy 466.000998 -143.912529) (xy 466.0011 -143.90751)
			(xy 466.0011 -110.057438) (xy 466.000665 -110.047373) (xy 465.992935 -110.028785) (xy 465.986114 -110.02137)
			(xy 464.348322 -108.383578) (xy 464.341477 -108.376179) (xy 464.333747 -108.357581) (xy 464.333336 -108.34751)
			(xy 464.333336 -106.381296) (xy 464.333761 -106.371227) (xy 464.34148 -106.352627) (xy 464.348322 -106.345228)
			(xy 466.354414 -104.339136) (xy 466.354922 -104.338628) (xy 466.361505 -104.331247) (xy 466.368953 -104.312948)
			(xy 466.3694 -104.303068) (xy 466.3694 -102.247192) (xy 466.368975 -102.237122) (xy 466.361259 -102.21852)
			(xy 466.354414 -102.211124) (xy 463.551778 -99.408488) (xy 463.544925 -99.401093) (xy 463.537183 -99.382494)
			(xy 463.536792 -99.37242) (xy 463.536792 -93.453966) (xy 463.536362 -93.443899) (xy 463.528638 -93.425304)
			(xy 463.521806 -93.417898) (xy 458.736446 -88.632538) (xy 458.729334 -88.625172) (xy 458.710538 -88.617552)
			(xy 449.111878 -88.617552) (xy 449.108145 -88.617521) (xy 449.10075 -88.616497) (xy 449.097146 -88.61552)
			(xy 449.083684 -88.611456) (xy 449.05676 -88.61806) (xy 449.007738 -88.667082) (xy 449.000337 -88.67392)
			(xy 448.981739 -88.681635) (xy 448.97167 -88.682068) (xy 438.332372 -88.682068) (xy 438.322303 -88.682495)
			(xy 438.303703 -88.690213) (xy 438.296304 -88.697054) (xy 437.933338 -89.06002) (xy 437.925972 -89.067132)
			(xy 437.918352 -89.085928) (xy 437.918352 -90.619834) (xy 437.919016 -90.631908) (xy 437.930013 -90.653405)
			(xy 437.939434 -90.660982) (xy 438.016396 -90.716354) (xy 438.040526 -90.720164) (xy 438.05221 -90.7161)
			(xy 438.082135 -90.706558) (xy 438.143512 -90.693199) (xy 438.205969 -90.686512) (xy 438.237376 -90.686128)
			(xy 438.271402 -90.686602) (xy 438.338996 -90.6945) (xy 438.405215 -90.710192) (xy 438.469164 -90.733465)
			(xy 438.529979 -90.764006) (xy 438.586838 -90.8014) (xy 438.63897 -90.845142) (xy 438.685672 -90.894641)
			(xy 438.726311 -90.949227) (xy 438.760339 -91.008162) (xy 438.787294 -91.070649) (xy 438.806812 -91.135843)
			(xy 438.818629 -91.202862) (xy 438.822587 -91.2708) (xy 438.818629 -91.338738) (xy 438.806812 -91.405757)
			(xy 438.787294 -91.470951) (xy 438.760339 -91.533438) (xy 438.726311 -91.592373) (xy 438.685672 -91.646959)
			(xy 438.63897 -91.696458) (xy 438.586838 -91.7402) (xy 438.529979 -91.777594) (xy 438.469164 -91.808135)
			(xy 438.405215 -91.831408) (xy 438.338996 -91.8471) (xy 438.271402 -91.854998) (xy 438.237376 -91.855544)
			(xy 438.20597 -91.855142) (xy 438.143516 -91.848444) (xy 438.082137 -91.835104) (xy 438.05221 -91.825572)
			(xy 438.040526 -91.821508) (xy 438.016396 -91.825318) (xy 437.939434 -91.88069) (xy 437.930044 -91.888298)
			(xy 437.919027 -91.909773) (xy 437.918352 -91.921838) (xy 437.918352 -92.52356) (xy 449.254862 -92.52356)
			(xy 449.254862 -92.463624) (xy 449.262685 -92.404202) (xy 449.278198 -92.346309) (xy 449.301134 -92.290936)
			(xy 449.331101 -92.23903) (xy 449.367588 -92.19148) (xy 449.409968 -92.1491) (xy 449.457518 -92.112613)
			(xy 449.509424 -92.082646) (xy 449.564797 -92.05971) (xy 449.62269 -92.044197) (xy 449.682112 -92.036374)
			(xy 449.742048 -92.036374) (xy 449.80147 -92.044197) (xy 449.859363 -92.05971) (xy 449.914736 -92.082646)
			(xy 449.920026 -92.0857) (xy 456.731536 -92.0857) (xy 456.735551 -92.021894) (xy 456.747531 -91.959095)
			(xy 456.767288 -91.898292) (xy 456.79451 -91.840446) (xy 456.828768 -91.786467) (xy 456.869522 -91.737208)
			(xy 456.916128 -91.693446) (xy 456.967852 -91.65587) (xy 457.023877 -91.625073) (xy 457.083321 -91.601542)
			(xy 457.145246 -91.585647) (xy 457.208674 -91.577639) (xy 457.24064 -91.57716) (xy 457.270817 -91.577611)
			(xy 457.330748 -91.584745) (xy 457.389414 -91.598921) (xy 457.44599 -91.619938) (xy 457.499682 -91.647502)
			(xy 457.549735 -91.681225) (xy 457.572872 -91.700604) (xy 457.580347 -91.706577) (xy 457.598357 -91.712984)
			(xy 457.607924 -91.71305) (xy 457.638912 -91.71178) (xy 457.648356 -91.711026) (xy 457.665709 -91.703449)
			(xy 457.672694 -91.697048) (xy 457.694177 -91.67642) (xy 457.741584 -91.640367) (xy 457.793271 -91.610774)
			(xy 457.848362 -91.588142) (xy 457.905925 -91.572854) (xy 457.964986 -91.565169) (xy 457.994766 -91.564714)
			(xy 458.024738 -91.565137) (xy 458.084169 -91.572957) (xy 458.142072 -91.588468) (xy 458.197454 -91.611405)
			(xy 458.249368 -91.641374) (xy 458.296926 -91.677863) (xy 458.339314 -91.720248) (xy 458.375807 -91.767804)
			(xy 458.40578 -91.819716) (xy 458.428721 -91.875096) (xy 458.444236 -91.932997) (xy 458.452061 -91.992428)
			(xy 458.452061 -92.052372) (xy 458.444236 -92.111803) (xy 458.428721 -92.169704) (xy 458.40578 -92.225084)
			(xy 458.375807 -92.276996) (xy 458.339314 -92.324552) (xy 458.296926 -92.366937) (xy 458.249368 -92.403426)
			(xy 458.197454 -92.433395) (xy 458.142072 -92.456332) (xy 458.084169 -92.471843) (xy 458.024738 -92.479663)
			(xy 457.994766 -92.48013) (xy 457.966694 -92.479707) (xy 457.910969 -92.47285) (xy 457.856502 -92.459229)
			(xy 457.804109 -92.439051) (xy 457.754577 -92.412616) (xy 457.731368 -92.396818) (xy 457.723416 -92.391636)
			(xy 457.705007 -92.387072) (xy 457.695554 -92.387928) (xy 457.66482 -92.391992) (xy 457.655406 -92.393656)
			(xy 457.638698 -92.402916) (xy 457.632308 -92.410026) (xy 457.611544 -92.434304) (xy 457.564947 -92.478008)
			(xy 457.513244 -92.515533) (xy 457.45725 -92.546289) (xy 457.397844 -92.569791) (xy 457.335964 -92.585669)
			(xy 457.272582 -92.593674) (xy 457.24064 -92.594176) (xy 457.208674 -92.593761) (xy 457.145246 -92.585753)
			(xy 457.083321 -92.569858) (xy 457.023877 -92.546327) (xy 456.967852 -92.51553) (xy 456.916128 -92.477954)
			(xy 456.869522 -92.434192) (xy 456.828768 -92.384933) (xy 456.79451 -92.330954) (xy 456.767288 -92.273108)
			(xy 456.747531 -92.212305) (xy 456.735551 -92.149506) (xy 456.731536 -92.0857) (xy 449.920026 -92.0857)
			(xy 449.966642 -92.112613) (xy 450.014192 -92.1491) (xy 450.056572 -92.19148) (xy 450.093059 -92.23903)
			(xy 450.123026 -92.290936) (xy 450.145962 -92.346309) (xy 450.161475 -92.404202) (xy 450.169298 -92.463624)
			(xy 450.169788 -92.493592) (xy 450.169298 -92.52356) (xy 450.161475 -92.582982) (xy 450.145962 -92.640875)
			(xy 450.123026 -92.696248) (xy 450.093059 -92.748154) (xy 450.056572 -92.795704) (xy 450.014192 -92.838084)
			(xy 449.966642 -92.874571) (xy 449.914736 -92.904538) (xy 449.859363 -92.927474) (xy 449.80147 -92.942987)
			(xy 449.742048 -92.95081) (xy 449.682112 -92.95081) (xy 449.62269 -92.942987) (xy 449.564797 -92.927474)
			(xy 449.509424 -92.904538) (xy 449.457518 -92.874571) (xy 449.409968 -92.838084) (xy 449.367588 -92.795704)
			(xy 449.331101 -92.748154) (xy 449.301134 -92.696248) (xy 449.278198 -92.640875) (xy 449.262685 -92.582982)
			(xy 449.254862 -92.52356) (xy 437.918352 -92.52356) (xy 437.918352 -93.505528) (xy 440.882022 -93.505528)
			(xy 440.886093 -93.449906) (xy 440.898219 -93.395469) (xy 440.918142 -93.343378) (xy 440.945438 -93.294743)
			(xy 440.979524 -93.2506) (xy 441.019673 -93.211891) (xy 441.065031 -93.17944) (xy 441.114631 -93.153939)
			(xy 441.167415 -93.135932) (xy 441.222258 -93.125802) (xy 441.277992 -93.123765) (xy 441.333429 -93.129865)
			(xy 441.387386 -93.143971) (xy 441.438715 -93.165783) (xy 441.486321 -93.194837) (xy 441.529189 -93.230512)
			(xy 441.566406 -93.272049) (xy 441.597179 -93.318562) (xy 441.620851 -93.369059) (xy 441.636919 -93.422466)
			(xy 441.645039 -93.477642) (xy 441.645548 -93.505528) (xy 441.645474 -93.509592) (xy 449.330062 -93.509592)
			(xy 449.334133 -93.45397) (xy 449.346259 -93.399533) (xy 449.366182 -93.347442) (xy 449.393478 -93.298807)
			(xy 449.427564 -93.254664) (xy 449.467713 -93.215955) (xy 449.513071 -93.183504) (xy 449.562671 -93.158003)
			(xy 449.615455 -93.139996) (xy 449.670298 -93.129866) (xy 449.726032 -93.127829) (xy 449.781469 -93.133929)
			(xy 449.835426 -93.148035) (xy 449.886755 -93.169847) (xy 449.934361 -93.198901) (xy 449.977229 -93.234576)
			(xy 450.014446 -93.276113) (xy 450.045219 -93.322626) (xy 450.068891 -93.373123) (xy 450.084959 -93.42653)
			(xy 450.091649 -93.471991) (xy 454.017621 -93.471991) (xy 454.017621 -93.403937) (xy 454.025521 -93.336344)
			(xy 454.041215 -93.270126) (xy 454.064491 -93.206177) (xy 454.095033 -93.145362) (xy 454.132429 -93.088505)
			(xy 454.176172 -93.036373) (xy 454.225672 -92.989672) (xy 454.280259 -92.949034) (xy 454.339195 -92.915007)
			(xy 454.401683 -92.888053) (xy 454.466877 -92.868535) (xy 454.533896 -92.856717) (xy 454.601834 -92.852761)
			(xy 454.669772 -92.856717) (xy 454.736791 -92.868535) (xy 454.801985 -92.888053) (xy 454.864473 -92.915007)
			(xy 454.923409 -92.949034) (xy 454.977996 -92.989672) (xy 455.027496 -93.036373) (xy 455.071239 -93.088505)
			(xy 455.108635 -93.145362) (xy 455.139177 -93.206177) (xy 455.162453 -93.270126) (xy 455.178147 -93.336344)
			(xy 455.186047 -93.403937) (xy 455.186542 -93.437964) (xy 455.186047 -93.471991) (xy 455.178147 -93.539584)
			(xy 455.162453 -93.605802) (xy 455.139177 -93.669751) (xy 455.108635 -93.730566) (xy 455.071239 -93.787423)
			(xy 455.027496 -93.839555) (xy 454.977996 -93.886256) (xy 454.923409 -93.926894) (xy 454.864473 -93.960921)
			(xy 454.801985 -93.987875) (xy 454.736791 -94.007393) (xy 454.669772 -94.019211) (xy 454.601834 -94.023168)
			(xy 454.533896 -94.019211) (xy 454.466877 -94.007393) (xy 454.401683 -93.987875) (xy 454.339195 -93.960921)
			(xy 454.280259 -93.926894) (xy 454.225672 -93.886256) (xy 454.176172 -93.839555) (xy 454.132429 -93.787423)
			(xy 454.095033 -93.730566) (xy 454.064491 -93.669751) (xy 454.041215 -93.605802) (xy 454.025521 -93.539584)
			(xy 454.017621 -93.471991) (xy 450.091649 -93.471991) (xy 450.093079 -93.481706) (xy 450.093588 -93.509592)
			(xy 450.093079 -93.537478) (xy 450.084959 -93.592654) (xy 450.068891 -93.646061) (xy 450.045219 -93.696558)
			(xy 450.014446 -93.743071) (xy 449.977229 -93.784608) (xy 449.934361 -93.820283) (xy 449.886755 -93.849337)
			(xy 449.835426 -93.871149) (xy 449.781469 -93.885255) (xy 449.726032 -93.891355) (xy 449.670298 -93.889318)
			(xy 449.615455 -93.879188) (xy 449.562671 -93.861181) (xy 449.513071 -93.83568) (xy 449.467713 -93.803229)
			(xy 449.427564 -93.76452) (xy 449.393478 -93.720377) (xy 449.366182 -93.671742) (xy 449.346259 -93.619651)
			(xy 449.334133 -93.565214) (xy 449.330062 -93.509592) (xy 441.645474 -93.509592) (xy 441.645039 -93.533414)
			(xy 441.636919 -93.58859) (xy 441.620851 -93.641997) (xy 441.597179 -93.692494) (xy 441.566406 -93.739007)
			(xy 441.529189 -93.780544) (xy 441.486321 -93.816219) (xy 441.438715 -93.845273) (xy 441.387386 -93.867085)
			(xy 441.333429 -93.881191) (xy 441.277992 -93.887291) (xy 441.222258 -93.885254) (xy 441.167415 -93.875124)
			(xy 441.114631 -93.857117) (xy 441.065031 -93.831616) (xy 441.019673 -93.799165) (xy 440.979524 -93.760456)
			(xy 440.945438 -93.716313) (xy 440.918142 -93.667678) (xy 440.898219 -93.615587) (xy 440.886093 -93.56115)
			(xy 440.882022 -93.505528) (xy 437.918352 -93.505528) (xy 437.918352 -94.079822) (xy 437.918725 -94.08861)
			(xy 437.924683 -94.105145) (xy 437.935887 -94.118686) (xy 437.943244 -94.12351) (xy 438.030112 -94.175072)
			(xy 438.056528 -94.17558) (xy 438.06872 -94.168976) (xy 438.096937 -94.154273) (xy 438.15705 -94.133434)
			(xy 438.219789 -94.12286) (xy 438.2516 -94.12224) (xy 438.278848 -94.122726) (xy 438.332789 -94.130482)
			(xy 438.385077 -94.145835) (xy 438.434648 -94.168473) (xy 438.480492 -94.197936) (xy 438.521677 -94.233623)
			(xy 438.557364 -94.274808) (xy 438.586827 -94.320652) (xy 438.609465 -94.370223) (xy 438.624818 -94.422511)
			(xy 438.632574 -94.476452) (xy 438.632574 -94.530948) (xy 438.624818 -94.584889) (xy 438.609465 -94.637177)
			(xy 438.597321 -94.663768) (xy 439.713622 -94.663768) (xy 439.717693 -94.608146) (xy 439.729819 -94.553709)
			(xy 439.749742 -94.501618) (xy 439.777038 -94.452983) (xy 439.811124 -94.40884) (xy 439.851273 -94.370131)
			(xy 439.896631 -94.33768) (xy 439.946231 -94.312179) (xy 439.999015 -94.294172) (xy 440.053858 -94.284042)
			(xy 440.109592 -94.282005) (xy 440.165029 -94.288105) (xy 440.218986 -94.302211) (xy 440.270315 -94.324023)
			(xy 440.317921 -94.353077) (xy 440.360789 -94.388752) (xy 440.398006 -94.430289) (xy 440.428779 -94.476802)
			(xy 440.452451 -94.527299) (xy 440.468519 -94.580706) (xy 440.476475 -94.634769) (xy 445.752976 -94.634769)
			(xy 445.752976 -94.570847) (xy 445.760987 -94.507429) (xy 445.776884 -94.445515) (xy 445.800416 -94.386082)
			(xy 445.83121 -94.330067) (xy 445.868783 -94.278352) (xy 445.91254 -94.231755) (xy 445.961793 -94.19101)
			(xy 446.015764 -94.156759) (xy 446.073603 -94.129542) (xy 446.134396 -94.109789) (xy 446.197186 -94.097811)
			(xy 446.260982 -94.093798) (xy 446.324778 -94.097811) (xy 446.387568 -94.109789) (xy 446.448361 -94.129542)
			(xy 446.5062 -94.156759) (xy 446.560171 -94.19101) (xy 446.609424 -94.231755) (xy 446.653181 -94.278352)
			(xy 446.690754 -94.330067) (xy 446.721548 -94.386082) (xy 446.74508 -94.445515) (xy 446.760977 -94.507429)
			(xy 446.768988 -94.570847) (xy 446.76949 -94.602808) (xy 446.768988 -94.634769) (xy 446.760977 -94.698187)
			(xy 446.74508 -94.760101) (xy 446.721548 -94.819534) (xy 446.690754 -94.875549) (xy 446.653181 -94.927264)
			(xy 446.609424 -94.973861) (xy 446.59894 -94.982534) (xy 461.90076 -94.982534) (xy 461.90076 -94.922598)
			(xy 461.908583 -94.863176) (xy 461.924096 -94.805283) (xy 461.947032 -94.74991) (xy 461.976999 -94.698004)
			(xy 462.013486 -94.650454) (xy 462.055866 -94.608074) (xy 462.103416 -94.571587) (xy 462.155322 -94.54162)
			(xy 462.210695 -94.518684) (xy 462.268588 -94.503171) (xy 462.32801 -94.495348) (xy 462.387946 -94.495348)
			(xy 462.447368 -94.503171) (xy 462.505261 -94.518684) (xy 462.560634 -94.54162) (xy 462.61254 -94.571587)
			(xy 462.66009 -94.608074) (xy 462.70247 -94.650454) (xy 462.738957 -94.698004) (xy 462.768924 -94.74991)
			(xy 462.79186 -94.805283) (xy 462.807373 -94.863176) (xy 462.815196 -94.922598) (xy 462.815686 -94.952566)
			(xy 462.815196 -94.982534) (xy 462.807373 -95.041956) (xy 462.79186 -95.099849) (xy 462.768924 -95.155222)
			(xy 462.738957 -95.207128) (xy 462.70247 -95.254678) (xy 462.66009 -95.297058) (xy 462.61254 -95.333545)
			(xy 462.560634 -95.363512) (xy 462.505261 -95.386448) (xy 462.447368 -95.401961) (xy 462.387946 -95.409784)
			(xy 462.32801 -95.409784) (xy 462.268588 -95.401961) (xy 462.210695 -95.386448) (xy 462.155322 -95.363512)
			(xy 462.103416 -95.333545) (xy 462.055866 -95.297058) (xy 462.013486 -95.254678) (xy 461.976999 -95.207128)
			(xy 461.947032 -95.155222) (xy 461.924096 -95.099849) (xy 461.908583 -95.041956) (xy 461.90076 -94.982534)
			(xy 446.59894 -94.982534) (xy 446.560171 -95.014606) (xy 446.5062 -95.048857) (xy 446.448361 -95.076074)
			(xy 446.387568 -95.095827) (xy 446.324778 -95.107805) (xy 446.260982 -95.111819) (xy 446.197186 -95.107805)
			(xy 446.134396 -95.095827) (xy 446.073603 -95.076074) (xy 446.015764 -95.048857) (xy 445.961793 -95.014606)
			(xy 445.91254 -94.973861) (xy 445.868783 -94.927264) (xy 445.83121 -94.875549) (xy 445.800416 -94.819534)
			(xy 445.776884 -94.760101) (xy 445.760987 -94.698187) (xy 445.752976 -94.634769) (xy 440.476475 -94.634769)
			(xy 440.476639 -94.635882) (xy 440.477148 -94.663768) (xy 440.476639 -94.691654) (xy 440.468519 -94.74683)
			(xy 440.452451 -94.800237) (xy 440.428779 -94.850734) (xy 440.398006 -94.897247) (xy 440.360789 -94.938784)
			(xy 440.317921 -94.974459) (xy 440.270315 -95.003513) (xy 440.218986 -95.025325) (xy 440.165029 -95.039431)
			(xy 440.109592 -95.045531) (xy 440.053858 -95.043494) (xy 439.999015 -95.033364) (xy 439.946231 -95.015357)
			(xy 439.896631 -94.989856) (xy 439.851273 -94.957405) (xy 439.811124 -94.918696) (xy 439.777038 -94.874553)
			(xy 439.749742 -94.825918) (xy 439.729819 -94.773827) (xy 439.717693 -94.71939) (xy 439.713622 -94.663768)
			(xy 438.597321 -94.663768) (xy 438.586827 -94.686748) (xy 438.557364 -94.732592) (xy 438.521677 -94.773777)
			(xy 438.480492 -94.809464) (xy 438.434648 -94.838927) (xy 438.385077 -94.861565) (xy 438.332789 -94.876918)
			(xy 438.278848 -94.884674) (xy 438.2516 -94.885256) (xy 438.219789 -94.884618) (xy 438.157051 -94.874054)
			(xy 438.096937 -94.85322) (xy 438.06872 -94.83852) (xy 438.056528 -94.831916) (xy 438.030112 -94.832424)
			(xy 437.943244 -94.883986) (xy 437.935874 -94.888789) (xy 437.924683 -94.902345) (xy 437.918733 -94.918885)
			(xy 437.918352 -94.927674) (xy 437.918352 -95.145606) (xy 437.918809 -95.155485) (xy 437.926244 -95.173791)
			(xy 437.93283 -95.181166) (xy 437.933084 -95.18142) (xy 438.658499 -95.906835) (xy 442.521327 -95.906835)
			(xy 442.521327 -95.838781) (xy 442.529227 -95.771188) (xy 442.544921 -95.70497) (xy 442.568197 -95.641021)
			(xy 442.598739 -95.580206) (xy 442.636135 -95.523349) (xy 442.679878 -95.471217) (xy 442.729378 -95.424516)
			(xy 442.783965 -95.383878) (xy 442.842901 -95.349851) (xy 442.905389 -95.322897) (xy 442.970583 -95.303379)
			(xy 443.037602 -95.291561) (xy 443.10554 -95.287605) (xy 443.173478 -95.291561) (xy 443.240497 -95.303379)
			(xy 443.305691 -95.322897) (xy 443.368179 -95.349851) (xy 443.427115 -95.383878) (xy 443.481702 -95.424516)
			(xy 443.531202 -95.471217) (xy 443.574945 -95.523349) (xy 443.612341 -95.580206) (xy 443.642883 -95.641021)
			(xy 443.666159 -95.70497) (xy 443.681853 -95.771188) (xy 443.689753 -95.838781) (xy 443.690248 -95.872808)
			(xy 443.689783 -95.904769) (xy 449.127874 -95.904769) (xy 449.127874 -95.840847) (xy 449.135885 -95.777429)
			(xy 449.151782 -95.715515) (xy 449.175314 -95.656082) (xy 449.206108 -95.600067) (xy 449.243681 -95.548352)
			(xy 449.287438 -95.501755) (xy 449.336691 -95.46101) (xy 449.390662 -95.426759) (xy 449.448501 -95.399542)
			(xy 449.509294 -95.379789) (xy 449.572084 -95.367811) (xy 449.63588 -95.363798) (xy 449.699676 -95.367811)
			(xy 449.762466 -95.379789) (xy 449.823259 -95.399542) (xy 449.881098 -95.426759) (xy 449.935069 -95.46101)
			(xy 449.984322 -95.501755) (xy 450.028079 -95.548352) (xy 450.065652 -95.600067) (xy 450.096446 -95.656082)
			(xy 450.119978 -95.715515) (xy 450.135875 -95.777429) (xy 450.143886 -95.840847) (xy 450.144388 -95.872808)
			(xy 450.143886 -95.904769) (xy 450.135875 -95.968187) (xy 450.119978 -96.030101) (xy 450.096446 -96.089534)
			(xy 450.065652 -96.145549) (xy 450.028079 -96.197264) (xy 449.984322 -96.243861) (xy 449.935069 -96.284606)
			(xy 449.887155 -96.315013) (xy 453.125827 -96.315013) (xy 453.125827 -96.246959) (xy 453.133727 -96.179366)
			(xy 453.149421 -96.113148) (xy 453.172697 -96.049199) (xy 453.203239 -95.988384) (xy 453.240635 -95.931527)
			(xy 453.284378 -95.879395) (xy 453.333878 -95.832694) (xy 453.388465 -95.792056) (xy 453.447401 -95.758029)
			(xy 453.509889 -95.731075) (xy 453.575083 -95.711557) (xy 453.642102 -95.699739) (xy 453.71004 -95.695783)
			(xy 453.777978 -95.699739) (xy 453.844997 -95.711557) (xy 453.910191 -95.731075) (xy 453.972679 -95.758029)
			(xy 454.031615 -95.792056) (xy 454.086202 -95.832694) (xy 454.135702 -95.879395) (xy 454.179445 -95.931527)
			(xy 454.216841 -95.988384) (xy 454.247383 -96.049199) (xy 454.270659 -96.113148) (xy 454.286353 -96.179366)
			(xy 454.294253 -96.246959) (xy 454.294748 -96.280986) (xy 454.294253 -96.315013) (xy 454.286353 -96.382606)
			(xy 454.270659 -96.448824) (xy 454.247383 -96.512773) (xy 454.216841 -96.573588) (xy 454.179445 -96.630445)
			(xy 454.135702 -96.682577) (xy 454.086202 -96.729278) (xy 454.031615 -96.769916) (xy 453.972679 -96.803943)
			(xy 453.910191 -96.830897) (xy 453.844997 -96.850415) (xy 453.777978 -96.862233) (xy 453.71004 -96.86619)
			(xy 453.642102 -96.862233) (xy 453.575083 -96.850415) (xy 453.509889 -96.830897) (xy 453.447401 -96.803943)
			(xy 453.388465 -96.769916) (xy 453.333878 -96.729278) (xy 453.284378 -96.682577) (xy 453.240635 -96.630445)
			(xy 453.203239 -96.573588) (xy 453.172697 -96.512773) (xy 453.149421 -96.448824) (xy 453.133727 -96.382606)
			(xy 453.125827 -96.315013) (xy 449.887155 -96.315013) (xy 449.881098 -96.318857) (xy 449.823259 -96.346074)
			(xy 449.762466 -96.365827) (xy 449.699676 -96.377805) (xy 449.63588 -96.381819) (xy 449.572084 -96.377805)
			(xy 449.509294 -96.365827) (xy 449.448501 -96.346074) (xy 449.390662 -96.318857) (xy 449.336691 -96.284606)
			(xy 449.287438 -96.243861) (xy 449.243681 -96.197264) (xy 449.206108 -96.145549) (xy 449.175314 -96.089534)
			(xy 449.151782 -96.030101) (xy 449.135885 -95.968187) (xy 449.127874 -95.904769) (xy 443.689783 -95.904769)
			(xy 443.689753 -95.906835) (xy 443.681853 -95.974428) (xy 443.666159 -96.040646) (xy 443.642883 -96.104595)
			(xy 443.612341 -96.16541) (xy 443.574945 -96.222267) (xy 443.531202 -96.274399) (xy 443.481702 -96.3211)
			(xy 443.427115 -96.361738) (xy 443.368179 -96.395765) (xy 443.305691 -96.422719) (xy 443.240497 -96.442237)
			(xy 443.173478 -96.454055) (xy 443.10554 -96.458012) (xy 443.037602 -96.454055) (xy 442.970583 -96.442237)
			(xy 442.905389 -96.422719) (xy 442.842901 -96.395765) (xy 442.783965 -96.361738) (xy 442.729378 -96.3211)
			(xy 442.679878 -96.274399) (xy 442.636135 -96.222267) (xy 442.598739 -96.16541) (xy 442.568197 -96.104595)
			(xy 442.544921 -96.040646) (xy 442.529227 -95.974428) (xy 442.521327 -95.906835) (xy 438.658499 -95.906835)
			(xy 440.040259 -97.288595) (xy 442.488307 -97.288595) (xy 442.488307 -97.220541) (xy 442.496207 -97.152948)
			(xy 442.511901 -97.08673) (xy 442.535177 -97.022781) (xy 442.565719 -96.961966) (xy 442.603115 -96.905109)
			(xy 442.646858 -96.852977) (xy 442.696358 -96.806276) (xy 442.750945 -96.765638) (xy 442.809881 -96.731611)
			(xy 442.872369 -96.704657) (xy 442.937563 -96.685139) (xy 443.004582 -96.673321) (xy 443.07252 -96.669365)
			(xy 443.140458 -96.673321) (xy 443.207477 -96.685139) (xy 443.272671 -96.704657) (xy 443.335159 -96.731611)
			(xy 443.394095 -96.765638) (xy 443.448682 -96.806276) (xy 443.498182 -96.852977) (xy 443.541925 -96.905109)
			(xy 443.579321 -96.961966) (xy 443.609863 -97.022781) (xy 443.633139 -97.08673) (xy 443.648833 -97.152948)
			(xy 443.656733 -97.220541) (xy 443.657228 -97.254568) (xy 443.656733 -97.288595) (xy 443.655193 -97.301769)
			(xy 449.127874 -97.301769) (xy 449.127874 -97.237847) (xy 449.135885 -97.174429) (xy 449.151782 -97.112515)
			(xy 449.175314 -97.053082) (xy 449.206108 -96.997067) (xy 449.243681 -96.945352) (xy 449.287438 -96.898755)
			(xy 449.336691 -96.85801) (xy 449.390662 -96.823759) (xy 449.448501 -96.796542) (xy 449.509294 -96.776789)
			(xy 449.572084 -96.764811) (xy 449.63588 -96.760798) (xy 449.699676 -96.764811) (xy 449.762466 -96.776789)
			(xy 449.823259 -96.796542) (xy 449.881098 -96.823759) (xy 449.935069 -96.85801) (xy 449.984322 -96.898755)
			(xy 450.028079 -96.945352) (xy 450.065652 -96.997067) (xy 450.096446 -97.053082) (xy 450.119978 -97.112515)
			(xy 450.135875 -97.174429) (xy 450.143886 -97.237847) (xy 450.144388 -97.269808) (xy 450.143886 -97.301769)
			(xy 450.135875 -97.365187) (xy 450.119978 -97.427101) (xy 450.096446 -97.486534) (xy 450.065652 -97.542549)
			(xy 450.028079 -97.594264) (xy 449.984322 -97.640861) (xy 449.935069 -97.681606) (xy 449.881098 -97.715857)
			(xy 449.823259 -97.743074) (xy 449.762466 -97.762827) (xy 449.699676 -97.774805) (xy 449.63588 -97.778819)
			(xy 449.572084 -97.774805) (xy 449.509294 -97.762827) (xy 449.448501 -97.743074) (xy 449.390662 -97.715857)
			(xy 449.336691 -97.681606) (xy 449.287438 -97.640861) (xy 449.243681 -97.594264) (xy 449.206108 -97.542549)
			(xy 449.175314 -97.486534) (xy 449.151782 -97.427101) (xy 449.135885 -97.365187) (xy 449.127874 -97.301769)
			(xy 443.655193 -97.301769) (xy 443.648833 -97.356188) (xy 443.633139 -97.422406) (xy 443.609863 -97.486355)
			(xy 443.579321 -97.54717) (xy 443.541925 -97.604027) (xy 443.498182 -97.656159) (xy 443.448682 -97.70286)
			(xy 443.394095 -97.743498) (xy 443.335159 -97.777525) (xy 443.272671 -97.804479) (xy 443.207477 -97.823997)
			(xy 443.140458 -97.835815) (xy 443.07252 -97.839772) (xy 443.004582 -97.835815) (xy 442.937563 -97.823997)
			(xy 442.872369 -97.804479) (xy 442.809881 -97.777525) (xy 442.750945 -97.743498) (xy 442.696358 -97.70286)
			(xy 442.646858 -97.656159) (xy 442.603115 -97.604027) (xy 442.565719 -97.54717) (xy 442.535177 -97.486355)
			(xy 442.511901 -97.422406) (xy 442.496207 -97.356188) (xy 442.488307 -97.288595) (xy 440.040259 -97.288595)
			(xy 440.650113 -97.898449) (xy 456.089753 -97.898449) (xy 456.089753 -97.830395) (xy 456.097653 -97.762802)
			(xy 456.113347 -97.696584) (xy 456.136623 -97.632635) (xy 456.167165 -97.57182) (xy 456.204561 -97.514963)
			(xy 456.248304 -97.462831) (xy 456.297804 -97.41613) (xy 456.352391 -97.375492) (xy 456.411327 -97.341465)
			(xy 456.473815 -97.314511) (xy 456.539009 -97.294993) (xy 456.606028 -97.283175) (xy 456.673966 -97.279219)
			(xy 456.741904 -97.283175) (xy 456.808923 -97.294993) (xy 456.874117 -97.314511) (xy 456.936605 -97.341465)
			(xy 456.995541 -97.375492) (xy 457.050128 -97.41613) (xy 457.099628 -97.462831) (xy 457.143371 -97.514963)
			(xy 457.180767 -97.57182) (xy 457.211309 -97.632635) (xy 457.234585 -97.696584) (xy 457.250279 -97.762802)
			(xy 457.258179 -97.830395) (xy 457.258674 -97.864422) (xy 457.258238 -97.89439) (xy 457.486748 -97.89439)
			(xy 457.486748 -97.834454) (xy 457.494571 -97.775032) (xy 457.510084 -97.717139) (xy 457.53302 -97.661766)
			(xy 457.562987 -97.60986) (xy 457.599474 -97.56231) (xy 457.641854 -97.51993) (xy 457.689404 -97.483443)
			(xy 457.74131 -97.453476) (xy 457.796683 -97.43054) (xy 457.854576 -97.415027) (xy 457.913998 -97.407204)
			(xy 457.973934 -97.407204) (xy 458.033356 -97.415027) (xy 458.091249 -97.43054) (xy 458.146622 -97.453476)
			(xy 458.198528 -97.483443) (xy 458.246078 -97.51993) (xy 458.288458 -97.56231) (xy 458.324945 -97.60986)
			(xy 458.354912 -97.661766) (xy 458.377848 -97.717139) (xy 458.393361 -97.775032) (xy 458.401184 -97.834454)
			(xy 458.401674 -97.864422) (xy 458.401184 -97.89439) (xy 458.393361 -97.953812) (xy 458.377848 -98.011705)
			(xy 458.354912 -98.067078) (xy 458.324945 -98.118984) (xy 458.288458 -98.166534) (xy 458.246078 -98.208914)
			(xy 458.198528 -98.245401) (xy 458.146622 -98.275368) (xy 458.091249 -98.298304) (xy 458.033356 -98.313817)
			(xy 457.973934 -98.32164) (xy 457.913998 -98.32164) (xy 457.854576 -98.313817) (xy 457.796683 -98.298304)
			(xy 457.74131 -98.275368) (xy 457.689404 -98.245401) (xy 457.641854 -98.208914) (xy 457.599474 -98.166534)
			(xy 457.562987 -98.118984) (xy 457.53302 -98.067078) (xy 457.510084 -98.011705) (xy 457.494571 -97.953812)
			(xy 457.486748 -97.89439) (xy 457.258238 -97.89439) (xy 457.258179 -97.898449) (xy 457.250279 -97.966042)
			(xy 457.234585 -98.03226) (xy 457.211309 -98.096209) (xy 457.180767 -98.157024) (xy 457.143371 -98.213881)
			(xy 457.099628 -98.266013) (xy 457.050128 -98.312714) (xy 456.995541 -98.353352) (xy 456.936605 -98.387379)
			(xy 456.874117 -98.414333) (xy 456.808923 -98.433851) (xy 456.741904 -98.445669) (xy 456.673966 -98.449626)
			(xy 456.606028 -98.445669) (xy 456.539009 -98.433851) (xy 456.473815 -98.414333) (xy 456.411327 -98.387379)
			(xy 456.352391 -98.353352) (xy 456.297804 -98.312714) (xy 456.248304 -98.266013) (xy 456.204561 -98.213881)
			(xy 456.167165 -98.157024) (xy 456.136623 -98.096209) (xy 456.113347 -98.03226) (xy 456.097653 -97.966042)
			(xy 456.089753 -97.898449) (xy 440.650113 -97.898449) (xy 441.346586 -98.594922) (xy 461.989406 -98.594922)
			(xy 461.989406 -98.534986) (xy 461.997229 -98.475564) (xy 462.012742 -98.417671) (xy 462.035678 -98.362298)
			(xy 462.065645 -98.310392) (xy 462.102132 -98.262842) (xy 462.144512 -98.220462) (xy 462.192062 -98.183975)
			(xy 462.243968 -98.154008) (xy 462.299341 -98.131072) (xy 462.357234 -98.115559) (xy 462.416656 -98.107736)
			(xy 462.476592 -98.107736) (xy 462.536014 -98.115559) (xy 462.593907 -98.131072) (xy 462.64928 -98.154008)
			(xy 462.701186 -98.183975) (xy 462.748736 -98.220462) (xy 462.791116 -98.262842) (xy 462.827603 -98.310392)
			(xy 462.85757 -98.362298) (xy 462.880506 -98.417671) (xy 462.896019 -98.475564) (xy 462.903842 -98.534986)
			(xy 462.904332 -98.564954) (xy 462.903842 -98.594922) (xy 462.896019 -98.654344) (xy 462.880506 -98.712237)
			(xy 462.85757 -98.76761) (xy 462.827603 -98.819516) (xy 462.791116 -98.867066) (xy 462.748736 -98.909446)
			(xy 462.701186 -98.945933) (xy 462.64928 -98.9759) (xy 462.593907 -98.998836) (xy 462.536014 -99.014349)
			(xy 462.476592 -99.022172) (xy 462.416656 -99.022172) (xy 462.357234 -99.014349) (xy 462.299341 -98.998836)
			(xy 462.243968 -98.9759) (xy 462.192062 -98.945933) (xy 462.144512 -98.909446) (xy 462.102132 -98.867066)
			(xy 462.065645 -98.819516) (xy 462.035678 -98.76761) (xy 462.012742 -98.712237) (xy 461.997229 -98.654344)
			(xy 461.989406 -98.594922) (xy 441.346586 -98.594922) (xy 443.88684 -101.135176) (xy 461.859358 -101.135176)
			(xy 461.859358 -101.07524) (xy 461.867181 -101.015818) (xy 461.882694 -100.957925) (xy 461.90563 -100.902552)
			(xy 461.935597 -100.850646) (xy 461.972084 -100.803096) (xy 462.014464 -100.760716) (xy 462.062014 -100.724229)
			(xy 462.11392 -100.694262) (xy 462.169293 -100.671326) (xy 462.227186 -100.655813) (xy 462.286608 -100.64799)
			(xy 462.346544 -100.64799) (xy 462.405966 -100.655813) (xy 462.463859 -100.671326) (xy 462.519232 -100.694262)
			(xy 462.571138 -100.724229) (xy 462.618688 -100.760716) (xy 462.661068 -100.803096) (xy 462.697555 -100.850646)
			(xy 462.727522 -100.902552) (xy 462.750458 -100.957925) (xy 462.765971 -101.015818) (xy 462.773794 -101.07524)
			(xy 462.774284 -101.105208) (xy 462.773794 -101.135176) (xy 462.765971 -101.194598) (xy 462.750458 -101.252491)
			(xy 462.727522 -101.307864) (xy 462.697555 -101.35977) (xy 462.661068 -101.40732) (xy 462.618688 -101.4497)
			(xy 462.571138 -101.486187) (xy 462.519232 -101.516154) (xy 462.463859 -101.53909) (xy 462.405966 -101.554603)
			(xy 462.346544 -101.562426) (xy 462.286608 -101.562426) (xy 462.227186 -101.554603) (xy 462.169293 -101.53909)
			(xy 462.11392 -101.516154) (xy 462.062014 -101.486187) (xy 462.014464 -101.4497) (xy 461.972084 -101.40732)
			(xy 461.935597 -101.35977) (xy 461.90563 -101.307864) (xy 461.882694 -101.252491) (xy 461.867181 -101.194598)
			(xy 461.859358 -101.135176) (xy 443.88684 -101.135176) (xy 445.384419 -102.632755) (xy 454.712565 -102.632755)
			(xy 454.712565 -102.564701) (xy 454.720465 -102.497108) (xy 454.736159 -102.43089) (xy 454.759435 -102.366941)
			(xy 454.789977 -102.306126) (xy 454.827373 -102.249269) (xy 454.871116 -102.197137) (xy 454.920616 -102.150436)
			(xy 454.975203 -102.109798) (xy 455.034139 -102.075771) (xy 455.096627 -102.048817) (xy 455.161821 -102.029299)
			(xy 455.22884 -102.017481) (xy 455.296778 -102.013525) (xy 455.364716 -102.017481) (xy 455.431735 -102.029299)
			(xy 455.496929 -102.048817) (xy 455.559417 -102.075771) (xy 455.618353 -102.109798) (xy 455.67294 -102.150436)
			(xy 455.72244 -102.197137) (xy 455.766183 -102.249269) (xy 455.803579 -102.306126) (xy 455.834121 -102.366941)
			(xy 455.857397 -102.43089) (xy 455.873091 -102.497108) (xy 455.880991 -102.564701) (xy 455.881486 -102.598728)
			(xy 455.880991 -102.632755) (xy 455.873091 -102.700348) (xy 455.857397 -102.766566) (xy 455.834121 -102.830515)
			(xy 455.803579 -102.89133) (xy 455.766183 -102.948187) (xy 455.72244 -103.000319) (xy 455.67294 -103.04702)
			(xy 455.618353 -103.087658) (xy 455.559417 -103.121685) (xy 455.496929 -103.148639) (xy 455.431735 -103.168157)
			(xy 455.364716 -103.179975) (xy 455.296778 -103.183932) (xy 455.22884 -103.179975) (xy 455.161821 -103.168157)
			(xy 455.096627 -103.148639) (xy 455.034139 -103.121685) (xy 454.975203 -103.087658) (xy 454.920616 -103.04702)
			(xy 454.871116 -103.000319) (xy 454.827373 -102.948187) (xy 454.789977 -102.89133) (xy 454.759435 -102.830515)
			(xy 454.736159 -102.766566) (xy 454.720465 -102.700348) (xy 454.712565 -102.632755) (xy 445.384419 -102.632755)
			(xy 447.059351 -104.307687) (xy 454.6972 -104.307687) (xy 454.699906 -104.238836) (xy 454.710685 -104.170781)
			(xy 454.729389 -104.104464) (xy 454.755757 -104.040806) (xy 454.789425 -103.980688) (xy 454.829926 -103.924944)
			(xy 454.876698 -103.874346) (xy 454.929093 -103.829597) (xy 454.986384 -103.791316) (xy 455.047778 -103.760035)
			(xy 455.112422 -103.736186) (xy 455.179422 -103.720101) (xy 455.247848 -103.712002) (xy 455.2823 -103.711502)
			(xy 455.313852 -103.711925) (xy 455.376591 -103.718718) (xy 455.438233 -103.732224) (xy 455.498064 -103.752286)
			(xy 455.526902 -103.765096) (xy 455.540683 -103.770901) (xy 455.570295 -103.774989) (xy 455.599821 -103.770325)
			(xy 455.626731 -103.757308) (xy 455.648718 -103.737056) (xy 455.663896 -103.711303) (xy 455.670964 -103.682259)
			(xy 455.670666 -103.667306) (xy 455.670158 -103.646224) (xy 455.670629 -103.618968) (xy 455.678384 -103.565012)
			(xy 455.693739 -103.512708) (xy 455.716381 -103.463122) (xy 455.74585 -103.417263) (xy 455.781545 -103.376065)
			(xy 455.82274 -103.340367) (xy 455.868597 -103.310895) (xy 455.918181 -103.288249) (xy 455.970484 -103.27289)
			(xy 456.02444 -103.265131) (xy 456.078951 -103.265131) (xy 456.132907 -103.272888) (xy 456.18521 -103.288245)
			(xy 456.234795 -103.31089) (xy 456.280652 -103.340361) (xy 456.321848 -103.376059) (xy 456.357545 -103.417256)
			(xy 456.387015 -103.463114) (xy 456.409658 -103.512699) (xy 456.425014 -103.565003) (xy 456.43277 -103.618959)
			(xy 456.432768 -103.67347) (xy 456.425008 -103.727426) (xy 456.409648 -103.779728) (xy 456.387001 -103.829312)
			(xy 456.357527 -103.875168) (xy 456.321828 -103.916362) (xy 456.280629 -103.952056) (xy 456.234769 -103.981524)
			(xy 456.185182 -104.004165) (xy 456.132878 -104.019518) (xy 456.078922 -104.027271) (xy 456.051666 -104.027732)
			(xy 456.030404 -104.02745) (xy 455.988142 -104.022736) (xy 455.967338 -104.018334) (xy 455.952633 -104.015522)
			(xy 455.922783 -104.017622) (xy 455.89482 -104.028279) (xy 455.871145 -104.046581) (xy 455.853787 -104.070956)
			(xy 455.844235 -104.099315) (xy 455.843308 -104.129225) (xy 455.846688 -104.14381) (xy 455.856165 -104.181196)
			(xy 455.866357 -104.257647) (xy 455.866729 -104.279696) (xy 461.663778 -104.279696) (xy 461.663778 -104.21976)
			(xy 461.671601 -104.160338) (xy 461.687114 -104.102445) (xy 461.71005 -104.047072) (xy 461.740017 -103.995166)
			(xy 461.776504 -103.947616) (xy 461.818884 -103.905236) (xy 461.866434 -103.868749) (xy 461.91834 -103.838782)
			(xy 461.973713 -103.815846) (xy 462.031606 -103.800333) (xy 462.091028 -103.79251) (xy 462.150964 -103.79251)
			(xy 462.210386 -103.800333) (xy 462.268279 -103.815846) (xy 462.323652 -103.838782) (xy 462.375558 -103.868749)
			(xy 462.423108 -103.905236) (xy 462.465488 -103.947616) (xy 462.501975 -103.995166) (xy 462.531942 -104.047072)
			(xy 462.554878 -104.102445) (xy 462.570391 -104.160338) (xy 462.578214 -104.21976) (xy 462.578704 -104.249728)
			(xy 462.578214 -104.279696) (xy 462.570391 -104.339118) (xy 462.554878 -104.397011) (xy 462.531942 -104.452384)
			(xy 462.501975 -104.50429) (xy 462.465488 -104.55184) (xy 462.423108 -104.59422) (xy 462.375558 -104.630707)
			(xy 462.323652 -104.660674) (xy 462.268279 -104.68361) (xy 462.210386 -104.699123) (xy 462.150964 -104.706946)
			(xy 462.091028 -104.706946) (xy 462.031606 -104.699123) (xy 461.973713 -104.68361) (xy 461.91834 -104.660674)
			(xy 461.866434 -104.630707) (xy 461.818884 -104.59422) (xy 461.776504 -104.55184) (xy 461.740017 -104.50429)
			(xy 461.71005 -104.452384) (xy 461.687114 -104.397011) (xy 461.671601 -104.339118) (xy 461.663778 -104.279696)
			(xy 455.866729 -104.279696) (xy 455.867008 -104.29621) (xy 455.866497 -104.330662) (xy 455.858397 -104.399088)
			(xy 455.842311 -104.466087) (xy 455.818461 -104.530732) (xy 455.787178 -104.592125) (xy 455.748897 -104.649415)
			(xy 455.704147 -104.701809) (xy 455.653549 -104.748581) (xy 455.597804 -104.78908) (xy 455.537685 -104.822747)
			(xy 455.474026 -104.849115) (xy 455.407709 -104.867817) (xy 455.339654 -104.878595) (xy 455.270803 -104.8813)
			(xy 455.202112 -104.875893) (xy 455.134533 -104.86245) (xy 455.069002 -104.841156) (xy 455.006428 -104.812309)
			(xy 454.947678 -104.776306) (xy 454.893567 -104.733648) (xy 454.844846 -104.684925) (xy 454.802188 -104.630814)
			(xy 454.766187 -104.572063) (xy 454.73734 -104.509489) (xy 454.716048 -104.443957) (xy 454.702606 -104.376378)
			(xy 454.6972 -104.307687) (xy 447.059351 -104.307687) (xy 449.108951 -106.357287) (xy 454.668001 -106.357287)
			(xy 454.67341 -106.288594) (xy 454.686855 -106.221014) (xy 454.708151 -106.155483) (xy 454.737002 -106.092908)
			(xy 454.773007 -106.034159) (xy 454.815668 -105.980049) (xy 454.864394 -105.931329) (xy 454.918508 -105.888673)
			(xy 454.977261 -105.852673) (xy 455.039839 -105.823829) (xy 455.105372 -105.80254) (xy 455.172954 -105.789102)
			(xy 455.241647 -105.7837) (xy 455.310498 -105.786409) (xy 455.378554 -105.797193) (xy 455.444871 -105.815901)
			(xy 455.508529 -105.842274) (xy 455.568645 -105.875946) (xy 455.624388 -105.916452) (xy 455.674983 -105.963228)
			(xy 455.719729 -106.015627) (xy 455.758006 -106.072922) (xy 455.789283 -106.134319) (xy 455.813127 -106.198967)
			(xy 455.829207 -106.26597) (xy 455.8373 -106.334398) (xy 455.837798 -106.36885) (xy 455.837154 -106.409055)
			(xy 455.826191 -106.488715) (xy 455.815954 -106.5276) (xy 455.81269 -106.540746) (xy 455.812472 -106.567822)
			(xy 455.819383 -106.594002) (xy 455.832938 -106.617442) (xy 455.852181 -106.636491) (xy 455.875757 -106.649807)
			(xy 455.902006 -106.656452) (xy 455.929078 -106.655959) (xy 455.942192 -106.652568) (xy 455.968285 -106.645447)
			(xy 456.021829 -106.637798) (xy 456.048872 -106.637328) (xy 456.076125 -106.637748) (xy 456.130077 -106.645501)
			(xy 456.182377 -106.660853) (xy 456.231959 -106.683492) (xy 456.277815 -106.712957) (xy 456.319011 -106.748648)
			(xy 456.354708 -106.789838) (xy 456.38418 -106.835689) (xy 456.406826 -106.885268) (xy 456.422187 -106.937565)
			(xy 456.429948 -106.991516) (xy 456.429952 -107.046022) (xy 456.4222 -107.099975) (xy 456.406848 -107.152274)
			(xy 456.384209 -107.201857) (xy 456.354745 -107.247713) (xy 456.319054 -107.288909) (xy 456.277864 -107.324606)
			(xy 456.232013 -107.354078) (xy 456.182434 -107.376725) (xy 456.130137 -107.392086) (xy 456.076186 -107.399848)
			(xy 456.02168 -107.399853) (xy 455.967728 -107.3921) (xy 455.915428 -107.376749) (xy 455.865846 -107.35411)
			(xy 455.819989 -107.324646) (xy 455.778793 -107.288956) (xy 455.743095 -107.247766) (xy 455.713623 -107.201915)
			(xy 455.690976 -107.152337) (xy 455.675615 -107.10004) (xy 455.667852 -107.046089) (xy 455.667364 -107.018836)
			(xy 455.668634 -106.98734) (xy 455.66936 -106.973805) (xy 455.664406 -106.947163) (xy 455.652624 -106.922759)
			(xy 455.634843 -106.902311) (xy 455.612312 -106.887255) (xy 455.586615 -106.87865) (xy 455.559561 -106.877101)
			(xy 455.533051 -106.882718) (xy 455.520806 -106.888534) (xy 455.489662 -106.904014) (xy 455.424503 -106.928336)
			(xy 455.356919 -106.944755) (xy 455.287865 -106.953041) (xy 455.25309 -106.953558) (xy 455.218638 -106.952997)
			(xy 455.15021 -106.944897) (xy 455.08321 -106.92881) (xy 455.018564 -106.904959) (xy 454.95717 -106.873676)
			(xy 454.899879 -106.835393) (xy 454.847485 -106.790641) (xy 454.800714 -106.740041) (xy 454.760214 -106.684295)
			(xy 454.726548 -106.624175) (xy 454.700181 -106.560514) (xy 454.68148 -106.494195) (xy 454.670703 -106.426138)
			(xy 454.668001 -106.357287) (xy 449.108951 -106.357287) (xy 450.845419 -108.093755) (xy 454.639667 -108.093755)
			(xy 454.639667 -108.025701) (xy 454.647567 -107.958108) (xy 454.663261 -107.89189) (xy 454.686537 -107.827941)
			(xy 454.717079 -107.767126) (xy 454.754475 -107.710269) (xy 454.798218 -107.658137) (xy 454.847718 -107.611436)
			(xy 454.902305 -107.570798) (xy 454.961241 -107.536771) (xy 455.023729 -107.509817) (xy 455.088923 -107.490299)
			(xy 455.155942 -107.478481) (xy 455.22388 -107.474525) (xy 455.291818 -107.478481) (xy 455.358837 -107.490299)
			(xy 455.424031 -107.509817) (xy 455.486519 -107.536771) (xy 455.545455 -107.570798) (xy 455.600042 -107.611436)
			(xy 455.649542 -107.658137) (xy 455.69194 -107.708666) (xy 461.53681 -107.708666) (xy 461.53681 -107.648734)
			(xy 461.544633 -107.589316) (xy 461.560144 -107.531427) (xy 461.583078 -107.476057) (xy 461.613044 -107.424155)
			(xy 461.649528 -107.376608) (xy 461.691905 -107.33423) (xy 461.739452 -107.297746) (xy 461.791354 -107.26778)
			(xy 461.846723 -107.244845) (xy 461.904612 -107.229333) (xy 461.96403 -107.22151) (xy 461.993996 -107.22102)
			(xy 462.023235 -107.221421) (xy 462.081238 -107.228858) (xy 462.137821 -107.243622) (xy 462.192062 -107.265475)
			(xy 462.243077 -107.294059) (xy 462.290036 -107.32891) (xy 462.332172 -107.369458) (xy 462.368799 -107.415044)
			(xy 462.399321 -107.464925) (xy 462.42324 -107.518287) (xy 462.432146 -107.54614) (xy 462.437061 -107.560528)
			(xy 462.453986 -107.585767) (xy 462.477589 -107.604909) (xy 462.505778 -107.616258) (xy 462.536059 -107.61881)
			(xy 462.565751 -107.612339) (xy 462.592224 -107.597418) (xy 462.603088 -107.58678) (xy 462.627166 -107.562201)
			(xy 462.680822 -107.51913) (xy 462.739798 -107.483688) (xy 462.803014 -107.456524) (xy 462.869316 -107.438134)
			(xy 462.937493 -107.428854) (xy 462.971896 -107.428284) (xy 463.003858 -107.428781) (xy 463.067278 -107.436792)
			(xy 463.129194 -107.452689) (xy 463.188629 -107.476221) (xy 463.244646 -107.507016) (xy 463.296362 -107.544589)
			(xy 463.342961 -107.588348) (xy 463.383708 -107.637602) (xy 463.41796 -107.691575) (xy 463.445178 -107.749415)
			(xy 463.464931 -107.81021) (xy 463.47691 -107.873002) (xy 463.480924 -107.9368) (xy 463.47691 -108.000598)
			(xy 463.464931 -108.06339) (xy 463.445178 -108.124185) (xy 463.41796 -108.182025) (xy 463.383708 -108.235998)
			(xy 463.342961 -108.285252) (xy 463.296362 -108.329011) (xy 463.244646 -108.366584) (xy 463.188629 -108.397379)
			(xy 463.129194 -108.420911) (xy 463.067278 -108.436808) (xy 463.003858 -108.444819) (xy 462.971896 -108.4453)
			(xy 462.941199 -108.444912) (xy 462.880252 -108.437508) (xy 462.820639 -108.422821) (xy 462.763229 -108.401064)
			(xy 462.708855 -108.372554) (xy 462.658309 -108.337705) (xy 462.612326 -108.297024) (xy 462.571576 -108.251104)
			(xy 462.536649 -108.200611) (xy 462.508056 -108.146281) (xy 462.486211 -108.088904) (xy 462.478374 -108.05922)
			(xy 462.47416 -108.044623) (xy 462.4585 -108.018607) (xy 462.435883 -107.998345) (xy 462.408309 -107.985628)
			(xy 462.378214 -107.981581) (xy 462.34826 -107.986561) (xy 462.321094 -108.000127) (xy 462.309718 -108.010198)
			(xy 462.288376 -108.029898) (xy 462.241579 -108.064301) (xy 462.190808 -108.09251) (xy 462.136877 -108.114073)
			(xy 462.080652 -108.128643) (xy 462.023037 -108.135987) (xy 461.993996 -108.136436) (xy 461.96403 -108.13589)
			(xy 461.904612 -108.128067) (xy 461.846723 -108.112555) (xy 461.791354 -108.08962) (xy 461.739452 -108.059654)
			(xy 461.691905 -108.02317) (xy 461.649528 -107.980792) (xy 461.613044 -107.933245) (xy 461.583078 -107.881343)
			(xy 461.560144 -107.825973) (xy 461.544633 -107.768084) (xy 461.53681 -107.708666) (xy 455.69194 -107.708666)
			(xy 455.693285 -107.710269) (xy 455.730681 -107.767126) (xy 455.761223 -107.827941) (xy 455.784499 -107.89189)
			(xy 455.800193 -107.958108) (xy 455.808093 -108.025701) (xy 455.808588 -108.059728) (xy 455.808093 -108.093755)
			(xy 455.800193 -108.161348) (xy 455.784499 -108.227566) (xy 455.761223 -108.291515) (xy 455.730681 -108.35233)
			(xy 455.693285 -108.409187) (xy 455.649542 -108.461319) (xy 455.600042 -108.50802) (xy 455.545455 -108.548658)
			(xy 455.486519 -108.582685) (xy 455.424031 -108.609639) (xy 455.358837 -108.629157) (xy 455.291818 -108.640975)
			(xy 455.22388 -108.644932) (xy 455.155942 -108.640975) (xy 455.088923 -108.629157) (xy 455.023729 -108.609639)
			(xy 454.961241 -108.582685) (xy 454.902305 -108.548658) (xy 454.847718 -108.50802) (xy 454.798218 -108.461319)
			(xy 454.754475 -108.409187) (xy 454.717079 -108.35233) (xy 454.686537 -108.291515) (xy 454.663261 -108.227566)
			(xy 454.647567 -108.161348) (xy 454.639667 -108.093755) (xy 450.845419 -108.093755) (xy 451.77202 -109.020356)
			(xy 451.772528 -109.020864) (xy 451.779909 -109.027449) (xy 451.798207 -109.034907) (xy 451.808088 -109.035342)
			(xy 453.9234 -109.035342) (xy 453.933469 -109.035766) (xy 453.95207 -109.043485) (xy 453.959468 -109.050328)
			(xy 455.744317 -110.835177) (xy 462.303863 -110.835177) (xy 462.303863 -110.767123) (xy 462.311763 -110.69953)
			(xy 462.327457 -110.633312) (xy 462.350733 -110.569363) (xy 462.381275 -110.508548) (xy 462.418671 -110.451691)
			(xy 462.462414 -110.399559) (xy 462.511914 -110.352858) (xy 462.566501 -110.31222) (xy 462.625437 -110.278193)
			(xy 462.687925 -110.251239) (xy 462.753119 -110.231721) (xy 462.820138 -110.219903) (xy 462.888076 -110.215947)
			(xy 462.956014 -110.219903) (xy 463.023033 -110.231721) (xy 463.088227 -110.251239) (xy 463.150715 -110.278193)
			(xy 463.209651 -110.31222) (xy 463.264238 -110.352858) (xy 463.313738 -110.399559) (xy 463.357481 -110.451691)
			(xy 463.394877 -110.508548) (xy 463.425419 -110.569363) (xy 463.448695 -110.633312) (xy 463.464389 -110.69953)
			(xy 463.472289 -110.767123) (xy 463.472784 -110.80115) (xy 463.472289 -110.835177) (xy 463.464389 -110.90277)
			(xy 463.448695 -110.968988) (xy 463.425419 -111.032937) (xy 463.394877 -111.093752) (xy 463.357481 -111.150609)
			(xy 463.313738 -111.202741) (xy 463.264238 -111.249442) (xy 463.209651 -111.29008) (xy 463.150715 -111.324107)
			(xy 463.088227 -111.351061) (xy 463.023033 -111.370579) (xy 462.956014 -111.382397) (xy 462.888076 -111.386354)
			(xy 462.820138 -111.382397) (xy 462.753119 -111.370579) (xy 462.687925 -111.351061) (xy 462.625437 -111.324107)
			(xy 462.566501 -111.29008) (xy 462.511914 -111.249442) (xy 462.462414 -111.202741) (xy 462.418671 -111.150609)
			(xy 462.381275 -111.093752) (xy 462.350733 -111.032937) (xy 462.327457 -110.968988) (xy 462.311763 -110.90277)
			(xy 462.303863 -110.835177) (xy 455.744317 -110.835177) (xy 460.324454 -115.415314) (xy 460.331303 -115.422711)
			(xy 460.33904 -115.44131) (xy 460.33944 -115.451382) (xy 460.33944 -145.031968) (xy 460.339003 -145.042031)
			(xy 460.331264 -145.060612) (xy 460.324454 -145.068036) (xy 451.480428 -153.912062) (xy 451.473588 -153.919463)
			(xy 451.465872 -153.938061) (xy 451.465442 -153.94813) (xy 451.465442 -166.205916) (xy 451.465869 -166.215984)
			(xy 451.473593 -166.23458) (xy 451.480428 -166.241984) (xy 460.883254 -175.64481) (xy 460.890603 -175.651611)
			(xy 460.909065 -175.659322) (xy 460.919068 -175.659796) (xy 461.200246 -175.659796) (xy 461.21021 -175.660279)
			(xy 461.22864 -175.667861) (xy 461.23606 -175.674528) (xy 461.913478 -176.351946) (xy 461.920284 -176.359293)
			(xy 461.928003 -176.377755) (xy 461.928464 -176.38776) (xy 461.928464 -182.240174) (xy 461.92793 -182.250163)
			(xy 461.920219 -182.268598) (xy 461.913478 -182.275988) (xy 461.85963 -182.329836) (xy 461.852786 -182.337235)
			(xy 461.84506 -182.355833) (xy 461.844644 -182.365904) (xy 461.844644 -330.693522) (xy 461.844215 -330.703589)
			(xy 461.836489 -330.722183) (xy 461.829658 -330.72959) (xy 449.271898 -343.28735) (xy 449.26506 -343.294751)
			(xy 449.257344 -343.313349) (xy 449.256912 -343.323418) (xy 449.256912 -364.286038) (xy 449.256482 -364.296105)
			(xy 449.24876 -364.314701) (xy 449.241926 -364.322106) (xy 444.962026 -368.602006) (xy 444.954623 -368.60884)
			(xy 444.936025 -368.616547) (xy 444.925958 -368.616992) (xy 440.944254 -368.616992) (xy 440.934187 -368.617423)
			(xy 440.915594 -368.625148) (xy 440.908186 -368.631978) (xy 438.647883 -370.892281) (xy 447.615812 -370.892281)
			(xy 447.615812 -370.828359) (xy 447.623823 -370.764941) (xy 447.63972 -370.703027) (xy 447.663252 -370.643594)
			(xy 447.694046 -370.587579) (xy 447.731619 -370.535864) (xy 447.775376 -370.489267) (xy 447.824629 -370.448522)
			(xy 447.8786 -370.414271) (xy 447.936439 -370.387054) (xy 447.997232 -370.367301) (xy 448.060022 -370.355323)
			(xy 448.123818 -370.35131) (xy 448.187614 -370.355323) (xy 448.250404 -370.367301) (xy 448.311197 -370.387054)
			(xy 448.369036 -370.414271) (xy 448.423007 -370.448522) (xy 448.47226 -370.489267) (xy 448.516017 -370.535864)
			(xy 448.55359 -370.587579) (xy 448.584384 -370.643594) (xy 448.607916 -370.703027) (xy 448.623813 -370.764941)
			(xy 448.631824 -370.828359) (xy 448.632326 -370.86032) (xy 448.631824 -370.892281) (xy 448.623813 -370.955699)
			(xy 448.607916 -371.017613) (xy 448.584384 -371.077046) (xy 448.55359 -371.133061) (xy 448.516017 -371.184776)
			(xy 448.47226 -371.231373) (xy 448.423007 -371.272118) (xy 448.369036 -371.306369) (xy 448.311197 -371.333586)
			(xy 448.250404 -371.353339) (xy 448.187614 -371.365317) (xy 448.123818 -371.369331) (xy 448.060022 -371.365317)
			(xy 447.997232 -371.353339) (xy 447.936439 -371.333586) (xy 447.8786 -371.306369) (xy 447.824629 -371.272118)
			(xy 447.775376 -371.231373) (xy 447.731619 -371.184776) (xy 447.694046 -371.133061) (xy 447.663252 -371.077046)
			(xy 447.63972 -371.017613) (xy 447.623823 -370.955699) (xy 447.615812 -370.892281) (xy 438.647883 -370.892281)
			(xy 437.61152 -371.928644) (xy 437.604678 -371.936044) (xy 437.596957 -371.954642) (xy 437.596534 -371.964712)
			(xy 437.596534 -372.217442) (xy 437.59708 -372.227425) (xy 437.604808 -372.245843) (xy 437.61152 -372.253256)
			(xy 437.870092 -372.511828) (xy 437.892096 -372.534414) (xy 437.89674 -372.540233) (xy 450.515222 -372.540233)
			(xy 450.515222 -372.476311) (xy 450.523233 -372.412893) (xy 450.53913 -372.350979) (xy 450.562662 -372.291546)
			(xy 450.593456 -372.235531) (xy 450.631029 -372.183816) (xy 450.674786 -372.137219) (xy 450.724039 -372.096474)
			(xy 450.77801 -372.062223) (xy 450.835849 -372.035006) (xy 450.896642 -372.015253) (xy 450.959432 -372.003275)
			(xy 451.023228 -371.999262) (xy 451.087024 -372.003275) (xy 451.149814 -372.015253) (xy 451.210607 -372.035006)
			(xy 451.268446 -372.062223) (xy 451.322417 -372.096474) (xy 451.37167 -372.137219) (xy 451.415427 -372.183816)
			(xy 451.453 -372.235531) (xy 451.483794 -372.291546) (xy 451.507326 -372.350979) (xy 451.523223 -372.412893)
			(xy 451.531234 -372.476311) (xy 451.531736 -372.508272) (xy 451.531234 -372.540233) (xy 451.523223 -372.603651)
			(xy 451.507326 -372.665565) (xy 451.483794 -372.724998) (xy 451.453 -372.781013) (xy 451.415427 -372.832728)
			(xy 451.37167 -372.879325) (xy 451.322417 -372.92007) (xy 451.268446 -372.954321) (xy 451.210607 -372.981538)
			(xy 451.149814 -373.001291) (xy 451.087024 -373.013269) (xy 451.023228 -373.017283) (xy 450.959432 -373.013269)
			(xy 450.896642 -373.001291) (xy 450.835849 -372.981538) (xy 450.77801 -372.954321) (xy 450.724039 -372.92007)
			(xy 450.674786 -372.879325) (xy 450.631029 -372.832728) (xy 450.593456 -372.781013) (xy 450.562662 -372.724998)
			(xy 450.53913 -372.665565) (xy 450.523233 -372.603651) (xy 450.515222 -372.540233) (xy 437.89674 -372.540233)
			(xy 437.931432 -372.583701) (xy 437.964998 -372.637085) (xy 437.99237 -372.693894) (xy 438.013205 -372.753412)
			(xy 438.027239 -372.814891) (xy 438.034295 -372.877554) (xy 438.034684 -372.909084) (xy 438.034209 -372.941573)
			(xy 438.026688 -373.006114) (xy 438.011766 -373.069355) (xy 437.989644 -373.130451) (xy 437.960617 -373.188585)
			(xy 437.925073 -373.24298) (xy 437.904636 -373.26824) (xy 437.899256 -373.275317) (xy 437.893256 -373.292036)
			(xy 437.893333 -373.309798) (xy 437.899476 -373.326465) (xy 437.90489 -373.333518) (xy 437.925773 -373.358933)
			(xy 437.962095 -373.413777) (xy 437.991762 -373.472489) (xy 438.014367 -373.534265) (xy 438.029599 -373.598258)
			(xy 438.037251 -373.663593) (xy 438.037732 -373.696484) (xy 438.037302 -373.728004) (xy 438.03027 -373.790649)
			(xy 438.01627 -373.852114) (xy 437.995477 -373.911625) (xy 437.968153 -373.968434) (xy 437.934642 -374.021828)
			(xy 437.895365 -374.071136) (xy 437.873394 -374.09374) (xy 436.712614 -375.25452) (xy 436.690026 -375.276521)
			(xy 436.640738 -375.31585) (xy 436.587352 -375.349408) (xy 436.530543 -375.376773) (xy 436.471025 -375.397601)
			(xy 436.409548 -375.411627) (xy 436.346887 -375.418677) (xy 436.315358 -375.419112) (xy 428.850298 -375.419112)
			(xy 428.818769 -375.418686) (xy 428.756109 -375.411625) (xy 428.694633 -375.397593) (xy 428.635115 -375.376765)
			(xy 428.578303 -375.349404) (xy 428.524912 -375.315854) (xy 428.475614 -375.276536) (xy 428.453042 -375.25452)
			(xy 426.142404 -372.943628) (xy 426.134981 -372.936847) (xy 426.116384 -372.929247) (xy 426.106336 -372.928896)
			(xy 299.767498 -372.928896) (xy 299.75747 -372.929343) (xy 299.738907 -372.936929) (xy 299.73143 -372.943628)
			(xy 295.94048 -376.734832) (xy 295.917893 -376.756835) (xy 295.868606 -376.796169) (xy 295.815221 -376.829733)
			(xy 295.758412 -376.857104) (xy 295.698894 -376.877938) (xy 295.637416 -376.891972) (xy 295.574754 -376.899029)
			(xy 295.543224 -376.899424) (xy 290.971224 -376.899424) (xy 290.937399 -376.898902) (xy 290.870241 -376.890744)
			(xy 290.80455 -376.874579) (xy 290.741276 -376.850641) (xy 290.681335 -376.819276) (xy 290.625595 -376.780939)
			(xy 290.599876 -376.758962) (xy 290.592665 -376.753149) (xy 290.575347 -376.746623) (xy 290.566094 -376.746262)
			(xy 288.688526 -376.746262) (xy 288.677772 -376.746731) (xy 288.65815 -376.755532) (xy 288.65068 -376.76328)
			(xy 288.592768 -376.82805) (xy 288.586418 -376.84837) (xy 288.587688 -376.859292) (xy 288.58924 -376.87372)
			(xy 288.59089 -376.902694) (xy 288.59099 -376.917204) (xy 288.590544 -376.947936) (xy 288.583135 -377.00895)
			(xy 288.568425 -377.068627) (xy 288.546629 -377.126096) (xy 288.518065 -377.180519) (xy 288.483149 -377.231101)
			(xy 288.44239 -377.277106) (xy 288.396384 -377.317863) (xy 288.3458 -377.352776) (xy 288.291376 -377.381338)
			(xy 288.233906 -377.403132) (xy 288.174229 -377.417839) (xy 288.113214 -377.425245) (xy 288.082482 -377.425712)
			(xy 288.052671 -377.425272) (xy 287.993462 -377.418272) (xy 287.964372 -377.411742) (xy 287.955116 -377.409936)
			(xy 287.936452 -377.41254) (xy 287.92805 -377.416822) (xy 287.901126 -377.431808) (xy 287.893018 -377.436682)
			(xy 287.886415 -377.444549) (xy 299.675308 -377.444549) (xy 299.675308 -377.390051) (xy 299.683064 -377.336108)
			(xy 299.698418 -377.283818) (xy 299.721057 -377.234245) (xy 299.75052 -377.188398) (xy 299.786209 -377.147211)
			(xy 299.827395 -377.111523) (xy 299.873241 -377.082059) (xy 299.922814 -377.059419) (xy 299.975104 -377.044065)
			(xy 300.029047 -377.036308) (xy 300.056296 -377.035822) (xy 300.084998 -377.036838) (xy 300.098206 -377.037854)
			(xy 300.121828 -377.026932) (xy 300.18863 -376.936254) (xy 300.191932 -376.910346) (xy 300.186852 -376.8979)
			(xy 300.178317 -376.875389) (xy 300.166313 -376.828766) (xy 300.16028 -376.781002) (xy 300.159928 -376.75693)
			(xy 300.160414 -376.729679) (xy 300.16817 -376.675731) (xy 300.183525 -376.623436) (xy 300.206167 -376.573859)
			(xy 300.235633 -376.528009) (xy 300.271324 -376.486818) (xy 300.312515 -376.451127) (xy 300.358365 -376.421661)
			(xy 300.407942 -376.399019) (xy 300.460237 -376.383664) (xy 300.514185 -376.375908) (xy 300.568687 -376.375908)
			(xy 300.622635 -376.383664) (xy 300.67493 -376.399019) (xy 300.724507 -376.421661) (xy 300.770357 -376.451127)
			(xy 300.811548 -376.486818) (xy 300.847239 -376.528009) (xy 300.876705 -376.573859) (xy 300.899347 -376.623436)
			(xy 300.914702 -376.675731) (xy 300.922458 -376.729679) (xy 300.922944 -376.75693) (xy 300.922253 -376.789462)
			(xy 300.911143 -376.853571) (xy 300.900846 -376.884438) (xy 300.897798 -376.893074) (xy 300.898052 -376.910854)
			(xy 300.927516 -376.98934) (xy 300.938946 -377.002548) (xy 300.947074 -377.00712) (xy 300.979332 -377.026932)
			(xy 300.985733 -377.030973) (xy 301.000213 -377.035365) (xy 301.00778 -377.035568) (xy 301.289212 -377.035568)
			(xy 301.296765 -377.03527) (xy 301.311223 -377.030892) (xy 301.31766 -377.026932) (xy 301.349918 -377.00712)
			(xy 301.358046 -377.002548) (xy 301.369476 -376.98934) (xy 301.39894 -376.910854) (xy 301.399194 -376.893074)
			(xy 301.396146 -376.884438) (xy 301.385853 -376.85357) (xy 301.374748 -376.789461) (xy 301.374048 -376.75693)
			(xy 301.374534 -376.729679) (xy 301.38229 -376.675731) (xy 301.397645 -376.623436) (xy 301.420287 -376.573859)
			(xy 301.449753 -376.528009) (xy 301.485444 -376.486818) (xy 301.526635 -376.451127) (xy 301.572485 -376.421661)
			(xy 301.622062 -376.399019) (xy 301.674357 -376.383664) (xy 301.728305 -376.375908) (xy 301.782807 -376.375908)
			(xy 301.836755 -376.383664) (xy 301.88905 -376.399019) (xy 301.938627 -376.421661) (xy 301.984477 -376.451127)
			(xy 302.025668 -376.486818) (xy 302.061359 -376.528009) (xy 302.090825 -376.573859) (xy 302.113467 -376.623436)
			(xy 302.128822 -376.675731) (xy 302.136578 -376.729679) (xy 302.137064 -376.75693) (xy 302.136702 -376.781001)
			(xy 302.130665 -376.828764) (xy 302.118676 -376.87539) (xy 302.11014 -376.8979) (xy 302.10506 -376.910346)
			(xy 302.108362 -376.936254) (xy 302.175164 -377.026932) (xy 302.198786 -377.037854) (xy 302.211994 -377.036838)
			(xy 302.240696 -377.035822) (xy 302.267951 -377.036225) (xy 302.321907 -377.043982) (xy 302.374209 -377.059339)
			(xy 302.423794 -377.081983) (xy 302.469651 -377.111453) (xy 302.510848 -377.147149) (xy 302.546545 -377.188346)
			(xy 302.576015 -377.234203) (xy 302.59866 -377.283787) (xy 302.614017 -377.336089) (xy 302.621775 -377.390045)
			(xy 302.621775 -377.444555) (xy 302.614017 -377.498511) (xy 302.59866 -377.550813) (xy 302.576015 -377.600397)
			(xy 302.546545 -377.646254) (xy 302.510848 -377.687451) (xy 302.469651 -377.723147) (xy 302.423794 -377.752617)
			(xy 302.374209 -377.775261) (xy 302.321907 -377.790618) (xy 302.267951 -377.798375) (xy 302.240696 -377.798838)
			(xy 302.211994 -377.797822) (xy 302.198786 -377.796806) (xy 302.175164 -377.807728) (xy 302.108362 -377.898406)
			(xy 302.10506 -377.924314) (xy 302.11014 -377.93676) (xy 302.118692 -377.959265) (xy 302.13069 -378.005891)
			(xy 302.136716 -378.053657) (xy 302.137064 -378.07773) (xy 302.136578 -378.104981) (xy 302.128822 -378.158929)
			(xy 302.113467 -378.211224) (xy 302.090825 -378.260801) (xy 302.061359 -378.306651) (xy 302.025668 -378.347842)
			(xy 301.984477 -378.383533) (xy 301.938627 -378.412999) (xy 301.88905 -378.435641) (xy 301.836755 -378.450996)
			(xy 301.782807 -378.458752) (xy 301.728305 -378.458752) (xy 301.674357 -378.450996) (xy 301.622062 -378.435641)
			(xy 301.572485 -378.412999) (xy 301.526635 -378.383533) (xy 301.485444 -378.347842) (xy 301.449753 -378.306651)
			(xy 301.420287 -378.260801) (xy 301.397645 -378.211224) (xy 301.38229 -378.158929) (xy 301.374534 -378.104981)
			(xy 301.374048 -378.07773) (xy 301.37473 -378.045198) (xy 301.385846 -377.981089) (xy 301.396146 -377.950222)
			(xy 301.399194 -377.941586) (xy 301.39894 -377.923806) (xy 301.369476 -377.84532) (xy 301.358046 -377.832112)
			(xy 301.349918 -377.82754) (xy 301.31766 -377.807728) (xy 301.311258 -377.803689) (xy 301.296779 -377.799295)
			(xy 301.289212 -377.799092) (xy 301.00778 -377.799092) (xy 301.000226 -377.799377) (xy 300.985768 -377.803763)
			(xy 300.979332 -377.807728) (xy 300.947074 -377.82754) (xy 300.938946 -377.832112) (xy 300.927516 -377.84532)
			(xy 300.898052 -377.923806) (xy 300.897798 -377.941586) (xy 300.900846 -377.950222) (xy 300.911132 -377.981092)
			(xy 300.922241 -378.045199) (xy 300.922944 -378.07773) (xy 300.922458 -378.104981) (xy 300.914702 -378.158929)
			(xy 300.899347 -378.211224) (xy 300.876705 -378.260801) (xy 300.847239 -378.306651) (xy 300.811548 -378.347842)
			(xy 300.770357 -378.383533) (xy 300.724507 -378.412999) (xy 300.67493 -378.435641) (xy 300.622635 -378.450996)
			(xy 300.568687 -378.458752) (xy 300.514185 -378.458752) (xy 300.460237 -378.450996) (xy 300.407942 -378.435641)
			(xy 300.358365 -378.412999) (xy 300.312515 -378.383533) (xy 300.271324 -378.347842) (xy 300.235633 -378.306651)
			(xy 300.206167 -378.260801) (xy 300.183525 -378.211224) (xy 300.16817 -378.158929) (xy 300.160414 -378.104981)
			(xy 300.159928 -378.07773) (xy 300.160278 -378.053658) (xy 300.16632 -378.005895) (xy 300.178314 -377.95927)
			(xy 300.186852 -377.93676) (xy 300.191932 -377.924314) (xy 300.18863 -377.898406) (xy 300.121828 -377.807728)
			(xy 300.098206 -377.796806) (xy 300.084998 -377.797822) (xy 300.056296 -377.798838) (xy 300.029047 -377.798292)
			(xy 299.975104 -377.790535) (xy 299.922814 -377.775181) (xy 299.873241 -377.752541) (xy 299.827395 -377.723077)
			(xy 299.786209 -377.687389) (xy 299.75052 -377.646202) (xy 299.721057 -377.600355) (xy 299.698418 -377.550782)
			(xy 299.683064 -377.498492) (xy 299.675308 -377.444549) (xy 287.886415 -377.444549) (xy 287.880866 -377.451161)
			(xy 287.877504 -377.460002) (xy 287.867124 -377.489461) (xy 287.840167 -377.545806) (xy 287.806516 -377.598428)
			(xy 287.766678 -377.646536) (xy 287.721251 -377.689407) (xy 287.670919 -377.726395) (xy 287.616438 -377.756945)
			(xy 287.558628 -377.780598) (xy 287.498358 -377.796998) (xy 287.436534 -377.805898) (xy 287.405318 -377.806966)
			(xy 287.395412 -377.806966) (xy 287.377632 -377.814586) (xy 286.240982 -378.951236) (xy 289.295332 -378.951236)
			(xy 289.295786 -378.920539) (xy 289.303192 -378.859593) (xy 289.317888 -378.799984) (xy 289.339661 -378.74258)
			(xy 289.368192 -378.688219) (xy 289.385248 -378.662692) (xy 289.390685 -378.653922) (xy 289.39482 -378.63373)
			(xy 289.390709 -378.613533) (xy 289.385248 -378.60478) (xy 289.368212 -378.579243) (xy 289.339702 -378.524875)
			(xy 289.317938 -378.467473) (xy 289.303237 -378.407869) (xy 289.295813 -378.34693) (xy 289.295332 -378.316236)
			(xy 289.295772 -378.285503) (xy 289.303177 -378.224485) (xy 289.317884 -378.164805) (xy 289.339678 -378.107333)
			(xy 289.368241 -378.052907) (xy 289.403157 -378.002321) (xy 289.443916 -377.956313) (xy 289.489924 -377.915554)
			(xy 289.54051 -377.880639) (xy 289.594936 -377.852076) (xy 289.652409 -377.830282) (xy 289.712089 -377.815576)
			(xy 289.773107 -377.808171) (xy 289.80384 -377.807728) (xy 289.834537 -377.808195) (xy 289.895482 -377.815598)
			(xy 289.955091 -377.830292) (xy 290.012495 -377.852061) (xy 290.066857 -377.880589) (xy 290.092384 -377.897644)
			(xy 290.101136 -377.903115) (xy 290.12134 -377.907243) (xy 290.141544 -377.903115) (xy 290.150296 -377.897644)
			(xy 290.17584 -377.880618) (xy 290.230206 -377.852106) (xy 290.287606 -377.830341) (xy 290.347208 -377.815637)
			(xy 290.408146 -377.80821) (xy 290.43884 -377.807728) (xy 290.469537 -377.808195) (xy 290.530482 -377.815598)
			(xy 290.590091 -377.830292) (xy 290.647495 -377.852061) (xy 290.701857 -377.880589) (xy 290.727384 -377.897644)
			(xy 290.736136 -377.903115) (xy 290.75634 -377.907243) (xy 290.776544 -377.903115) (xy 290.785296 -377.897644)
			(xy 290.81084 -377.880618) (xy 290.865206 -377.852106) (xy 290.922606 -377.830341) (xy 290.982208 -377.815637)
			(xy 291.043146 -377.80821) (xy 291.07384 -377.807728) (xy 291.104537 -377.808195) (xy 291.165482 -377.815598)
			(xy 291.225091 -377.830292) (xy 291.282495 -377.852061) (xy 291.336857 -377.880589) (xy 291.362384 -377.897644)
			(xy 291.371136 -377.903115) (xy 291.39134 -377.907243) (xy 291.411544 -377.903115) (xy 291.420296 -377.897644)
			(xy 291.44584 -377.880618) (xy 291.500206 -377.852106) (xy 291.557606 -377.830341) (xy 291.617208 -377.815637)
			(xy 291.678146 -377.80821) (xy 291.70884 -377.807728) (xy 291.739537 -377.808195) (xy 291.800482 -377.815598)
			(xy 291.860091 -377.830292) (xy 291.917495 -377.852061) (xy 291.971857 -377.880589) (xy 291.997384 -377.897644)
			(xy 292.006136 -377.903115) (xy 292.02634 -377.907243) (xy 292.046544 -377.903115) (xy 292.055296 -377.897644)
			(xy 292.08084 -377.880618) (xy 292.135206 -377.852106) (xy 292.192606 -377.830341) (xy 292.252208 -377.815637)
			(xy 292.313146 -377.80821) (xy 292.34384 -377.807728) (xy 292.374537 -377.808195) (xy 292.435482 -377.815598)
			(xy 292.495091 -377.830292) (xy 292.552495 -377.852061) (xy 292.606857 -377.880589) (xy 292.632384 -377.897644)
			(xy 292.641136 -377.903115) (xy 292.66134 -377.907243) (xy 292.681544 -377.903115) (xy 292.690296 -377.897644)
			(xy 292.71584 -377.880618) (xy 292.770206 -377.852106) (xy 292.827606 -377.830341) (xy 292.887208 -377.815637)
			(xy 292.948146 -377.80821) (xy 292.97884 -377.807728) (xy 293.009537 -377.808195) (xy 293.070482 -377.815598)
			(xy 293.130091 -377.830292) (xy 293.187495 -377.852061) (xy 293.241857 -377.880589) (xy 293.267384 -377.897644)
			(xy 293.276136 -377.903115) (xy 293.29634 -377.907243) (xy 293.316544 -377.903115) (xy 293.325296 -377.897644)
			(xy 293.35084 -377.880618) (xy 293.405206 -377.852106) (xy 293.462606 -377.830341) (xy 293.522208 -377.815637)
			(xy 293.583146 -377.80821) (xy 293.61384 -377.807728) (xy 293.644537 -377.808195) (xy 293.705482 -377.815598)
			(xy 293.765091 -377.830292) (xy 293.822495 -377.852061) (xy 293.876857 -377.880589) (xy 293.902384 -377.897644)
			(xy 293.911136 -377.903115) (xy 293.93134 -377.907243) (xy 293.951544 -377.903115) (xy 293.960296 -377.897644)
			(xy 293.98584 -377.880618) (xy 294.040206 -377.852106) (xy 294.097606 -377.830341) (xy 294.157208 -377.815637)
			(xy 294.218146 -377.80821) (xy 294.24884 -377.807728) (xy 294.279573 -377.808118) (xy 294.340591 -377.815532)
			(xy 294.40027 -377.830246) (xy 294.457741 -377.852047) (xy 294.512165 -377.880616) (xy 294.562748 -377.915537)
			(xy 294.608753 -377.9563) (xy 294.64951 -378.002312) (xy 294.684423 -378.0529) (xy 294.712984 -378.107328)
			(xy 294.734776 -378.164802) (xy 294.749482 -378.224484) (xy 294.756887 -378.285503) (xy 294.757348 -378.316236)
			(xy 294.756883 -378.346933) (xy 294.74948 -378.407878) (xy 294.734787 -378.467487) (xy 294.713016 -378.524891)
			(xy 294.684487 -378.579253) (xy 294.667432 -378.60478) (xy 294.661926 -378.613514) (xy 294.657805 -378.63373)
			(xy 294.66195 -378.653941) (xy 294.667432 -378.662692) (xy 294.684453 -378.688239) (xy 294.712967 -378.742604)
			(xy 294.734733 -378.800003) (xy 294.749438 -378.859605) (xy 294.756865 -378.920542) (xy 294.757348 -378.951236)
			(xy 294.756878 -378.981966) (xy 294.749466 -379.042978) (xy 294.734755 -379.102652) (xy 294.712959 -379.160118)
			(xy 294.684395 -379.214538) (xy 294.649481 -379.265118) (xy 294.608725 -379.311122) (xy 294.562722 -379.351879)
			(xy 294.512141 -379.386793) (xy 294.457722 -379.415357) (xy 294.400256 -379.437154) (xy 294.340582 -379.451866)
			(xy 294.27957 -379.459278) (xy 294.24884 -379.459744) (xy 294.218144 -379.459274) (xy 294.157199 -379.45187)
			(xy 294.09759 -379.437177) (xy 294.040186 -379.415408) (xy 293.985824 -379.386882) (xy 293.960296 -379.369828)
			(xy 293.951544 -379.364357) (xy 293.93134 -379.360229) (xy 293.911136 -379.364357) (xy 293.902384 -379.369828)
			(xy 293.876844 -379.386859) (xy 293.822477 -379.415371) (xy 293.765076 -379.437136) (xy 293.705473 -379.451838)
			(xy 293.644534 -379.459263) (xy 293.61384 -379.459744) (xy 293.583144 -379.459274) (xy 293.522199 -379.45187)
			(xy 293.46259 -379.437177) (xy 293.405186 -379.415408) (xy 293.350824 -379.386882) (xy 293.325296 -379.369828)
			(xy 293.316544 -379.364357) (xy 293.29634 -379.360229) (xy 293.276136 -379.364357) (xy 293.267384 -379.369828)
			(xy 293.241844 -379.386859) (xy 293.187477 -379.415371) (xy 293.130076 -379.437136) (xy 293.070473 -379.451838)
			(xy 293.009534 -379.459263) (xy 292.97884 -379.459744) (xy 292.948144 -379.459274) (xy 292.887199 -379.45187)
			(xy 292.82759 -379.437177) (xy 292.770186 -379.415408) (xy 292.715824 -379.386882) (xy 292.690296 -379.369828)
			(xy 292.681544 -379.364357) (xy 292.66134 -379.360229) (xy 292.641136 -379.364357) (xy 292.632384 -379.369828)
			(xy 292.606844 -379.386859) (xy 292.552477 -379.415371) (xy 292.495076 -379.437136) (xy 292.435473 -379.451838)
			(xy 292.374534 -379.459263) (xy 292.34384 -379.459744) (xy 292.313144 -379.459274) (xy 292.252199 -379.45187)
			(xy 292.19259 -379.437177) (xy 292.135186 -379.415408) (xy 292.080824 -379.386882) (xy 292.055296 -379.369828)
			(xy 292.046544 -379.364357) (xy 292.02634 -379.360229) (xy 292.006136 -379.364357) (xy 291.997384 -379.369828)
			(xy 291.971844 -379.386859) (xy 291.917477 -379.415371) (xy 291.860076 -379.437136) (xy 291.800473 -379.451838)
			(xy 291.739534 -379.459263) (xy 291.70884 -379.459744) (xy 291.678144 -379.459274) (xy 291.617199 -379.45187)
			(xy 291.55759 -379.437177) (xy 291.500186 -379.415408) (xy 291.445824 -379.386882) (xy 291.420296 -379.369828)
			(xy 291.411544 -379.364357) (xy 291.39134 -379.360229) (xy 291.371136 -379.364357) (xy 291.362384 -379.369828)
			(xy 291.336844 -379.386859) (xy 291.282477 -379.415371) (xy 291.225076 -379.437136) (xy 291.165473 -379.451838)
			(xy 291.104534 -379.459263) (xy 291.07384 -379.459744) (xy 291.043144 -379.459274) (xy 290.982199 -379.45187)
			(xy 290.92259 -379.437177) (xy 290.865186 -379.415408) (xy 290.810824 -379.386882) (xy 290.785296 -379.369828)
			(xy 290.776544 -379.364357) (xy 290.75634 -379.360229) (xy 290.736136 -379.364357) (xy 290.727384 -379.369828)
			(xy 290.701844 -379.386859) (xy 290.647477 -379.415371) (xy 290.590076 -379.437136) (xy 290.530473 -379.451838)
			(xy 290.469534 -379.459263) (xy 290.43884 -379.459744) (xy 290.408144 -379.459274) (xy 290.347199 -379.45187)
			(xy 290.28759 -379.437177) (xy 290.230186 -379.415408) (xy 290.175824 -379.386882) (xy 290.150296 -379.369828)
			(xy 290.141544 -379.364357) (xy 290.12134 -379.360229) (xy 290.101136 -379.364357) (xy 290.092384 -379.369828)
			(xy 290.066844 -379.386859) (xy 290.012477 -379.415371) (xy 289.955076 -379.437136) (xy 289.895473 -379.451838)
			(xy 289.834534 -379.459263) (xy 289.80384 -379.459744) (xy 289.77311 -379.459225) (xy 289.712098 -379.451821)
			(xy 289.652423 -379.437118) (xy 289.594956 -379.415328) (xy 289.540533 -379.386771) (xy 289.48995 -379.351861)
			(xy 289.443944 -379.31111) (xy 289.403185 -379.265109) (xy 289.368269 -379.214532) (xy 289.339703 -379.160114)
			(xy 289.317905 -379.10265) (xy 289.303192 -379.042977) (xy 289.29578 -378.981966) (xy 289.295332 -378.951236)
			(xy 286.240982 -378.951236) (xy 283.086556 -382.105662) (xy 283.079713 -382.113061) (xy 283.071992 -382.13166)
			(xy 283.07157 -382.14173) (xy 283.07157 -384.743452) (xy 283.072098 -384.753444) (xy 283.079796 -384.771892)
			(xy 283.086556 -384.779266) (xy 283.884878 -385.577588) (xy 283.892227 -385.584388) (xy 283.91069 -385.592094)
			(xy 283.920692 -385.592574)
		)
		(stroke
			(width 0)
			(type solid)
		)
		(fill yes)
		(layer "B.Cu")
		(net "P3V3_AUX")
	)
	(gr_poly
		(pts
			(xy 232.120694 -370.04752) (xy 232.130682 -370.046984) (xy 232.149118 -370.039275) (xy 232.156508 -370.032534)
			(xy 235.901992 -366.28705) (xy 235.920592 -366.269228) (xy 235.962599 -366.239418) (xy 236.008976 -366.217005)
			(xy 236.033564 -366.209326) (xy 236.039914 -366.207548) (xy 236.050836 -366.200944) (xy 236.05744 -366.19434)
			(xy 236.075982 -366.18672) (xy 252.086618 -366.18672) (xy 252.096686 -366.187147) (xy 252.115284 -366.194868)
			(xy 252.122686 -366.201706) (xy 252.875034 -366.954054) (xy 252.882432 -366.9609) (xy 252.901031 -366.968629)
			(xy 252.911102 -366.96904) (xy 270.171418 -366.96904) (xy 270.181485 -366.968612) (xy 270.200079 -366.960886)
			(xy 270.207486 -366.954054) (xy 270.55064 -366.6109) (xy 270.569182 -366.60328) (xy 270.57858 -366.60328)
			(xy 270.894556 -366.28705) (xy 270.911997 -366.27028) (xy 270.951138 -366.24184) (xy 270.994245 -366.219872)
			(xy 271.040258 -366.204915) (xy 271.088043 -366.197339) (xy 271.112234 -366.19688) (xy 272.482564 -366.19688)
			(xy 272.506758 -366.197327) (xy 272.55455 -366.204892) (xy 272.60057 -366.219841) (xy 272.643684 -366.241806)
			(xy 272.682832 -366.270246) (xy 272.700242 -366.28705) (xy 273.737832 -367.324894) (xy 273.745232 -367.331736)
			(xy 273.76383 -367.33946) (xy 273.7739 -367.33988) (xy 288.151062 -367.33988) (xy 288.17524 -367.340342)
			(xy 288.223006 -367.347877) (xy 288.269008 -367.362784) (xy 288.312115 -367.384696) (xy 288.351268 -367.413076)
			(xy 288.36874 -367.429796) (xy 289.144456 -368.205512) (xy 290.223954 -368.205512) (xy 290.228025 -368.14989)
			(xy 290.240151 -368.095453) (xy 290.260074 -368.043362) (xy 290.28737 -367.994727) (xy 290.321456 -367.950584)
			(xy 290.361605 -367.911875) (xy 290.406963 -367.879424) (xy 290.456563 -367.853923) (xy 290.509347 -367.835916)
			(xy 290.56419 -367.825786) (xy 290.619924 -367.823749) (xy 290.675361 -367.829849) (xy 290.729318 -367.843955)
			(xy 290.780647 -367.865767) (xy 290.828253 -367.894821) (xy 290.871121 -367.930496) (xy 290.908338 -367.972033)
			(xy 290.939111 -368.018546) (xy 290.962783 -368.069043) (xy 290.978851 -368.12245) (xy 290.986971 -368.177626)
			(xy 290.98748 -368.205512) (xy 290.986971 -368.233398) (xy 290.978851 -368.288574) (xy 290.962783 -368.341981)
			(xy 290.939111 -368.392478) (xy 290.908338 -368.438991) (xy 290.871121 -368.480528) (xy 290.828253 -368.516203)
			(xy 290.780647 -368.545257) (xy 290.729318 -368.567069) (xy 290.675361 -368.581175) (xy 290.619924 -368.587275)
			(xy 290.56419 -368.585238) (xy 290.509347 -368.575108) (xy 290.456563 -368.557101) (xy 290.406963 -368.5316)
			(xy 290.361605 -368.499149) (xy 290.321456 -368.46044) (xy 290.28737 -368.416297) (xy 290.260074 -368.367662)
			(xy 290.240151 -368.315571) (xy 290.228025 -368.261134) (xy 290.223954 -368.205512) (xy 289.144456 -368.205512)
			(xy 289.617658 -368.678714) (xy 289.625002 -368.685525) (xy 289.643466 -368.69325) (xy 289.653472 -368.6937)
			(xy 293.753286 -368.6937) (xy 293.763275 -368.693165) (xy 293.78171 -368.685455) (xy 293.7891 -368.678714)
			(xy 294.207438 -368.260376) (xy 294.224865 -368.243602) (xy 294.264014 -368.215196) (xy 294.30713 -368.193276)
			(xy 294.353148 -368.178383) (xy 294.400931 -368.170884) (xy 294.425116 -368.17046) (xy 296.034206 -368.17046)
			(xy 296.044275 -368.170035) (xy 296.062874 -368.162314) (xy 296.070274 -368.155474) (xy 296.884598 -367.340896)
			(xy 296.901893 -367.324285) (xy 296.940676 -367.296086) (xy 296.961814 -367.284762) (xy 296.974768 -367.278158)
			(xy 296.9895 -367.254028) (xy 296.9895 -367.250218) (xy 297.019218 -367.2205) (xy 301.311818 -367.2205)
			(xy 301.321887 -367.220927) (xy 301.340486 -367.228646) (xy 301.347886 -367.235486) (xy 301.809361 -367.696961)
			(xy 302.767994 -367.696961) (xy 302.767994 -367.633039) (xy 302.776005 -367.569621) (xy 302.791902 -367.507707)
			(xy 302.815434 -367.448274) (xy 302.846228 -367.392259) (xy 302.883801 -367.340544) (xy 302.927558 -367.293947)
			(xy 302.976811 -367.253202) (xy 303.030782 -367.218951) (xy 303.088621 -367.191734) (xy 303.149414 -367.171981)
			(xy 303.212204 -367.160003) (xy 303.276 -367.15599) (xy 303.339796 -367.160003) (xy 303.402586 -367.171981)
			(xy 303.463379 -367.191734) (xy 303.521218 -367.218951) (xy 303.575189 -367.253202) (xy 303.624442 -367.293947)
			(xy 303.668199 -367.340544) (xy 303.705772 -367.392259) (xy 303.736566 -367.448274) (xy 303.760098 -367.507707)
			(xy 303.775995 -367.569621) (xy 303.784006 -367.633039) (xy 303.784508 -367.665) (xy 303.784006 -367.696961)
			(xy 303.775995 -367.760379) (xy 303.760098 -367.822293) (xy 303.736566 -367.881726) (xy 303.705772 -367.937741)
			(xy 303.668199 -367.989456) (xy 303.624442 -368.036053) (xy 303.575189 -368.076798) (xy 303.521218 -368.111049)
			(xy 303.463379 -368.138266) (xy 303.402586 -368.158019) (xy 303.339796 -368.169997) (xy 303.276 -368.174011)
			(xy 303.212204 -368.169997) (xy 303.149414 -368.158019) (xy 303.088621 -368.138266) (xy 303.030782 -368.111049)
			(xy 302.976811 -368.076798) (xy 302.927558 -368.036053) (xy 302.883801 -367.989456) (xy 302.846228 -367.937741)
			(xy 302.815434 -367.881726) (xy 302.791902 -367.822293) (xy 302.776005 -367.760379) (xy 302.767994 -367.696961)
			(xy 301.809361 -367.696961) (xy 302.78959 -368.67719) (xy 302.796934 -368.684003) (xy 302.815397 -368.691741)
			(xy 302.825404 -368.692176) (xy 309.481728 -368.692176) (xy 309.492098 -368.691686) (xy 309.511156 -368.6835)
			(xy 309.525444 -368.668466) (xy 309.52948 -368.658902) (xy 309.568342 -368.554762) (xy 309.560468 -368.524028)
			(xy 309.548276 -368.513614) (xy 309.521532 -368.489763) (xy 309.47347 -368.436608) (xy 309.432264 -368.377978)
			(xy 309.398533 -368.314751) (xy 309.372782 -368.247876) (xy 309.355397 -368.178355) (xy 309.346639 -368.107231)
			(xy 309.346092 -368.0714) (xy 309.346625 -368.036064) (xy 309.355144 -367.965907) (xy 309.372057 -367.897289)
			(xy 309.397117 -367.831209) (xy 309.42996 -367.768632) (xy 309.470107 -367.71047) (xy 309.516971 -367.657571)
			(xy 309.56987 -367.610707) (xy 309.628032 -367.57056) (xy 309.690609 -367.537717) (xy 309.756689 -367.512657)
			(xy 309.825307 -367.495744) (xy 309.895464 -367.487225) (xy 309.9308 -367.486692) (xy 309.95239 -367.4872)
			(xy 309.963312 -367.487454) (xy 309.982616 -367.479834) (xy 310.050688 -367.411762) (xy 310.058054 -367.392204)
			(xy 310.0578 -367.381282) (xy 310.057292 -367.3602) (xy 310.057756 -367.329469) (xy 310.065165 -367.268455)
			(xy 310.079873 -367.208779) (xy 310.101668 -367.151311) (xy 310.130231 -367.096889) (xy 310.165145 -367.046307)
			(xy 310.205902 -367.000302) (xy 310.251907 -366.959545) (xy 310.302489 -366.924631) (xy 310.356911 -366.896068)
			(xy 310.414379 -366.874273) (xy 310.474055 -366.859565) (xy 310.535069 -366.852156) (xy 310.5658 -366.851692)
			(xy 310.59609 -366.85213) (xy 310.65624 -366.85933) (xy 310.715108 -366.873629) (xy 310.771859 -366.894823)
			(xy 310.798972 -366.908334) (xy 310.810656 -366.91443) (xy 310.836056 -366.913922) (xy 310.933084 -366.85855)
			(xy 310.946292 -366.83696) (xy 310.947054 -366.823752) (xy 310.94934 -366.791722) (xy 310.960977 -366.728571)
			(xy 310.980474 -366.667387) (xy 311.007519 -366.609146) (xy 311.041683 -366.554773) (xy 311.082421 -366.505135)
			(xy 311.129085 -366.461021) (xy 311.180932 -366.423134) (xy 311.237137 -366.392077) (xy 311.296805 -366.368345)
			(xy 311.358987 -366.352315) (xy 311.422692 -366.344241) (xy 311.4548 -366.343692) (xy 311.48395 -366.344117)
			(xy 311.541863 -366.350818) (xy 311.598633 -366.364087) (xy 311.653516 -366.38375) (xy 311.679844 -366.39627)
			(xy 311.69229 -366.402366) (xy 311.71896 -366.400588) (xy 311.815226 -366.336834) (xy 311.827164 -366.312704)
			(xy 311.826402 -366.298988) (xy 311.825386 -366.268) (xy 311.825862 -366.236459) (xy 311.833665 -366.17386)
			(xy 311.849151 -366.112707) (xy 311.872082 -366.05394) (xy 311.902106 -365.99846) (xy 311.938762 -365.94712)
			(xy 311.981487 -365.900709) (xy 312.029625 -365.859938) (xy 312.082436 -365.825435) (xy 312.139109 -365.797729)
			(xy 312.198774 -365.777247) (xy 312.260515 -365.764301) (xy 312.323382 -365.759092) (xy 312.386411 -365.761699)
			(xy 312.448634 -365.772083) (xy 312.509094 -365.790083) (xy 312.566864 -365.815423) (xy 312.621055 -365.847715)
			(xy 312.670836 -365.886461) (xy 312.715443 -365.931068) (xy 312.754189 -365.98085) (xy 312.786479 -366.035042)
			(xy 312.811819 -366.092811) (xy 312.829819 -366.153272) (xy 312.840201 -366.215495) (xy 312.842808 -366.278524)
			(xy 312.837598 -366.341391) (xy 312.826357 -366.395) (xy 313.841382 -366.395) (xy 313.845453 -366.339378)
			(xy 313.857579 -366.284941) (xy 313.877502 -366.23285) (xy 313.904798 -366.184215) (xy 313.938884 -366.140072)
			(xy 313.979033 -366.101363) (xy 314.024391 -366.068912) (xy 314.073991 -366.043411) (xy 314.126775 -366.025404)
			(xy 314.181618 -366.015274) (xy 314.237352 -366.013237) (xy 314.292789 -366.019337) (xy 314.346746 -366.033443)
			(xy 314.398075 -366.055255) (xy 314.445681 -366.084309) (xy 314.488549 -366.119984) (xy 314.525766 -366.161521)
			(xy 314.556539 -366.208034) (xy 314.580211 -366.258531) (xy 314.596279 -366.311938) (xy 314.604399 -366.367114)
			(xy 314.604908 -366.395) (xy 314.604399 -366.422886) (xy 314.596279 -366.478062) (xy 314.580211 -366.531469)
			(xy 314.556539 -366.581966) (xy 314.525766 -366.628479) (xy 314.488549 -366.670016) (xy 314.445681 -366.705691)
			(xy 314.398075 -366.734745) (xy 314.346746 -366.756557) (xy 314.292789 -366.770663) (xy 314.237352 -366.776763)
			(xy 314.181618 -366.774726) (xy 314.126775 -366.764596) (xy 314.073991 -366.746589) (xy 314.024391 -366.721088)
			(xy 313.979033 -366.688637) (xy 313.938884 -366.649928) (xy 313.904798 -366.605785) (xy 313.877502 -366.55715)
			(xy 313.857579 -366.505059) (xy 313.845453 -366.450622) (xy 313.841382 -366.395) (xy 312.826357 -366.395)
			(xy 312.824652 -366.403132) (xy 312.804168 -366.462796) (xy 312.776462 -366.519469) (xy 312.741958 -366.57228)
			(xy 312.701187 -366.620417) (xy 312.654775 -366.663142) (xy 312.603435 -366.699797) (xy 312.547955 -366.729821)
			(xy 312.489187 -366.752751) (xy 312.428034 -366.768237) (xy 312.365435 -366.776039) (xy 312.333894 -366.776508)
			(xy 312.304745 -366.776082) (xy 312.246831 -366.769381) (xy 312.190062 -366.756111) (xy 312.135179 -366.736448)
			(xy 312.10885 -366.72393) (xy 312.096404 -366.717834) (xy 312.069734 -366.719612) (xy 311.973468 -366.783366)
			(xy 311.96153 -366.807496) (xy 311.962292 -366.821212) (xy 311.963308 -366.8522) (xy 311.962844 -366.882931)
			(xy 311.955435 -366.943945) (xy 311.940727 -367.003621) (xy 311.918932 -367.061089) (xy 311.890369 -367.115511)
			(xy 311.855455 -367.166093) (xy 311.814698 -367.212098) (xy 311.768693 -367.252855) (xy 311.718111 -367.287769)
			(xy 311.663689 -367.316332) (xy 311.606221 -367.338127) (xy 311.546545 -367.352835) (xy 311.485531 -367.360244)
			(xy 311.4548 -367.360708) (xy 311.42451 -367.36027) (xy 311.36436 -367.35307) (xy 311.305492 -367.338771)
			(xy 311.248741 -367.317577) (xy 311.221628 -367.304066) (xy 311.209944 -367.29797) (xy 311.184544 -367.298478)
			(xy 311.087516 -367.35385) (xy 311.074308 -367.37544) (xy 311.073546 -367.388648) (xy 311.07138 -367.419167)
			(xy 311.060652 -367.479405) (xy 311.042774 -367.537921) (xy 311.018003 -367.593868) (xy 310.986699 -367.646439)
			(xy 310.949312 -367.694874) (xy 310.906384 -367.738473) (xy 310.858535 -367.776607) (xy 310.806456 -367.808723)
			(xy 310.7509 -367.834359) (xy 310.692669 -367.853143) (xy 310.632605 -367.864804) (xy 310.602122 -367.867438)
			(xy 310.591454 -367.8682) (xy 310.572912 -367.877852) (xy 310.512714 -367.953036) (xy 310.50738 -367.973356)
			(xy 310.508904 -367.984024) (xy 310.511993 -368.005736) (xy 310.515302 -368.04947) (xy 310.515508 -368.0714)
			(xy 310.514966 -368.107231) (xy 310.506207 -368.178356) (xy 310.488822 -368.247878) (xy 310.463071 -368.314753)
			(xy 310.42934 -368.37798) (xy 310.388134 -368.436611) (xy 310.340072 -368.489766) (xy 310.313324 -368.513614)
			(xy 310.301132 -368.524028) (xy 310.293258 -368.554762) (xy 310.33212 -368.658902) (xy 310.336149 -368.668475)
			(xy 310.350421 -368.683537) (xy 310.369496 -368.691702) (xy 310.379872 -368.692176) (xy 319.812416 -368.692176)
			(xy 319.822402 -368.691635) (xy 319.840827 -368.683915) (xy 319.84823 -368.67719) (xy 321.013074 -367.512346)
			(xy 321.019915 -367.504946) (xy 321.027633 -367.486347) (xy 321.02806 -367.476278) (xy 321.02806 -362.783882)
			(xy 321.027632 -362.773814) (xy 321.019909 -362.755218) (xy 321.013074 -362.747814) (xy 320.766186 -362.500926)
			(xy 320.758788 -362.494079) (xy 320.74019 -362.486346) (xy 320.730118 -362.48594) (xy 320.312542 -362.48594)
			(xy 320.302478 -362.485505) (xy 320.283894 -362.477769) (xy 320.276474 -362.470954) (xy 320.123566 -362.318046)
			(xy 320.116168 -362.3112) (xy 320.097569 -362.303471) (xy 320.087498 -362.30306) (xy 316.545722 -362.30306)
			(xy 316.535659 -362.303499) (xy 316.517081 -362.31124) (xy 316.509654 -362.318046) (xy 315.881766 -362.945934)
			(xy 315.879734 -362.984288) (xy 315.89218 -362.999782) (xy 315.908074 -363.020203) (xy 315.934788 -363.064522)
			(xy 315.955263 -363.112046) (xy 315.969123 -363.161903) (xy 315.976114 -363.213176) (xy 315.976508 -363.23905)
			(xy 318.698878 -363.23905) (xy 318.702949 -363.183428) (xy 318.715075 -363.128991) (xy 318.734998 -363.0769)
			(xy 318.762294 -363.028265) (xy 318.79638 -362.984122) (xy 318.836529 -362.945413) (xy 318.881887 -362.912962)
			(xy 318.931487 -362.887461) (xy 318.984271 -362.869454) (xy 319.039114 -362.859324) (xy 319.094848 -362.857287)
			(xy 319.150285 -362.863387) (xy 319.204242 -362.877493) (xy 319.255571 -362.899305) (xy 319.303177 -362.928359)
			(xy 319.346045 -362.964034) (xy 319.383262 -363.005571) (xy 319.414035 -363.052084) (xy 319.437707 -363.102581)
			(xy 319.453775 -363.155988) (xy 319.461895 -363.211164) (xy 319.462404 -363.23905) (xy 319.461895 -363.266936)
			(xy 319.453775 -363.322112) (xy 319.437707 -363.375519) (xy 319.414035 -363.426016) (xy 319.383262 -363.472529)
			(xy 319.346045 -363.514066) (xy 319.303177 -363.549741) (xy 319.255571 -363.578795) (xy 319.204242 -363.600607)
			(xy 319.150285 -363.614713) (xy 319.094848 -363.620813) (xy 319.039114 -363.618776) (xy 318.984271 -363.608646)
			(xy 318.931487 -363.590639) (xy 318.881887 -363.565138) (xy 318.836529 -363.532687) (xy 318.79638 -363.493978)
			(xy 318.762294 -363.449835) (xy 318.734998 -363.4012) (xy 318.715075 -363.349109) (xy 318.702949 -363.294672)
			(xy 318.698878 -363.23905) (xy 315.976508 -363.23905) (xy 315.976048 -363.266305) (xy 315.968297 -363.320262)
			(xy 315.952945 -363.372565) (xy 315.930306 -363.422152) (xy 315.900839 -363.468011) (xy 315.865145 -363.50921)
			(xy 315.823951 -363.544909) (xy 315.778096 -363.574382) (xy 315.728512 -363.597028) (xy 315.67621 -363.612386)
			(xy 315.622255 -363.620145) (xy 315.595 -363.620558) (xy 315.569128 -363.620127) (xy 315.517858 -363.613136)
			(xy 315.468003 -363.599282) (xy 315.420477 -363.578819) (xy 315.376151 -363.552123) (xy 315.355732 -363.53623)
			(xy 315.340238 -363.523784) (xy 315.301884 -363.525816) (xy 314.860686 -363.967014) (xy 314.853291 -363.973868)
			(xy 314.834692 -363.98161) (xy 314.824618 -363.982) (xy 308.556914 -363.982) (xy 308.547163 -363.982424)
			(xy 308.529073 -363.989702) (xy 308.515037 -364.003237) (xy 308.510686 -364.011972) (xy 308.46649 -364.110524)
			(xy 308.471062 -364.139988) (xy 308.481222 -364.151164) (xy 308.501469 -364.174526) (xy 308.536754 -364.225291)
			(xy 308.565628 -364.279956) (xy 308.587668 -364.337717) (xy 308.602548 -364.397723) (xy 308.61005 -364.459089)
			(xy 308.610508 -364.49) (xy 308.610044 -364.520731) (xy 308.602635 -364.581745) (xy 308.587927 -364.641421)
			(xy 308.566132 -364.698889) (xy 308.542456 -364.744) (xy 309.168292 -364.744) (xy 309.168787 -364.709973)
			(xy 309.176687 -364.64238) (xy 309.192381 -364.576162) (xy 309.215657 -364.512213) (xy 309.246199 -364.451398)
			(xy 309.283595 -364.394541) (xy 309.327338 -364.342409) (xy 309.376838 -364.295708) (xy 309.431425 -364.25507)
			(xy 309.490361 -364.221043) (xy 309.552849 -364.194089) (xy 309.618043 -364.174571) (xy 309.685062 -364.162753)
			(xy 309.753 -364.158797) (xy 309.820938 -364.162753) (xy 309.887957 -364.174571) (xy 309.953151 -364.194089)
			(xy 310.015639 -364.221043) (xy 310.074575 -364.25507) (xy 310.129162 -364.295708) (xy 310.178662 -364.342409)
			(xy 310.222405 -364.394541) (xy 310.259801 -364.451398) (xy 310.290343 -364.512213) (xy 310.313619 -364.576162)
			(xy 310.329313 -364.64238) (xy 310.337213 -364.709973) (xy 310.337708 -364.744) (xy 310.337496 -364.766892)
			(xy 310.333937 -364.812538) (xy 310.330596 -364.835186) (xy 310.329072 -364.845346) (xy 310.333644 -364.864904)
			(xy 310.38927 -364.939834) (xy 310.406542 -364.950248) (xy 310.416956 -364.951518) (xy 310.449679 -364.956613)
			(xy 310.513522 -364.974223) (xy 310.574539 -364.999971) (xy 310.592872 -365.0107) (xy 314.082702 -365.0107)
			(xy 314.086617 -364.933509) (xy 314.098321 -364.85711) (xy 314.117694 -364.782287) (xy 314.144537 -364.709807)
			(xy 314.178575 -364.640416) (xy 314.219459 -364.574823) (xy 314.266769 -364.513704) (xy 314.32002 -364.457685)
			(xy 314.378664 -364.40734) (xy 314.442102 -364.363186) (xy 314.50968 -364.325677) (xy 314.580707 -364.295197)
			(xy 314.654453 -364.272059) (xy 314.730161 -364.256501) (xy 314.807055 -364.248681) (xy 314.8457 -364.248192)
			(xy 314.884765 -364.248684) (xy 314.962487 -364.256665) (xy 315.038984 -364.272553) (xy 315.113456 -364.296181)
			(xy 315.18512 -364.327303) (xy 315.253226 -364.36559) (xy 315.29484 -364.394961) (xy 318.668394 -364.394961)
			(xy 318.668394 -364.331039) (xy 318.676405 -364.267621) (xy 318.692302 -364.205707) (xy 318.715834 -364.146274)
			(xy 318.746628 -364.090259) (xy 318.784201 -364.038544) (xy 318.827958 -363.991947) (xy 318.877211 -363.951202)
			(xy 318.931182 -363.916951) (xy 318.989021 -363.889734) (xy 319.049814 -363.869981) (xy 319.112604 -363.858003)
			(xy 319.1764 -363.85399) (xy 319.240196 -363.858003) (xy 319.302986 -363.869981) (xy 319.363779 -363.889734)
			(xy 319.421618 -363.916951) (xy 319.475589 -363.951202) (xy 319.524842 -363.991947) (xy 319.568599 -364.038544)
			(xy 319.606172 -364.090259) (xy 319.636966 -364.146274) (xy 319.660498 -364.205707) (xy 319.676395 -364.267621)
			(xy 319.684406 -364.331039) (xy 319.684908 -364.363) (xy 319.684406 -364.394961) (xy 319.676395 -364.458379)
			(xy 319.660498 -364.520293) (xy 319.636966 -364.579726) (xy 319.606172 -364.635741) (xy 319.568599 -364.687456)
			(xy 319.524842 -364.734053) (xy 319.475589 -364.774798) (xy 319.421618 -364.809049) (xy 319.363779 -364.836266)
			(xy 319.302986 -364.856019) (xy 319.240196 -364.867997) (xy 319.1764 -364.872011) (xy 319.112604 -364.867997)
			(xy 319.049814 -364.856019) (xy 318.989021 -364.836266) (xy 318.931182 -364.809049) (xy 318.877211 -364.774798)
			(xy 318.827958 -364.734053) (xy 318.784201 -364.687456) (xy 318.746628 -364.635741) (xy 318.715834 -364.579726)
			(xy 318.692302 -364.520293) (xy 318.676405 -364.458379) (xy 318.668394 -364.394961) (xy 315.29484 -364.394961)
			(xy 315.317059 -364.410643) (xy 315.375949 -364.461987) (xy 315.429279 -364.519086) (xy 315.476489 -364.581339)
			(xy 315.49721 -364.61446) (xy 315.502694 -364.622575) (xy 315.518329 -364.634331) (xy 315.537233 -364.639361)
			(xy 315.546994 -364.63859) (xy 315.558944 -364.63716) (xy 315.582965 -364.635634) (xy 315.595 -364.635542)
			(xy 315.622255 -364.635928) (xy 315.67621 -364.643685) (xy 315.728511 -364.659043) (xy 315.778095 -364.681687)
			(xy 315.823951 -364.711157) (xy 315.865147 -364.746853) (xy 315.900843 -364.788049) (xy 315.930313 -364.833905)
			(xy 315.952957 -364.883489) (xy 315.968315 -364.93579) (xy 315.976072 -364.989745) (xy 315.976072 -365.044255)
			(xy 315.968315 -365.09821) (xy 315.952957 -365.150511) (xy 315.930313 -365.200095) (xy 315.900843 -365.245951)
			(xy 315.865147 -365.287147) (xy 315.823951 -365.322843) (xy 315.778095 -365.352313) (xy 315.728511 -365.374957)
			(xy 315.67621 -365.390315) (xy 315.622255 -365.398072) (xy 315.595 -365.398558) (xy 315.581364 -365.39846)
			(xy 315.55416 -365.396555) (xy 315.540644 -365.394748) (xy 315.530892 -365.393801) (xy 315.511874 -365.398428)
			(xy 315.495968 -365.409835) (xy 315.490352 -365.417862) (xy 315.469395 -365.450064) (xy 315.422052 -365.510579)
			(xy 315.368862 -365.566024) (xy 315.310363 -365.615837) (xy 315.247151 -365.659513) (xy 315.179865 -365.696607)
			(xy 315.109189 -365.726745) (xy 315.035839 -365.74962) (xy 314.960561 -365.765001) (xy 314.884117 -365.77273)
			(xy 314.8457 -365.773208) (xy 314.807055 -365.772719) (xy 314.730161 -365.764899) (xy 314.654453 -365.749341)
			(xy 314.580707 -365.726203) (xy 314.50968 -365.695723) (xy 314.442102 -365.658214) (xy 314.378664 -365.61406)
			(xy 314.32002 -365.563715) (xy 314.266769 -365.507696) (xy 314.219459 -365.446577) (xy 314.178575 -365.380984)
			(xy 314.144537 -365.311593) (xy 314.117694 -365.239113) (xy 314.098321 -365.16429) (xy 314.086617 -365.087891)
			(xy 314.082702 -365.0107) (xy 310.592872 -365.0107) (xy 310.631697 -365.033421) (xy 310.684031 -365.074007)
			(xy 310.730654 -365.121042) (xy 310.770777 -365.173732) (xy 310.803722 -365.231183) (xy 310.828931 -365.292424)
			(xy 310.845977 -365.35642) (xy 310.854574 -365.422087) (xy 310.855106 -365.4552) (xy 310.854604 -365.487161)
			(xy 310.846593 -365.550579) (xy 310.830696 -365.612493) (xy 310.807164 -365.671926) (xy 310.77637 -365.727941)
			(xy 310.738797 -365.779656) (xy 310.69504 -365.826253) (xy 310.645787 -365.866998) (xy 310.591816 -365.901249)
			(xy 310.533977 -365.928466) (xy 310.473184 -365.948219) (xy 310.410394 -365.960197) (xy 310.346598 -365.964211)
			(xy 310.282802 -365.960197) (xy 310.220012 -365.948219) (xy 310.159219 -365.928466) (xy 310.10138 -365.901249)
			(xy 310.047409 -365.866998) (xy 309.998156 -365.826253) (xy 309.954399 -365.779656) (xy 309.916826 -365.727941)
			(xy 309.886032 -365.671926) (xy 309.8625 -365.612493) (xy 309.846603 -365.550579) (xy 309.838592 -365.487161)
			(xy 309.83809 -365.4552) (xy 309.838598 -365.434372) (xy 309.838852 -365.423958) (xy 309.831994 -365.405162)
			(xy 309.76824 -365.33709) (xy 309.749698 -365.328708) (xy 309.739284 -365.328454) (xy 309.704497 -365.327145)
			(xy 309.635582 -365.317279) (xy 309.568328 -365.299297) (xy 309.503686 -365.273455) (xy 309.442571 -365.240116)
			(xy 309.385849 -365.199754) (xy 309.334322 -365.15294) (xy 309.288721 -365.100338) (xy 309.249692 -365.042691)
			(xy 309.217786 -364.980816) (xy 309.193456 -364.915589) (xy 309.177046 -364.847934) (xy 309.168788 -364.778808)
			(xy 309.168292 -364.744) (xy 308.542456 -364.744) (xy 308.537569 -364.753311) (xy 308.502655 -364.803893)
			(xy 308.461898 -364.849898) (xy 308.415893 -364.890655) (xy 308.365311 -364.925569) (xy 308.310889 -364.954132)
			(xy 308.253421 -364.975927) (xy 308.193745 -364.990635) (xy 308.132731 -364.998044) (xy 308.102 -364.998508)
			(xy 308.067666 -364.997976) (xy 307.999614 -364.988797) (xy 307.966364 -364.98022) (xy 307.956966 -364.977426)
			(xy 307.93817 -364.979458) (xy 307.85943 -365.020098) (xy 307.846984 -365.034322) (xy 307.843682 -365.043466)
			(xy 307.831794 -365.0748) (xy 307.800956 -365.134302) (xy 307.782214 -365.162084) (xy 307.776626 -365.170212)
			(xy 307.772308 -365.189008) (xy 307.785516 -365.2774) (xy 307.795168 -365.294164) (xy 307.802788 -365.30026)
			(xy 307.833135 -365.324936) (xy 307.887649 -365.381025) (xy 307.934206 -365.443876) (xy 307.953664 -365.477806)
			(xy 307.960522 -365.490252) (xy 307.984652 -365.504222) (xy 308.102762 -365.502698) (xy 308.126384 -365.48822)
			(xy 308.132988 -365.47552) (xy 308.147593 -365.44829) (xy 308.182433 -365.397258) (xy 308.223199 -365.350823)
			(xy 308.269291 -365.309668) (xy 308.320028 -365.2744) (xy 308.374665 -365.245539) (xy 308.432396 -365.22351)
			(xy 308.49237 -365.208636) (xy 308.553705 -365.201138) (xy 308.5846 -365.200692) (xy 308.616561 -365.201194)
			(xy 308.679979 -365.209205) (xy 308.741893 -365.225102) (xy 308.801326 -365.248634) (xy 308.857341 -365.279428)
			(xy 308.909056 -365.317001) (xy 308.955653 -365.360758) (xy 308.996398 -365.410011) (xy 309.030649 -365.463982)
			(xy 309.057866 -365.521821) (xy 309.077619 -365.582614) (xy 309.089597 -365.645404) (xy 309.093611 -365.7092)
			(xy 309.089597 -365.772996) (xy 309.077619 -365.835786) (xy 309.057866 -365.896579) (xy 309.030649 -365.954418)
			(xy 308.996398 -366.008389) (xy 308.955653 -366.057642) (xy 308.909056 -366.101399) (xy 308.857341 -366.138972)
			(xy 308.801326 -366.169766) (xy 308.741893 -366.193298) (xy 308.679979 -366.209195) (xy 308.616561 -366.217206)
			(xy 308.5846 -366.217708) (xy 308.552657 -366.217208) (xy 308.489274 -366.209209) (xy 308.427391 -366.193336)
			(xy 308.367982 -366.169839) (xy 308.311984 -366.139089) (xy 308.260276 -366.101568) (xy 308.213674 -366.057869)
			(xy 308.17291 -366.008678) (xy 308.15534 -365.981996) (xy 308.14772 -365.970058) (xy 308.122828 -365.957612)
			(xy 308.005226 -365.966502) (xy 307.982366 -365.982504) (xy 307.976778 -365.995458) (xy 307.962717 -366.026214)
			(xy 307.928519 -366.084558) (xy 307.887819 -366.138568) (xy 307.841161 -366.187523) (xy 307.789167 -366.230769)
			(xy 307.732533 -366.267729) (xy 307.672012 -366.297909) (xy 307.608415 -366.320907) (xy 307.542589 -366.336416)
			(xy 307.475414 -366.344228) (xy 307.4416 -366.344708) (xy 307.406264 -366.344175) (xy 307.336107 -366.335656)
			(xy 307.267489 -366.318743) (xy 307.201409 -366.293683) (xy 307.138832 -366.26084) (xy 307.08067 -366.220693)
			(xy 307.027771 -366.173829) (xy 306.980907 -366.12093) (xy 306.94076 -366.062768) (xy 306.907917 -366.000191)
			(xy 306.882857 -365.934111) (xy 306.865944 -365.865493) (xy 306.857425 -365.795336) (xy 306.856892 -365.76)
			(xy 306.857431 -365.724221) (xy 306.866166 -365.653197) (xy 306.883504 -365.58377) (xy 306.909187 -365.516979)
			(xy 306.94283 -365.453822) (xy 306.983931 -365.395244) (xy 307.007514 -365.368332) (xy 307.013864 -365.36122)
			(xy 307.020722 -365.342932) (xy 307.01869 -365.253524) (xy 307.01107 -365.235744) (xy 307.004212 -365.228886)
			(xy 306.981284 -365.205008) (xy 306.941169 -365.152348) (xy 306.908233 -365.094924) (xy 306.883034 -365.033709)
			(xy 306.865998 -364.969739) (xy 306.857414 -364.9041) (xy 306.856892 -364.871) (xy 306.857356 -364.840269)
			(xy 306.864765 -364.779255) (xy 306.879473 -364.719579) (xy 306.901268 -364.662111) (xy 306.929831 -364.607689)
			(xy 306.964745 -364.557107) (xy 307.005502 -364.511102) (xy 307.051507 -364.470345) (xy 307.102089 -364.435431)
			(xy 307.156511 -364.406868) (xy 307.213979 -364.385073) (xy 307.273655 -364.370365) (xy 307.334669 -364.362956)
			(xy 307.3654 -364.362492) (xy 307.399734 -364.363024) (xy 307.467786 -364.372203) (xy 307.501036 -364.38078)
			(xy 307.510434 -364.383574) (xy 307.52923 -364.381542) (xy 307.60797 -364.340902) (xy 307.620416 -364.326678)
			(xy 307.623718 -364.317534) (xy 307.6352 -364.287146) (xy 307.664805 -364.229322) (xy 307.701537 -364.175743)
			(xy 307.722778 -364.151164) (xy 307.732938 -364.139988) (xy 307.73751 -364.110524) (xy 307.693314 -364.011972)
			(xy 307.688911 -364.003273) (xy 307.674872 -363.989768) (xy 307.656824 -363.982438) (xy 307.647086 -363.982)
			(xy 306.019708 -363.982) (xy 305.992784 -364.001812) (xy 305.987704 -364.017814) (xy 305.977348 -364.050068)
			(xy 305.950209 -364.112138) (xy 305.916077 -364.170654) (xy 305.875408 -364.224832) (xy 305.828749 -364.273946)
			(xy 305.776726 -364.317337) (xy 305.720035 -364.354422) (xy 305.659437 -364.384706) (xy 305.595744 -364.407781)
			(xy 305.529811 -364.423339) (xy 305.462522 -364.43117) (xy 305.394778 -364.43117) (xy 305.327489 -364.423339)
			(xy 305.261556 -364.407781) (xy 305.197863 -364.384706) (xy 305.137265 -364.354422) (xy 305.080574 -364.317337)
			(xy 305.028551 -364.273946) (xy 304.981892 -364.224832) (xy 304.941223 -364.170654) (xy 304.907091 -364.112138)
			(xy 304.879952 -364.050068) (xy 304.869596 -364.017814) (xy 304.864516 -364.001812) (xy 304.837592 -363.982)
			(xy 303.685702 -363.982) (xy 303.657254 -364.0074) (xy 303.654968 -364.026704) (xy 303.651223 -364.054197)
			(xy 303.636811 -364.107779) (xy 303.614791 -364.158708) (xy 303.585627 -364.20591) (xy 303.549935 -364.248392)
			(xy 303.508466 -364.285257) (xy 303.462096 -364.315727) (xy 303.411801 -364.33916) (xy 303.358643 -364.355062)
			(xy 303.303743 -364.363098) (xy 303.248257 -364.363098) (xy 303.193357 -364.355062) (xy 303.140199 -364.33916)
			(xy 303.089904 -364.315727) (xy 303.043534 -364.285257) (xy 303.002065 -364.248392) (xy 302.966373 -364.20591)
			(xy 302.937209 -364.158708) (xy 302.915189 -364.107779) (xy 302.900777 -364.054197) (xy 302.897032 -364.026704)
			(xy 302.894746 -364.0074) (xy 302.866298 -363.982) (xy 301.676562 -363.982) (xy 301.666495 -363.98243)
			(xy 301.647901 -363.990154) (xy 301.640494 -363.996986) (xy 301.245016 -364.392464) (xy 301.239428 -364.422944)
			(xy 301.245778 -364.437422) (xy 301.259409 -364.469857) (xy 301.278622 -364.537539) (xy 301.288334 -364.607222)
			(xy 301.288958 -364.6424) (xy 301.288494 -364.673132) (xy 301.281086 -364.734148) (xy 301.266378 -364.793827)
			(xy 301.244584 -364.851297) (xy 301.216021 -364.905722) (xy 301.181108 -364.956307) (xy 301.140351 -365.002316)
			(xy 301.094347 -365.043077) (xy 301.043765 -365.077995) (xy 300.989343 -365.106563) (xy 300.931874 -365.128363)
			(xy 300.872198 -365.143077) (xy 300.811182 -365.150491) (xy 300.78045 -365.150908) (xy 300.74527 -365.150313)
			(xy 300.675584 -365.140604) (xy 300.607906 -365.121367) (xy 300.575472 -365.107728) (xy 300.560994 -365.101378)
			(xy 300.530514 -365.106966) (xy 300.480519 -365.156961) (xy 302.767994 -365.156961) (xy 302.767994 -365.093039)
			(xy 302.776005 -365.029621) (xy 302.791902 -364.967707) (xy 302.815434 -364.908274) (xy 302.846228 -364.852259)
			(xy 302.883801 -364.800544) (xy 302.927558 -364.753947) (xy 302.976811 -364.713202) (xy 303.030782 -364.678951)
			(xy 303.088621 -364.651734) (xy 303.149414 -364.631981) (xy 303.212204 -364.620003) (xy 303.276 -364.61599)
			(xy 303.339796 -364.620003) (xy 303.402586 -364.631981) (xy 303.463379 -364.651734) (xy 303.521218 -364.678951)
			(xy 303.575189 -364.713202) (xy 303.624442 -364.753947) (xy 303.668199 -364.800544) (xy 303.705772 -364.852259)
			(xy 303.736566 -364.908274) (xy 303.760098 -364.967707) (xy 303.775995 -365.029621) (xy 303.784006 -365.093039)
			(xy 303.784508 -365.125) (xy 303.784006 -365.156961) (xy 303.783745 -365.159027) (xy 304.987947 -365.159027)
			(xy 304.987947 -365.090973) (xy 304.995847 -365.02338) (xy 305.011541 -364.957162) (xy 305.034817 -364.893213)
			(xy 305.065359 -364.832398) (xy 305.102755 -364.775541) (xy 305.146498 -364.723409) (xy 305.195998 -364.676708)
			(xy 305.250585 -364.63607) (xy 305.309521 -364.602043) (xy 305.372009 -364.575089) (xy 305.437203 -364.555571)
			(xy 305.504222 -364.543753) (xy 305.57216 -364.539797) (xy 305.640098 -364.543753) (xy 305.707117 -364.555571)
			(xy 305.772311 -364.575089) (xy 305.834799 -364.602043) (xy 305.893735 -364.63607) (xy 305.948322 -364.676708)
			(xy 305.997822 -364.723409) (xy 306.041565 -364.775541) (xy 306.078961 -364.832398) (xy 306.109503 -364.893213)
			(xy 306.132779 -364.957162) (xy 306.148473 -365.02338) (xy 306.156373 -365.090973) (xy 306.156868 -365.125)
			(xy 306.156373 -365.159027) (xy 306.148473 -365.22662) (xy 306.132779 -365.292838) (xy 306.109503 -365.356787)
			(xy 306.078961 -365.417602) (xy 306.041565 -365.474459) (xy 305.997822 -365.526591) (xy 305.948322 -365.573292)
			(xy 305.893735 -365.61393) (xy 305.834799 -365.647957) (xy 305.772311 -365.674911) (xy 305.707117 -365.694429)
			(xy 305.640098 -365.706247) (xy 305.57216 -365.710204) (xy 305.504222 -365.706247) (xy 305.437203 -365.694429)
			(xy 305.372009 -365.674911) (xy 305.309521 -365.647957) (xy 305.250585 -365.61393) (xy 305.195998 -365.573292)
			(xy 305.146498 -365.526591) (xy 305.102755 -365.474459) (xy 305.065359 -365.417602) (xy 305.034817 -365.356787)
			(xy 305.011541 -365.292838) (xy 304.995847 -365.22662) (xy 304.987947 -365.159027) (xy 303.783745 -365.159027)
			(xy 303.775995 -365.220379) (xy 303.760098 -365.282293) (xy 303.736566 -365.341726) (xy 303.705772 -365.397741)
			(xy 303.668199 -365.449456) (xy 303.624442 -365.496053) (xy 303.575189 -365.536798) (xy 303.521218 -365.571049)
			(xy 303.463379 -365.598266) (xy 303.402586 -365.618019) (xy 303.339796 -365.629997) (xy 303.276 -365.634011)
			(xy 303.212204 -365.629997) (xy 303.149414 -365.618019) (xy 303.088621 -365.598266) (xy 303.030782 -365.571049)
			(xy 302.976811 -365.536798) (xy 302.927558 -365.496053) (xy 302.883801 -365.449456) (xy 302.846228 -365.397741)
			(xy 302.815434 -365.341726) (xy 302.791902 -365.282293) (xy 302.776005 -365.220379) (xy 302.767994 -365.156961)
			(xy 300.480519 -365.156961) (xy 300.085506 -365.551974) (xy 300.078109 -365.558824) (xy 300.059511 -365.566565)
			(xy 300.049438 -365.56696) (xy 299.489622 -365.56696) (xy 299.479634 -365.567495) (xy 299.461202 -365.57521)
			(xy 299.453808 -365.581946) (xy 299.394626 -365.641128) (xy 299.377198 -365.6579) (xy 299.338049 -365.6863)
			(xy 299.294932 -365.708215) (xy 299.248914 -365.723103) (xy 299.201132 -365.730596) (xy 299.176948 -365.731044)
			(xy 297.491404 -365.731044) (xy 297.481417 -365.731582) (xy 297.462988 -365.739299) (xy 297.45559 -365.74603)
			(xy 297.34002 -365.8616) (xy 301.350932 -365.8616) (xy 301.355003 -365.805978) (xy 301.367129 -365.751541)
			(xy 301.387052 -365.69945) (xy 301.414348 -365.650815) (xy 301.448434 -365.606672) (xy 301.488583 -365.567963)
			(xy 301.533941 -365.535512) (xy 301.583541 -365.510011) (xy 301.636325 -365.492004) (xy 301.691168 -365.481874)
			(xy 301.746902 -365.479837) (xy 301.802339 -365.485937) (xy 301.856296 -365.500043) (xy 301.907625 -365.521855)
			(xy 301.955231 -365.550909) (xy 301.998099 -365.586584) (xy 302.035316 -365.628121) (xy 302.066089 -365.674634)
			(xy 302.089761 -365.725131) (xy 302.105829 -365.778538) (xy 302.113949 -365.833714) (xy 302.114458 -365.8616)
			(xy 302.113949 -365.889486) (xy 302.105829 -365.944662) (xy 302.089761 -365.998069) (xy 302.066089 -366.048566)
			(xy 302.035316 -366.095079) (xy 301.998099 -366.136616) (xy 301.955231 -366.172291) (xy 301.907625 -366.201345)
			(xy 301.856296 -366.223157) (xy 301.802339 -366.237263) (xy 301.746902 -366.243363) (xy 301.691168 -366.241326)
			(xy 301.636325 -366.231196) (xy 301.583541 -366.213189) (xy 301.533941 -366.187688) (xy 301.488583 -366.155237)
			(xy 301.448434 -366.116528) (xy 301.414348 -366.072385) (xy 301.387052 -366.02375) (xy 301.367129 -365.971659)
			(xy 301.355003 -365.917222) (xy 301.350932 -365.8616) (xy 297.34002 -365.8616) (xy 296.772593 -366.429027)
			(xy 302.691787 -366.429027) (xy 302.691787 -366.360973) (xy 302.699687 -366.29338) (xy 302.715381 -366.227162)
			(xy 302.738657 -366.163213) (xy 302.769199 -366.102398) (xy 302.806595 -366.045541) (xy 302.850338 -365.993409)
			(xy 302.899838 -365.946708) (xy 302.954425 -365.90607) (xy 303.013361 -365.872043) (xy 303.075849 -365.845089)
			(xy 303.141043 -365.825571) (xy 303.208062 -365.813753) (xy 303.276 -365.809797) (xy 303.343938 -365.813753)
			(xy 303.410957 -365.825571) (xy 303.476151 -365.845089) (xy 303.538639 -365.872043) (xy 303.597575 -365.90607)
			(xy 303.652162 -365.946708) (xy 303.701662 -365.993409) (xy 303.745405 -366.045541) (xy 303.782801 -366.102398)
			(xy 303.813343 -366.163213) (xy 303.836619 -366.227162) (xy 303.852313 -366.29338) (xy 303.860213 -366.360973)
			(xy 303.860708 -366.395) (xy 303.860213 -366.429027) (xy 303.852313 -366.49662) (xy 303.836619 -366.562838)
			(xy 303.813343 -366.626787) (xy 303.782801 -366.687602) (xy 303.745405 -366.744459) (xy 303.701662 -366.796591)
			(xy 303.652162 -366.843292) (xy 303.597575 -366.88393) (xy 303.538639 -366.917957) (xy 303.476151 -366.944911)
			(xy 303.410957 -366.964429) (xy 303.343938 -366.976247) (xy 303.276 -366.980204) (xy 303.208062 -366.976247)
			(xy 303.141043 -366.964429) (xy 303.075849 -366.944911) (xy 303.013361 -366.917957) (xy 302.954425 -366.88393)
			(xy 302.899838 -366.843292) (xy 302.850338 -366.796591) (xy 302.806595 -366.744459) (xy 302.769199 -366.687602)
			(xy 302.738657 -366.626787) (xy 302.715381 -366.562838) (xy 302.699687 -366.49662) (xy 302.691787 -366.429027)
			(xy 296.772593 -366.429027) (xy 296.659046 -366.542574) (xy 296.651646 -366.549415) (xy 296.633047 -366.557133)
			(xy 296.622978 -366.55756) (xy 296.437812 -366.55756) (xy 296.427825 -366.558097) (xy 296.409395 -366.565814)
			(xy 296.401998 -366.572546) (xy 296.022268 -366.952022) (xy 296.014648 -366.973358) (xy 296.015664 -366.984534)
			(xy 296.016621 -366.995876) (xy 296.017639 -367.018618) (xy 296.017696 -367.03) (xy 296.01725 -367.060732)
			(xy 296.009842 -367.121747) (xy 295.995132 -367.181425) (xy 295.973337 -367.238894) (xy 295.944773 -367.293318)
			(xy 295.909857 -367.343901) (xy 295.869098 -367.389907) (xy 295.823092 -367.430664) (xy 295.772507 -367.465579)
			(xy 295.718083 -367.494141) (xy 295.660614 -367.515936) (xy 295.600936 -367.530644) (xy 295.53992 -367.538051)
			(xy 295.509188 -367.538508) (xy 295.480057 -367.53812) (xy 295.422174 -367.531489) (xy 295.36543 -367.518281)
			(xy 295.310569 -367.498669) (xy 295.25831 -367.472911) (xy 295.233598 -367.457482) (xy 295.225216 -367.451894)
			(xy 295.20642 -367.448338) (xy 295.117774 -367.465356) (xy 295.101518 -367.47577) (xy 295.09593 -367.483898)
			(xy 295.078012 -367.508329) (xy 295.037275 -367.553177) (xy 294.9915 -367.59287) (xy 294.941335 -367.626846)
			(xy 294.887491 -367.654626) (xy 294.83073 -367.675815) (xy 294.771853 -367.690114) (xy 294.711696 -367.697321)
			(xy 294.681402 -367.697766) (xy 294.649442 -367.697285) (xy 294.586027 -367.689274) (xy 294.524115 -367.673378)
			(xy 294.464684 -367.649848) (xy 294.408671 -367.619055) (xy 294.356959 -367.581484) (xy 294.310363 -367.537728)
			(xy 294.269619 -367.488477) (xy 294.235369 -367.434508) (xy 294.208154 -367.376672) (xy 294.188401 -367.315881)
			(xy 294.176424 -367.253093) (xy 294.17241 -367.1893) (xy 294.176424 -367.125507) (xy 294.188401 -367.062719)
			(xy 294.208154 -367.001928) (xy 294.235369 -366.944092) (xy 294.269619 -366.890123) (xy 294.310363 -366.840872)
			(xy 294.356959 -366.797116) (xy 294.408671 -366.759545) (xy 294.464684 -366.728752) (xy 294.524115 -366.705222)
			(xy 294.586027 -366.689326) (xy 294.649442 -366.681315) (xy 294.681402 -366.68075) (xy 294.710533 -366.681137)
			(xy 294.768417 -366.687767) (xy 294.825162 -366.700973) (xy 294.880025 -366.720582) (xy 294.932285 -366.746338)
			(xy 294.956992 -366.761776) (xy 294.965374 -366.767364) (xy 294.98417 -366.77092) (xy 295.072816 -366.753902)
			(xy 295.089072 -366.743488) (xy 295.09466 -366.73536) (xy 295.105328 -366.720882) (xy 295.114218 -366.709452)
			(xy 295.117012 -366.680496) (xy 295.070276 -366.585754) (xy 295.065698 -366.577509) (xy 295.051789 -366.564796)
			(xy 295.034231 -366.557959) (xy 295.02481 -366.55756) (xy 294.22598 -366.55756) (xy 294.220392 -366.55883)
			(xy 294.192146 -366.564918) (xy 294.13473 -366.571413) (xy 294.105838 -366.571784) (xy 275.710396 -366.571784)
			(xy 275.681504 -366.571407) (xy 275.624088 -366.564917) (xy 275.595842 -366.55883) (xy 275.590254 -366.55756)
			(xy 275.532342 -366.55756) (xy 275.522277 -366.557125) (xy 275.503692 -366.549391) (xy 275.496274 -366.542574)
			(xy 275.459444 -366.505744) (xy 275.453602 -366.502442) (xy 275.425798 -366.485505) (xy 275.374333 -366.44563)
			(xy 275.350986 -366.42294) (xy 274.3073 -365.379254) (xy 274.299904 -365.372402) (xy 274.281306 -365.364659)
			(xy 274.271232 -365.364268) (xy 271.25168 -365.364268) (xy 271.220994 -365.363806) (xy 271.160069 -365.356419)
			(xy 271.100475 -365.341756) (xy 271.043078 -365.320028) (xy 270.988713 -365.291552) (xy 270.938169 -365.256742)
			(xy 270.914876 -365.23676) (xy 270.907665 -365.230948) (xy 270.890347 -365.224421) (xy 270.881094 -365.22406)
			(xy 270.767302 -365.22406) (xy 270.757233 -365.223636) (xy 270.738631 -365.215918) (xy 270.731234 -365.209074)
			(xy 268.482826 -362.960666) (xy 268.475427 -362.953824) (xy 268.456828 -362.946106) (xy 268.446758 -362.94568)
			(xy 261.82193 -362.94568) (xy 261.813197 -362.946025) (xy 261.796748 -362.951896) (xy 261.78326 -362.962991)
			(xy 261.778496 -362.970318) (xy 261.729828 -363.049936) (xy 261.626464 -363.205324) (xy 261.516408 -363.356045)
			(xy 261.399868 -363.501812) (xy 261.277069 -363.642346) (xy 261.148243 -363.777377) (xy 261.013639 -363.906648)
			(xy 260.873512 -364.029912) (xy 260.728132 -364.146933) (xy 260.577775 -364.257487) (xy 260.42273 -364.361364)
			(xy 260.263292 -364.458363) (xy 260.099766 -364.548301) (xy 259.932466 -364.631006) (xy 259.76171 -364.706318)
			(xy 259.587826 -364.774094) (xy 259.411145 -364.834205) (xy 259.232006 -364.886535) (xy 259.05075 -364.930985)
			(xy 258.867725 -364.96747) (xy 258.683279 -364.99592) (xy 258.497767 -365.01628) (xy 258.311542 -365.028511)
			(xy 258.12496 -365.032591) (xy 257.938378 -365.028511) (xy 257.752153 -365.01628) (xy 257.566641 -364.99592)
			(xy 257.382195 -364.96747) (xy 257.19917 -364.930985) (xy 257.017914 -364.886535) (xy 256.838775 -364.834205)
			(xy 256.662094 -364.774094) (xy 256.48821 -364.706318) (xy 256.317454 -364.631006) (xy 256.150154 -364.548301)
			(xy 255.986628 -364.458363) (xy 255.82719 -364.361364) (xy 255.672145 -364.257487) (xy 255.521788 -364.146933)
			(xy 255.376408 -364.029912) (xy 255.236281 -363.906648) (xy 255.101677 -363.777377) (xy 254.972851 -363.642346)
			(xy 254.850052 -363.501812) (xy 254.733512 -363.356045) (xy 254.623456 -363.205324) (xy 254.520092 -363.049936)
			(xy 254.471424 -362.970318) (xy 254.466608 -362.96304) (xy 254.453114 -362.951993) (xy 254.436708 -362.946081)
			(xy 254.42799 -362.94568) (xy 236.042962 -362.94568) (xy 236.032894 -362.946109) (xy 236.014298 -362.953831)
			(xy 236.006894 -362.960666) (xy 231.37241 -367.59515) (xy 231.371394 -367.635282) (xy 231.384856 -367.650522)
			(xy 231.405181 -367.673895) (xy 231.440608 -367.724706) (xy 231.469601 -367.779444) (xy 231.491731 -367.837298)
			(xy 231.506671 -367.897412) (xy 231.514198 -367.958895) (xy 231.51465 -367.989866) (xy 231.514188 -368.020599)
			(xy 231.506784 -368.081618) (xy 231.492078 -368.1413) (xy 231.470286 -368.198773) (xy 231.441725 -368.253201)
			(xy 231.406811 -368.30379) (xy 231.366055 -368.349801) (xy 231.32005 -368.390564) (xy 231.269466 -368.425485)
			(xy 231.215043 -368.454054) (xy 231.157572 -368.475855) (xy 231.097893 -368.49057) (xy 231.036875 -368.497984)
			(xy 231.006142 -368.498374) (xy 230.974342 -368.497879) (xy 230.911238 -368.489943) (xy 230.849615 -368.474202)
			(xy 230.790436 -368.450902) (xy 230.734623 -368.420406) (xy 230.683048 -368.383189) (xy 230.636514 -368.339834)
			(xy 230.615744 -368.315748) (xy 230.60819 -368.307532) (xy 230.588026 -368.29803) (xy 230.576882 -368.29746)
			(xy 227.274374 -368.29746) (xy 227.250194 -368.297001) (xy 227.202424 -368.289472) (xy 227.156418 -368.274571)
			(xy 227.113305 -368.252664) (xy 227.074145 -368.224289) (xy 227.056696 -368.207544) (xy 226.892358 -368.043206)
			(xy 226.885011 -368.036401) (xy 226.866548 -368.028683) (xy 226.856544 -368.02822) (xy 224.70745 -368.02822)
			(xy 224.696727 -368.02864) (xy 224.677125 -368.037328) (xy 224.669604 -368.044984) (xy 224.611692 -368.108992)
			(xy 224.605088 -368.129312) (xy 224.606358 -368.140234) (xy 224.607803 -368.155241) (xy 224.60933 -368.185355)
			(xy 224.609406 -368.200432) (xy 224.608871 -368.235767) (xy 224.600349 -368.305921) (xy 224.583434 -368.374536)
			(xy 224.558371 -368.440612) (xy 224.525527 -368.503186) (xy 224.48538 -368.561344) (xy 224.438515 -368.61424)
			(xy 224.385617 -368.661101) (xy 224.327456 -368.701244) (xy 224.264881 -368.734085) (xy 224.198803 -368.759144)
			(xy 224.130187 -368.776055) (xy 224.060033 -368.784573) (xy 224.024698 -368.78514) (xy 223.985218 -368.784509)
			(xy 223.906971 -368.773937) (xy 223.868742 -368.764058) (xy 223.862138 -368.76228) (xy 216.985342 -368.76228)
			(xy 216.97531 -368.762718) (xy 216.956734 -368.770292) (xy 216.949274 -368.777012) (xy 216.560654 -369.165886)
			(xy 216.538058 -369.187866) (xy 216.488756 -369.227155) (xy 216.435364 -369.260673) (xy 216.378552 -369.287998)
			(xy 216.319038 -369.308788) (xy 216.257569 -369.322779) (xy 216.194919 -369.329796) (xy 216.163398 -369.330224)
			(xy 190.221616 -369.330224) (xy 190.190096 -369.329794) (xy 190.127451 -369.322762) (xy 190.065987 -369.308761)
			(xy 190.006476 -369.287968) (xy 189.949666 -369.260644) (xy 189.896273 -369.227133) (xy 189.846966 -369.187855)
			(xy 189.82436 -369.165886) (xy 189.180216 -368.521488) (xy 189.172792 -368.514709) (xy 189.154195 -368.507111)
			(xy 189.144148 -368.506756) (xy 185.737754 -368.506756) (xy 185.727722 -368.507194) (xy 185.70915 -368.514773)
			(xy 185.701686 -368.521488) (xy 185.163968 -369.05946) (xy 185.14138 -369.081461) (xy 185.092092 -369.120793)
			(xy 185.038707 -369.154354) (xy 184.981898 -369.181723) (xy 184.92238 -369.202554) (xy 184.860903 -369.216586)
			(xy 184.798241 -369.223641) (xy 184.766712 -369.224052) (xy 181.196234 -369.224052) (xy 181.164707 -369.223623)
			(xy 181.102051 -369.216555) (xy 181.04058 -369.202515) (xy 180.981068 -369.181681) (xy 180.924263 -369.154313)
			(xy 180.87088 -369.120757) (xy 180.82159 -369.081434) (xy 180.798978 -369.05946) (xy 176.773332 -365.03356)
			(xy 176.765907 -365.026782) (xy 176.747311 -365.019183) (xy 176.737264 -365.018828) (xy 173.965616 -365.018828)
			(xy 173.93409 -365.018381) (xy 173.871436 -365.011312) (xy 173.809966 -364.997273) (xy 173.750456 -364.97644)
			(xy 173.693651 -364.949075) (xy 173.640268 -364.915522) (xy 173.590978 -364.876203) (xy 173.56836 -364.854236)
			(xy 167.93083 -359.216706) (xy 167.923481 -359.209906) (xy 167.905018 -359.202198) (xy 167.895016 -359.20172)
			(xy 136.205722 -359.20172) (xy 136.195659 -359.202158) (xy 136.177077 -359.209894) (xy 136.169654 -359.216706)
			(xy 134.382256 -361.004104) (xy 165.274498 -361.004104) (xy 165.274959 -360.976851) (xy 165.282716 -360.9229)
			(xy 165.298071 -360.870601) (xy 165.320714 -360.821021) (xy 165.350182 -360.775167) (xy 165.385876 -360.733975)
			(xy 165.427069 -360.698281) (xy 165.472923 -360.668813) (xy 165.522503 -360.646171) (xy 165.574802 -360.630815)
			(xy 165.628753 -360.623059) (xy 165.656006 -360.622596) (xy 165.684279 -360.623102) (xy 165.740207 -360.63145)
			(xy 165.794289 -360.647961) (xy 165.845342 -360.672274) (xy 165.892247 -360.703856) (xy 165.933977 -360.742016)
			(xy 165.969617 -360.785918) (xy 165.998386 -360.834599) (xy 166.019655 -360.886993) (xy 166.032957 -360.941953)
			(xy 166.03599 -360.970068) (xy 166.036752 -360.979466) (xy 166.04488 -360.995976) (xy 166.10711 -361.055158)
			(xy 166.124128 -361.06227) (xy 166.133272 -361.062524) (xy 166.163305 -361.064083) (xy 166.222627 -361.073982)
			(xy 166.280203 -361.091358) (xy 166.335096 -361.115928) (xy 166.386411 -361.147293) (xy 166.433312 -361.184941)
			(xy 166.475033 -361.228257) (xy 166.510895 -361.276537) (xy 166.540312 -361.328992) (xy 166.562806 -361.384769)
			(xy 166.57801 -361.442957) (xy 166.585676 -361.502607) (xy 166.586154 -361.532678) (xy 166.585735 -361.560546)
			(xy 166.579167 -361.615893) (xy 166.56611 -361.670078) (xy 166.546745 -361.722342) (xy 166.521344 -361.771953)
			(xy 166.506144 -361.795314) (xy 166.502117 -361.801723) (xy 166.497715 -361.816196) (xy 166.497508 -361.823762)
			(xy 166.497508 -362.105194) (xy 166.497801 -362.112747) (xy 166.502181 -362.127206) (xy 166.506144 -362.133642)
			(xy 166.521343 -362.157006) (xy 166.546763 -362.206609) (xy 166.566139 -362.258871) (xy 166.579199 -362.313058)
			(xy 166.585758 -362.368409) (xy 166.586154 -362.396278) (xy 166.586076 -362.407854) (xy 166.584933 -362.430979)
			(xy 166.583868 -362.442506) (xy 166.582852 -362.452158) (xy 166.587932 -362.469938) (xy 166.640256 -362.540296)
			(xy 166.65575 -362.550202) (xy 166.665402 -362.55198) (xy 166.691097 -362.557465) (xy 166.740766 -362.574602)
			(xy 166.787615 -362.59839) (xy 166.830758 -362.62838) (xy 166.869379 -362.664004) (xy 166.902748 -362.70459)
			(xy 166.930234 -362.749369) (xy 166.951317 -362.797496) (xy 166.965599 -362.84806) (xy 166.97281 -362.900105)
			(xy 166.97325 -362.926376) (xy 166.9727 -362.953625) (xy 166.964947 -363.007568) (xy 166.949597 -363.059859)
			(xy 166.926962 -363.109433) (xy 166.897502 -363.155282) (xy 166.861818 -363.196471) (xy 166.820634 -363.232163)
			(xy 166.774791 -363.261631) (xy 166.725221 -363.284274) (xy 166.672932 -363.299633) (xy 166.618991 -363.307395)
			(xy 166.591742 -363.307884) (xy 166.563424 -363.307352) (xy 166.507413 -363.298958) (xy 166.453259 -363.282376)
			(xy 166.40215 -363.257973) (xy 166.355209 -363.226282) (xy 166.313469 -363.188002) (xy 166.277845 -363.143972)
			(xy 166.24912 -363.095161) (xy 166.227926 -363.04264) (xy 166.214728 -362.987563) (xy 166.211758 -362.959396)
			(xy 166.210742 -362.949744) (xy 166.202614 -362.933234) (xy 166.138352 -362.873544) (xy 166.12108 -362.866686)
			(xy 166.111428 -362.866686) (xy 166.080812 -362.865965) (xy 166.020163 -362.857454) (xy 165.961131 -362.841145)
			(xy 165.904715 -362.817314) (xy 165.851868 -362.786363) (xy 165.803484 -362.748817) (xy 165.760381 -362.70531)
			(xy 165.723288 -362.656577) (xy 165.692833 -362.603443) (xy 165.66953 -362.546807) (xy 165.653773 -362.487625)
			(xy 165.645829 -362.4269) (xy 165.645338 -362.396278) (xy 165.645737 -362.368409) (xy 165.652309 -362.313061)
			(xy 165.665372 -362.258876) (xy 165.684741 -362.206613) (xy 165.710146 -362.157003) (xy 165.725348 -362.133642)
			(xy 165.729391 -362.127242) (xy 165.733783 -362.112762) (xy 165.733984 -362.105194) (xy 165.733984 -361.823762)
			(xy 165.73371 -361.816207) (xy 165.729317 -361.801749) (xy 165.725348 -361.795314) (xy 165.71013 -361.771963)
			(xy 165.684712 -361.722355) (xy 165.665341 -361.67009) (xy 165.652286 -361.615901) (xy 165.645732 -361.560548)
			(xy 165.645338 -361.532678) (xy 165.645443 -361.520718) (xy 165.646714 -361.49683) (xy 165.647878 -361.484926)
			(xy 165.64864 -361.475782) (xy 165.644068 -361.457748) (xy 165.59403 -361.388152) (xy 165.57879 -361.377738)
			(xy 165.569646 -361.375706) (xy 165.542039 -361.368744) (xy 165.489115 -361.347759) (xy 165.439897 -361.319143)
			(xy 165.395478 -361.283529) (xy 165.356845 -361.241711) (xy 165.324856 -361.194615) (xy 165.300221 -361.143288)
			(xy 165.283487 -361.088871) (xy 165.275025 -361.03257) (xy 165.274498 -361.004104) (xy 134.382256 -361.004104)
			(xy 131.724146 -363.662214) (xy 131.716749 -363.669061) (xy 131.698149 -363.676789) (xy 131.688078 -363.6772)
			(xy 131.277106 -363.6772) (xy 131.267118 -363.677736) (xy 131.248684 -363.685448) (xy 131.241292 -363.692186)
			(xy 131.225232 -363.708188) (xy 170.603926 -363.708188) (xy 170.604428 -363.676227) (xy 170.612439 -363.612809)
			(xy 170.628336 -363.550895) (xy 170.651868 -363.491462) (xy 170.682662 -363.435447) (xy 170.720235 -363.383732)
			(xy 170.763992 -363.337135) (xy 170.813245 -363.29639) (xy 170.867216 -363.262139) (xy 170.925055 -363.234922)
			(xy 170.985848 -363.215169) (xy 171.048638 -363.203191) (xy 171.112434 -363.199178) (xy 171.17623 -363.203191)
			(xy 171.23902 -363.215169) (xy 171.299813 -363.234922) (xy 171.357652 -363.262139) (xy 171.411623 -363.29639)
			(xy 171.460876 -363.337135) (xy 171.504633 -363.383732) (xy 171.542206 -363.435447) (xy 171.573 -363.491462)
			(xy 171.596532 -363.550895) (xy 171.612429 -363.612809) (xy 171.62044 -363.676227) (xy 171.620942 -363.708188)
			(xy 171.620676 -363.730856) (xy 171.616611 -363.776009) (xy 171.612814 -363.798358) (xy 171.611661 -363.807576)
			(xy 171.615157 -363.825802) (xy 171.619672 -363.833918) (xy 171.635674 -363.86008) (xy 171.640881 -363.86778)
			(xy 171.655603 -363.879105) (xy 171.664376 -363.882178) (xy 171.695449 -363.891974) (xy 171.755001 -363.918404)
			(xy 171.810688 -363.952226) (xy 171.861598 -363.992886) (xy 171.906895 -364.039716) (xy 171.945839 -364.09195)
			(xy 171.97779 -364.148732) (xy 172.002224 -364.20913) (xy 172.018742 -364.272155) (xy 172.027073 -364.336773)
			(xy 172.027596 -364.36935) (xy 172.027094 -364.401311) (xy 172.019083 -364.464729) (xy 172.003186 -364.526643)
			(xy 171.979654 -364.586076) (xy 171.94886 -364.642091) (xy 171.911287 -364.693806) (xy 171.86753 -364.740403)
			(xy 171.818277 -364.781148) (xy 171.764306 -364.815399) (xy 171.706467 -364.842616) (xy 171.645674 -364.862369)
			(xy 171.582884 -364.874347) (xy 171.519088 -364.878361) (xy 171.455292 -364.874347) (xy 171.392502 -364.862369)
			(xy 171.331709 -364.842616) (xy 171.27387 -364.815399) (xy 171.219899 -364.781148) (xy 171.170646 -364.740403)
			(xy 171.126889 -364.693806) (xy 171.089316 -364.642091) (xy 171.058522 -364.586076) (xy 171.03499 -364.526643)
			(xy 171.019093 -364.464729) (xy 171.011082 -364.401311) (xy 171.01058 -364.36935) (xy 171.010837 -364.346682)
			(xy 171.014909 -364.301529) (xy 171.018708 -364.27918) (xy 171.019904 -364.269965) (xy 171.016381 -364.251733)
			(xy 171.01185 -364.24362) (xy 170.995848 -364.217458) (xy 170.990625 -364.209771) (xy 170.975915 -364.198437)
			(xy 170.967146 -364.19536) (xy 170.936089 -364.185516) (xy 170.876538 -364.159091) (xy 170.820852 -364.125275)
			(xy 170.769942 -364.084621) (xy 170.724644 -364.037796) (xy 170.685699 -363.985567) (xy 170.653746 -363.928791)
			(xy 170.629308 -363.868398) (xy 170.612787 -363.805378) (xy 170.604452 -363.740763) (xy 170.603926 -363.708188)
			(xy 131.225232 -363.708188) (xy 131.171442 -363.761782) (xy 131.164094 -363.768585) (xy 131.145632 -363.776299)
			(xy 131.135628 -363.776768) (xy 47.390558 -363.776768) (xy 47.381069 -363.777168) (xy 47.363343 -363.783937)
			(xy 47.356014 -363.789976) (xy 47.319103 -363.823227) (xy 47.240905 -363.884515) (xy 47.158157 -363.939507)
			(xy 47.071366 -363.987866) (xy 46.981063 -364.029297) (xy 46.887798 -364.063545) (xy 46.792143 -364.090402)
			(xy 46.694682 -364.109704) (xy 46.59601 -364.121333) (xy 46.496732 -364.125217) (xy 46.397454 -364.121333)
			(xy 46.298782 -364.109704) (xy 46.201321 -364.090402) (xy 46.105666 -364.063545) (xy 46.012401 -364.029297)
			(xy 45.922098 -363.987866) (xy 45.835307 -363.939507) (xy 45.752559 -363.884515) (xy 45.674361 -363.823227)
			(xy 45.63745 -363.789976) (xy 45.630166 -363.783862) (xy 45.612412 -363.777088) (xy 45.602906 -363.776768)
			(xy 44.716192 -363.776768) (xy 44.706163 -363.777215) (xy 44.6876 -363.7848) (xy 44.680124 -363.7915)
			(xy 44.064682 -364.406942) (xy 44.057338 -364.413756) (xy 44.038875 -364.421491) (xy 44.028868 -364.421928)
			(xy 41.23182 -364.421928) (xy 41.22183 -364.421395) (xy 41.20339 -364.41369) (xy 41.196006 -364.406942)
			(xy 40.126412 -363.337602) (xy 40.1103 -363.320893) (xy 40.082809 -363.283494) (xy 40.061298 -363.242363)
			(xy 40.046264 -363.198449) (xy 40.038054 -363.152765) (xy 40.037004 -363.129576) (xy 40.03675 -363.11967)
			(xy 40.02913 -363.10189) (xy 39.989506 -363.062266) (xy 39.982664 -363.054866) (xy 39.974941 -363.036268)
			(xy 39.97452 -363.026198) (xy 39.97452 -362.118402) (xy 39.974098 -362.108331) (xy 39.966386 -362.089724)
			(xy 39.959534 -362.082334) (xy 38.952678 -361.075478) (xy 38.945335 -361.068662) (xy 38.926872 -361.060926)
			(xy 38.916864 -361.060492) (xy 36.367466 -361.060492) (xy 36.341687 -361.059958) (xy 36.290862 -361.051292)
			(xy 36.242221 -361.034195) (xy 36.197151 -361.009155) (xy 36.176712 -360.993436) (xy 36.169854 -360.988102)
			(xy 36.153598 -360.98226) (xy 36.142422 -360.98226) (xy 36.132359 -360.981821) (xy 36.113779 -360.974083)
			(xy 36.106354 -360.967274) (xy 33.073848 -357.934768) (xy 33.066439 -357.92808) (xy 33.048004 -357.920485)
			(xy 33.038034 -357.920036) (xy 31.40837 -357.920036) (xy 31.398391 -357.920468) (xy 31.379916 -357.928002)
			(xy 31.365727 -357.94203) (xy 31.36138 -357.951024) (xy 31.345209 -357.98843) (xy 31.305998 -358.059875)
			(xy 31.259389 -358.126728) (xy 31.205912 -358.188227) (xy 31.146179 -358.243669) (xy 31.080872 -358.292421)
			(xy 31.010736 -358.333927) (xy 30.936572 -358.367713) (xy 30.859226 -358.393393) (xy 30.779582 -358.410674)
			(xy 30.698549 -358.419359) (xy 30.6578 -358.419908) (xy 30.6248 -358.419545) (xy 30.559048 -358.413823)
			(xy 30.526482 -358.408478) (xy 30.51429 -358.406446) (xy 30.490668 -358.413812) (xy 30.4673 -358.43718)
			(xy 30.460442 -358.449626) (xy 30.458918 -358.456484) (xy 30.449798 -358.49389) (xy 30.425603 -358.566988)
			(xy 30.394807 -358.63756) (xy 30.357672 -358.705012) (xy 30.314508 -358.768774) (xy 30.26568 -358.828311)
			(xy 30.238954 -358.856026) (xy 30.231588 -358.863392) (xy 30.224222 -358.881426) (xy 30.224222 -358.973374)
			(xy 30.231588 -358.991408) (xy 30.238954 -358.998774) (xy 30.267265 -359.028184) (xy 30.318664 -359.091613)
			(xy 30.363658 -359.159735) (xy 30.401823 -359.231905) (xy 30.432797 -359.30744) (xy 30.456287 -359.385627)
			(xy 30.472072 -359.465727) (xy 30.480002 -359.54698) (xy 30.480508 -359.5878) (xy 30.480003 -359.628978)
			(xy 30.47193 -359.710938) (xy 30.455863 -359.791712) (xy 30.431956 -359.870523) (xy 30.40044 -359.94661)
			(xy 30.361617 -360.019242) (xy 30.315863 -360.087719) (xy 30.263616 -360.151381) (xy 30.205381 -360.209616)
			(xy 30.141719 -360.261863) (xy 30.073242 -360.307617) (xy 30.00061 -360.34644) (xy 29.924523 -360.377956)
			(xy 29.845712 -360.401863) (xy 29.764938 -360.41793) (xy 29.682978 -360.426003) (xy 29.600622 -360.426003)
			(xy 29.518662 -360.41793) (xy 29.437888 -360.401863) (xy 29.359077 -360.377956) (xy 29.28299 -360.34644)
			(xy 29.210358 -360.307617) (xy 29.141881 -360.261863) (xy 29.078219 -360.209616) (xy 29.019984 -360.151381)
			(xy 28.967737 -360.087719) (xy 28.921983 -360.019242) (xy 28.88316 -359.94661) (xy 28.851644 -359.870523)
			(xy 28.827737 -359.791712) (xy 28.81167 -359.710938) (xy 28.803597 -359.628978) (xy 28.803092 -359.5878)
			(xy 28.803579 -359.54698) (xy 28.81151 -359.465725) (xy 28.827297 -359.385626) (xy 28.85079 -359.307438)
			(xy 28.881768 -359.231903) (xy 28.919936 -359.159735) (xy 28.964935 -359.091615) (xy 29.016339 -359.028189)
			(xy 29.044646 -358.998774) (xy 29.052012 -358.991408) (xy 29.059378 -358.973374) (xy 29.059378 -358.881426)
			(xy 29.052012 -358.863392) (xy 29.044646 -358.856026) (xy 29.016802 -358.827089) (xy 28.96617 -358.76475)
			(xy 28.943554 -358.731566) (xy 28.935988 -358.721467) (xy 28.913739 -358.709624) (xy 28.901136 -358.70896)
			(xy 28.605988 -358.70896) (xy 28.594229 -358.709549) (xy 28.573166 -358.720005) (xy 28.565602 -358.729026)
			(xy 28.541595 -358.75973) (xy 28.488281 -358.816591) (xy 28.429445 -358.867716) (xy 28.365701 -358.912572)
			(xy 28.297713 -358.950692) (xy 28.226192 -358.981678) (xy 28.151882 -359.005205) (xy 28.07556 -359.02103)
			(xy 27.998023 -359.028986) (xy 27.95905 -359.029508) (xy 27.919113 -359.029006) (xy 27.839677 -359.020662)
			(xy 27.761549 -359.00406) (xy 27.685584 -358.979381) (xy 27.612614 -358.946898) (xy 27.54344 -358.906964)
			(xy 27.47882 -358.860018) (xy 27.419461 -358.806575) (xy 27.366013 -358.747219) (xy 27.319063 -358.682602)
			(xy 27.279125 -358.61343) (xy 27.246637 -358.540463) (xy 27.221953 -358.4645) (xy 27.205346 -358.386372)
			(xy 27.196997 -358.306937) (xy 27.196542 -358.267) (xy 27.197168 -358.22342) (xy 27.207104 -358.136829)
			(xy 27.226836 -358.051932) (xy 27.256107 -357.969834) (xy 27.274774 -357.93045) (xy 27.2796 -357.920544)
			(xy 27.280362 -357.898446) (xy 27.272488 -357.879904) (xy 27.270431 -357.87554) (xy 27.264931 -357.867614)
			(xy 27.261566 -357.864156) (xy 26.913332 -357.515922) (xy 26.896663 -357.498653) (xy 26.86843 -357.459841)
			(xy 26.846635 -357.41708) (xy 26.831818 -357.37143) (xy 26.824347 -357.32402) (xy 26.823924 -357.300022)
			(xy 26.823924 -356.84333) (xy 26.82374 -356.838161) (xy 26.821568 -356.82805) (xy 26.819606 -356.823264)
			(xy 26.597864 -356.305612) (xy 26.595972 -356.300812) (xy 26.593921 -356.290703) (xy 26.5938 -356.285546)
			(xy 26.5938 -356.145084) (xy 26.59326 -356.135098) (xy 26.585542 -356.11667) (xy 26.578814 -356.10927)
			(xy 25.381204 -354.91166) (xy 25.364237 -354.894025) (xy 25.335573 -354.854363) (xy 25.313593 -354.810641)
			(xy 25.305766 -354.787454) (xy 25.303988 -354.781612) (xy 25.297892 -354.771452) (xy 25.29332 -354.76688)
			(xy 25.29332 -354.727256) (xy 25.293066 -354.72497) (xy 25.291796 -354.69576) (xy 25.291796 -351.695004)
			(xy 25.291259 -351.685016) (xy 25.283546 -351.666584) (xy 25.27681 -351.65919) (xy 25.216866 -351.599246)
			(xy 25.209468 -351.5924) (xy 25.190869 -351.584671) (xy 25.180798 -351.58426) (xy 24.5364 -351.58426)
			(xy 24.526389 -351.584747) (xy 24.507891 -351.592406) (xy 24.493728 -351.606557) (xy 24.486055 -351.62505)
			(xy 24.4856 -351.63506) (xy 24.4856 -355.329236) (xy 24.486035 -355.33927) (xy 24.493605 -355.357849)
			(xy 24.500332 -355.365304) (xy 26.23947 -357.104188) (xy 26.265061 -357.130625) (xy 26.309815 -357.189029)
			(xy 26.346556 -357.252778) (xy 26.361136 -357.28656) (xy 27.46121 -359.942384) (xy 27.474754 -359.976575)
			(xy 27.493847 -360.047594) (xy 27.503511 -360.120498) (xy 27.504136 -360.157268) (xy 27.504136 -360.538014)
			(xy 27.504614 -360.54798) (xy 27.512192 -360.566414) (xy 27.518868 -360.573828) (xy 28.339034 -361.393994)
			(xy 28.346434 -361.400836) (xy 28.365032 -361.408559) (xy 28.375102 -361.40898) (xy 30.489398 -361.40898)
			(xy 30.499468 -361.408557) (xy 30.518071 -361.400841) (xy 30.525466 -361.393994) (xy 30.97276 -360.9467)
			(xy 30.979506 -360.939331) (xy 30.987105 -360.920869) (xy 30.987492 -360.910886) (xy 30.987492 -360.553)
			(xy 30.987974 -360.517339) (xy 30.995962 -360.446465) (xy 31.011837 -360.376932) (xy 31.0354 -360.309614)
			(xy 31.066353 -360.245359) (xy 31.104309 -360.184974) (xy 31.148788 -360.129221) (xy 31.173674 -360.103674)
			(xy 31.554674 -359.722674) (xy 31.56489 -359.712604) (xy 31.586108 -359.693293) (xy 31.597092 -359.684066)
			(xy 31.605342 -359.676461) (xy 31.614827 -359.656158) (xy 31.61538 -359.64495) (xy 31.61538 -359.412032)
			(xy 31.615209 -359.4053) (xy 31.611734 -359.392296) (xy 31.608522 -359.386378) (xy 31.593738 -359.360051)
			(xy 31.570462 -359.304338) (xy 31.554721 -359.246046) (xy 31.546788 -359.18619) (xy 31.546292 -359.156)
			(xy 31.546782 -359.126032) (xy 31.554605 -359.06661) (xy 31.570118 -359.008717) (xy 31.593054 -358.953344)
			(xy 31.623021 -358.901438) (xy 31.659508 -358.853888) (xy 31.701888 -358.811508) (xy 31.749438 -358.775021)
			(xy 31.801344 -358.745054) (xy 31.856717 -358.722118) (xy 31.91461 -358.706605) (xy 31.974032 -358.698782)
			(xy 32.004 -358.698292) (xy 32.03331 -358.69876) (xy 32.091449 -358.706247) (xy 32.148155 -358.7211)
			(xy 32.2025 -358.743074) (xy 32.253592 -358.77181) (xy 32.300596 -358.806836) (xy 32.342741 -358.84758)
			(xy 32.379336 -358.893373) (xy 32.409782 -358.943466) (xy 32.422084 -358.970072) (xy 32.426148 -358.978708)
			(xy 34.765488 -361.318048) (xy 34.788602 -361.325414) (xy 34.801048 -361.323382) (xy 34.827078 -361.319254)
			(xy 34.879597 -361.314803) (xy 34.90595 -361.314492) (xy 34.941608 -361.314971) (xy 35.012476 -361.322953)
			(xy 35.082004 -361.338822) (xy 35.149317 -361.362379) (xy 35.213568 -361.393327) (xy 35.273948 -361.431277)
			(xy 35.329698 -361.47575) (xy 35.380117 -361.526188) (xy 35.424568 -361.581956) (xy 35.462494 -361.642351)
			(xy 35.493417 -361.706614) (xy 35.516947 -361.773937) (xy 35.532789 -361.843471) (xy 35.540743 -361.914342)
			(xy 35.541204 -361.95) (xy 35.541204 -362.108961) (xy 37.820594 -362.108961) (xy 37.820594 -362.045039)
			(xy 37.828605 -361.981621) (xy 37.844502 -361.919707) (xy 37.868034 -361.860274) (xy 37.898828 -361.804259)
			(xy 37.936401 -361.752544) (xy 37.980158 -361.705947) (xy 38.029411 -361.665202) (xy 38.083382 -361.630951)
			(xy 38.141221 -361.603734) (xy 38.202014 -361.583981) (xy 38.264804 -361.572003) (xy 38.3286 -361.56799)
			(xy 38.392396 -361.572003) (xy 38.455186 -361.583981) (xy 38.515979 -361.603734) (xy 38.573818 -361.630951)
			(xy 38.627789 -361.665202) (xy 38.677042 -361.705947) (xy 38.720799 -361.752544) (xy 38.758372 -361.804259)
			(xy 38.789166 -361.860274) (xy 38.812698 -361.919707) (xy 38.828595 -361.981621) (xy 38.836606 -362.045039)
			(xy 38.837108 -362.077) (xy 38.836606 -362.108961) (xy 38.828595 -362.172379) (xy 38.812698 -362.234293)
			(xy 38.789166 -362.293726) (xy 38.758372 -362.349741) (xy 38.720799 -362.401456) (xy 38.677042 -362.448053)
			(xy 38.627789 -362.488798) (xy 38.573818 -362.523049) (xy 38.515979 -362.550266) (xy 38.455186 -362.570019)
			(xy 38.392396 -362.581997) (xy 38.3286 -362.586011) (xy 38.264804 -362.581997) (xy 38.202014 -362.570019)
			(xy 38.141221 -362.550266) (xy 38.083382 -362.523049) (xy 38.029411 -362.488798) (xy 37.980158 -362.448053)
			(xy 37.936401 -362.401456) (xy 37.898828 -362.349741) (xy 37.868034 -362.293726) (xy 37.844502 -362.234293)
			(xy 37.828605 -362.172379) (xy 37.820594 -362.108961) (xy 35.541204 -362.108961) (xy 35.541204 -362.304076)
			(xy 35.541737 -362.314065) (xy 35.549445 -362.332503) (xy 35.55619 -362.33989) (xy 35.604958 -362.388658)
			(xy 35.634676 -362.3945) (xy 35.649154 -362.388658) (xy 35.683915 -362.374727) (xy 35.755575 -362.352962)
			(xy 35.829024 -362.338329) (xy 35.903554 -362.330966) (xy 35.941 -362.330492) (xy 35.980934 -362.331015)
			(xy 36.060364 -362.339363) (xy 36.138487 -362.355969) (xy 36.214446 -362.380649) (xy 36.287409 -362.413134)
			(xy 36.356576 -362.453068) (xy 36.421191 -362.500014) (xy 36.480544 -362.553456) (xy 36.533986 -362.612809)
			(xy 36.580932 -362.677424) (xy 36.620866 -362.746591) (xy 36.653351 -362.819554) (xy 36.678031 -362.895513)
			(xy 36.694637 -362.973636) (xy 36.702985 -363.053066) (xy 36.703508 -363.093) (xy 37.946582 -363.093)
			(xy 37.950653 -363.037378) (xy 37.962779 -362.982941) (xy 37.982702 -362.93085) (xy 38.009998 -362.882215)
			(xy 38.044084 -362.838072) (xy 38.084233 -362.799363) (xy 38.129591 -362.766912) (xy 38.179191 -362.741411)
			(xy 38.231975 -362.723404) (xy 38.286818 -362.713274) (xy 38.342552 -362.711237) (xy 38.397989 -362.717337)
			(xy 38.451946 -362.731443) (xy 38.503275 -362.753255) (xy 38.550881 -362.782309) (xy 38.593749 -362.817984)
			(xy 38.630966 -362.859521) (xy 38.661739 -362.906034) (xy 38.685411 -362.956531) (xy 38.701479 -363.009938)
			(xy 38.709599 -363.065114) (xy 38.710108 -363.093) (xy 38.709599 -363.120886) (xy 38.701479 -363.176062)
			(xy 38.685411 -363.229469) (xy 38.661739 -363.279966) (xy 38.630966 -363.326479) (xy 38.593749 -363.368016)
			(xy 38.550881 -363.403691) (xy 38.503275 -363.432745) (xy 38.451946 -363.454557) (xy 38.397989 -363.468663)
			(xy 38.342552 -363.474763) (xy 38.286818 -363.472726) (xy 38.231975 -363.462596) (xy 38.179191 -363.444589)
			(xy 38.129591 -363.419088) (xy 38.084233 -363.386637) (xy 38.044084 -363.347928) (xy 38.009998 -363.303785)
			(xy 37.982702 -363.25515) (xy 37.962779 -363.203059) (xy 37.950653 -363.148622) (xy 37.946582 -363.093)
			(xy 36.703508 -363.093) (xy 36.70307 -363.129706) (xy 36.696012 -363.202779) (xy 36.681962 -363.274835)
			(xy 36.661051 -363.345206) (xy 36.63347 -363.413241) (xy 36.599477 -363.47831) (xy 36.57981 -363.509306)
			(xy 36.574232 -363.518668) (xy 36.570843 -363.540172) (xy 36.576704 -363.561137) (xy 36.583366 -363.569758)
			(xy 36.609881 -363.602134) (xy 36.657033 -363.671275) (xy 36.697064 -363.744769) (xy 36.729578 -363.821884)
			(xy 36.754251 -363.901853) (xy 36.770836 -363.983882) (xy 36.779171 -364.067155) (xy 36.779708 -364.109)
			(xy 37.947092 -364.109) (xy 37.947578 -364.081749) (xy 37.955334 -364.027801) (xy 37.970689 -363.975506)
			(xy 37.993331 -363.925929) (xy 38.022797 -363.880079) (xy 38.058488 -363.838888) (xy 38.099679 -363.803197)
			(xy 38.145529 -363.773731) (xy 38.195106 -363.751089) (xy 38.247401 -363.735734) (xy 38.301349 -363.727978)
			(xy 38.355851 -363.727978) (xy 38.409799 -363.735734) (xy 38.462094 -363.751089) (xy 38.511671 -363.773731)
			(xy 38.557521 -363.803197) (xy 38.598712 -363.838888) (xy 38.634403 -363.880079) (xy 38.663869 -363.925929)
			(xy 38.686511 -363.975506) (xy 38.701866 -364.027801) (xy 38.709622 -364.081749) (xy 38.710108 -364.109)
			(xy 38.7096 -364.138328) (xy 38.700627 -364.196294) (xy 38.682893 -364.252205) (xy 38.656816 -364.304746)
			(xy 38.623008 -364.352679) (xy 38.582266 -364.394876) (xy 38.559232 -364.413038) (xy 38.548156 -364.422009)
			(xy 38.531075 -364.444812) (xy 38.520963 -364.471449) (xy 38.518607 -364.499842) (xy 38.524193 -364.527781)
			(xy 38.537283 -364.553086) (xy 38.556859 -364.573788) (xy 38.568884 -364.58144) (xy 38.592975 -364.596252)
			(xy 38.625382 -364.622545) (xy 39.16019 -364.622545) (xy 39.16019 -364.558623) (xy 39.168201 -364.495205)
			(xy 39.184098 -364.433291) (xy 39.20763 -364.373858) (xy 39.238424 -364.317843) (xy 39.275997 -364.266128)
			(xy 39.319754 -364.219531) (xy 39.369007 -364.178786) (xy 39.422978 -364.144535) (xy 39.480817 -364.117318)
			(xy 39.54161 -364.097565) (xy 39.6044 -364.085587) (xy 39.668196 -364.081574) (xy 39.731992 -364.085587)
			(xy 39.794782 -364.097565) (xy 39.855575 -364.117318) (xy 39.913414 -364.144535) (xy 39.967385 -364.178786)
			(xy 40.016638 -364.219531) (xy 40.060395 -364.266128) (xy 40.097968 -364.317843) (xy 40.128762 -364.373858)
			(xy 40.152294 -364.433291) (xy 40.168191 -364.495205) (xy 40.176202 -364.558623) (xy 40.176704 -364.590584)
			(xy 40.176202 -364.622545) (xy 40.168191 -364.685963) (xy 40.152294 -364.747877) (xy 40.128762 -364.80731)
			(xy 40.097968 -364.863325) (xy 40.060395 -364.91504) (xy 40.016638 -364.961637) (xy 39.967385 -365.002382)
			(xy 39.913414 -365.036633) (xy 39.855575 -365.06385) (xy 39.794782 -365.083603) (xy 39.731992 -365.095581)
			(xy 39.668196 -365.099595) (xy 39.6044 -365.095581) (xy 39.54161 -365.083603) (xy 39.480817 -365.06385)
			(xy 39.422978 -365.036633) (xy 39.369007 -365.002382) (xy 39.319754 -364.961637) (xy 39.275997 -364.91504)
			(xy 39.238424 -364.863325) (xy 39.20763 -364.80731) (xy 39.184098 -364.747877) (xy 39.168201 -364.685963)
			(xy 39.16019 -364.622545) (xy 38.625382 -364.622545) (xy 38.63689 -364.631882) (xy 38.675063 -364.673606)
			(xy 38.706654 -364.720511) (xy 38.730973 -364.771566) (xy 38.747484 -364.825654) (xy 38.755827 -364.881586)
			(xy 38.756336 -364.909862) (xy 38.75585 -364.937113) (xy 38.748094 -364.991061) (xy 38.732739 -365.043356)
			(xy 38.710097 -365.092933) (xy 38.680631 -365.138783) (xy 38.64494 -365.179974) (xy 38.603749 -365.215665)
			(xy 38.557899 -365.245131) (xy 38.508322 -365.267773) (xy 38.456027 -365.283128) (xy 38.402079 -365.290884)
			(xy 38.347577 -365.290884) (xy 38.293629 -365.283128) (xy 38.241334 -365.267773) (xy 38.191757 -365.245131)
			(xy 38.145907 -365.215665) (xy 38.104716 -365.179974) (xy 38.069025 -365.138783) (xy 38.039559 -365.092933)
			(xy 38.016917 -365.043356) (xy 38.001562 -364.991061) (xy 37.993806 -364.937113) (xy 37.99332 -364.909862)
			(xy 37.993901 -364.880537) (xy 38.002862 -364.822576) (xy 38.020584 -364.766667) (xy 38.046648 -364.714127)
			(xy 38.080441 -364.666192) (xy 38.121169 -364.623989) (xy 38.144196 -364.605824) (xy 38.155307 -364.596894)
			(xy 38.172383 -364.57408) (xy 38.18249 -364.547435) (xy 38.184839 -364.519035) (xy 38.179248 -364.491091)
			(xy 38.166152 -364.465781) (xy 38.146572 -364.445076) (xy 38.134544 -364.437422) (xy 38.110465 -364.422593)
			(xy 38.066552 -364.386963) (xy 38.028382 -364.34524) (xy 37.996791 -364.298339) (xy 37.972471 -364.247287)
			(xy 37.955955 -364.193203) (xy 37.947605 -364.137274) (xy 37.947092 -364.109) (xy 36.779708 -364.109)
			(xy 36.779271 -364.147229) (xy 36.772288 -364.223369) (xy 36.758407 -364.298557) (xy 36.737743 -364.37217)
			(xy 36.710468 -364.443599) (xy 36.676808 -364.51225) (xy 36.65728 -364.545118) (xy 36.651673 -364.555543)
			(xy 36.649709 -364.579104) (xy 36.65347 -364.59033) (xy 36.666325 -364.623892) (xy 36.686394 -364.692908)
			(xy 36.69987 -364.763507) (xy 36.706634 -364.835063) (xy 36.707064 -364.871) (xy 36.706645 -364.90705)
			(xy 36.69984 -364.978827) (xy 36.686292 -365.049642) (xy 36.666121 -365.118862) (xy 36.639507 -365.185869)
			(xy 36.606688 -365.250066) (xy 36.587684 -365.280702) (xy 36.582096 -365.289592) (xy 36.578794 -365.31042)
			(xy 36.60267 -365.402876) (xy 36.615624 -365.419386) (xy 36.625022 -365.424466) (xy 36.650539 -365.438884)
			(xy 36.697209 -365.474334) (xy 36.737906 -365.516505) (xy 36.771674 -365.564406) (xy 36.797717 -365.616909)
			(xy 36.815422 -365.672777) (xy 36.824372 -365.730696) (xy 36.82492 -365.76) (xy 36.950394 -365.76)
			(xy 36.954465 -365.704378) (xy 36.966591 -365.649941) (xy 36.986514 -365.59785) (xy 37.01381 -365.549215)
			(xy 37.047896 -365.505072) (xy 37.088045 -365.466363) (xy 37.133403 -365.433912) (xy 37.183003 -365.408411)
			(xy 37.235787 -365.390404) (xy 37.29063 -365.380274) (xy 37.346364 -365.378237) (xy 37.401801 -365.384337)
			(xy 37.455758 -365.398443) (xy 37.507087 -365.420255) (xy 37.554693 -365.449309) (xy 37.597561 -365.484984)
			(xy 37.634778 -365.526521) (xy 37.665551 -365.573034) (xy 37.683065 -365.610394) (xy 39.802308 -365.610394)
			(xy 39.802732 -365.579661) (xy 39.810142 -365.518644) (xy 39.824852 -365.458964) (xy 39.846649 -365.401493)
			(xy 39.875215 -365.347068) (xy 39.910132 -365.296484) (xy 39.950893 -365.250477) (xy 39.996901 -365.209719)
			(xy 40.047487 -365.174803) (xy 40.101913 -365.14624) (xy 40.159385 -365.124446) (xy 40.219065 -365.109738)
			(xy 40.280083 -365.102331) (xy 40.310816 -365.101886) (xy 40.34421 -365.102433) (xy 40.410424 -365.111154)
			(xy 40.474927 -365.12847) (xy 40.536607 -365.154083) (xy 40.594402 -365.187553) (xy 40.647317 -365.228302)
			(xy 40.694441 -365.275628) (xy 40.734962 -365.328718) (xy 40.768183 -365.386657) (xy 40.79353 -365.448446)
			(xy 40.80256 -365.4806) (xy 40.80582 -365.490697) (xy 40.819006 -365.507283) (xy 40.83775 -365.517164)
			(xy 40.84828 -365.518446) (xy 40.881316 -365.521238) (xy 40.946317 -365.534287) (xy 41.009069 -365.555677)
			(xy 41.068507 -365.585045) (xy 41.123621 -365.621894) (xy 41.173475 -365.665597) (xy 41.195752 -365.69015)
			(xy 41.203399 -365.698013) (xy 41.223394 -365.706966) (xy 41.245301 -365.706771) (xy 41.255442 -365.702596)
			(xy 41.289327 -365.68752) (xy 41.360371 -365.666237) (xy 41.433752 -365.655499) (xy 41.470834 -365.654844)
			(xy 41.501564 -365.655324) (xy 41.562575 -365.662735) (xy 41.622249 -365.677446) (xy 41.679714 -365.699241)
			(xy 41.734133 -365.727804) (xy 41.784714 -365.762718) (xy 41.830717 -365.803473) (xy 41.871474 -365.849475)
			(xy 41.906389 -365.900055) (xy 41.934953 -365.954473) (xy 41.95675 -366.011938) (xy 41.971462 -366.071611)
			(xy 41.978876 -366.132622) (xy 41.979342 -366.163352) (xy 41.97887 -366.195422) (xy 41.970822 -366.259056)
			(xy 41.954834 -366.321172) (xy 41.931161 -366.380784) (xy 41.900179 -366.436945) (xy 41.862379 -366.488764)
			(xy 41.818363 -366.535417) (xy 41.768828 -366.576164) (xy 41.714562 -366.610357) (xy 41.656426 -366.637454)
			(xy 41.595345 -366.657024) (xy 41.532286 -366.668757) (xy 41.500298 -366.671098) (xy 41.491399 -366.671898)
			(xy 41.474985 -366.678932) (xy 41.462018 -366.69121) (xy 41.454099 -366.707215) (xy 41.4528 -366.716056)
			(xy 41.448927 -366.746756) (xy 41.434638 -366.806963) (xy 41.41315 -366.864992) (xy 41.384782 -366.919987)
			(xy 41.349951 -366.971133) (xy 41.309174 -367.017677) (xy 41.263051 -367.05893) (xy 41.212265 -367.094284)
			(xy 41.157565 -367.123215) (xy 41.09976 -367.145298) (xy 41.039702 -367.160205) (xy 40.97828 -367.167716)
			(xy 40.94734 -367.168176) (xy 40.916608 -367.167725) (xy 40.85559 -367.16032) (xy 40.795911 -367.145614)
			(xy 40.738439 -367.123821) (xy 40.684013 -367.095259) (xy 40.633428 -367.060344) (xy 40.58742 -367.019586)
			(xy 40.546661 -366.973578) (xy 40.511746 -366.922994) (xy 40.483182 -366.868568) (xy 40.461388 -366.811097)
			(xy 40.446681 -366.751418) (xy 40.439276 -366.6904) (xy 40.438832 -366.659668) (xy 40.439381 -366.624904)
			(xy 40.448864 -366.556025) (xy 40.467649 -366.489081) (xy 40.480996 -366.456976) (xy 40.484704 -366.447118)
			(xy 40.484662 -366.426081) (xy 40.476191 -366.406824) (xy 40.468804 -366.399318) (xy 40.447856 -366.379466)
			(xy 40.410128 -366.33579) (xy 40.377599 -366.288115) (xy 40.350687 -366.237059) (xy 40.32974 -366.183279)
			(xy 40.321992 -366.155478) (xy 40.31878 -366.145362) (xy 40.305574 -366.128775) (xy 40.28681 -366.118905)
			(xy 40.276272 -366.117632) (xy 40.244527 -366.114986) (xy 40.182006 -366.102776) (xy 40.1215 -366.082848)
			(xy 40.063959 -366.055517) (xy 40.010284 -366.021209) (xy 39.961317 -365.980463) (xy 39.917825 -365.933918)
			(xy 39.88049 -365.882303) (xy 39.849897 -365.826427) (xy 39.826526 -365.767167) (xy 39.810744 -365.70545)
			(xy 39.802797 -365.642245) (xy 39.802308 -365.610394) (xy 37.683065 -365.610394) (xy 37.689223 -365.623531)
			(xy 37.705291 -365.676938) (xy 37.713411 -365.732114) (xy 37.71392 -365.76) (xy 37.713411 -365.787886)
			(xy 37.705291 -365.843062) (xy 37.689223 -365.896469) (xy 37.665551 -365.946966) (xy 37.634778 -365.993479)
			(xy 37.597561 -366.035016) (xy 37.563298 -366.06353) (xy 38.846504 -366.06353) (xy 38.850575 -366.007908)
			(xy 38.862701 -365.953471) (xy 38.882624 -365.90138) (xy 38.90992 -365.852745) (xy 38.944006 -365.808602)
			(xy 38.984155 -365.769893) (xy 39.029513 -365.737442) (xy 39.079113 -365.711941) (xy 39.131897 -365.693934)
			(xy 39.18674 -365.683804) (xy 39.242474 -365.681767) (xy 39.297911 -365.687867) (xy 39.351868 -365.701973)
			(xy 39.403197 -365.723785) (xy 39.450803 -365.752839) (xy 39.493671 -365.788514) (xy 39.530888 -365.830051)
			(xy 39.561661 -365.876564) (xy 39.585333 -365.927061) (xy 39.601401 -365.980468) (xy 39.609521 -366.035644)
			(xy 39.61003 -366.06353) (xy 39.609521 -366.091416) (xy 39.601401 -366.146592) (xy 39.585333 -366.199999)
			(xy 39.561661 -366.250496) (xy 39.530888 -366.297009) (xy 39.493671 -366.338546) (xy 39.450803 -366.374221)
			(xy 39.403197 -366.403275) (xy 39.351868 -366.425087) (xy 39.297911 -366.439193) (xy 39.242474 -366.445293)
			(xy 39.18674 -366.443256) (xy 39.131897 -366.433126) (xy 39.079113 -366.415119) (xy 39.029513 -366.389618)
			(xy 38.984155 -366.357167) (xy 38.944006 -366.318458) (xy 38.90992 -366.274315) (xy 38.882624 -366.22568)
			(xy 38.862701 -366.173589) (xy 38.850575 -366.119152) (xy 38.846504 -366.06353) (xy 37.563298 -366.06353)
			(xy 37.554693 -366.070691) (xy 37.507087 -366.099745) (xy 37.455758 -366.121557) (xy 37.401801 -366.135663)
			(xy 37.346364 -366.141763) (xy 37.29063 -366.139726) (xy 37.235787 -366.129596) (xy 37.183003 -366.111589)
			(xy 37.133403 -366.086088) (xy 37.088045 -366.053637) (xy 37.047896 -366.014928) (xy 37.01381 -365.970785)
			(xy 36.986514 -365.92215) (xy 36.966591 -365.870059) (xy 36.954465 -365.815622) (xy 36.950394 -365.76)
			(xy 36.82492 -365.76) (xy 36.82439 -365.78875) (xy 36.815744 -365.845595) (xy 36.798664 -365.900499)
			(xy 36.773536 -365.952217) (xy 36.740929 -365.999578) (xy 36.701583 -366.041507) (xy 36.656389 -366.077055)
			(xy 36.606372 -366.105417) (xy 36.552663 -366.12595) (xy 36.524692 -366.132618) (xy 36.510976 -366.135666)
			(xy 36.49091 -366.154462) (xy 36.4617 -366.253522) (xy 36.459522 -366.262375) (xy 36.460877 -366.280543)
			(xy 36.46849 -366.297095) (xy 36.474654 -366.303814) (xy 37.528754 -367.357914) (xy 37.536151 -367.364761)
			(xy 37.554751 -367.372489) (xy 37.564822 -367.3729) (xy 39.252906 -367.3729) (xy 39.264194 -367.372295)
			(xy 39.284621 -367.362676) (xy 39.292276 -367.354358) (xy 39.314519 -367.327919) (xy 39.364224 -367.279926)
			(xy 39.41924 -367.238125) (xy 39.478798 -367.2031) (xy 39.54207 -367.175339) (xy 39.608172 -367.155228)
			(xy 39.676184 -367.143048) (xy 39.745158 -367.138969) (xy 39.814132 -367.143048) (xy 39.882144 -367.155228)
			(xy 39.948246 -367.175339) (xy 40.011518 -367.2031) (xy 40.071076 -367.238125) (xy 40.126092 -367.279926)
			(xy 40.175797 -367.327919) (xy 40.19804 -367.354358) (xy 40.205661 -367.362724) (xy 40.226106 -367.372355)
			(xy 40.23741 -367.3729) (xy 41.990518 -367.3729) (xy 42.000587 -367.372473) (xy 42.019186 -367.364754)
			(xy 42.026586 -367.357914) (xy 43.479974 -365.904526) (xy 43.487375 -365.897688) (xy 43.505974 -365.889977)
			(xy 43.516042 -365.88954) (xy 43.528234 -365.88954) (xy 43.579288 -365.838232) (xy 43.60203 -365.816251)
			(xy 43.652233 -365.777782) (xy 43.707029 -365.746195) (xy 43.765478 -365.722029) (xy 43.826582 -365.7057)
			(xy 43.889294 -365.697486) (xy 43.920918 -365.697008) (xy 171.92117 -365.697008) (xy 171.952793 -365.697509)
			(xy 172.015501 -365.705729) (xy 172.076602 -365.722059) (xy 172.13505 -365.746219) (xy 172.189848 -365.777797)
			(xy 172.240058 -365.816254) (xy 172.2628 -365.838232) (xy 173.045882 -366.621314) (xy 173.053227 -366.628121)
			(xy 173.071691 -366.635837) (xy 173.081696 -366.6363) (xy 175.262286 -366.6363) (xy 175.271623 -366.635819)
			(xy 175.289025 -366.629029) (xy 175.302865 -366.616483) (xy 175.307498 -366.60836) (xy 175.354996 -366.514634)
			(xy 175.35271 -366.486186) (xy 175.344074 -366.474502) (xy 175.325326 -366.448212) (xy 175.293915 -366.391793)
			(xy 175.269906 -366.331848) (xy 175.253686 -366.269345) (xy 175.245517 -366.205291) (xy 175.245014 -366.173004)
			(xy 175.245459 -366.142272) (xy 175.252868 -366.081257) (xy 175.267577 -366.021579) (xy 175.289372 -365.96411)
			(xy 175.317936 -365.909687) (xy 175.352852 -365.859104) (xy 175.393611 -365.813098) (xy 175.439618 -365.772341)
			(xy 175.490202 -365.737427) (xy 175.544626 -365.708865) (xy 175.602096 -365.687072) (xy 175.661774 -365.672365)
			(xy 175.72279 -365.664958) (xy 175.753522 -365.664496) (xy 175.786698 -365.665034) (xy 175.852486 -365.673667)
			(xy 175.916593 -365.690784) (xy 175.977928 -365.716094) (xy 176.035451 -365.749166) (xy 176.062132 -365.76889)
			(xy 176.069752 -365.774732) (xy 176.087532 -365.779812) (xy 176.175162 -365.772446) (xy 176.191672 -365.764318)
			(xy 176.198276 -365.757206) (xy 176.21892 -365.73556) (xy 176.264443 -365.696755) (xy 176.314209 -365.663565)
			(xy 176.367527 -365.636448) (xy 176.423661 -365.61578) (xy 176.481833 -365.601846) (xy 176.541239 -365.594839)
			(xy 176.571148 -365.594392) (xy 176.601877 -365.594859) (xy 176.662887 -365.602272) (xy 176.722558 -365.616985)
			(xy 176.780021 -365.638782) (xy 176.834438 -365.667347) (xy 176.885015 -365.702262) (xy 176.931015 -365.743019)
			(xy 176.971767 -365.789023) (xy 177.006678 -365.839604) (xy 177.035237 -365.894023) (xy 177.057029 -365.951488)
			(xy 177.071736 -366.011161) (xy 177.079144 -366.072171) (xy 177.079656 -366.1029) (xy 177.079132 -366.13624)
			(xy 177.070416 -366.202347) (xy 177.053134 -366.266748) (xy 177.027582 -366.328337) (xy 176.994199 -366.386058)
			(xy 176.953557 -366.43892) (xy 176.930304 -366.462818) (xy 176.919382 -366.47374) (xy 176.91354 -366.503966)
			(xy 176.955196 -366.604804) (xy 176.959405 -366.613936) (xy 176.973584 -366.628175) (xy 176.992139 -366.635886)
			(xy 177.002186 -366.6363) (xy 177.603658 -366.6363) (xy 177.613723 -366.636734) (xy 177.632313 -366.644463)
			(xy 177.639726 -366.651286) (xy 177.68062 -366.69218) (xy 177.68803 -366.698863) (xy 177.706466 -366.706441)
			(xy 177.716434 -366.706912) (xy 177.83175 -366.706912) (xy 177.863381 -366.707432) (xy 177.9261 -366.715693)
			(xy 177.987206 -366.732066) (xy 178.045653 -366.756273) (xy 178.100442 -366.787898) (xy 178.150636 -366.826402)
			(xy 178.17338 -366.84839) (xy 180.819298 -369.494562) (xy 180.826641 -369.501377) (xy 180.845104 -369.509116)
			(xy 180.855112 -369.509548) (xy 186.466734 -369.509548) (xy 186.476718 -369.509003) (xy 186.495136 -369.501275)
			(xy 186.502548 -369.494562) (xy 186.97702 -369.019836) (xy 186.999748 -368.99784) (xy 187.049954 -368.959372)
			(xy 187.104752 -368.927786) (xy 187.163205 -368.903624) (xy 187.224311 -368.887297) (xy 187.287025 -368.879087)
			(xy 187.31865 -368.878612) (xy 188.549534 -368.878612) (xy 188.581155 -368.879117) (xy 188.64386 -368.887345)
			(xy 188.704955 -368.903681) (xy 188.763398 -368.927847) (xy 188.818189 -368.95943) (xy 188.868393 -368.997889)
			(xy 188.891164 -369.019836) (xy 189.61735 -369.746276) (xy 189.624756 -369.752971) (xy 189.643192 -369.760574)
			(xy 189.653164 -369.761008) (xy 216.73185 -369.761008) (xy 216.741814 -369.760525) (xy 216.760243 -369.752942)
			(xy 216.767664 -369.746276) (xy 217.126058 -369.387628) (xy 217.148784 -369.36563) (xy 217.198989 -369.327159)
			(xy 217.253787 -369.295571) (xy 217.31224 -369.271409) (xy 217.373347 -369.255084) (xy 217.436063 -369.246877)
			(xy 217.467688 -369.246404) (xy 223.310958 -369.246404) (xy 223.342581 -369.246904) (xy 223.405291 -369.255123)
			(xy 223.466392 -369.271451) (xy 223.524842 -369.29561) (xy 223.579641 -369.327188) (xy 223.629852 -369.365643)
			(xy 223.652588 -369.387628) (xy 223.708976 -369.44427) (xy 223.716324 -369.451072) (xy 223.734787 -369.458782)
			(xy 223.74479 -369.459256) (xy 229.0445 -369.459256) (xy 229.051866 -369.456716) (xy 229.088902 -369.445893)
			(xy 229.165179 -369.434285) (xy 229.203758 -369.433602) (xy 229.236969 -369.434138) (xy 229.302825 -369.442781)
			(xy 229.366996 -369.459925) (xy 229.428388 -369.485279) (xy 229.485956 -369.51841) (xy 229.53872 -369.558755)
			(xy 229.585783 -369.605626) (xy 229.626341 -369.658226) (xy 229.659706 -369.71566) (xy 229.685308 -369.776948)
			(xy 229.702713 -369.841049) (xy 229.711623 -369.90687) (xy 229.712266 -369.940078) (xy 229.712266 -369.950238)
			(xy 229.719886 -369.968526) (xy 229.778052 -370.026438) (xy 229.785461 -370.033126) (xy 229.803896 -370.040719)
			(xy 229.813866 -370.04117) (xy 229.863396 -370.04117) (xy 229.890574 -370.020342) (xy 229.895146 -370.003578)
			(xy 229.90436 -369.971662) (xy 229.929948 -369.910357) (xy 229.963301 -369.852905) (xy 230.003849 -369.800285)
			(xy 230.050903 -369.753393) (xy 230.103663 -369.713026) (xy 230.161229 -369.679872) (xy 230.222621 -369.654495)
			(xy 230.286796 -369.637328) (xy 230.352659 -369.628662) (xy 230.385874 -369.628166) (xy 230.416342 -369.628613)
			(xy 230.476841 -369.635895) (xy 230.536035 -369.650357) (xy 230.593077 -369.671792) (xy 230.647146 -369.699892)
			(xy 230.697469 -369.734255) (xy 230.743322 -369.774388) (xy 230.784049 -369.819714) (xy 230.819065 -369.869584)
			(xy 230.847868 -369.923283) (xy 230.870045 -369.98004) (xy 230.878126 -370.00942) (xy 230.882698 -370.026438)
			(xy 230.909876 -370.04752)
		)
		(stroke
			(width 0)
			(type solid)
		)
		(fill yes)
		(layer "B.Cu")
		(net "P5V_AUX")
	)
	(gr_poly
		(pts
			(xy 96.445578 -404.838662) (xy 96.44634 -404.818088) (xy 96.447902 -404.786925) (xy 96.457696 -404.7253)
			(xy 96.474961 -404.665339) (xy 96.499439 -404.607943) (xy 96.53076 -404.553975) (xy 96.568453 -404.504249)
			(xy 96.58985 -404.481538) (xy 96.597216 -404.473918) (xy 96.604582 -404.454868) (xy 96.601788 -404.361142)
			(xy 96.593152 -404.3426) (xy 96.585532 -404.335488) (xy 96.563498 -404.314822) (xy 96.523985 -404.269124)
			(xy 96.490169 -404.219063) (xy 96.462528 -404.165346) (xy 96.441451 -404.10873) (xy 96.427235 -404.050015)
			(xy 96.420081 -403.990028) (xy 96.41967 -403.959822) (xy 96.420172 -403.927861) (xy 96.428183 -403.864443)
			(xy 96.44408 -403.802529) (xy 96.467612 -403.743096) (xy 96.498406 -403.687081) (xy 96.535979 -403.635366)
			(xy 96.579736 -403.588769) (xy 96.628989 -403.548024) (xy 96.68296 -403.513773) (xy 96.740799 -403.486556)
			(xy 96.801592 -403.466803) (xy 96.864382 -403.454825) (xy 96.928178 -403.450812) (xy 96.991974 -403.454825)
			(xy 97.054764 -403.466803) (xy 97.115557 -403.486556) (xy 97.173396 -403.513773) (xy 97.227367 -403.548024)
			(xy 97.27662 -403.588769) (xy 97.320377 -403.635366) (xy 97.35795 -403.687081) (xy 97.388744 -403.743096)
			(xy 97.412276 -403.802529) (xy 97.428173 -403.864443) (xy 97.436184 -403.927861) (xy 97.436686 -403.959822)
			(xy 97.43618 -403.992503) (xy 97.427804 -404.057325) (xy 97.411192 -404.12054) (xy 97.386618 -404.181106)
			(xy 97.354487 -404.238024) (xy 97.315329 -404.290357) (xy 97.292922 -404.314152) (xy 97.285556 -404.321772)
			(xy 97.27819 -404.340822) (xy 97.280984 -404.434548) (xy 97.28962 -404.45309) (xy 97.29724 -404.460202)
			(xy 97.321804 -404.483364) (xy 97.365221 -404.535067) (xy 97.401425 -404.592055) (xy 97.429779 -404.653328)
			(xy 97.449787 -404.71781) (xy 97.461097 -404.784371) (xy 97.462848 -404.818088) (xy 97.46361 -404.838662)
			(xy 97.493074 -404.86711) (xy 99.21621 -404.86711) (xy 99.224988 -404.866803) (xy 99.241536 -404.860959)
			(xy 99.255108 -404.849833) (xy 99.259898 -404.842472) (xy 99.311714 -404.75662) (xy 99.312476 -404.72995)
			(xy 99.306126 -404.718012) (xy 99.290025 -404.686382) (xy 99.264746 -404.620058) (xy 99.247687 -404.551161)
			(xy 99.2391 -404.480705) (xy 99.238562 -404.445216) (xy 99.239094 -404.409879) (xy 99.247611 -404.339719)
			(xy 99.264523 -404.271098) (xy 99.289582 -404.205015) (xy 99.322424 -404.142434) (xy 99.36257 -404.084269)
			(xy 99.409434 -404.031366) (xy 99.462332 -403.984498) (xy 99.520495 -403.944348) (xy 99.583073 -403.911501)
			(xy 99.649154 -403.886436) (xy 99.717774 -403.869519) (xy 99.787933 -403.860997) (xy 99.82327 -403.860508)
			(xy 99.855528 -403.861524) (xy 99.864928 -403.861558) (xy 99.882767 -403.855684) (xy 99.890326 -403.850094)
			(xy 99.914202 -403.83079) (xy 99.921115 -403.824759) (xy 99.9305 -403.809011) (xy 99.93249 -403.800056)
			(xy 99.937459 -403.773791) (xy 99.953778 -403.722887) (xy 99.97704 -403.674758) (xy 100.006791 -403.630347)
			(xy 100.042449 -403.590523) (xy 100.083315 -403.556064) (xy 100.12859 -403.527645) (xy 100.177388 -403.505822)
			(xy 100.228754 -403.491023) (xy 100.281683 -403.483537) (xy 100.30841 -403.483064) (xy 100.335662 -403.48355)
			(xy 100.38961 -403.491308) (xy 100.441905 -403.506664) (xy 100.491483 -403.529305) (xy 100.537334 -403.558771)
			(xy 100.578525 -403.594462) (xy 100.614218 -403.635652) (xy 100.643686 -403.681502) (xy 100.66633 -403.731078)
			(xy 100.681688 -403.783373) (xy 100.689448 -403.837321) (xy 100.689918 -403.864572) (xy 100.689368 -403.893709)
			(xy 100.680506 -403.951305) (xy 100.662983 -404.006882) (xy 100.637208 -404.059146) (xy 100.603781 -404.10688)
			(xy 100.563481 -404.148972) (xy 100.517245 -404.184442) (xy 100.466151 -404.212464) (xy 100.438966 -404.222966)
			(xy 100.430478 -404.226495) (xy 100.416546 -404.238469) (xy 100.411788 -404.246334) (xy 100.396802 -404.273258)
			(xy 100.392679 -404.281712) (xy 100.390205 -404.300342) (xy 100.391976 -404.30958) (xy 100.399461 -404.342989)
			(xy 100.407487 -404.410983) (xy 100.407978 -404.445216) (xy 100.407455 -404.480705) (xy 100.398859 -404.551161)
			(xy 100.381796 -404.620058) (xy 100.356516 -404.686382) (xy 100.340414 -404.718012) (xy 100.334064 -404.72995)
			(xy 100.334826 -404.75662) (xy 100.386642 -404.842472) (xy 100.391488 -404.849776) (xy 100.405068 -404.860839)
			(xy 100.421572 -404.866705) (xy 100.43033 -404.86711) (xy 102.183946 -404.86711) (xy 102.211632 -404.845012)
			(xy 102.215696 -404.827486) (xy 102.223741 -404.794157) (xy 102.246592 -404.729512) (xy 102.276848 -404.667983)
			(xy 102.314093 -404.610416) (xy 102.357816 -404.557601) (xy 102.407417 -404.510263) (xy 102.462215 -404.469051)
			(xy 102.521457 -404.434533) (xy 102.58433 -404.407181) (xy 102.649971 -404.387371) (xy 102.717479 -404.375375)
			(xy 102.785926 -404.371358) (xy 102.854373 -404.375375) (xy 102.921881 -404.387371) (xy 102.987522 -404.407181)
			(xy 103.050395 -404.434533) (xy 103.109637 -404.469051) (xy 103.164435 -404.510263) (xy 103.214036 -404.557601)
			(xy 103.257759 -404.610416) (xy 103.295004 -404.667983) (xy 103.32526 -404.729512) (xy 103.348111 -404.794157)
			(xy 103.356156 -404.827486) (xy 103.36022 -404.845012) (xy 103.387906 -404.86711) (xy 104.500426 -404.86711)
			(xy 104.525826 -404.849838) (xy 104.531668 -404.835614) (xy 104.544787 -404.804833) (xy 104.57795 -404.746717)
			(xy 104.618449 -404.693454) (xy 104.665585 -404.645963) (xy 104.718543 -404.605066) (xy 104.776409 -404.571469)
			(xy 104.838181 -404.545752) (xy 104.902793 -404.52836) (xy 104.969128 -404.519594) (xy 105.002584 -404.51913)
			(xy 105.03231 -404.519567) (xy 105.091353 -404.526528) (xy 105.149182 -404.540322) (xy 105.20501 -404.56076)
			(xy 105.258077 -404.587565) (xy 105.307658 -404.620371) (xy 105.353078 -404.658732) (xy 105.373678 -404.680166)
			(xy 105.380504 -404.686703) (xy 105.397569 -404.694788) (xy 105.406952 -404.695914) (xy 105.43794 -404.698454)
			(xy 105.447262 -404.698748) (xy 105.465117 -404.693415) (xy 105.472738 -404.68804) (xy 105.492812 -404.673074)
			(xy 105.536137 -404.647971) (xy 105.582373 -404.628752) (xy 105.630727 -404.615749) (xy 105.680366 -404.609184)
			(xy 105.705402 -404.608792) (xy 105.732999 -404.60928) (xy 105.787615 -404.617236) (xy 105.840515 -404.632981)
			(xy 105.890593 -404.656187) (xy 105.936803 -404.686368) (xy 105.978181 -404.722895) (xy 106.013861 -404.765004)
			(xy 106.043099 -404.811817) (xy 106.054652 -404.836884) (xy 106.060748 -404.8506) (xy 106.086148 -404.86711)
			(xy 106.840274 -404.86711) (xy 106.849378 -404.866735) (xy 106.866431 -404.860354) (xy 106.873548 -404.854664)
			(xy 106.885994 -404.84425) (xy 106.894122 -404.837646) (xy 106.903774 -404.82012) (xy 106.91241 -404.726648)
			(xy 106.906314 -404.707344) (xy 106.899456 -404.69947) (xy 106.882306 -404.678661) (xy 106.85343 -404.633122)
			(xy 106.831266 -404.583965) (xy 106.816258 -404.532173) (xy 106.808705 -404.478782) (xy 106.80827 -404.45182)
			(xy 106.808756 -404.424569) (xy 106.816512 -404.370621) (xy 106.831867 -404.318326) (xy 106.854509 -404.268749)
			(xy 106.883975 -404.222899) (xy 106.919666 -404.181708) (xy 106.960857 -404.146017) (xy 107.006707 -404.116551)
			(xy 107.056284 -404.093909) (xy 107.108579 -404.078554) (xy 107.162527 -404.070798) (xy 107.217029 -404.070798)
			(xy 107.270977 -404.078554) (xy 107.323272 -404.093909) (xy 107.372849 -404.116551) (xy 107.418699 -404.146017)
			(xy 107.45989 -404.181708) (xy 107.495581 -404.222899) (xy 107.525047 -404.268749) (xy 107.547689 -404.318326)
			(xy 107.563044 -404.370621) (xy 107.5708 -404.424569) (xy 107.571286 -404.45182) (xy 107.570865 -404.477238)
			(xy 107.564111 -404.527623) (xy 107.550724 -404.576664) (xy 107.530944 -404.623493) (xy 107.505118 -404.66728)
			(xy 107.489752 -404.687532) (xy 107.483148 -404.695914) (xy 107.477814 -404.715218) (xy 107.49026 -404.808182)
			(xy 107.50042 -404.825708) (xy 107.509056 -404.831804) (xy 107.528106 -404.84679) (xy 107.535125 -404.852023)
			(xy 107.551616 -404.857868) (xy 107.560364 -404.85822) (xy 107.714288 -404.85822) (xy 107.723041 -404.8579)
			(xy 107.739533 -404.85204) (xy 107.746546 -404.84679) (xy 107.773945 -404.825077) (xy 107.833568 -404.788577)
			(xy 107.897629 -404.760586) (xy 107.964919 -404.741634) (xy 108.034172 -404.732076) (xy 108.069126 -404.731474)
			(xy 108.099277 -404.731883) (xy 108.15916 -404.738979) (xy 108.217782 -404.753115) (xy 108.274317 -404.774093)
			(xy 108.327971 -404.801618) (xy 108.377988 -404.835301) (xy 108.401104 -404.854664) (xy 108.408227 -404.860343)
			(xy 108.425277 -404.866723) (xy 108.434378 -404.86711) (xy 108.60913 -404.86711) (xy 108.636562 -404.846028)
			(xy 108.64088 -404.829264) (xy 108.650214 -404.795567) (xy 108.675837 -404.730506) (xy 108.709038 -404.668966)
			(xy 108.749342 -404.611826) (xy 108.796173 -404.5599) (xy 108.848864 -404.513932) (xy 108.906662 -404.474576)
			(xy 108.968741 -404.442395) (xy 109.034216 -404.417849) (xy 109.10215 -404.401287) (xy 109.171576 -404.392947)
			(xy 109.2415 -404.392947) (xy 109.310926 -404.401287) (xy 109.37886 -404.417849) (xy 109.444335 -404.442395)
			(xy 109.506414 -404.474576) (xy 109.564212 -404.513932) (xy 109.616903 -404.5599) (xy 109.663734 -404.611826)
			(xy 109.704038 -404.668966) (xy 109.737239 -404.730506) (xy 109.762862 -404.795567) (xy 109.772196 -404.829264)
			(xy 109.776514 -404.846028) (xy 109.803946 -404.86711) (xy 111.923068 -404.86711) (xy 111.931704 -404.863808)
			(xy 111.95234 -404.856213) (xy 111.994553 -404.843879) (xy 112.016032 -404.83917) (xy 112.023398 -404.837646)
			(xy 112.036098 -404.830788) (xy 112.11306 -404.753826) (xy 112.119918 -404.741126) (xy 112.121442 -404.733506)
			(xy 112.128449 -404.701408) (xy 112.148969 -404.638994) (xy 112.176629 -404.5794) (xy 112.211054 -404.52344)
			(xy 112.251771 -404.471878) (xy 112.298225 -404.425418) (xy 112.349782 -404.384694) (xy 112.405738 -404.350263)
			(xy 112.465329 -404.322595) (xy 112.52774 -404.302067) (xy 112.559846 -404.295102) (xy 112.567466 -404.293578)
			(xy 112.580166 -404.28672) (xy 112.997488 -403.869398) (xy 113.004886 -403.86255) (xy 113.023484 -403.854811)
			(xy 113.033556 -403.854412) (xy 114.310668 -403.854412) (xy 114.339878 -403.82698) (xy 114.341148 -403.806914)
			(xy 114.343409 -403.780203) (xy 114.354941 -403.727853) (xy 114.374189 -403.677822) (xy 114.400717 -403.631242)
			(xy 114.433927 -403.589163) (xy 114.473069 -403.552537) (xy 114.517257 -403.522191) (xy 114.565495 -403.498811)
			(xy 114.616692 -403.482924) (xy 114.669691 -403.47489) (xy 114.723297 -403.47489) (xy 114.776296 -403.482924)
			(xy 114.827493 -403.498811) (xy 114.875731 -403.522191) (xy 114.919919 -403.552537) (xy 114.959061 -403.589163)
			(xy 114.992271 -403.631242) (xy 115.018799 -403.677822) (xy 115.038047 -403.727853) (xy 115.049579 -403.780203)
			(xy 115.05184 -403.806914) (xy 115.05311 -403.82698) (xy 115.08232 -403.854412) (xy 115.569492 -403.854412)
			(xy 115.598702 -403.82698) (xy 115.599972 -403.806914) (xy 115.602233 -403.780203) (xy 115.613765 -403.727853)
			(xy 115.633013 -403.677822) (xy 115.659541 -403.631242) (xy 115.692751 -403.589163) (xy 115.731893 -403.552537)
			(xy 115.776081 -403.522191) (xy 115.824319 -403.498811) (xy 115.875516 -403.482924) (xy 115.928515 -403.47489)
			(xy 115.982121 -403.47489) (xy 116.03512 -403.482924) (xy 116.086317 -403.498811) (xy 116.134555 -403.522191)
			(xy 116.178743 -403.552537) (xy 116.217885 -403.589163) (xy 116.251095 -403.631242) (xy 116.277623 -403.677822)
			(xy 116.296871 -403.727853) (xy 116.308403 -403.780203) (xy 116.310664 -403.806914) (xy 116.311934 -403.82698)
			(xy 116.341144 -403.854412) (xy 117.373908 -403.854412) (xy 117.403118 -403.82698) (xy 117.404388 -403.806914)
			(xy 117.406649 -403.780203) (xy 117.418181 -403.727853) (xy 117.437429 -403.677822) (xy 117.463957 -403.631242)
			(xy 117.497167 -403.589163) (xy 117.536309 -403.552537) (xy 117.580497 -403.522191) (xy 117.628735 -403.498811)
			(xy 117.679932 -403.482924) (xy 117.732931 -403.47489) (xy 117.786537 -403.47489) (xy 117.839536 -403.482924)
			(xy 117.890733 -403.498811) (xy 117.938971 -403.522191) (xy 117.983159 -403.552537) (xy 118.022301 -403.589163)
			(xy 118.055511 -403.631242) (xy 118.082039 -403.677822) (xy 118.101287 -403.727853) (xy 118.112819 -403.780203)
			(xy 118.11508 -403.806914) (xy 118.11635 -403.82698) (xy 118.14556 -403.854412) (xy 118.632732 -403.854412)
			(xy 118.661942 -403.82698) (xy 118.663212 -403.806914) (xy 118.665473 -403.780203) (xy 118.677005 -403.727853)
			(xy 118.696253 -403.677822) (xy 118.722781 -403.631242) (xy 118.755991 -403.589163) (xy 118.795133 -403.552537)
			(xy 118.839321 -403.522191) (xy 118.887559 -403.498811) (xy 118.938756 -403.482924) (xy 118.991755 -403.47489)
			(xy 119.045361 -403.47489) (xy 119.09836 -403.482924) (xy 119.149557 -403.498811) (xy 119.197795 -403.522191)
			(xy 119.241983 -403.552537) (xy 119.281125 -403.589163) (xy 119.314335 -403.631242) (xy 119.340863 -403.677822)
			(xy 119.360111 -403.727853) (xy 119.371643 -403.780203) (xy 119.373904 -403.806914) (xy 119.375174 -403.82698)
			(xy 119.404384 -403.854412) (xy 120.437148 -403.854412) (xy 120.466358 -403.82698) (xy 120.467628 -403.806914)
			(xy 120.469889 -403.780203) (xy 120.481421 -403.727853) (xy 120.500669 -403.677822) (xy 120.527197 -403.631242)
			(xy 120.560407 -403.589163) (xy 120.599549 -403.552537) (xy 120.643737 -403.522191) (xy 120.691975 -403.498811)
			(xy 120.743172 -403.482924) (xy 120.796171 -403.47489) (xy 120.849777 -403.47489) (xy 120.902776 -403.482924)
			(xy 120.953973 -403.498811) (xy 121.002211 -403.522191) (xy 121.046399 -403.552537) (xy 121.085541 -403.589163)
			(xy 121.118751 -403.631242) (xy 121.145279 -403.677822) (xy 121.164527 -403.727853) (xy 121.176059 -403.780203)
			(xy 121.17832 -403.806914) (xy 121.17959 -403.82698) (xy 121.2088 -403.854412) (xy 121.695972 -403.854412)
			(xy 121.725182 -403.82698) (xy 121.726452 -403.806914) (xy 121.728713 -403.780203) (xy 121.740245 -403.727853)
			(xy 121.759493 -403.677822) (xy 121.786021 -403.631242) (xy 121.819231 -403.589163) (xy 121.858373 -403.552537)
			(xy 121.902561 -403.522191) (xy 121.950799 -403.498811) (xy 122.001996 -403.482924) (xy 122.054995 -403.47489)
			(xy 122.108601 -403.47489) (xy 122.1616 -403.482924) (xy 122.212797 -403.498811) (xy 122.261035 -403.522191)
			(xy 122.305223 -403.552537) (xy 122.344365 -403.589163) (xy 122.377575 -403.631242) (xy 122.404103 -403.677822)
			(xy 122.423351 -403.727853) (xy 122.434883 -403.780203) (xy 122.437144 -403.806914) (xy 122.438414 -403.82698)
			(xy 122.467624 -403.854412) (xy 123.500388 -403.854412) (xy 123.529598 -403.82698) (xy 123.530868 -403.806914)
			(xy 123.533129 -403.780203) (xy 123.544661 -403.727853) (xy 123.563909 -403.677822) (xy 123.590437 -403.631242)
			(xy 123.623647 -403.589163) (xy 123.662789 -403.552537) (xy 123.706977 -403.522191) (xy 123.755215 -403.498811)
			(xy 123.806412 -403.482924) (xy 123.859411 -403.47489) (xy 123.913017 -403.47489) (xy 123.966016 -403.482924)
			(xy 124.017213 -403.498811) (xy 124.065451 -403.522191) (xy 124.109639 -403.552537) (xy 124.148781 -403.589163)
			(xy 124.181991 -403.631242) (xy 124.208519 -403.677822) (xy 124.227767 -403.727853) (xy 124.239299 -403.780203)
			(xy 124.24156 -403.806914) (xy 124.24283 -403.82698) (xy 124.27204 -403.854412) (xy 124.759212 -403.854412)
			(xy 124.788422 -403.82698) (xy 124.789692 -403.806914) (xy 124.791953 -403.780203) (xy 124.803485 -403.727853)
			(xy 124.822733 -403.677822) (xy 124.849261 -403.631242) (xy 124.882471 -403.589163) (xy 124.921613 -403.552537)
			(xy 124.965801 -403.522191) (xy 125.014039 -403.498811) (xy 125.065236 -403.482924) (xy 125.118235 -403.47489)
			(xy 125.171841 -403.47489) (xy 125.22484 -403.482924) (xy 125.276037 -403.498811) (xy 125.324275 -403.522191)
			(xy 125.368463 -403.552537) (xy 125.407605 -403.589163) (xy 125.440815 -403.631242) (xy 125.467343 -403.677822)
			(xy 125.486591 -403.727853) (xy 125.498123 -403.780203) (xy 125.500384 -403.806914) (xy 125.501654 -403.82698)
			(xy 125.530864 -403.854412) (xy 126.563628 -403.854412) (xy 126.592838 -403.82698) (xy 126.594108 -403.806914)
			(xy 126.596369 -403.780203) (xy 126.607901 -403.727853) (xy 126.627149 -403.677822) (xy 126.653677 -403.631242)
			(xy 126.686887 -403.589163) (xy 126.726029 -403.552537) (xy 126.770217 -403.522191) (xy 126.818455 -403.498811)
			(xy 126.869652 -403.482924) (xy 126.922651 -403.47489) (xy 126.976257 -403.47489) (xy 127.029256 -403.482924)
			(xy 127.080453 -403.498811) (xy 127.128691 -403.522191) (xy 127.172879 -403.552537) (xy 127.212021 -403.589163)
			(xy 127.245231 -403.631242) (xy 127.271759 -403.677822) (xy 127.291007 -403.727853) (xy 127.302539 -403.780203)
			(xy 127.3048 -403.806914) (xy 127.30607 -403.82698) (xy 127.33528 -403.854412) (xy 127.822452 -403.854412)
			(xy 127.851662 -403.82698) (xy 127.852932 -403.806914) (xy 127.855193 -403.780203) (xy 127.866725 -403.727853)
			(xy 127.885973 -403.677822) (xy 127.912501 -403.631242) (xy 127.945711 -403.589163) (xy 127.984853 -403.552537)
			(xy 128.029041 -403.522191) (xy 128.077279 -403.498811) (xy 128.128476 -403.482924) (xy 128.181475 -403.47489)
			(xy 128.235081 -403.47489) (xy 128.28808 -403.482924) (xy 128.339277 -403.498811) (xy 128.387515 -403.522191)
			(xy 128.431703 -403.552537) (xy 128.470845 -403.589163) (xy 128.504055 -403.631242) (xy 128.530583 -403.677822)
			(xy 128.549831 -403.727853) (xy 128.561363 -403.780203) (xy 128.563624 -403.806914) (xy 128.564894 -403.82698)
			(xy 128.594104 -403.854412) (xy 129.626868 -403.854412) (xy 129.656078 -403.82698) (xy 129.657348 -403.806914)
			(xy 129.659609 -403.780203) (xy 129.671141 -403.727853) (xy 129.690389 -403.677822) (xy 129.716917 -403.631242)
			(xy 129.750127 -403.589163) (xy 129.789269 -403.552537) (xy 129.833457 -403.522191) (xy 129.881695 -403.498811)
			(xy 129.932892 -403.482924) (xy 129.985891 -403.47489) (xy 130.039497 -403.47489) (xy 130.092496 -403.482924)
			(xy 130.143693 -403.498811) (xy 130.191931 -403.522191) (xy 130.236119 -403.552537) (xy 130.275261 -403.589163)
			(xy 130.308471 -403.631242) (xy 130.334999 -403.677822) (xy 130.354247 -403.727853) (xy 130.365779 -403.780203)
			(xy 130.36804 -403.806914) (xy 130.36931 -403.82698) (xy 130.39852 -403.854412) (xy 130.885692 -403.854412)
			(xy 130.914902 -403.82698) (xy 130.916172 -403.806914) (xy 130.918433 -403.780203) (xy 130.929965 -403.727853)
			(xy 130.949213 -403.677822) (xy 130.975741 -403.631242) (xy 131.008951 -403.589163) (xy 131.048093 -403.552537)
			(xy 131.092281 -403.522191) (xy 131.140519 -403.498811) (xy 131.191716 -403.482924) (xy 131.244715 -403.47489)
			(xy 131.298321 -403.47489) (xy 131.35132 -403.482924) (xy 131.402517 -403.498811) (xy 131.450755 -403.522191)
			(xy 131.494943 -403.552537) (xy 131.534085 -403.589163) (xy 131.567295 -403.631242) (xy 131.593823 -403.677822)
			(xy 131.613071 -403.727853) (xy 131.624603 -403.780203) (xy 131.626864 -403.806914) (xy 131.628134 -403.82698)
			(xy 131.657344 -403.854412) (xy 132.690108 -403.854412) (xy 132.719318 -403.82698) (xy 132.720588 -403.806914)
			(xy 132.722849 -403.780203) (xy 132.734381 -403.727853) (xy 132.753629 -403.677822) (xy 132.780157 -403.631242)
			(xy 132.813367 -403.589163) (xy 132.852509 -403.552537) (xy 132.896697 -403.522191) (xy 132.944935 -403.498811)
			(xy 132.996132 -403.482924) (xy 133.049131 -403.47489) (xy 133.102737 -403.47489) (xy 133.155736 -403.482924)
			(xy 133.206933 -403.498811) (xy 133.255171 -403.522191) (xy 133.299359 -403.552537) (xy 133.338501 -403.589163)
			(xy 133.371711 -403.631242) (xy 133.398239 -403.677822) (xy 133.417487 -403.727853) (xy 133.429019 -403.780203)
			(xy 133.43128 -403.806914) (xy 133.43255 -403.82698) (xy 133.46176 -403.854412) (xy 133.948932 -403.854412)
			(xy 133.978142 -403.82698) (xy 133.979412 -403.806914) (xy 133.981673 -403.780203) (xy 133.993205 -403.727853)
			(xy 134.012453 -403.677822) (xy 134.038981 -403.631242) (xy 134.072191 -403.589163) (xy 134.111333 -403.552537)
			(xy 134.155521 -403.522191) (xy 134.203759 -403.498811) (xy 134.254956 -403.482924) (xy 134.307955 -403.47489)
			(xy 134.361561 -403.47489) (xy 134.41456 -403.482924) (xy 134.465757 -403.498811) (xy 134.513995 -403.522191)
			(xy 134.558183 -403.552537) (xy 134.597325 -403.589163) (xy 134.630535 -403.631242) (xy 134.657063 -403.677822)
			(xy 134.676311 -403.727853) (xy 134.687843 -403.780203) (xy 134.690104 -403.806914) (xy 134.691374 -403.82698)
			(xy 134.720584 -403.854412) (xy 135.753348 -403.854412) (xy 135.782558 -403.82698) (xy 135.783828 -403.806914)
			(xy 135.786089 -403.780203) (xy 135.797621 -403.727853) (xy 135.816869 -403.677822) (xy 135.843397 -403.631242)
			(xy 135.876607 -403.589163) (xy 135.915749 -403.552537) (xy 135.959937 -403.522191) (xy 136.008175 -403.498811)
			(xy 136.059372 -403.482924) (xy 136.112371 -403.47489) (xy 136.165977 -403.47489) (xy 136.218976 -403.482924)
			(xy 136.270173 -403.498811) (xy 136.318411 -403.522191) (xy 136.362599 -403.552537) (xy 136.401741 -403.589163)
			(xy 136.434951 -403.631242) (xy 136.461479 -403.677822) (xy 136.480727 -403.727853) (xy 136.492259 -403.780203)
			(xy 136.49452 -403.806914) (xy 136.49579 -403.82698) (xy 136.525 -403.854412) (xy 137.012172 -403.854412)
			(xy 137.041382 -403.82698) (xy 137.042652 -403.806914) (xy 137.044913 -403.780203) (xy 137.056445 -403.727853)
			(xy 137.075693 -403.677822) (xy 137.102221 -403.631242) (xy 137.135431 -403.589163) (xy 137.174573 -403.552537)
			(xy 137.218761 -403.522191) (xy 137.266999 -403.498811) (xy 137.318196 -403.482924) (xy 137.371195 -403.47489)
			(xy 137.424801 -403.47489) (xy 137.4778 -403.482924) (xy 137.528997 -403.498811) (xy 137.577235 -403.522191)
			(xy 137.621423 -403.552537) (xy 137.660565 -403.589163) (xy 137.693775 -403.631242) (xy 137.720303 -403.677822)
			(xy 137.739551 -403.727853) (xy 137.751083 -403.780203) (xy 137.753344 -403.806914) (xy 137.754614 -403.82698)
			(xy 137.783824 -403.854412) (xy 138.589512 -403.854412) (xy 138.599582 -403.853987) (xy 138.618184 -403.846271)
			(xy 138.62558 -403.839426) (xy 139.05865 -403.406356) (xy 139.065495 -403.398957) (xy 139.073221 -403.380359)
			(xy 139.073636 -403.370288) (xy 139.073636 -394.126974) (xy 139.074065 -394.116907) (xy 139.08179 -394.098312)
			(xy 139.088622 -394.090906) (xy 139.109704 -394.069824) (xy 139.144756 -394.034772) (xy 139.151106 -394.024104)
			(xy 139.152884 -394.018262) (xy 139.16244 -393.988909) (xy 139.187688 -393.932578) (xy 139.219569 -393.879717)
			(xy 139.257613 -393.831102) (xy 139.301261 -393.78745) (xy 139.349871 -393.7494) (xy 139.402729 -393.717514)
			(xy 139.459058 -393.692259) (xy 139.488418 -393.682728) (xy 139.49426 -393.680696) (xy 139.504928 -393.674346)
			(xy 139.594844 -393.58443) (xy 139.601686 -393.577031) (xy 139.609403 -393.558432) (xy 139.60983 -393.548362)
			(xy 139.60983 -392.837162) (xy 139.610261 -392.827095) (xy 139.617988 -392.808504) (xy 139.624816 -392.801094)
			(xy 139.850622 -392.575288) (xy 139.858017 -392.568435) (xy 139.876617 -392.560695) (xy 139.88669 -392.560302)
			(xy 140.14323 -392.560302) (xy 140.153298 -392.559873) (xy 140.171894 -392.552151) (xy 140.179298 -392.545316)
			(xy 140.352018 -392.372596) (xy 140.358873 -392.365201) (xy 140.366619 -392.346602) (xy 140.367004 -392.336528)
			(xy 140.367004 -391.281412) (xy 140.366469 -391.271423) (xy 140.358759 -391.252988) (xy 140.352018 -391.245598)
			(xy 140.351764 -391.24509) (xy 140.345085 -391.237678) (xy 140.337512 -391.219242) (xy 140.337032 -391.209276)
			(xy 140.337032 -390.176766) (xy 140.336489 -390.166781) (xy 140.328771 -390.148354) (xy 140.322046 -390.140952)
			(xy 140.211048 -390.029954) (xy 140.203649 -390.02311) (xy 140.18505 -390.015386) (xy 140.17498 -390.014968)
			(xy 139.039092 -390.014968) (xy 139.029022 -390.015392) (xy 139.010416 -390.023105) (xy 139.003024 -390.029954)
			(xy 138.625834 -390.407144) (xy 138.619027 -390.41449) (xy 138.611305 -390.432953) (xy 138.610848 -390.442958)
			(xy 138.610848 -392.4681) (xy 138.610372 -392.478066) (xy 138.602796 -392.496503) (xy 138.596116 -392.503914)
			(xy 138.428222 -392.671808) (xy 138.420813 -392.678495) (xy 138.402377 -392.686083) (xy 138.392408 -392.68654)
			(xy 137.2108 -392.68654) (xy 137.200832 -392.686067) (xy 137.182386 -392.6785) (xy 137.174986 -392.671808)
			(xy 137.160508 -392.657584) (xy 137.153167 -392.650763) (xy 137.134704 -392.643015) (xy 137.124694 -392.642598)
			(xy 136.746996 -392.642598) (xy 136.736926 -392.643022) (xy 136.718323 -392.650737) (xy 136.710928 -392.657584)
			(xy 136.589008 -392.779504) (xy 136.582162 -392.786903) (xy 136.574427 -392.8055) (xy 136.574022 -392.815572)
			(xy 136.574022 -394.735812) (xy 136.573597 -394.745882) (xy 136.565882 -394.764485) (xy 136.559036 -394.77188)
			(xy 132.917692 -398.413224) (xy 132.910297 -398.420077) (xy 132.891698 -398.427821) (xy 132.881624 -398.42821)
			(xy 111.638842 -398.42821) (xy 111.628776 -398.427777) (xy 111.610186 -398.420049) (xy 111.602774 -398.413224)
			(xy 110.033562 -396.844012) (xy 110.000034 -396.839186) (xy 109.985302 -396.847314) (xy 109.957115 -396.862197)
			(xy 109.897825 -396.885598) (xy 109.836071 -396.901391) (xy 109.772825 -396.909329) (xy 109.740954 -396.909798)
			(xy 109.710225 -396.909331) (xy 109.649216 -396.901918) (xy 109.589545 -396.887205) (xy 109.532082 -396.865408)
			(xy 109.477666 -396.836843) (xy 109.427089 -396.801928) (xy 109.381089 -396.761171) (xy 109.340338 -396.715167)
			(xy 109.305428 -396.664586) (xy 109.276869 -396.610167) (xy 109.255078 -396.552702) (xy 109.240372 -396.493029)
			(xy 109.232965 -396.432019) (xy 109.232446 -396.40129) (xy 109.232946 -396.369422) (xy 109.240909 -396.306184)
			(xy 109.256696 -396.244433) (xy 109.280061 -396.185133) (xy 109.29493 -396.156942) (xy 109.303058 -396.14221)
			(xy 109.298232 -396.108682) (xy 108.74756 -395.55801) (xy 108.74016 -395.551169) (xy 108.721562 -395.543447)
			(xy 108.711492 -395.543024) (xy 107.61853 -395.543024) (xy 107.608288 -395.543496) (xy 107.589432 -395.551501)
			(xy 107.581954 -395.558518) (xy 107.524042 -395.618208) (xy 107.516676 -395.637512) (xy 107.51693 -395.647672)
			(xy 107.517184 -395.663166) (xy 107.516422 -395.692884) (xy 107.51566 -395.705838) (xy 107.526836 -395.72946)
			(xy 107.61853 -395.794738) (xy 107.644692 -395.797532) (xy 107.656884 -395.792452) (xy 107.686724 -395.780547)
			(xy 107.748668 -395.763498) (xy 107.812266 -395.754388) (xy 107.876506 -395.753362) (xy 107.940362 -395.760436)
			(xy 108.002819 -395.775498) (xy 108.062881 -395.798307) (xy 108.119592 -395.828501) (xy 108.172047 -395.865598)
			(xy 108.219411 -395.909008) (xy 108.260929 -395.958038) (xy 108.29594 -396.011907) (xy 108.323887 -396.069758)
			(xy 108.344323 -396.130668) (xy 108.356924 -396.193668) (xy 108.361489 -396.257753) (xy 108.357944 -396.321902)
			(xy 108.346346 -396.385094) (xy 108.326881 -396.446322) (xy 108.299858 -396.50461) (xy 108.265708 -396.559029)
			(xy 108.224974 -396.608713) (xy 108.178306 -396.65287) (xy 108.126448 -396.690797) (xy 108.070225 -396.721889)
			(xy 108.010533 -396.74565) (xy 107.948324 -396.761704) (xy 107.884588 -396.769792) (xy 107.852464 -396.770352)
			(xy 107.819514 -396.769834) (xy 107.754164 -396.761326) (xy 107.690463 -396.744445) (xy 107.629476 -396.719473)
			(xy 107.572229 -396.68683) (xy 107.519679 -396.647063) (xy 107.495848 -396.624302) (xy 107.488228 -396.616936)
			(xy 107.46867 -396.609316) (xy 107.373166 -396.61338) (xy 107.35437 -396.622524) (xy 107.347512 -396.630652)
			(xy 107.326758 -396.654118) (xy 107.280449 -396.696308) (xy 107.229306 -396.732488) (xy 107.174106 -396.762112)
			(xy 107.115685 -396.784729) (xy 107.054928 -396.799997) (xy 106.992755 -396.807685) (xy 106.961432 -396.808198)
			(xy 106.930699 -396.807754) (xy 106.86968 -396.800349) (xy 106.809999 -396.785642) (xy 106.752527 -396.763848)
			(xy 106.6981 -396.735285) (xy 106.647513 -396.70037) (xy 106.601504 -396.659612) (xy 106.560743 -396.613604)
			(xy 106.525826 -396.563019) (xy 106.497261 -396.508594) (xy 106.475465 -396.451122) (xy 106.460755 -396.391441)
			(xy 106.453347 -396.330423) (xy 106.452924 -396.29969) (xy 106.453512 -396.265028) (xy 106.46293 -396.196347)
			(xy 106.48159 -396.129581) (xy 106.509146 -396.065969) (xy 106.545088 -396.00669) (xy 106.566462 -395.979396)
			(xy 106.57259 -395.971103) (xy 106.578231 -395.951291) (xy 106.575586 -395.930863) (xy 106.57078 -395.921738)
			(xy 106.554023 -395.892242) (xy 106.527611 -395.829758) (xy 106.509736 -395.764319) (xy 106.500713 -395.697084)
			(xy 106.500168 -395.663166) (xy 106.500725 -395.628913) (xy 106.50992 -395.561027) (xy 106.528153 -395.494992)
			(xy 106.555093 -395.432005) (xy 106.590251 -395.373209) (xy 106.63299 -395.31967) (xy 106.657394 -395.295628)
			(xy 106.66476 -395.288262) (xy 106.672888 -395.269974) (xy 106.673904 -395.186916) (xy 106.673559 -395.176715)
			(xy 106.665844 -395.157835) (xy 106.658918 -395.15034) (xy 106.55046 -395.041882) (xy 106.54361 -395.034485)
			(xy 106.535873 -395.015887) (xy 106.535474 -395.005814) (xy 106.535474 -394.074142) (xy 106.535907 -394.064076)
			(xy 106.543633 -394.045484) (xy 106.55046 -394.038074) (xy 106.665776 -393.922758) (xy 106.669078 -393.916916)
			(xy 106.685278 -393.889398) (xy 106.723553 -393.838281) (xy 106.767934 -393.792366) (xy 106.817723 -393.752378)
			(xy 106.872132 -393.718948) (xy 106.930303 -393.692604) (xy 106.96067 -393.682728) (xy 106.966512 -393.680696)
			(xy 106.97718 -393.674346) (xy 107.067096 -393.58443) (xy 107.073932 -393.577028) (xy 107.081641 -393.55843)
			(xy 107.082082 -393.548362) (xy 107.082082 -392.837162) (xy 107.082511 -392.827094) (xy 107.090234 -392.808498)
			(xy 107.097068 -392.801094) (xy 107.322874 -392.575288) (xy 107.330272 -392.568444) (xy 107.348872 -392.560722)
			(xy 107.358942 -392.560302) (xy 107.615482 -392.560302) (xy 107.625546 -392.559864) (xy 107.644129 -392.552129)
			(xy 107.65155 -392.545316) (xy 107.82427 -392.372596) (xy 107.831119 -392.365199) (xy 107.838857 -392.3466)
			(xy 107.839256 -392.336528) (xy 107.839256 -390.206992) (xy 107.83883 -390.196923) (xy 107.831109 -390.178325)
			(xy 107.82427 -390.170924) (xy 107.6833 -390.029954) (xy 107.675904 -390.023102) (xy 107.657306 -390.015359)
			(xy 107.647232 -390.014968) (xy 105.682034 -390.014968) (xy 105.671982 -390.015471) (xy 105.653417 -390.023188)
			(xy 105.645966 -390.029954) (xy 105.307892 -390.368028) (xy 105.301051 -390.375429) (xy 105.293328 -390.394026)
			(xy 105.292906 -390.404096) (xy 105.292906 -392.174984) (xy 105.292468 -392.185048) (xy 105.284733 -392.203631)
			(xy 105.27792 -392.211052) (xy 104.79151 -392.697462) (xy 104.784114 -392.704314) (xy 104.765516 -392.712058)
			(xy 104.755442 -392.712448) (xy 102.466902 -392.712448) (xy 102.456833 -392.712872) (xy 102.438232 -392.720591)
			(xy 102.430834 -392.727434) (xy 102.083616 -393.074652) (xy 102.076776 -393.082052) (xy 102.069058 -393.100651)
			(xy 102.06863 -393.11072) (xy 102.06863 -393.459673) (xy 102.446068 -393.459673) (xy 102.446068 -393.395751)
			(xy 102.454079 -393.332333) (xy 102.469976 -393.270419) (xy 102.493508 -393.210986) (xy 102.524302 -393.154971)
			(xy 102.561875 -393.103256) (xy 102.605632 -393.056659) (xy 102.654885 -393.015914) (xy 102.708856 -392.981663)
			(xy 102.766695 -392.954446) (xy 102.827488 -392.934693) (xy 102.890278 -392.922715) (xy 102.954074 -392.918702)
			(xy 103.01787 -392.922715) (xy 103.08066 -392.934693) (xy 103.141453 -392.954446) (xy 103.199292 -392.981663)
			(xy 103.253263 -393.015914) (xy 103.302516 -393.056659) (xy 103.346273 -393.103256) (xy 103.383846 -393.154971)
			(xy 103.41464 -393.210986) (xy 103.438172 -393.270419) (xy 103.454069 -393.332333) (xy 103.46208 -393.395751)
			(xy 103.462582 -393.427712) (xy 103.46208 -393.459673) (xy 103.454069 -393.523091) (xy 103.438172 -393.585005)
			(xy 103.41464 -393.644438) (xy 103.383846 -393.700453) (xy 103.346273 -393.752168) (xy 103.302516 -393.798765)
			(xy 103.253263 -393.83951) (xy 103.199292 -393.873761) (xy 103.141453 -393.900978) (xy 103.08066 -393.920731)
			(xy 103.01787 -393.932709) (xy 102.954074 -393.936723) (xy 102.890278 -393.932709) (xy 102.827488 -393.920731)
			(xy 102.766695 -393.900978) (xy 102.708856 -393.873761) (xy 102.654885 -393.83951) (xy 102.605632 -393.798765)
			(xy 102.561875 -393.752168) (xy 102.524302 -393.700453) (xy 102.493508 -393.644438) (xy 102.469976 -393.585005)
			(xy 102.454079 -393.523091) (xy 102.446068 -393.459673) (xy 102.06863 -393.459673) (xy 102.06863 -394.478002)
			(xy 102.068207 -394.488073) (xy 102.060496 -394.506679) (xy 102.053644 -394.51407) (xy 101.942138 -394.625576)
			(xy 103.274622 -394.625576) (xy 103.275117 -394.591549) (xy 103.283017 -394.523956) (xy 103.298711 -394.457738)
			(xy 103.321987 -394.393789) (xy 103.352529 -394.332974) (xy 103.389925 -394.276117) (xy 103.433668 -394.223985)
			(xy 103.483168 -394.177284) (xy 103.537755 -394.136646) (xy 103.596691 -394.102619) (xy 103.659179 -394.075665)
			(xy 103.724373 -394.056147) (xy 103.791392 -394.044329) (xy 103.85933 -394.040373) (xy 103.927268 -394.044329)
			(xy 103.994287 -394.056147) (xy 104.059481 -394.075665) (xy 104.121969 -394.102619) (xy 104.180905 -394.136646)
			(xy 104.235492 -394.177284) (xy 104.284992 -394.223985) (xy 104.328735 -394.276117) (xy 104.366131 -394.332974)
			(xy 104.396673 -394.393789) (xy 104.419949 -394.457738) (xy 104.435643 -394.523956) (xy 104.443543 -394.591549)
			(xy 104.444038 -394.625576) (xy 104.443605 -394.657767) (xy 104.436526 -394.721757) (xy 104.422461 -394.784584)
			(xy 104.401581 -394.845485) (xy 104.374138 -394.903725) (xy 104.357678 -394.931392) (xy 104.35082 -394.942314)
			(xy 104.34955 -394.967714) (xy 104.396286 -395.068044) (xy 104.41686 -395.083284) (xy 104.42956 -395.085062)
			(xy 104.444505 -395.087333) (xy 104.474116 -395.093433) (xy 104.488742 -395.097254) (xy 104.499345 -395.099601)
			(xy 104.520771 -395.096214) (xy 104.5389 -395.084302) (xy 104.54513 -395.07541) (xy 104.56299 -395.048009)
			(xy 104.603911 -394.996981) (xy 104.650273 -394.950841) (xy 104.701496 -394.910165) (xy 104.75694 -394.875462)
			(xy 104.815912 -394.847165) (xy 104.877674 -394.825629) (xy 104.941454 -394.811123) (xy 105.006455 -394.803827)
			(xy 105.03916 -394.803376) (xy 105.074496 -394.803942) (xy 105.144653 -394.812456) (xy 105.213272 -394.829364)
			(xy 105.279353 -394.854421) (xy 105.341931 -394.88726) (xy 105.400095 -394.927403) (xy 105.452996 -394.974265)
			(xy 105.499862 -395.027161) (xy 105.540011 -395.085321) (xy 105.572856 -395.147896) (xy 105.597919 -395.213975)
			(xy 105.614834 -395.282592) (xy 105.623355 -395.352748) (xy 105.623868 -395.388084) (xy 105.623359 -395.424003)
			(xy 105.614583 -395.495303) (xy 105.597124 -395.564987) (xy 105.571247 -395.632002) (xy 105.55478 -395.663928)
			(xy 105.550039 -395.673812) (xy 105.548607 -395.695661) (xy 105.556456 -395.716102) (xy 105.563924 -395.724126)
			(xy 105.587548 -395.748081) (xy 105.628871 -395.801175) (xy 105.662829 -395.859256) (xy 105.688827 -395.92131)
			(xy 105.706413 -395.986251) (xy 105.715277 -396.052944) (xy 105.715816 -396.086584) (xy 105.715347 -396.117315)
			(xy 105.707941 -396.17833) (xy 105.693233 -396.238008) (xy 105.67144 -396.295477) (xy 105.642878 -396.349901)
			(xy 105.607964 -396.400485) (xy 105.567208 -396.446491) (xy 105.521203 -396.48725) (xy 105.470621 -396.522166)
			(xy 105.416199 -396.55073) (xy 105.358731 -396.572526) (xy 105.299054 -396.587236) (xy 105.238039 -396.594646)
			(xy 105.207308 -396.595092) (xy 105.176127 -396.594604) (xy 105.114232 -396.586978) (xy 105.053735 -396.57184)
			(xy 104.995543 -396.549417) (xy 104.940531 -396.520045) (xy 104.889524 -396.484166) (xy 104.843287 -396.442317)
			(xy 104.802516 -396.395129) (xy 104.767822 -396.343308) (xy 104.739725 -396.287633) (xy 104.718649 -396.22894)
			(xy 104.704909 -396.16811) (xy 104.70134 -396.13713) (xy 104.70007 -396.124938) (xy 104.687116 -396.104618)
			(xy 104.594914 -396.05077) (xy 104.571038 -396.049246) (xy 104.559608 -396.054326) (xy 104.557322 -396.055342)
			(xy 104.544876 -396.060676) (xy 104.52862 -396.08252) (xy 104.515412 -396.197074) (xy 104.526334 -396.22222)
			(xy 104.537256 -396.230348) (xy 104.560837 -396.248465) (xy 104.602628 -396.290763) (xy 104.637347 -396.339036)
			(xy 104.664151 -396.392114) (xy 104.682391 -396.448709) (xy 104.691625 -396.507449) (xy 104.692196 -396.53718)
			(xy 104.69171 -396.564431) (xy 104.683954 -396.618379) (xy 104.668599 -396.670674) (xy 104.645957 -396.720251)
			(xy 104.616491 -396.766101) (xy 104.5808 -396.807292) (xy 104.539609 -396.842983) (xy 104.493759 -396.872449)
			(xy 104.444182 -396.895091) (xy 104.391887 -396.910446) (xy 104.337939 -396.918202) (xy 104.283437 -396.918202)
			(xy 104.229489 -396.910446) (xy 104.177194 -396.895091) (xy 104.127617 -396.872449) (xy 104.081767 -396.842983)
			(xy 104.040576 -396.807292) (xy 104.004885 -396.766101) (xy 103.975419 -396.720251) (xy 103.952777 -396.670674)
			(xy 103.937422 -396.618379) (xy 103.929666 -396.564431) (xy 103.92918 -396.53718) (xy 103.929647 -396.509075)
			(xy 103.93789 -396.453473) (xy 103.954211 -396.399685) (xy 103.978254 -396.348877) (xy 104.009499 -396.302151)
			(xy 104.047267 -396.260521) (xy 104.09074 -396.224889) (xy 104.1146 -396.210028) (xy 104.126284 -396.202916)
			(xy 104.139492 -396.17904) (xy 104.137206 -396.063724) (xy 104.123236 -396.040356) (xy 104.111298 -396.033752)
			(xy 104.085058 -396.018826) (xy 104.035952 -395.98371) (xy 103.991352 -395.943023) (xy 103.951887 -395.89734)
			(xy 103.91811 -395.847303) (xy 103.890499 -395.793618) (xy 103.869442 -395.73704) (xy 103.855236 -395.678365)
			(xy 103.84808 -395.618421) (xy 103.847646 -395.588236) (xy 103.84811 -395.558162) (xy 103.855227 -395.498437)
			(xy 103.869329 -395.439966) (xy 103.890222 -395.383563) (xy 103.903526 -395.356588) (xy 103.909368 -395.345158)
			(xy 103.90886 -395.319758) (xy 103.85425 -395.223492) (xy 103.83266 -395.209776) (xy 103.81996 -395.209014)
			(xy 103.786256 -395.206185) (xy 103.719749 -395.193869) (xy 103.655108 -395.173961) (xy 103.593196 -395.14673)
			(xy 103.534838 -395.112537) (xy 103.480815 -395.071839) (xy 103.431848 -395.025181) (xy 103.388592 -394.973185)
			(xy 103.351623 -394.916545) (xy 103.321435 -394.856018) (xy 103.298432 -394.792413) (xy 103.282921 -394.726579)
			(xy 103.275109 -394.659394) (xy 103.274622 -394.625576) (xy 101.942138 -394.625576) (xy 100.832914 -395.7348)
			(xy 101.830562 -395.7348) (xy 101.834577 -395.670997) (xy 101.846557 -395.6082) (xy 101.866313 -395.5474)
			(xy 101.893534 -395.489556) (xy 101.927791 -395.43558) (xy 101.968543 -395.386323) (xy 102.015148 -395.342563)
			(xy 102.06687 -395.304989) (xy 102.122894 -395.274194) (xy 102.182335 -395.250665) (xy 102.244257 -395.234771)
			(xy 102.307683 -395.226764) (xy 102.339648 -395.226286) (xy 102.373013 -395.226788) (xy 102.439171 -395.235511)
			(xy 102.503622 -395.252803) (xy 102.565262 -395.278367) (xy 102.59441 -395.294612) (xy 102.604182 -395.299689)
			(xy 102.626079 -395.301785) (xy 102.646839 -395.294509) (xy 102.655116 -395.287246) (xy 102.678522 -395.265118)
			(xy 102.729369 -395.225575) (xy 102.784256 -395.191862) (xy 102.842516 -395.164388) (xy 102.903445 -395.143487)
			(xy 102.966302 -395.129412) (xy 103.030325 -395.122333) (xy 103.062532 -395.121892) (xy 103.096557 -395.122388)
			(xy 103.164148 -395.130292) (xy 103.230363 -395.145989) (xy 103.294309 -395.169266) (xy 103.35512 -395.19981)
			(xy 103.411975 -395.237206) (xy 103.464103 -395.28095) (xy 103.510801 -395.330449) (xy 103.551437 -395.385035)
			(xy 103.585461 -395.44397) (xy 103.612414 -395.506455) (xy 103.63193 -395.571647) (xy 103.643747 -395.638664)
			(xy 103.647704 -395.7066) (xy 103.643747 -395.774536) (xy 103.63193 -395.841553) (xy 103.612414 -395.906745)
			(xy 103.585461 -395.96923) (xy 103.551437 -396.028165) (xy 103.510801 -396.082751) (xy 103.464103 -396.13225)
			(xy 103.411975 -396.175994) (xy 103.35512 -396.21339) (xy 103.294309 -396.243934) (xy 103.230363 -396.267211)
			(xy 103.164148 -396.282908) (xy 103.096557 -396.290812) (xy 103.062532 -396.291308) (xy 103.028768 -396.290798)
			(xy 102.961691 -396.283017) (xy 102.895958 -396.267555) (xy 102.832446 -396.244618) (xy 102.772001 -396.214512)
			(xy 102.71543 -396.177639) (xy 102.689152 -396.156434) (xy 102.68033 -396.149819) (xy 102.659044 -396.144144)
			(xy 102.637331 -396.147863) (xy 102.627938 -396.15364) (xy 102.602417 -396.170643) (xy 102.548092 -396.199094)
			(xy 102.490738 -396.220804) (xy 102.431189 -396.235456) (xy 102.37031 -396.242839) (xy 102.339648 -396.243302)
			(xy 102.307683 -396.242836) (xy 102.244257 -396.234829) (xy 102.182335 -396.218935) (xy 102.122894 -396.195406)
			(xy 102.06687 -396.164611) (xy 102.015148 -396.127037) (xy 101.968543 -396.083277) (xy 101.927791 -396.03402)
			(xy 101.893534 -395.980044) (xy 101.866313 -395.9222) (xy 101.846557 -395.8614) (xy 101.834577 -395.798603)
			(xy 101.830562 -395.7348) (xy 100.832914 -395.7348) (xy 99.170499 -397.397215) (xy 101.333033 -397.397215)
			(xy 101.333033 -397.329161) (xy 101.340933 -397.261568) (xy 101.356627 -397.19535) (xy 101.379903 -397.131401)
			(xy 101.410445 -397.070586) (xy 101.447841 -397.013729) (xy 101.491584 -396.961597) (xy 101.541084 -396.914896)
			(xy 101.595671 -396.874258) (xy 101.654607 -396.840231) (xy 101.717095 -396.813277) (xy 101.782289 -396.793759)
			(xy 101.849308 -396.781941) (xy 101.917246 -396.777985) (xy 101.985184 -396.781941) (xy 102.052203 -396.793759)
			(xy 102.117397 -396.813277) (xy 102.179885 -396.840231) (xy 102.238821 -396.874258) (xy 102.293408 -396.914896)
			(xy 102.342908 -396.961597) (xy 102.386651 -397.013729) (xy 102.424047 -397.070586) (xy 102.454589 -397.131401)
			(xy 102.477865 -397.19535) (xy 102.493559 -397.261568) (xy 102.501459 -397.329161) (xy 102.501954 -397.363188)
			(xy 102.501459 -397.397215) (xy 102.493559 -397.464808) (xy 102.477865 -397.531026) (xy 102.474057 -397.541487)
			(xy 102.844079 -397.541487) (xy 102.844079 -397.473433) (xy 102.851979 -397.40584) (xy 102.867673 -397.339622)
			(xy 102.890949 -397.275673) (xy 102.921491 -397.214858) (xy 102.958887 -397.158001) (xy 103.00263 -397.105869)
			(xy 103.05213 -397.059168) (xy 103.106717 -397.01853) (xy 103.165653 -396.984503) (xy 103.228141 -396.957549)
			(xy 103.293335 -396.938031) (xy 103.360354 -396.926213) (xy 103.428292 -396.922257) (xy 103.49623 -396.926213)
			(xy 103.563249 -396.938031) (xy 103.628443 -396.957549) (xy 103.690931 -396.984503) (xy 103.749867 -397.01853)
			(xy 103.804454 -397.059168) (xy 103.853954 -397.105869) (xy 103.897697 -397.158001) (xy 103.935093 -397.214858)
			(xy 103.965635 -397.275673) (xy 103.988911 -397.339622) (xy 104.004605 -397.40584) (xy 104.012505 -397.473433)
			(xy 104.013 -397.50746) (xy 104.012505 -397.541487) (xy 104.004605 -397.60908) (xy 103.988911 -397.675298)
			(xy 103.965635 -397.739247) (xy 103.935093 -397.800062) (xy 103.897697 -397.856919) (xy 103.853954 -397.909051)
			(xy 103.804454 -397.955752) (xy 103.779539 -397.9743) (xy 105.905289 -397.9743) (xy 105.909247 -397.90636)
			(xy 105.921064 -397.839339) (xy 105.940583 -397.774143) (xy 105.967539 -397.711654) (xy 106.001567 -397.652717)
			(xy 106.042207 -397.598128) (xy 106.08891 -397.548628) (xy 106.141044 -397.504883) (xy 106.197904 -397.467488)
			(xy 106.258721 -397.436946) (xy 106.322672 -397.413671) (xy 106.388893 -397.397978) (xy 106.456488 -397.390079)
			(xy 106.490516 -397.389604) (xy 106.516437 -397.389873) (xy 106.568076 -397.394451) (xy 106.59364 -397.398748)
			(xy 106.60467 -397.400122) (xy 106.626142 -397.394497) (xy 106.643236 -397.380338) (xy 106.648504 -397.370554)
			(xy 106.662593 -397.342015) (xy 106.696922 -397.28842) (xy 106.737672 -397.239529) (xy 106.784205 -397.196106)
			(xy 106.835794 -397.15883) (xy 106.891632 -397.128284) (xy 106.950846 -397.104946) (xy 107.01251 -397.08918)
			(xy 107.075659 -397.081235) (xy 107.107482 -397.08074) (xy 107.137068 -397.081177) (xy 107.195842 -397.088031)
			(xy 107.253423 -397.10166) (xy 107.309033 -397.12188) (xy 107.361921 -397.148417) (xy 107.386882 -397.164306)
			(xy 107.396227 -397.169883) (xy 107.417692 -397.173326) (xy 107.438656 -397.16757) (xy 107.447334 -397.161004)
			(xy 107.473569 -397.139882) (xy 107.530067 -397.10321) (xy 107.590405 -397.073274) (xy 107.653784 -397.050469)
			(xy 107.719363 -397.035097) (xy 107.786274 -397.027363) (xy 107.819952 -397.026892) (xy 107.853981 -397.027365)
			(xy 107.921581 -397.035261) (xy 107.987806 -397.050952) (xy 108.051762 -397.074225) (xy 108.112584 -397.104766)
			(xy 108.169448 -397.142162) (xy 108.221586 -397.185907) (xy 108.268293 -397.23541) (xy 108.308936 -397.29)
			(xy 108.342968 -397.34894) (xy 108.369926 -397.411432) (xy 108.389446 -397.476631) (xy 108.401265 -397.543656)
			(xy 108.405223 -397.6116) (xy 108.401265 -397.679544) (xy 108.389778 -397.744687) (xy 109.124229 -397.744687)
			(xy 109.124229 -397.676633) (xy 109.132129 -397.60904) (xy 109.147823 -397.542822) (xy 109.171099 -397.478873)
			(xy 109.201641 -397.418058) (xy 109.239037 -397.361201) (xy 109.28278 -397.309069) (xy 109.33228 -397.262368)
			(xy 109.386867 -397.22173) (xy 109.445803 -397.187703) (xy 109.508291 -397.160749) (xy 109.573485 -397.141231)
			(xy 109.640504 -397.129413) (xy 109.708442 -397.125457) (xy 109.77638 -397.129413) (xy 109.843399 -397.141231)
			(xy 109.908593 -397.160749) (xy 109.971081 -397.187703) (xy 110.030017 -397.22173) (xy 110.084604 -397.262368)
			(xy 110.134104 -397.309069) (xy 110.177847 -397.361201) (xy 110.215243 -397.418058) (xy 110.245785 -397.478873)
			(xy 110.269061 -397.542822) (xy 110.284755 -397.60904) (xy 110.292655 -397.676633) (xy 110.29315 -397.71066)
			(xy 110.292655 -397.744687) (xy 110.284755 -397.81228) (xy 110.269061 -397.878498) (xy 110.245785 -397.942447)
			(xy 110.215243 -398.003262) (xy 110.177847 -398.060119) (xy 110.134104 -398.112251) (xy 110.084604 -398.158952)
			(xy 110.030017 -398.19959) (xy 109.971081 -398.233617) (xy 109.908593 -398.260571) (xy 109.843399 -398.280089)
			(xy 109.77638 -398.291907) (xy 109.708442 -398.295864) (xy 109.640504 -398.291907) (xy 109.573485 -398.280089)
			(xy 109.508291 -398.260571) (xy 109.445803 -398.233617) (xy 109.386867 -398.19959) (xy 109.33228 -398.158952)
			(xy 109.28278 -398.112251) (xy 109.239037 -398.060119) (xy 109.201641 -398.003262) (xy 109.171099 -397.942447)
			(xy 109.147823 -397.878498) (xy 109.132129 -397.81228) (xy 109.124229 -397.744687) (xy 108.389778 -397.744687)
			(xy 108.389446 -397.746569) (xy 108.369926 -397.811768) (xy 108.342968 -397.87426) (xy 108.308936 -397.9332)
			(xy 108.268293 -397.98779) (xy 108.221586 -398.037293) (xy 108.169448 -398.081038) (xy 108.112584 -398.118434)
			(xy 108.051762 -398.148975) (xy 107.987806 -398.172248) (xy 107.921581 -398.187939) (xy 107.853981 -398.195835)
			(xy 107.819952 -398.196308) (xy 107.783195 -398.195763) (xy 107.710261 -398.186554) (xy 107.639057 -398.168273)
			(xy 107.570706 -398.141209) (xy 107.506288 -398.10579) (xy 107.446818 -398.062574) (xy 107.419648 -398.037812)
			(xy 107.411439 -398.030728) (xy 107.390934 -398.023723) (xy 107.369363 -398.025767) (xy 107.359704 -398.0307)
			(xy 107.330779 -398.0466) (xy 107.269718 -398.071665) (xy 107.20593 -398.088629) (xy 107.140484 -398.097208)
			(xy 107.107482 -398.097756) (xy 107.096227 -398.097684) (xy 107.07374 -398.096669) (xy 107.062524 -398.095724)
			(xy 107.054396 -398.129252) (xy 107.05227 -398.138302) (xy 107.053977 -398.1568) (xy 107.057698 -398.16532)
			(xy 107.071414 -398.192752) (xy 107.075752 -398.20072) (xy 107.088887 -398.213217) (xy 107.097068 -398.217136)
			(xy 107.122648 -398.22844) (xy 107.170474 -398.257424) (xy 107.213554 -398.293082) (xy 107.250963 -398.334651)
			(xy 107.281899 -398.381239) (xy 107.305698 -398.431845) (xy 107.32185 -398.485385) (xy 107.330009 -398.54071)
			(xy 107.330494 -398.568672) (xy 107.330086 -398.593504) (xy 107.323635 -398.642748) (xy 107.310852 -398.69074)
			(xy 107.291951 -398.736668) (xy 107.279948 -398.75841) (xy 107.275689 -398.766684) (xy 107.272811 -398.785049)
			(xy 107.27436 -398.794224) (xy 107.28071 -398.82445) (xy 107.283129 -398.833553) (xy 107.293409 -398.849316)
			(xy 107.300776 -398.855184) (xy 107.325026 -398.873119) (xy 107.369531 -398.913832) (xy 107.408908 -398.959523)
			(xy 107.442603 -399.009551) (xy 107.470145 -399.063214) (xy 107.491145 -399.119758) (xy 107.505309 -399.178388)
			(xy 107.512439 -399.238283) (xy 107.512866 -399.268442) (xy 107.512364 -399.300403) (xy 107.504353 -399.363821)
			(xy 107.488456 -399.425735) (xy 107.464924 -399.485168) (xy 107.43413 -399.541183) (xy 107.396557 -399.592898)
			(xy 107.3528 -399.639495) (xy 107.35096 -399.641017) (xy 112.941856 -399.641017) (xy 112.941856 -399.577095)
			(xy 112.949867 -399.513677) (xy 112.965764 -399.451763) (xy 112.989296 -399.39233) (xy 113.02009 -399.336315)
			(xy 113.057663 -399.2846) (xy 113.10142 -399.238003) (xy 113.150673 -399.197258) (xy 113.204644 -399.163007)
			(xy 113.262483 -399.13579) (xy 113.323276 -399.116037) (xy 113.386066 -399.104059) (xy 113.449862 -399.100046)
			(xy 113.513658 -399.104059) (xy 113.576448 -399.116037) (xy 113.637241 -399.13579) (xy 113.69508 -399.163007)
			(xy 113.749051 -399.197258) (xy 113.798304 -399.238003) (xy 113.842061 -399.2846) (xy 113.879634 -399.336315)
			(xy 113.910428 -399.39233) (xy 113.93396 -399.451763) (xy 113.949857 -399.513677) (xy 113.957868 -399.577095)
			(xy 113.95837 -399.609056) (xy 113.957868 -399.641017) (xy 113.949857 -399.704435) (xy 113.93396 -399.766349)
			(xy 113.910428 -399.825782) (xy 113.879634 -399.881797) (xy 113.842061 -399.933512) (xy 113.798304 -399.980109)
			(xy 113.749051 -400.020854) (xy 113.69508 -400.055105) (xy 113.637241 -400.082322) (xy 113.576448 -400.102075)
			(xy 113.513658 -400.114053) (xy 113.449862 -400.118067) (xy 113.386066 -400.114053) (xy 113.323276 -400.102075)
			(xy 113.262483 -400.082322) (xy 113.204644 -400.055105) (xy 113.150673 -400.020854) (xy 113.10142 -399.980109)
			(xy 113.057663 -399.933512) (xy 113.02009 -399.881797) (xy 112.989296 -399.825782) (xy 112.965764 -399.766349)
			(xy 112.949867 -399.704435) (xy 112.941856 -399.641017) (xy 107.35096 -399.641017) (xy 107.303547 -399.68024)
			(xy 107.249576 -399.714491) (xy 107.191737 -399.741708) (xy 107.130944 -399.761461) (xy 107.068154 -399.773439)
			(xy 107.004358 -399.777453) (xy 106.940562 -399.773439) (xy 106.877772 -399.761461) (xy 106.816979 -399.741708)
			(xy 106.75914 -399.714491) (xy 106.705169 -399.68024) (xy 106.655916 -399.639495) (xy 106.612159 -399.592898)
			(xy 106.574586 -399.541183) (xy 106.543792 -399.485168) (xy 106.52026 -399.425735) (xy 106.504363 -399.363821)
			(xy 106.496352 -399.300403) (xy 106.49585 -399.268442) (xy 106.496382 -399.234922) (xy 106.50518 -399.168463)
			(xy 106.522643 -399.103738) (xy 106.548467 -399.041872) (xy 106.582203 -398.983939) (xy 106.623266 -398.930948)
			(xy 106.646726 -398.907) (xy 106.653167 -398.900098) (xy 106.660868 -398.882875) (xy 106.661712 -398.873472)
			(xy 106.663236 -398.842484) (xy 106.663257 -398.833234) (xy 106.657523 -398.815659) (xy 106.65206 -398.808194)
			(xy 106.636304 -398.788015) (xy 106.609747 -398.744244) (xy 106.589297 -398.697309) (xy 106.575323 -398.648056)
			(xy 106.571288 -398.622774) (xy 106.569644 -398.613799) (xy 106.560912 -398.59779) (xy 106.55427 -398.591532)
			(xy 106.53141 -398.571466) (xy 106.524139 -398.56566) (xy 106.506675 -398.559284) (xy 106.497374 -398.55902)
			(xy 106.490516 -398.55902) (xy 106.456488 -398.558521) (xy 106.388893 -398.550622) (xy 106.322672 -398.534929)
			(xy 106.258721 -398.511654) (xy 106.197904 -398.481112) (xy 106.141044 -398.443717) (xy 106.08891 -398.399972)
			(xy 106.042207 -398.350472) (xy 106.001567 -398.295883) (xy 105.967539 -398.236946) (xy 105.940583 -398.174457)
			(xy 105.921064 -398.109261) (xy 105.909247 -398.04224) (xy 105.905289 -397.9743) (xy 103.779539 -397.9743)
			(xy 103.749867 -397.99639) (xy 103.690931 -398.030417) (xy 103.628443 -398.057371) (xy 103.563249 -398.076889)
			(xy 103.49623 -398.088707) (xy 103.428292 -398.092664) (xy 103.360354 -398.088707) (xy 103.293335 -398.076889)
			(xy 103.228141 -398.057371) (xy 103.165653 -398.030417) (xy 103.106717 -397.99639) (xy 103.05213 -397.955752)
			(xy 103.00263 -397.909051) (xy 102.958887 -397.856919) (xy 102.921491 -397.800062) (xy 102.890949 -397.739247)
			(xy 102.867673 -397.675298) (xy 102.851979 -397.60908) (xy 102.844079 -397.541487) (xy 102.474057 -397.541487)
			(xy 102.454589 -397.594975) (xy 102.424047 -397.65579) (xy 102.386651 -397.712647) (xy 102.342908 -397.764779)
			(xy 102.293408 -397.81148) (xy 102.238821 -397.852118) (xy 102.179885 -397.886145) (xy 102.117397 -397.913099)
			(xy 102.052203 -397.932617) (xy 101.985184 -397.944435) (xy 101.917246 -397.948392) (xy 101.849308 -397.944435)
			(xy 101.782289 -397.932617) (xy 101.717095 -397.913099) (xy 101.654607 -397.886145) (xy 101.595671 -397.852118)
			(xy 101.541084 -397.81148) (xy 101.491584 -397.764779) (xy 101.447841 -397.712647) (xy 101.410445 -397.65579)
			(xy 101.379903 -397.594975) (xy 101.356627 -397.531026) (xy 101.340933 -397.464808) (xy 101.333033 -397.397215)
			(xy 99.170499 -397.397215) (xy 99.042982 -397.524732) (xy 99.035616 -397.547846) (xy 99.037902 -397.560292)
			(xy 99.041261 -397.581467) (xy 99.044824 -397.624197) (xy 99.045014 -397.645636) (xy 99.044722 -397.670824)
			(xy 99.039765 -397.720956) (xy 99.035108 -397.745712) (xy 99.03376 -397.754557) (xy 99.036498 -397.772224)
			(xy 99.040442 -397.780256) (xy 99.05492 -397.806418) (xy 99.059594 -397.814165) (xy 99.07326 -397.826002)
			(xy 99.08159 -397.829532) (xy 99.114579 -397.842474) (xy 99.177425 -397.875222) (xy 99.235852 -397.915324)
			(xy 99.289006 -397.962193) (xy 99.336106 -398.015142) (xy 99.376462 -398.073395) (xy 99.409483 -398.136097)
			(xy 99.434685 -398.20233) (xy 99.451698 -398.271124) (xy 99.460274 -398.341469) (xy 99.460812 -398.376902)
			(xy 99.460279 -398.412238) (xy 99.45176 -398.482395) (xy 99.434847 -398.551013) (xy 99.409786 -398.617093)
			(xy 99.376943 -398.67967) (xy 99.336797 -398.737832) (xy 99.289932 -398.790731) (xy 99.237034 -398.837595)
			(xy 99.178872 -398.877742) (xy 99.116295 -398.910585) (xy 99.050215 -398.935646) (xy 98.981597 -398.95256)
			(xy 98.91144 -398.961079) (xy 98.876104 -398.96161) (xy 98.842534 -398.961142) (xy 98.775835 -398.953451)
			(xy 98.710457 -398.938169) (xy 98.64726 -398.915499) (xy 98.587076 -398.885738) (xy 98.530698 -398.849278)
			(xy 98.478868 -398.806599) (xy 98.432269 -398.758264) (xy 98.391513 -398.704908) (xy 98.357138 -398.647235)
			(xy 98.329597 -398.586004) (xy 98.309251 -398.52202) (xy 98.302318 -398.48917) (xy 98.299524 -398.4752)
			(xy 98.280982 -398.454626) (xy 98.167952 -398.420082) (xy 98.140774 -398.42694) (xy 98.139504 -398.42821)
			(xy 75.128882 -398.42821) (xy 75.118813 -398.427784) (xy 75.100212 -398.420066) (xy 75.092814 -398.413224)
			(xy 71.986648 -395.307058) (xy 71.979803 -395.299659) (xy 71.972076 -395.281061) (xy 71.971662 -395.27099)
			(xy 71.971662 -394.128752) (xy 71.972096 -394.118687) (xy 71.979829 -394.100101) (xy 71.986648 -394.092684)
			(xy 72.044814 -394.034518) (xy 72.051164 -394.02385) (xy 72.053196 -394.018008) (xy 72.062752 -393.988683)
			(xy 72.087993 -393.932406) (xy 72.119857 -393.879597) (xy 72.157877 -393.83103) (xy 72.201494 -393.787421)
			(xy 72.250067 -393.749409) (xy 72.302882 -393.717553) (xy 72.359163 -393.692321) (xy 72.388476 -393.682728)
			(xy 72.394318 -393.680696) (xy 72.404986 -393.674346) (xy 72.494902 -393.58443) (xy 72.501737 -393.577028)
			(xy 72.509446 -393.558429) (xy 72.509888 -393.548362) (xy 72.509888 -392.837162) (xy 72.510318 -392.827095)
			(xy 72.51804 -392.808499) (xy 72.524874 -392.801094) (xy 72.75068 -392.575288) (xy 72.758079 -392.568445)
			(xy 72.776678 -392.560725) (xy 72.786748 -392.560302) (xy 73.043288 -392.560302) (xy 73.053359 -392.559881)
			(xy 73.071967 -392.55217) (xy 73.079356 -392.545316) (xy 73.252076 -392.372596) (xy 73.258924 -392.365198)
			(xy 73.266661 -392.3466) (xy 73.267062 -392.336528) (xy 73.267062 -390.206992) (xy 73.266637 -390.196923)
			(xy 73.258916 -390.178324) (xy 73.252076 -390.170924) (xy 73.111106 -390.029954) (xy 73.10371 -390.023101)
			(xy 73.085112 -390.015356) (xy 73.075038 -390.014968) (xy 71.93915 -390.014968) (xy 71.929083 -390.015399)
			(xy 71.910489 -390.023123) (xy 71.903082 -390.029954) (xy 71.515478 -390.417558) (xy 71.508874 -390.429242)
			(xy 71.507096 -390.435846) (xy 71.500669 -390.458459) (xy 71.483035 -390.502038) (xy 71.460193 -390.543127)
			(xy 71.446644 -390.562338) (xy 71.442203 -390.569024) (xy 71.437276 -390.584289) (xy 71.436992 -390.59231)
			(xy 71.436992 -392.355578) (xy 71.436554 -392.365642) (xy 71.428819 -392.384225) (xy 71.422006 -392.391646)
			(xy 71.400924 -392.412728) (xy 71.394242 -392.420138) (xy 71.386666 -392.438574) (xy 71.386192 -392.448542)
			(xy 71.386192 -392.44905) (xy 71.385688 -392.465757) (xy 71.37702 -392.498026) (xy 71.360289 -392.52695)
			(xy 71.336638 -392.550552) (xy 71.30768 -392.567222) (xy 71.275392 -392.575823) (xy 71.258684 -392.576304)
			(xy 71.258176 -392.576304) (xy 71.248191 -392.576846) (xy 71.229765 -392.584566) (xy 71.222362 -392.59129)
			(xy 71.18604 -392.627612) (xy 71.178642 -392.634458) (xy 71.160043 -392.642185) (xy 71.149972 -392.642598)
			(xy 69.647054 -392.642598) (xy 69.636988 -392.64303) (xy 69.618395 -392.650756) (xy 69.610986 -392.657584)
			(xy 69.489066 -392.779504) (xy 69.482213 -392.786899) (xy 69.474469 -392.805498) (xy 69.47408 -392.815572)
			(xy 69.47408 -394.77696) (xy 69.473645 -394.787025) (xy 69.465913 -394.805612) (xy 69.459094 -394.813028)
			(xy 65.858898 -398.413224) (xy 65.851503 -398.420078) (xy 65.832904 -398.427824) (xy 65.82283 -398.42821)
			(xy 47.651924 -398.42821) (xy 47.64186 -398.428647) (xy 47.623277 -398.436382) (xy 47.615856 -398.443196)
			(xy 47.263812 -398.79524) (xy 47.256971 -398.80264) (xy 47.249249 -398.821238) (xy 47.248826 -398.831308)
			(xy 47.248826 -399.630138) (xy 99.44608 -399.630138) (xy 99.44657 -399.60017) (xy 99.454393 -399.540748)
			(xy 99.469906 -399.482855) (xy 99.492842 -399.427482) (xy 99.522809 -399.375576) (xy 99.559296 -399.328026)
			(xy 99.601676 -399.285646) (xy 99.649226 -399.249159) (xy 99.701132 -399.219192) (xy 99.756505 -399.196256)
			(xy 99.814398 -399.180743) (xy 99.87382 -399.17292) (xy 99.933756 -399.17292) (xy 99.993178 -399.180743)
			(xy 100.051071 -399.196256) (xy 100.106444 -399.219192) (xy 100.15835 -399.249159) (xy 100.2059 -399.285646)
			(xy 100.24828 -399.328026) (xy 100.284767 -399.375576) (xy 100.314734 -399.427482) (xy 100.33767 -399.482855)
			(xy 100.353183 -399.540748) (xy 100.361006 -399.60017) (xy 100.361496 -399.630138) (xy 100.361182 -399.652901)
			(xy 100.356599 -399.698197) (xy 100.352352 -399.720562) (xy 100.350958 -399.729327) (xy 100.353557 -399.746868)
			(xy 100.357432 -399.754852) (xy 100.371656 -399.781268) (xy 100.376179 -399.788929) (xy 100.389432 -399.800778)
			(xy 100.397564 -399.804382) (xy 100.427873 -399.817125) (xy 100.485252 -399.849228) (xy 100.538012 -399.888463)
			(xy 100.58527 -399.934175) (xy 100.626238 -399.9856) (xy 100.660231 -400.041879) (xy 100.686681 -400.102073)
			(xy 100.705147 -400.165176) (xy 100.710746 -400.197574) (xy 100.712982 -400.208425) (xy 100.725312 -400.226802)
			(xy 100.744254 -400.238248) (xy 100.755196 -400.239992) (xy 100.785899 -400.24384) (xy 100.846106 -400.258134)
			(xy 100.904135 -400.279625) (xy 100.959129 -400.307997) (xy 101.010274 -400.34283) (xy 101.056817 -400.38361)
			(xy 101.09807 -400.429734) (xy 101.133423 -400.480522) (xy 101.148205 -400.50847) (xy 103.358442 -400.50847)
			(xy 103.358909 -400.478255) (xy 103.366089 -400.418254) (xy 103.380332 -400.359527) (xy 103.401437 -400.302902)
			(xy 103.429107 -400.24918) (xy 103.462951 -400.199116) (xy 103.482394 -400.175984) (xy 103.488026 -400.168851)
			(xy 103.494266 -400.151794) (xy 103.494586 -400.14271) (xy 103.494586 -400.11223) (xy 103.494277 -400.103147)
			(xy 103.488019 -400.086096) (xy 103.482394 -400.078956) (xy 103.462949 -400.055826) (xy 103.42911 -400.005759)
			(xy 103.401441 -399.952035) (xy 103.380333 -399.895411) (xy 103.366082 -399.836685) (xy 103.35889 -399.776685)
			(xy 103.358442 -399.74647) (xy 103.358944 -399.714509) (xy 103.366955 -399.651091) (xy 103.382852 -399.589177)
			(xy 103.406384 -399.529744) (xy 103.437178 -399.473729) (xy 103.474751 -399.422014) (xy 103.518508 -399.375417)
			(xy 103.567761 -399.334672) (xy 103.621732 -399.300421) (xy 103.679571 -399.273204) (xy 103.740364 -399.253451)
			(xy 103.803154 -399.241473) (xy 103.86695 -399.23746) (xy 103.930746 -399.241473) (xy 103.993536 -399.253451)
			(xy 104.054329 -399.273204) (xy 104.112168 -399.300421) (xy 104.166139 -399.334672) (xy 104.215392 -399.375417)
			(xy 104.259149 -399.422014) (xy 104.296722 -399.473729) (xy 104.327516 -399.529744) (xy 104.351048 -399.589177)
			(xy 104.366945 -399.651091) (xy 104.374956 -399.714509) (xy 104.375458 -399.74647) (xy 104.375015 -399.776685)
			(xy 104.36783 -399.836688) (xy 104.353582 -399.895416) (xy 104.332473 -399.95204) (xy 104.304799 -400.005762)
			(xy 104.270951 -400.055824) (xy 104.251506 -400.078956) (xy 104.2459 -400.086106) (xy 104.239644 -400.10315)
			(xy 104.239314 -400.11223) (xy 104.239314 -400.14271) (xy 104.239652 -400.15179) (xy 104.24589 -400.168841)
			(xy 104.251506 -400.175984) (xy 104.270923 -400.199137) (xy 104.304765 -400.249199) (xy 104.332438 -400.302918)
			(xy 104.353551 -400.359537) (xy 104.367808 -400.418259) (xy 104.370129 -400.437604) (xy 111.592866 -400.437604)
			(xy 111.596937 -400.381982) (xy 111.609063 -400.327545) (xy 111.628986 -400.275454) (xy 111.656282 -400.226819)
			(xy 111.690368 -400.182676) (xy 111.730517 -400.143967) (xy 111.775875 -400.111516) (xy 111.825475 -400.086015)
			(xy 111.878259 -400.068008) (xy 111.933102 -400.057878) (xy 111.988836 -400.055841) (xy 112.044273 -400.061941)
			(xy 112.09823 -400.076047) (xy 112.149559 -400.097859) (xy 112.197165 -400.126913) (xy 112.240033 -400.162588)
			(xy 112.27725 -400.204125) (xy 112.308023 -400.250638) (xy 112.331695 -400.301135) (xy 112.347763 -400.354542)
			(xy 112.355883 -400.409718) (xy 112.356392 -400.437604) (xy 112.355883 -400.46549) (xy 112.347763 -400.520666)
			(xy 112.331695 -400.574073) (xy 112.308023 -400.62457) (xy 112.27725 -400.671083) (xy 112.240033 -400.71262)
			(xy 112.197165 -400.748295) (xy 112.149559 -400.777349) (xy 112.09823 -400.799161) (xy 112.044273 -400.813267)
			(xy 111.988836 -400.819367) (xy 111.933102 -400.81733) (xy 111.878259 -400.8072) (xy 111.825475 -400.789193)
			(xy 111.775875 -400.763692) (xy 111.730517 -400.731241) (xy 111.690368 -400.692532) (xy 111.656282 -400.648389)
			(xy 111.628986 -400.599754) (xy 111.609063 -400.547663) (xy 111.596937 -400.493226) (xy 111.592866 -400.437604)
			(xy 104.370129 -400.437604) (xy 104.375006 -400.478256) (xy 104.375458 -400.50847) (xy 104.374956 -400.540431)
			(xy 104.366945 -400.603849) (xy 104.351048 -400.665763) (xy 104.327516 -400.725196) (xy 104.296722 -400.781211)
			(xy 104.259149 -400.832926) (xy 104.215392 -400.879523) (xy 104.166139 -400.920268) (xy 104.112168 -400.954519)
			(xy 104.054329 -400.981736) (xy 103.993536 -401.001489) (xy 103.930746 -401.013467) (xy 103.86695 -401.017481)
			(xy 103.803154 -401.013467) (xy 103.740364 -401.001489) (xy 103.679571 -400.981736) (xy 103.621732 -400.954519)
			(xy 103.567761 -400.920268) (xy 103.518508 -400.879523) (xy 103.474751 -400.832926) (xy 103.437178 -400.781211)
			(xy 103.406384 -400.725196) (xy 103.382852 -400.665763) (xy 103.366955 -400.603849) (xy 103.358944 -400.540431)
			(xy 103.358442 -400.50847) (xy 101.148205 -400.50847) (xy 101.162354 -400.535223) (xy 101.184436 -400.59303)
			(xy 101.199344 -400.653088) (xy 101.206856 -400.714512) (xy 101.207316 -400.745452) (xy 101.206817 -400.776183)
			(xy 101.199414 -400.837197) (xy 101.184711 -400.896874) (xy 101.16292 -400.954343) (xy 101.134362 -401.008766)
			(xy 101.099451 -401.05935) (xy 101.058697 -401.105357) (xy 101.012694 -401.146116) (xy 100.997394 -401.156678)
			(xy 101.818694 -401.156678) (xy 101.819189 -401.122651) (xy 101.827089 -401.055058) (xy 101.842783 -400.98884)
			(xy 101.866059 -400.924891) (xy 101.896601 -400.864076) (xy 101.933997 -400.807219) (xy 101.97774 -400.755087)
			(xy 102.02724 -400.708386) (xy 102.081827 -400.667748) (xy 102.140763 -400.633721) (xy 102.203251 -400.606767)
			(xy 102.268445 -400.587249) (xy 102.335464 -400.575431) (xy 102.403402 -400.571475) (xy 102.47134 -400.575431)
			(xy 102.538359 -400.587249) (xy 102.603553 -400.606767) (xy 102.666041 -400.633721) (xy 102.724977 -400.667748)
			(xy 102.779564 -400.708386) (xy 102.829064 -400.755087) (xy 102.872807 -400.807219) (xy 102.910203 -400.864076)
			(xy 102.940745 -400.924891) (xy 102.964021 -400.98884) (xy 102.979715 -401.055058) (xy 102.987615 -401.122651)
			(xy 102.98811 -401.156678) (xy 102.98763 -401.190592) (xy 102.97978 -401.257965) (xy 102.964184 -401.323977)
			(xy 102.94105 -401.387738) (xy 102.91069 -401.448393) (xy 102.873512 -401.505126) (xy 102.830016 -401.557172)
			(xy 102.805738 -401.580858) (xy 102.799546 -401.587139) (xy 102.791613 -401.602879) (xy 102.790244 -401.611592)
			(xy 102.786688 -401.641056) (xy 102.785993 -401.649683) (xy 102.789754 -401.666565) (xy 102.794054 -401.674076)
			(xy 102.812429 -401.704563) (xy 102.82444 -401.7315) (xy 107.893376 -401.7315) (xy 107.897333 -401.663562)
			(xy 107.90915 -401.596542) (xy 107.928668 -401.531347) (xy 107.955622 -401.468859) (xy 107.989648 -401.409922)
			(xy 108.030285 -401.355334) (xy 108.076985 -401.305833) (xy 108.129116 -401.262088) (xy 108.185973 -401.22469)
			(xy 108.246787 -401.194146) (xy 108.310736 -401.170868) (xy 108.376954 -401.155171) (xy 108.444547 -401.147268)
			(xy 108.478574 -401.146772) (xy 108.513731 -401.147256) (xy 108.583535 -401.155696) (xy 108.651824 -401.172446)
			(xy 108.717612 -401.197264) (xy 108.779949 -401.229792) (xy 108.837935 -401.26956) (xy 108.890735 -401.315995)
			(xy 108.937585 -401.368426) (xy 108.958126 -401.396962) (xy 108.96346 -401.404582) (xy 108.979208 -401.41525)
			(xy 109.064806 -401.434554) (xy 109.083348 -401.43176) (xy 109.09173 -401.426934) (xy 109.113396 -401.415025)
			(xy 109.159161 -401.396314) (xy 109.206957 -401.383664) (xy 109.255985 -401.377285) (xy 109.280706 -401.376896)
			(xy 109.307465 -401.377357) (xy 109.360458 -401.384831) (xy 109.411889 -401.399633) (xy 109.460748 -401.421473)
			(xy 109.483652 -401.435316) (xy 109.492034 -401.44065) (xy 109.51083 -401.444206) (xy 109.59846 -401.427188)
			(xy 109.614208 -401.417028) (xy 109.62005 -401.4089) (xy 109.640671 -401.381212) (xy 109.687472 -401.330457)
			(xy 109.739924 -401.285564) (xy 109.797296 -401.247159) (xy 109.85879 -401.215775) (xy 109.923552 -401.191849)
			(xy 109.990679 -401.175713) (xy 110.05924 -401.167593) (xy 110.09376 -401.167092) (xy 110.127789 -401.167565)
			(xy 110.195388 -401.175462) (xy 110.261612 -401.191154) (xy 110.325568 -401.214428) (xy 110.386388 -401.244969)
			(xy 110.443252 -401.282365) (xy 110.495389 -401.32611) (xy 110.542095 -401.375613) (xy 110.582738 -401.430203)
			(xy 110.616769 -401.489142) (xy 110.643726 -401.551634) (xy 110.663246 -401.616833) (xy 110.675065 -401.683857)
			(xy 110.679023 -401.7518) (xy 110.677723 -401.774109) (xy 111.742468 -401.774109) (xy 111.742468 -401.710187)
			(xy 111.750479 -401.646769) (xy 111.766376 -401.584855) (xy 111.789908 -401.525422) (xy 111.820702 -401.469407)
			(xy 111.858275 -401.417692) (xy 111.902032 -401.371095) (xy 111.951285 -401.33035) (xy 112.005256 -401.296099)
			(xy 112.063095 -401.268882) (xy 112.123888 -401.249129) (xy 112.186678 -401.237151) (xy 112.250474 -401.233138)
			(xy 112.31427 -401.237151) (xy 112.37706 -401.249129) (xy 112.437853 -401.268882) (xy 112.495692 -401.296099)
			(xy 112.549663 -401.33035) (xy 112.598916 -401.371095) (xy 112.642673 -401.417692) (xy 112.680246 -401.469407)
			(xy 112.71104 -401.525422) (xy 112.734572 -401.584855) (xy 112.750469 -401.646769) (xy 112.75848 -401.710187)
			(xy 112.758878 -401.735501) (xy 116.894604 -401.735501) (xy 116.894604 -401.671579) (xy 116.902615 -401.608161)
			(xy 116.918512 -401.546247) (xy 116.942044 -401.486814) (xy 116.972838 -401.430799) (xy 117.010411 -401.379084)
			(xy 117.054168 -401.332487) (xy 117.103421 -401.291742) (xy 117.157392 -401.257491) (xy 117.215231 -401.230274)
			(xy 117.276024 -401.210521) (xy 117.338814 -401.198543) (xy 117.40261 -401.19453) (xy 117.466406 -401.198543)
			(xy 117.529196 -401.210521) (xy 117.589989 -401.230274) (xy 117.647828 -401.257491) (xy 117.701799 -401.291742)
			(xy 117.751052 -401.332487) (xy 117.794809 -401.379084) (xy 117.832382 -401.430799) (xy 117.863176 -401.486814)
			(xy 117.886708 -401.546247) (xy 117.902605 -401.608161) (xy 117.910616 -401.671579) (xy 117.911118 -401.70354)
			(xy 117.910616 -401.735501) (xy 117.902605 -401.798919) (xy 117.886708 -401.860833) (xy 117.863176 -401.920266)
			(xy 117.832382 -401.976281) (xy 117.794809 -402.027996) (xy 117.751052 -402.074593) (xy 117.701799 -402.115338)
			(xy 117.647828 -402.149589) (xy 117.589989 -402.176806) (xy 117.529196 -402.196559) (xy 117.466406 -402.208537)
			(xy 117.40261 -402.212551) (xy 117.338814 -402.208537) (xy 117.276024 -402.196559) (xy 117.215231 -402.176806)
			(xy 117.157392 -402.149589) (xy 117.103421 -402.115338) (xy 117.054168 -402.074593) (xy 117.010411 -402.027996)
			(xy 116.972838 -401.976281) (xy 116.942044 -401.920266) (xy 116.918512 -401.860833) (xy 116.902615 -401.798919)
			(xy 116.894604 -401.735501) (xy 112.758878 -401.735501) (xy 112.758982 -401.742148) (xy 112.75848 -401.774109)
			(xy 112.750469 -401.837527) (xy 112.734572 -401.899441) (xy 112.71104 -401.958874) (xy 112.680246 -402.014889)
			(xy 112.642673 -402.066604) (xy 112.598916 -402.113201) (xy 112.549663 -402.153946) (xy 112.495692 -402.188197)
			(xy 112.437853 -402.215414) (xy 112.37706 -402.235167) (xy 112.31427 -402.247145) (xy 112.250474 -402.251159)
			(xy 112.186678 -402.247145) (xy 112.123888 -402.235167) (xy 112.063095 -402.215414) (xy 112.005256 -402.188197)
			(xy 111.951285 -402.153946) (xy 111.902032 -402.113201) (xy 111.858275 -402.066604) (xy 111.820702 -402.014889)
			(xy 111.789908 -401.958874) (xy 111.766376 -401.899441) (xy 111.750479 -401.837527) (xy 111.742468 -401.774109)
			(xy 110.677723 -401.774109) (xy 110.675065 -401.819743) (xy 110.663246 -401.886767) (xy 110.643726 -401.951966)
			(xy 110.616769 -402.014458) (xy 110.582738 -402.073397) (xy 110.542095 -402.127987) (xy 110.495389 -402.17749)
			(xy 110.443252 -402.221235) (xy 110.386388 -402.258631) (xy 110.325568 -402.289172) (xy 110.261612 -402.312446)
			(xy 110.195388 -402.328138) (xy 110.127789 -402.336035) (xy 110.09376 -402.336508) (xy 110.059832 -402.336031)
			(xy 109.992433 -402.328176) (xy 109.926395 -402.312576) (xy 109.862605 -402.28944) (xy 109.801921 -402.259079)
			(xy 109.745156 -402.221902) (xy 109.693074 -402.178407) (xy 109.646374 -402.129178) (xy 109.625638 -402.10232)
			(xy 109.619796 -402.094446) (xy 109.603794 -402.08454) (xy 109.51591 -402.068792) (xy 109.497368 -402.072602)
			(xy 109.488986 -402.077936) (xy 109.465644 -402.092591) (xy 109.415624 -402.115731) (xy 109.362798 -402.131446)
			(xy 109.308262 -402.139407) (xy 109.280706 -402.139912) (xy 109.252774 -402.139406) (xy 109.197507 -402.131266)
			(xy 109.144015 -402.11516) (xy 109.093442 -402.09143) (xy 109.069886 -402.076412) (xy 109.062012 -402.071078)
			(xy 109.04347 -402.067014) (xy 108.956856 -402.080476) (xy 108.9406 -402.090128) (xy 108.934504 -402.097494)
			(xy 108.913673 -402.122694) (xy 108.86732 -402.168806) (xy 108.81611 -402.209457) (xy 108.760684 -402.244139)
			(xy 108.701733 -402.272418) (xy 108.639995 -402.293942) (xy 108.57624 -402.308442) (xy 108.511265 -402.315736)
			(xy 108.478574 -402.316188) (xy 108.444547 -402.315732) (xy 108.376954 -402.307829) (xy 108.310736 -402.292132)
			(xy 108.246787 -402.268854) (xy 108.185973 -402.23831) (xy 108.129116 -402.200912) (xy 108.076985 -402.157167)
			(xy 108.030285 -402.107666) (xy 107.989648 -402.053078) (xy 107.955622 -401.994141) (xy 107.928668 -401.931653)
			(xy 107.90915 -401.866458) (xy 107.897333 -401.799438) (xy 107.893376 -401.7315) (xy 102.82444 -401.7315)
			(xy 102.841418 -401.769574) (xy 102.861052 -401.837995) (xy 102.870946 -401.908487) (xy 102.871524 -401.944078)
			(xy 102.871022 -401.976039) (xy 102.863011 -402.039457) (xy 102.847114 -402.101371) (xy 102.823582 -402.160804)
			(xy 102.792788 -402.216819) (xy 102.755215 -402.268534) (xy 102.711458 -402.315131) (xy 102.662205 -402.355876)
			(xy 102.608234 -402.390127) (xy 102.550395 -402.417344) (xy 102.489602 -402.437097) (xy 102.426812 -402.449075)
			(xy 102.363016 -402.453089) (xy 102.29922 -402.449075) (xy 102.23643 -402.437097) (xy 102.175637 -402.417344)
			(xy 102.117798 -402.390127) (xy 102.063827 -402.355876) (xy 102.014574 -402.315131) (xy 101.970817 -402.268534)
			(xy 101.933244 -402.216819) (xy 101.90245 -402.160804) (xy 101.878918 -402.101371) (xy 101.863021 -402.039457)
			(xy 101.85501 -401.976039) (xy 101.854508 -401.944078) (xy 101.855084 -401.910393) (xy 101.863977 -401.843613)
			(xy 101.881604 -401.77859) (xy 101.907657 -401.716461) (xy 101.941681 -401.658314) (xy 101.96195 -401.631404)
			(xy 101.966986 -401.624322) (xy 101.972439 -401.607834) (xy 101.972618 -401.599146) (xy 101.97211 -401.569428)
			(xy 101.97151 -401.560661) (xy 101.96514 -401.544297) (xy 101.959664 -401.537424) (xy 101.937539 -401.510865)
			(xy 101.899021 -401.453463) (xy 101.867541 -401.391919) (xy 101.843539 -401.327092) (xy 101.82735 -401.259887)
			(xy 101.8192 -401.191242) (xy 101.818694 -401.156678) (xy 100.997394 -401.156678) (xy 100.962114 -401.181033)
			(xy 100.907694 -401.209597) (xy 100.850227 -401.231394) (xy 100.790552 -401.246104) (xy 100.729539 -401.253514)
			(xy 100.698808 -401.25396) (xy 100.66608 -401.25343) (xy 100.601164 -401.245043) (xy 100.53786 -401.228395)
			(xy 100.477217 -401.20376) (xy 100.420237 -401.171546) (xy 100.367862 -401.132286) (xy 100.320959 -401.086629)
			(xy 100.280304 -401.03533) (xy 100.246568 -400.979237) (xy 100.220309 -400.919279) (xy 100.201963 -400.856447)
			(xy 100.196396 -400.824192) (xy 100.194086 -400.813362) (xy 100.181789 -400.794984) (xy 100.162877 -400.783527)
			(xy 100.151946 -400.781774) (xy 100.121257 -400.777827) (xy 100.061055 -400.763541) (xy 100.00303 -400.742058)
			(xy 99.948039 -400.713695) (xy 99.896895 -400.678871) (xy 99.850353 -400.6381) (xy 99.809099 -400.591985)
			(xy 99.773744 -400.541207) (xy 99.744809 -400.486515) (xy 99.722722 -400.428717) (xy 99.707809 -400.368667)
			(xy 99.70029 -400.307251) (xy 99.699826 -400.276314) (xy 99.700584 -400.237061) (xy 99.712709 -400.159496)
			(xy 99.723956 -400.121882) (xy 99.7262 -400.113323) (xy 99.725433 -400.095661) (xy 99.722432 -400.087338)
			(xy 99.711002 -400.059398) (xy 99.707391 -400.051379) (xy 99.695686 -400.038267) (xy 99.688142 -400.033744)
			(xy 99.66113 -400.018716) (xy 99.611014 -399.982531) (xy 99.566227 -399.939928) (xy 99.527583 -399.891682)
			(xy 99.495787 -399.838673) (xy 99.471418 -399.781866) (xy 99.45492 -399.722295) (xy 99.446592 -399.661045)
			(xy 99.44608 -399.630138) (xy 47.248826 -399.630138) (xy 47.248826 -400.35607) (xy 47.248322 -400.366121)
			(xy 47.240603 -400.384685) (xy 47.23384 -400.392138) (xy 46.824392 -400.801586) (xy 46.816994 -400.808433)
			(xy 46.798396 -400.816166) (xy 46.788324 -400.816572) (xy 46.169072 -400.816572) (xy 46.160944 -400.819366)
			(xy 46.134348 -400.828089) (xy 46.079723 -400.840301) (xy 46.024085 -400.846427) (xy 45.996098 -400.846798)
			(xy 45.968113 -400.846411) (xy 45.91248 -400.840265) (xy 45.857856 -400.828059) (xy 45.831252 -400.819366)
			(xy 45.823124 -400.816572) (xy 45.380656 -400.816572) (xy 45.37059 -400.81614) (xy 45.352 -400.808411)
			(xy 45.344588 -400.801586) (xy 45.159676 -400.616674) (xy 45.15104 -400.612864) (xy 45.123207 -400.599827)
			(xy 45.07061 -400.568027) (xy 45.022229 -400.530121) (xy 44.978769 -400.486659) (xy 44.940864 -400.438277)
			(xy 44.909066 -400.385679) (xy 44.896024 -400.357848) (xy 44.892214 -400.349212) (xy 43.93946 -399.396458)
			(xy 43.932614 -399.38906) (xy 43.924885 -399.370461) (xy 43.924474 -399.36039) (xy 43.924474 -396.90167)
			(xy 43.924045 -396.891603) (xy 43.91632 -396.873009) (xy 43.909488 -396.865602) (xy 43.576494 -396.532608)
			(xy 43.569095 -396.525762) (xy 43.550497 -396.518028) (xy 43.540426 -396.517622) (xy 40.850312 -396.517622)
			(xy 40.840241 -396.518043) (xy 40.821636 -396.525757) (xy 40.814244 -396.532608) (xy 40.4622 -396.884652)
			(xy 40.455362 -396.892053) (xy 40.447646 -396.910651) (xy 40.447214 -396.92072) (xy 40.447214 -399.993104)
			(xy 40.447638 -400.003174) (xy 40.455355 -400.021776) (xy 40.4622 -400.029172) (xy 40.890698 -400.45767)
			(xy 40.898095 -400.46452) (xy 40.916693 -400.47226) (xy 40.926766 -400.472656) (xy 43.272964 -400.472656)
			(xy 43.283028 -400.473092) (xy 43.30161 -400.480829) (xy 43.309032 -400.487642) (xy 44.833751 -402.012361)
			(xy 94.597722 -402.012361) (xy 94.597722 -401.948439) (xy 94.605733 -401.885021) (xy 94.62163 -401.823107)
			(xy 94.645162 -401.763674) (xy 94.675956 -401.707659) (xy 94.713529 -401.655944) (xy 94.757286 -401.609347)
			(xy 94.806539 -401.568602) (xy 94.86051 -401.534351) (xy 94.918349 -401.507134) (xy 94.979142 -401.487381)
			(xy 95.041932 -401.475403) (xy 95.105728 -401.47139) (xy 95.169524 -401.475403) (xy 95.232314 -401.487381)
			(xy 95.293107 -401.507134) (xy 95.350946 -401.534351) (xy 95.404917 -401.568602) (xy 95.45417 -401.609347)
			(xy 95.497927 -401.655944) (xy 95.5355 -401.707659) (xy 95.566294 -401.763674) (xy 95.589826 -401.823107)
			(xy 95.605723 -401.885021) (xy 95.613734 -401.948439) (xy 95.614236 -401.9804) (xy 95.613734 -402.012361)
			(xy 95.605723 -402.075779) (xy 95.589826 -402.137693) (xy 95.566294 -402.197126) (xy 95.5355 -402.253141)
			(xy 95.497927 -402.304856) (xy 95.45417 -402.351453) (xy 95.404917 -402.392198) (xy 95.350946 -402.426449)
			(xy 95.293107 -402.453666) (xy 95.232314 -402.473419) (xy 95.169524 -402.485397) (xy 95.105728 -402.489411)
			(xy 95.041932 -402.485397) (xy 94.979142 -402.473419) (xy 94.918349 -402.453666) (xy 94.86051 -402.426449)
			(xy 94.806539 -402.392198) (xy 94.757286 -402.351453) (xy 94.713529 -402.304856) (xy 94.675956 -402.253141)
			(xy 94.645162 -402.197126) (xy 94.62163 -402.137693) (xy 94.605733 -402.075779) (xy 94.597722 -402.012361)
			(xy 44.833751 -402.012361) (xy 45.639482 -402.818092) (xy 98.156522 -402.818092) (xy 98.156988 -402.787115)
			(xy 98.16453 -402.725622) (xy 98.179489 -402.665502) (xy 98.201643 -402.607645) (xy 98.230664 -402.552909)
			(xy 98.266121 -402.502105) (xy 98.30749 -402.455987) (xy 98.354156 -402.415237) (xy 98.379534 -402.397468)
			(xy 98.38944 -402.39061) (xy 98.401124 -402.369528) (xy 98.405442 -402.263356) (xy 98.395282 -402.241512)
			(xy 98.385884 -402.233892) (xy 98.360574 -402.213106) (xy 98.314314 -402.166742) (xy 98.273528 -402.115495)
			(xy 98.238728 -402.060009) (xy 98.21035 -402.00098) (xy 98.188751 -401.939147) (xy 98.174201 -401.875288)
			(xy 98.166883 -401.810202) (xy 98.166428 -401.777454) (xy 98.166882 -401.742116) (xy 98.175407 -401.671955)
			(xy 98.192326 -401.603333) (xy 98.217393 -401.537251) (xy 98.250243 -401.474672) (xy 98.290396 -401.416509)
			(xy 98.337268 -401.36361) (xy 98.390173 -401.316746) (xy 98.448342 -401.276601) (xy 98.510925 -401.24376)
			(xy 98.577011 -401.218702) (xy 98.645635 -401.201792) (xy 98.715798 -401.193277) (xy 98.751136 -401.192746)
			(xy 98.785019 -401.193184) (xy 98.852329 -401.201022) (xy 98.918283 -401.216589) (xy 98.981994 -401.239676)
			(xy 99.04261 -401.269974) (xy 99.099316 -401.307076) (xy 99.151353 -401.350485) (xy 99.198023 -401.399618)
			(xy 99.21875 -401.426426) (xy 99.225632 -401.434832) (xy 99.244632 -401.44533) (xy 99.266266 -401.447111)
			(xy 99.276662 -401.443952) (xy 99.304167 -401.434537) (xy 99.360781 -401.421314) (xy 99.418535 -401.414648)
			(xy 99.447604 -401.414234) (xy 99.479568 -401.414652) (xy 99.54299 -401.422665) (xy 99.604909 -401.438563)
			(xy 99.664347 -401.462097) (xy 99.720366 -401.492894) (xy 99.772084 -401.53047) (xy 99.818685 -401.574231)
			(xy 99.859433 -401.623488) (xy 99.893687 -401.677463) (xy 99.920905 -401.735306) (xy 99.94066 -401.796104)
			(xy 99.952639 -401.858899) (xy 99.956653 -401.9227) (xy 99.952639 -401.986501) (xy 99.94066 -402.049296)
			(xy 99.920905 -402.110094) (xy 99.893687 -402.167937) (xy 99.859433 -402.221912) (xy 99.818685 -402.271169)
			(xy 99.772084 -402.31493) (xy 99.720366 -402.352506) (xy 99.664347 -402.383303) (xy 99.604909 -402.406837)
			(xy 99.54299 -402.422735) (xy 99.479568 -402.430748) (xy 99.447604 -402.43125) (xy 99.415627 -402.430766)
			(xy 99.352176 -402.422757) (xy 99.29023 -402.406853) (xy 99.230769 -402.383304) (xy 99.174731 -402.352482)
			(xy 99.123002 -402.314876) (xy 99.09937 -402.293328) (xy 99.091147 -402.286262) (xy 99.07065 -402.27925)
			(xy 99.049084 -402.281286) (xy 99.039426 -402.286216) (xy 99.036378 -402.28774) (xy 99.02571 -402.293836)
			(xy 99.012248 -402.313648) (xy 98.99904 -402.419058) (xy 99.007168 -402.441664) (xy 99.015804 -402.450046)
			(xy 99.040255 -402.474125) (xy 99.083129 -402.527706) (xy 99.118404 -402.586569) (xy 99.145438 -402.649643)
			(xy 99.163738 -402.715781) (xy 99.172973 -402.78378) (xy 99.173538 -402.818092) (xy 99.173036 -402.850053)
			(xy 99.165025 -402.913471) (xy 99.149128 -402.975385) (xy 99.125596 -403.034818) (xy 99.094802 -403.090833)
			(xy 99.057229 -403.142548) (xy 99.013472 -403.189145) (xy 98.964219 -403.22989) (xy 98.910248 -403.264141)
			(xy 98.852409 -403.291358) (xy 98.791616 -403.311111) (xy 98.728826 -403.323089) (xy 98.66503 -403.327103)
			(xy 98.601234 -403.323089) (xy 98.538444 -403.311111) (xy 98.477651 -403.291358) (xy 98.419812 -403.264141)
			(xy 98.365841 -403.22989) (xy 98.316588 -403.189145) (xy 98.272831 -403.142548) (xy 98.235258 -403.090833)
			(xy 98.204464 -403.034818) (xy 98.180932 -402.975385) (xy 98.165035 -402.913471) (xy 98.157024 -402.850053)
			(xy 98.156522 -402.818092) (xy 45.639482 -402.818092) (xy 46.679866 -403.858476) (xy 46.687267 -403.865315)
			(xy 46.705865 -403.873029) (xy 46.715934 -403.873462) (xy 47.210472 -403.873462) (xy 47.24019 -403.844506)
			(xy 47.240444 -403.823678) (xy 47.241424 -403.797364) (xy 47.250178 -403.74544) (xy 47.266481 -403.695372)
			(xy 47.289978 -403.648249) (xy 47.320157 -403.605099) (xy 47.35636 -403.566862) (xy 47.397798 -403.534373)
			(xy 47.443567 -403.508338) (xy 47.492671 -403.489325) (xy 47.544039 -403.477749) (xy 47.596552 -403.473862)
			(xy 47.649065 -403.477749) (xy 47.700433 -403.489325) (xy 47.749537 -403.508338) (xy 47.795306 -403.534373)
			(xy 47.836744 -403.566862) (xy 47.872947 -403.605099) (xy 47.903126 -403.648249) (xy 47.926623 -403.695372)
			(xy 47.942926 -403.74544) (xy 47.95168 -403.797364) (xy 47.95266 -403.823678) (xy 47.952914 -403.844506)
			(xy 47.982632 -403.873462) (xy 48.469296 -403.873462) (xy 48.499014 -403.844506) (xy 48.499268 -403.823678)
			(xy 48.500248 -403.797364) (xy 48.509002 -403.74544) (xy 48.525305 -403.695372) (xy 48.548802 -403.648249)
			(xy 48.578981 -403.605099) (xy 48.615184 -403.566862) (xy 48.656622 -403.534373) (xy 48.702391 -403.508338)
			(xy 48.751495 -403.489325) (xy 48.802863 -403.477749) (xy 48.855376 -403.473862) (xy 48.907889 -403.477749)
			(xy 48.959257 -403.489325) (xy 49.008361 -403.508338) (xy 49.05413 -403.534373) (xy 49.095568 -403.566862)
			(xy 49.131771 -403.605099) (xy 49.16195 -403.648249) (xy 49.185447 -403.695372) (xy 49.20175 -403.74544)
			(xy 49.210504 -403.797364) (xy 49.211484 -403.823678) (xy 49.211738 -403.844506) (xy 49.241456 -403.873462)
			(xy 50.273712 -403.873462) (xy 50.30343 -403.844506) (xy 50.303684 -403.823678) (xy 50.304664 -403.797364)
			(xy 50.313418 -403.74544) (xy 50.329721 -403.695372) (xy 50.353218 -403.648249) (xy 50.383397 -403.605099)
			(xy 50.4196 -403.566862) (xy 50.461038 -403.534373) (xy 50.506807 -403.508338) (xy 50.555911 -403.489325)
			(xy 50.607279 -403.477749) (xy 50.659792 -403.473862) (xy 50.712305 -403.477749) (xy 50.763673 -403.489325)
			(xy 50.812777 -403.508338) (xy 50.858546 -403.534373) (xy 50.899984 -403.566862) (xy 50.936187 -403.605099)
			(xy 50.966366 -403.648249) (xy 50.989863 -403.695372) (xy 51.006166 -403.74544) (xy 51.01492 -403.797364)
			(xy 51.0159 -403.823678) (xy 51.016154 -403.844506) (xy 51.045872 -403.873462) (xy 51.532536 -403.873462)
			(xy 51.562254 -403.844506) (xy 51.562508 -403.823678) (xy 51.563488 -403.797364) (xy 51.572242 -403.74544)
			(xy 51.588545 -403.695372) (xy 51.612042 -403.648249) (xy 51.642221 -403.605099) (xy 51.678424 -403.566862)
			(xy 51.719862 -403.534373) (xy 51.765631 -403.508338) (xy 51.814735 -403.489325) (xy 51.866103 -403.477749)
			(xy 51.918616 -403.473862) (xy 51.971129 -403.477749) (xy 52.022497 -403.489325) (xy 52.071601 -403.508338)
			(xy 52.11737 -403.534373) (xy 52.158808 -403.566862) (xy 52.195011 -403.605099) (xy 52.22519 -403.648249)
			(xy 52.248687 -403.695372) (xy 52.26499 -403.74544) (xy 52.273744 -403.797364) (xy 52.274724 -403.823678)
			(xy 52.274978 -403.844506) (xy 52.304696 -403.873462) (xy 53.336952 -403.873462) (xy 53.36667 -403.844506)
			(xy 53.366924 -403.823678) (xy 53.367904 -403.797364) (xy 53.376658 -403.74544) (xy 53.392961 -403.695372)
			(xy 53.416458 -403.648249) (xy 53.446637 -403.605099) (xy 53.48284 -403.566862) (xy 53.524278 -403.534373)
			(xy 53.570047 -403.508338) (xy 53.619151 -403.489325) (xy 53.670519 -403.477749) (xy 53.723032 -403.473862)
			(xy 53.775545 -403.477749) (xy 53.826913 -403.489325) (xy 53.876017 -403.508338) (xy 53.921786 -403.534373)
			(xy 53.963224 -403.566862) (xy 53.999427 -403.605099) (xy 54.029606 -403.648249) (xy 54.053103 -403.695372)
			(xy 54.069406 -403.74544) (xy 54.07816 -403.797364) (xy 54.07914 -403.823678) (xy 54.079394 -403.844506)
			(xy 54.109112 -403.873462) (xy 54.595776 -403.873462) (xy 54.625494 -403.844506) (xy 54.625748 -403.823678)
			(xy 54.626728 -403.797364) (xy 54.635482 -403.74544) (xy 54.651785 -403.695372) (xy 54.675282 -403.648249)
			(xy 54.705461 -403.605099) (xy 54.741664 -403.566862) (xy 54.783102 -403.534373) (xy 54.828871 -403.508338)
			(xy 54.877975 -403.489325) (xy 54.929343 -403.477749) (xy 54.981856 -403.473862) (xy 55.034369 -403.477749)
			(xy 55.085737 -403.489325) (xy 55.134841 -403.508338) (xy 55.18061 -403.534373) (xy 55.222048 -403.566862)
			(xy 55.258251 -403.605099) (xy 55.28843 -403.648249) (xy 55.311927 -403.695372) (xy 55.32823 -403.74544)
			(xy 55.336984 -403.797364) (xy 55.337964 -403.823678) (xy 55.338218 -403.844506) (xy 55.367936 -403.873462)
			(xy 56.400192 -403.873462) (xy 56.42991 -403.844506) (xy 56.430164 -403.823678) (xy 56.431144 -403.797364)
			(xy 56.439898 -403.74544) (xy 56.456201 -403.695372) (xy 56.479698 -403.648249) (xy 56.509877 -403.605099)
			(xy 56.54608 -403.566862) (xy 56.587518 -403.534373) (xy 56.633287 -403.508338) (xy 56.682391 -403.489325)
			(xy 56.733759 -403.477749) (xy 56.786272 -403.473862) (xy 56.838785 -403.477749) (xy 56.890153 -403.489325)
			(xy 56.939257 -403.508338) (xy 56.985026 -403.534373) (xy 57.026464 -403.566862) (xy 57.062667 -403.605099)
			(xy 57.092846 -403.648249) (xy 57.116343 -403.695372) (xy 57.132646 -403.74544) (xy 57.1414 -403.797364)
			(xy 57.14238 -403.823678) (xy 57.142634 -403.844506) (xy 57.172352 -403.873462) (xy 57.659016 -403.873462)
			(xy 57.688734 -403.844506) (xy 57.688988 -403.823678) (xy 57.689968 -403.797364) (xy 57.698722 -403.74544)
			(xy 57.715025 -403.695372) (xy 57.738522 -403.648249) (xy 57.768701 -403.605099) (xy 57.804904 -403.566862)
			(xy 57.846342 -403.534373) (xy 57.892111 -403.508338) (xy 57.941215 -403.489325) (xy 57.992583 -403.477749)
			(xy 58.045096 -403.473862) (xy 58.097609 -403.477749) (xy 58.148977 -403.489325) (xy 58.198081 -403.508338)
			(xy 58.24385 -403.534373) (xy 58.285288 -403.566862) (xy 58.321491 -403.605099) (xy 58.35167 -403.648249)
			(xy 58.375167 -403.695372) (xy 58.39147 -403.74544) (xy 58.400224 -403.797364) (xy 58.401204 -403.823678)
			(xy 58.401458 -403.844506) (xy 58.431176 -403.873462) (xy 59.463432 -403.873462) (xy 59.49315 -403.844506)
			(xy 59.493404 -403.823678) (xy 59.494384 -403.797364) (xy 59.503138 -403.74544) (xy 59.519441 -403.695372)
			(xy 59.542938 -403.648249) (xy 59.573117 -403.605099) (xy 59.60932 -403.566862) (xy 59.650758 -403.534373)
			(xy 59.696527 -403.508338) (xy 59.745631 -403.489325) (xy 59.796999 -403.477749) (xy 59.849512 -403.473862)
			(xy 59.902025 -403.477749) (xy 59.953393 -403.489325) (xy 60.002497 -403.508338) (xy 60.048266 -403.534373)
			(xy 60.089704 -403.566862) (xy 60.125907 -403.605099) (xy 60.156086 -403.648249) (xy 60.179583 -403.695372)
			(xy 60.195886 -403.74544) (xy 60.20464 -403.797364) (xy 60.20562 -403.823678) (xy 60.205874 -403.844506)
			(xy 60.235592 -403.873462) (xy 60.722256 -403.873462) (xy 60.751974 -403.844506) (xy 60.752228 -403.823678)
			(xy 60.753208 -403.797364) (xy 60.761962 -403.74544) (xy 60.778265 -403.695372) (xy 60.801762 -403.648249)
			(xy 60.831941 -403.605099) (xy 60.868144 -403.566862) (xy 60.909582 -403.534373) (xy 60.955351 -403.508338)
			(xy 61.004455 -403.489325) (xy 61.055823 -403.477749) (xy 61.108336 -403.473862) (xy 61.160849 -403.477749)
			(xy 61.212217 -403.489325) (xy 61.261321 -403.508338) (xy 61.30709 -403.534373) (xy 61.348528 -403.566862)
			(xy 61.384731 -403.605099) (xy 61.41491 -403.648249) (xy 61.438407 -403.695372) (xy 61.45471 -403.74544)
			(xy 61.463464 -403.797364) (xy 61.464444 -403.823678) (xy 61.464698 -403.844506) (xy 61.494416 -403.873462)
			(xy 62.526672 -403.873462) (xy 62.55639 -403.844506) (xy 62.556644 -403.823678) (xy 62.557624 -403.797364)
			(xy 62.566378 -403.74544) (xy 62.582681 -403.695372) (xy 62.606178 -403.648249) (xy 62.636357 -403.605099)
			(xy 62.67256 -403.566862) (xy 62.713998 -403.534373) (xy 62.759767 -403.508338) (xy 62.808871 -403.489325)
			(xy 62.860239 -403.477749) (xy 62.912752 -403.473862) (xy 62.965265 -403.477749) (xy 63.016633 -403.489325)
			(xy 63.065737 -403.508338) (xy 63.111506 -403.534373) (xy 63.152944 -403.566862) (xy 63.189147 -403.605099)
			(xy 63.219326 -403.648249) (xy 63.242823 -403.695372) (xy 63.259126 -403.74544) (xy 63.26788 -403.797364)
			(xy 63.26886 -403.823678) (xy 63.269114 -403.844506) (xy 63.298832 -403.873462) (xy 63.785496 -403.873462)
			(xy 63.815214 -403.844506) (xy 63.815468 -403.823678) (xy 63.816448 -403.797364) (xy 63.825202 -403.74544)
			(xy 63.841505 -403.695372) (xy 63.865002 -403.648249) (xy 63.895181 -403.605099) (xy 63.931384 -403.566862)
			(xy 63.972822 -403.534373) (xy 64.018591 -403.508338) (xy 64.067695 -403.489325) (xy 64.119063 -403.477749)
			(xy 64.171576 -403.473862) (xy 64.224089 -403.477749) (xy 64.275457 -403.489325) (xy 64.324561 -403.508338)
			(xy 64.37033 -403.534373) (xy 64.411768 -403.566862) (xy 64.447971 -403.605099) (xy 64.47815 -403.648249)
			(xy 64.501647 -403.695372) (xy 64.51795 -403.74544) (xy 64.526704 -403.797364) (xy 64.527684 -403.823678)
			(xy 64.527938 -403.844506) (xy 64.557656 -403.873462) (xy 65.589912 -403.873462) (xy 65.61963 -403.844506)
			(xy 65.619884 -403.823678) (xy 65.620864 -403.797364) (xy 65.629618 -403.74544) (xy 65.645921 -403.695372)
			(xy 65.669418 -403.648249) (xy 65.699597 -403.605099) (xy 65.7358 -403.566862) (xy 65.777238 -403.534373)
			(xy 65.823007 -403.508338) (xy 65.872111 -403.489325) (xy 65.923479 -403.477749) (xy 65.975992 -403.473862)
			(xy 66.028505 -403.477749) (xy 66.079873 -403.489325) (xy 66.128977 -403.508338) (xy 66.174746 -403.534373)
			(xy 66.216184 -403.566862) (xy 66.252387 -403.605099) (xy 66.282566 -403.648249) (xy 66.306063 -403.695372)
			(xy 66.322366 -403.74544) (xy 66.33112 -403.797364) (xy 66.3321 -403.823678) (xy 66.332354 -403.844506)
			(xy 66.362072 -403.873462) (xy 66.848736 -403.873462) (xy 66.878454 -403.844506) (xy 66.878708 -403.823678)
			(xy 66.879688 -403.797364) (xy 66.888442 -403.74544) (xy 66.904745 -403.695372) (xy 66.928242 -403.648249)
			(xy 66.958421 -403.605099) (xy 66.994624 -403.566862) (xy 67.036062 -403.534373) (xy 67.081831 -403.508338)
			(xy 67.130935 -403.489325) (xy 67.182303 -403.477749) (xy 67.234816 -403.473862) (xy 67.287329 -403.477749)
			(xy 67.338697 -403.489325) (xy 67.387801 -403.508338) (xy 67.43357 -403.534373) (xy 67.475008 -403.566862)
			(xy 67.511211 -403.605099) (xy 67.54139 -403.648249) (xy 67.564887 -403.695372) (xy 67.58119 -403.74544)
			(xy 67.589944 -403.797364) (xy 67.590924 -403.823678) (xy 67.591178 -403.844506) (xy 67.620896 -403.873462)
			(xy 68.653152 -403.873462) (xy 68.68287 -403.844506) (xy 68.683124 -403.823678) (xy 68.684104 -403.797364)
			(xy 68.692858 -403.74544) (xy 68.709161 -403.695372) (xy 68.732658 -403.648249) (xy 68.762837 -403.605099)
			(xy 68.79904 -403.566862) (xy 68.840478 -403.534373) (xy 68.886247 -403.508338) (xy 68.935351 -403.489325)
			(xy 68.986719 -403.477749) (xy 69.039232 -403.473862) (xy 69.091745 -403.477749) (xy 69.143113 -403.489325)
			(xy 69.192217 -403.508338) (xy 69.237986 -403.534373) (xy 69.279424 -403.566862) (xy 69.315627 -403.605099)
			(xy 69.345806 -403.648249) (xy 69.369303 -403.695372) (xy 69.385606 -403.74544) (xy 69.39436 -403.797364)
			(xy 69.39534 -403.823678) (xy 69.395594 -403.844506) (xy 69.425312 -403.873462) (xy 69.911976 -403.873462)
			(xy 69.941694 -403.844506) (xy 69.941948 -403.823678) (xy 69.942928 -403.797364) (xy 69.951682 -403.74544)
			(xy 69.967985 -403.695372) (xy 69.991482 -403.648249) (xy 70.021661 -403.605099) (xy 70.057864 -403.566862)
			(xy 70.099302 -403.534373) (xy 70.145071 -403.508338) (xy 70.194175 -403.489325) (xy 70.245543 -403.477749)
			(xy 70.298056 -403.473862) (xy 70.350569 -403.477749) (xy 70.401937 -403.489325) (xy 70.451041 -403.508338)
			(xy 70.49681 -403.534373) (xy 70.538248 -403.566862) (xy 70.574451 -403.605099) (xy 70.60463 -403.648249)
			(xy 70.628127 -403.695372) (xy 70.64443 -403.74544) (xy 70.653184 -403.797364) (xy 70.654164 -403.823678)
			(xy 70.654418 -403.844506) (xy 70.684136 -403.873462) (xy 71.716392 -403.873462) (xy 71.74611 -403.844506)
			(xy 71.746364 -403.823678) (xy 71.747344 -403.797364) (xy 71.756098 -403.74544) (xy 71.772401 -403.695372)
			(xy 71.795898 -403.648249) (xy 71.826077 -403.605099) (xy 71.86228 -403.566862) (xy 71.903718 -403.534373)
			(xy 71.949487 -403.508338) (xy 71.998591 -403.489325) (xy 72.049959 -403.477749) (xy 72.102472 -403.473862)
			(xy 72.154985 -403.477749) (xy 72.206353 -403.489325) (xy 72.255457 -403.508338) (xy 72.301226 -403.534373)
			(xy 72.342664 -403.566862) (xy 72.378867 -403.605099) (xy 72.409046 -403.648249) (xy 72.432543 -403.695372)
			(xy 72.448846 -403.74544) (xy 72.4576 -403.797364) (xy 72.45858 -403.823678) (xy 72.458834 -403.844506)
			(xy 72.488552 -403.873462) (xy 72.975216 -403.873462) (xy 73.004934 -403.844506) (xy 73.005188 -403.823678)
			(xy 73.006168 -403.797364) (xy 73.014922 -403.74544) (xy 73.031225 -403.695372) (xy 73.054722 -403.648249)
			(xy 73.084901 -403.605099) (xy 73.121104 -403.566862) (xy 73.162542 -403.534373) (xy 73.208311 -403.508338)
			(xy 73.257415 -403.489325) (xy 73.308783 -403.477749) (xy 73.361296 -403.473862) (xy 73.413809 -403.477749)
			(xy 73.465177 -403.489325) (xy 73.514281 -403.508338) (xy 73.56005 -403.534373) (xy 73.601488 -403.566862)
			(xy 73.637691 -403.605099) (xy 73.66787 -403.648249) (xy 73.691367 -403.695372) (xy 73.70767 -403.74544)
			(xy 73.716424 -403.797364) (xy 73.717404 -403.823678) (xy 73.717658 -403.844506) (xy 73.747376 -403.873462)
			(xy 74.779632 -403.873462) (xy 74.80935 -403.844506) (xy 74.809604 -403.823678) (xy 74.810584 -403.797364)
			(xy 74.819338 -403.74544) (xy 74.835641 -403.695372) (xy 74.859138 -403.648249) (xy 74.889317 -403.605099)
			(xy 74.92552 -403.566862) (xy 74.966958 -403.534373) (xy 75.012727 -403.508338) (xy 75.061831 -403.489325)
			(xy 75.113199 -403.477749) (xy 75.165712 -403.473862) (xy 75.218225 -403.477749) (xy 75.269593 -403.489325)
			(xy 75.318697 -403.508338) (xy 75.364466 -403.534373) (xy 75.405904 -403.566862) (xy 75.442107 -403.605099)
			(xy 75.472286 -403.648249) (xy 75.495783 -403.695372) (xy 75.512086 -403.74544) (xy 75.52084 -403.797364)
			(xy 75.52182 -403.823678) (xy 75.522074 -403.844506) (xy 75.551792 -403.873462) (xy 76.038456 -403.873462)
			(xy 76.068174 -403.844506) (xy 76.068428 -403.823678) (xy 76.069408 -403.797364) (xy 76.078162 -403.74544)
			(xy 76.094465 -403.695372) (xy 76.117962 -403.648249) (xy 76.148141 -403.605099) (xy 76.184344 -403.566862)
			(xy 76.225782 -403.534373) (xy 76.271551 -403.508338) (xy 76.320655 -403.489325) (xy 76.372023 -403.477749)
			(xy 76.424536 -403.473862) (xy 76.477049 -403.477749) (xy 76.528417 -403.489325) (xy 76.577521 -403.508338)
			(xy 76.62329 -403.534373) (xy 76.664728 -403.566862) (xy 76.700931 -403.605099) (xy 76.73111 -403.648249)
			(xy 76.754607 -403.695372) (xy 76.77091 -403.74544) (xy 76.779664 -403.797364) (xy 76.780644 -403.823678)
			(xy 76.780898 -403.844506) (xy 76.810616 -403.873462) (xy 77.842872 -403.873462) (xy 77.87259 -403.844506)
			(xy 77.872844 -403.823678) (xy 77.873824 -403.797364) (xy 77.882578 -403.74544) (xy 77.898881 -403.695372)
			(xy 77.922378 -403.648249) (xy 77.952557 -403.605099) (xy 77.98876 -403.566862) (xy 78.030198 -403.534373)
			(xy 78.075967 -403.508338) (xy 78.125071 -403.489325) (xy 78.176439 -403.477749) (xy 78.228952 -403.473862)
			(xy 78.281465 -403.477749) (xy 78.332833 -403.489325) (xy 78.381937 -403.508338) (xy 78.427706 -403.534373)
			(xy 78.469144 -403.566862) (xy 78.505347 -403.605099) (xy 78.535526 -403.648249) (xy 78.559023 -403.695372)
			(xy 78.575326 -403.74544) (xy 78.58408 -403.797364) (xy 78.58506 -403.823678) (xy 78.585314 -403.844506)
			(xy 78.615032 -403.873462) (xy 79.101696 -403.873462) (xy 79.131414 -403.844506) (xy 79.131668 -403.823678)
			(xy 79.132648 -403.797364) (xy 79.141402 -403.74544) (xy 79.157705 -403.695372) (xy 79.181202 -403.648249)
			(xy 79.211381 -403.605099) (xy 79.247584 -403.566862) (xy 79.289022 -403.534373) (xy 79.334791 -403.508338)
			(xy 79.383895 -403.489325) (xy 79.435263 -403.477749) (xy 79.487776 -403.473862) (xy 79.540289 -403.477749)
			(xy 79.591657 -403.489325) (xy 79.640761 -403.508338) (xy 79.68653 -403.534373) (xy 79.727968 -403.566862)
			(xy 79.764171 -403.605099) (xy 79.79435 -403.648249) (xy 79.817847 -403.695372) (xy 79.83415 -403.74544)
			(xy 79.842904 -403.797364) (xy 79.843884 -403.823678) (xy 79.844138 -403.844506) (xy 79.873856 -403.873462)
			(xy 80.906112 -403.873462) (xy 80.93583 -403.844506) (xy 80.936084 -403.823678) (xy 80.937064 -403.797364)
			(xy 80.945818 -403.74544) (xy 80.962121 -403.695372) (xy 80.985618 -403.648249) (xy 81.015797 -403.605099)
			(xy 81.052 -403.566862) (xy 81.093438 -403.534373) (xy 81.139207 -403.508338) (xy 81.188311 -403.489325)
			(xy 81.239679 -403.477749) (xy 81.292192 -403.473862) (xy 81.344705 -403.477749) (xy 81.396073 -403.489325)
			(xy 81.445177 -403.508338) (xy 81.490946 -403.534373) (xy 81.532384 -403.566862) (xy 81.568587 -403.605099)
			(xy 81.598766 -403.648249) (xy 81.622263 -403.695372) (xy 81.638566 -403.74544) (xy 81.64732 -403.797364)
			(xy 81.6483 -403.823678) (xy 81.648554 -403.844506) (xy 81.678272 -403.873462) (xy 82.164936 -403.873462)
			(xy 82.194654 -403.844506) (xy 82.194908 -403.823678) (xy 82.195888 -403.797364) (xy 82.204642 -403.74544)
			(xy 82.220945 -403.695372) (xy 82.244442 -403.648249) (xy 82.274621 -403.605099) (xy 82.310824 -403.566862)
			(xy 82.352262 -403.534373) (xy 82.398031 -403.508338) (xy 82.447135 -403.489325) (xy 82.498503 -403.477749)
			(xy 82.551016 -403.473862) (xy 82.603529 -403.477749) (xy 82.654897 -403.489325) (xy 82.704001 -403.508338)
			(xy 82.74977 -403.534373) (xy 82.791208 -403.566862) (xy 82.827411 -403.605099) (xy 82.85759 -403.648249)
			(xy 82.881087 -403.695372) (xy 82.89739 -403.74544) (xy 82.906144 -403.797364) (xy 82.907124 -403.823678)
			(xy 82.907378 -403.844506) (xy 82.937096 -403.873462) (xy 83.969352 -403.873462) (xy 83.99907 -403.844506)
			(xy 83.999324 -403.823678) (xy 84.000304 -403.797364) (xy 84.009058 -403.74544) (xy 84.025361 -403.695372)
			(xy 84.048858 -403.648249) (xy 84.079037 -403.605099) (xy 84.11524 -403.566862) (xy 84.156678 -403.534373)
			(xy 84.202447 -403.508338) (xy 84.251551 -403.489325) (xy 84.302919 -403.477749) (xy 84.355432 -403.473862)
			(xy 84.407945 -403.477749) (xy 84.459313 -403.489325) (xy 84.508417 -403.508338) (xy 84.554186 -403.534373)
			(xy 84.595624 -403.566862) (xy 84.631827 -403.605099) (xy 84.662006 -403.648249) (xy 84.685503 -403.695372)
			(xy 84.701806 -403.74544) (xy 84.71056 -403.797364) (xy 84.71154 -403.823678) (xy 84.711794 -403.844506)
			(xy 84.741512 -403.873462) (xy 85.228176 -403.873462) (xy 85.257894 -403.844506) (xy 85.258148 -403.823678)
			(xy 85.259128 -403.797364) (xy 85.267882 -403.74544) (xy 85.284185 -403.695372) (xy 85.307682 -403.648249)
			(xy 85.337861 -403.605099) (xy 85.374064 -403.566862) (xy 85.415502 -403.534373) (xy 85.461271 -403.508338)
			(xy 85.510375 -403.489325) (xy 85.561743 -403.477749) (xy 85.614256 -403.473862) (xy 85.666769 -403.477749)
			(xy 85.718137 -403.489325) (xy 85.767241 -403.508338) (xy 85.81301 -403.534373) (xy 85.854448 -403.566862)
			(xy 85.890651 -403.605099) (xy 85.92083 -403.648249) (xy 85.944327 -403.695372) (xy 85.96063 -403.74544)
			(xy 85.969384 -403.797364) (xy 85.970364 -403.823678) (xy 85.970618 -403.844506) (xy 86.000336 -403.873462)
			(xy 87.032592 -403.873462) (xy 87.06231 -403.844506) (xy 87.062564 -403.823678) (xy 87.063544 -403.797364)
			(xy 87.072298 -403.74544) (xy 87.088601 -403.695372) (xy 87.112098 -403.648249) (xy 87.142277 -403.605099)
			(xy 87.17848 -403.566862) (xy 87.219918 -403.534373) (xy 87.265687 -403.508338) (xy 87.314791 -403.489325)
			(xy 87.366159 -403.477749) (xy 87.418672 -403.473862) (xy 87.471185 -403.477749) (xy 87.522553 -403.489325)
			(xy 87.571657 -403.508338) (xy 87.617426 -403.534373) (xy 87.658864 -403.566862) (xy 87.695067 -403.605099)
			(xy 87.725246 -403.648249) (xy 87.748743 -403.695372) (xy 87.765046 -403.74544) (xy 87.7738 -403.797364)
			(xy 87.77478 -403.823678) (xy 87.775034 -403.844506) (xy 87.804752 -403.873462) (xy 88.291416 -403.873462)
			(xy 88.321134 -403.844506) (xy 88.321388 -403.823678) (xy 88.322368 -403.797364) (xy 88.331122 -403.74544)
			(xy 88.347425 -403.695372) (xy 88.370922 -403.648249) (xy 88.401101 -403.605099) (xy 88.437304 -403.566862)
			(xy 88.478742 -403.534373) (xy 88.524511 -403.508338) (xy 88.573615 -403.489325) (xy 88.624983 -403.477749)
			(xy 88.677496 -403.473862) (xy 88.730009 -403.477749) (xy 88.781377 -403.489325) (xy 88.830481 -403.508338)
			(xy 88.87625 -403.534373) (xy 88.917688 -403.566862) (xy 88.953891 -403.605099) (xy 88.98407 -403.648249)
			(xy 89.007567 -403.695372) (xy 89.02387 -403.74544) (xy 89.032624 -403.797364) (xy 89.033604 -403.823678)
			(xy 89.033858 -403.844506) (xy 89.063576 -403.873462) (xy 90.095832 -403.873462) (xy 90.12555 -403.844506)
			(xy 90.125804 -403.823678) (xy 90.126784 -403.797364) (xy 90.135538 -403.74544) (xy 90.151841 -403.695372)
			(xy 90.175338 -403.648249) (xy 90.205517 -403.605099) (xy 90.24172 -403.566862) (xy 90.283158 -403.534373)
			(xy 90.328927 -403.508338) (xy 90.378031 -403.489325) (xy 90.429399 -403.477749) (xy 90.481912 -403.473862)
			(xy 90.534425 -403.477749) (xy 90.585793 -403.489325) (xy 90.634897 -403.508338) (xy 90.680666 -403.534373)
			(xy 90.722104 -403.566862) (xy 90.758307 -403.605099) (xy 90.788486 -403.648249) (xy 90.811983 -403.695372)
			(xy 90.828286 -403.74544) (xy 90.83704 -403.797364) (xy 90.83802 -403.823678) (xy 90.838274 -403.844506)
			(xy 90.867992 -403.873462) (xy 91.354656 -403.873462) (xy 91.384374 -403.844506) (xy 91.384628 -403.823678)
			(xy 91.385608 -403.797364) (xy 91.394362 -403.74544) (xy 91.410665 -403.695372) (xy 91.434162 -403.648249)
			(xy 91.464341 -403.605099) (xy 91.500544 -403.566862) (xy 91.541982 -403.534373) (xy 91.587751 -403.508338)
			(xy 91.636855 -403.489325) (xy 91.688223 -403.477749) (xy 91.740736 -403.473862) (xy 91.793249 -403.477749)
			(xy 91.844617 -403.489325) (xy 91.893721 -403.508338) (xy 91.93949 -403.534373) (xy 91.980928 -403.566862)
			(xy 92.017131 -403.605099) (xy 92.04731 -403.648249) (xy 92.070807 -403.695372) (xy 92.08711 -403.74544)
			(xy 92.095864 -403.797364) (xy 92.096844 -403.823678) (xy 92.097098 -403.844506) (xy 92.126816 -403.873462)
			(xy 93.159072 -403.873462) (xy 93.18879 -403.844506) (xy 93.189044 -403.823678) (xy 93.190024 -403.797364)
			(xy 93.198778 -403.74544) (xy 93.215081 -403.695372) (xy 93.238578 -403.648249) (xy 93.268757 -403.605099)
			(xy 93.30496 -403.566862) (xy 93.346398 -403.534373) (xy 93.392167 -403.508338) (xy 93.441271 -403.489325)
			(xy 93.492639 -403.477749) (xy 93.545152 -403.473862) (xy 93.597665 -403.477749) (xy 93.649033 -403.489325)
			(xy 93.698137 -403.508338) (xy 93.743906 -403.534373) (xy 93.785344 -403.566862) (xy 93.821547 -403.605099)
			(xy 93.851726 -403.648249) (xy 93.875223 -403.695372) (xy 93.891526 -403.74544) (xy 93.90028 -403.797364)
			(xy 93.90126 -403.823678) (xy 93.901514 -403.844506) (xy 93.931232 -403.873462) (xy 94.417896 -403.873462)
			(xy 94.447614 -403.844506) (xy 94.447868 -403.823678) (xy 94.44892 -403.796048) (xy 94.458511 -403.741595)
			(xy 94.476403 -403.689279) (xy 94.502166 -403.640357) (xy 94.535181 -403.596005) (xy 94.574655 -403.557289)
			(xy 94.619638 -403.525139) (xy 94.669049 -403.500329) (xy 94.721702 -403.483454) (xy 94.77633 -403.474919)
			(xy 94.803976 -403.474428) (xy 94.831962 -403.474947) (xy 94.887244 -403.4837) (xy 94.940476 -403.500994)
			(xy 94.990347 -403.526403) (xy 95.035629 -403.559302) (xy 95.075205 -403.598881) (xy 95.108103 -403.644163)
			(xy 95.133511 -403.694035) (xy 95.150803 -403.747268) (xy 95.159554 -403.80255) (xy 95.160084 -403.830536)
			(xy 95.15983 -403.843236) (xy 95.159576 -403.853904) (xy 95.167196 -403.873462) (xy 96.145858 -404.852124)
			(xy 96.153256 -404.85897) (xy 96.171855 -404.866695) (xy 96.181926 -404.86711) (xy 96.416114 -404.86711)
		)
		(stroke
			(width 0)
			(type solid)
		)
		(fill yes)
		(layer "B.Cu")
		(net "P0V9_CPU1_RT_2D")
	)
	(gr_poly
		(pts
			(xy 303.154334 -412.433262) (xy 303.166044 -412.432663) (xy 303.187066 -412.422334) (xy 303.19472 -412.41345)
			(xy 303.250854 -412.340044) (xy 303.255426 -412.316676) (xy 303.252378 -412.305246) (xy 303.246648 -412.282499)
			(xy 303.240531 -412.235991) (xy 303.240186 -412.212536) (xy 303.240722 -412.184676) (xy 303.249392 -412.129636)
			(xy 303.266526 -412.076617) (xy 303.291706 -412.026913) (xy 303.324319 -411.981735) (xy 303.343564 -411.961584)
			(xy 303.351692 -411.953456) (xy 303.359312 -411.932374) (xy 303.349406 -411.83179) (xy 303.337976 -411.812232)
			(xy 303.328578 -411.805882) (xy 303.306845 -411.790583) (xy 303.267428 -411.754931) (xy 303.233341 -411.714154)
			(xy 303.205242 -411.669041) (xy 303.183676 -411.620465) (xy 303.169059 -411.569367) (xy 303.161676 -411.516734)
			(xy 303.161192 -411.49016) (xy 303.161678 -411.462909) (xy 303.169434 -411.408961) (xy 303.184789 -411.356666)
			(xy 303.207431 -411.307089) (xy 303.236897 -411.261239) (xy 303.272588 -411.220048) (xy 303.313779 -411.184357)
			(xy 303.359629 -411.154891) (xy 303.409206 -411.132249) (xy 303.461501 -411.116894) (xy 303.515449 -411.109138)
			(xy 303.569951 -411.109138) (xy 303.623899 -411.116894) (xy 303.676194 -411.132249) (xy 303.725771 -411.154891)
			(xy 303.771621 -411.184357) (xy 303.812812 -411.220048) (xy 303.848503 -411.261239) (xy 303.877969 -411.307089)
			(xy 303.900611 -411.356666) (xy 303.915966 -411.408961) (xy 303.923722 -411.462909) (xy 303.924208 -411.49016)
			(xy 303.923763 -411.516456) (xy 303.916529 -411.568549) (xy 303.902206 -411.619153) (xy 303.881066 -411.66731)
			(xy 303.85351 -411.712105) (xy 303.820061 -411.75269) (xy 303.801018 -411.77083) (xy 303.792636 -411.778704)
			(xy 303.784254 -411.799532) (xy 303.789334 -411.90037) (xy 303.800002 -411.920182) (xy 303.809146 -411.92704)
			(xy 303.830975 -411.943965) (xy 303.869626 -411.983423) (xy 303.90172 -412.028376) (xy 303.926488 -412.077745)
			(xy 303.943336 -412.130347) (xy 303.951859 -412.184919) (xy 303.952402 -412.212536) (xy 303.951865 -412.240371)
			(xy 303.943185 -412.29536) (xy 303.93513 -412.32201) (xy 303.932561 -412.331072) (xy 303.933606 -412.349864)
			(xy 303.937162 -412.358586) (xy 303.950116 -412.387034) (xy 303.954376 -412.39554) (xy 303.967941 -412.408858)
			(xy 303.976532 -412.412942) (xy 304.008028 -412.427674) (xy 304.013454 -412.43026) (xy 304.025134 -412.433089)
			(xy 304.031142 -412.433262) (xy 304.42027 -412.433262) (xy 304.426279 -412.433092) (xy 304.437958 -412.430262)
			(xy 304.443384 -412.427674) (xy 304.47488 -412.412942) (xy 304.48348 -412.40887) (xy 304.497047 -412.395549)
			(xy 304.501296 -412.387034) (xy 304.51425 -412.358586) (xy 304.517722 -412.349843) (xy 304.518782 -412.331077)
			(xy 304.516282 -412.32201) (xy 304.508239 -412.295358) (xy 304.499567 -412.24037) (xy 304.49901 -412.212536)
			(xy 304.499508 -412.185887) (xy 304.507451 -412.133183) (xy 304.523161 -412.082253) (xy 304.546287 -412.034232)
			(xy 304.576311 -411.990195) (xy 304.612563 -411.951124) (xy 304.654234 -411.917893) (xy 304.700392 -411.891244)
			(xy 304.750006 -411.871772) (xy 304.801968 -411.859912) (xy 304.855118 -411.855929) (xy 304.908268 -411.859912)
			(xy 304.96023 -411.871772) (xy 305.009844 -411.891244) (xy 305.056002 -411.917893) (xy 305.097673 -411.951124)
			(xy 305.133925 -411.990195) (xy 305.163949 -412.034232) (xy 305.187075 -412.082253) (xy 305.202785 -412.133183)
			(xy 305.210728 -412.185887) (xy 305.211226 -412.212536) (xy 305.210867 -412.23599) (xy 305.204749 -412.282496)
			(xy 305.199034 -412.305246) (xy 305.195986 -412.316676) (xy 305.200558 -412.340044) (xy 305.256692 -412.41345)
			(xy 305.264292 -412.422398) (xy 305.285349 -412.432715) (xy 305.297078 -412.433262) (xy 306.217574 -412.433262)
			(xy 306.22929 -412.432676) (xy 306.250332 -412.422362) (xy 306.25796 -412.41345) (xy 306.314094 -412.340044)
			(xy 306.318666 -412.316676) (xy 306.315618 -412.305246) (xy 306.309888 -412.282499) (xy 306.30377 -412.235991)
			(xy 306.303426 -412.212536) (xy 306.303924 -412.185887) (xy 306.311867 -412.133183) (xy 306.327577 -412.082253)
			(xy 306.350703 -412.034232) (xy 306.380727 -411.990195) (xy 306.416979 -411.951124) (xy 306.45865 -411.917893)
			(xy 306.504808 -411.891244) (xy 306.554422 -411.871772) (xy 306.606384 -411.859912) (xy 306.659534 -411.855929)
			(xy 306.712684 -411.859912) (xy 306.764646 -411.871772) (xy 306.81426 -411.891244) (xy 306.860418 -411.917893)
			(xy 306.902089 -411.951124) (xy 306.938341 -411.990195) (xy 306.968365 -412.034232) (xy 306.991491 -412.082253)
			(xy 307.007201 -412.133183) (xy 307.015144 -412.185887) (xy 307.015642 -412.212536) (xy 307.015105 -412.240371)
			(xy 307.006426 -412.295361) (xy 306.99837 -412.32201) (xy 306.995803 -412.331072) (xy 306.996846 -412.349864)
			(xy 307.000402 -412.358586) (xy 307.013356 -412.387034) (xy 307.017618 -412.395537) (xy 307.031188 -412.408846)
			(xy 307.039772 -412.412942) (xy 307.071268 -412.427674) (xy 307.076695 -412.430256) (xy 307.088375 -412.433075)
			(xy 307.094382 -412.433262) (xy 307.48351 -412.433262) (xy 307.489521 -412.433099) (xy 307.501206 -412.430282)
			(xy 307.506624 -412.427674) (xy 307.53812 -412.412942) (xy 307.546715 -412.408865) (xy 307.560272 -412.39554)
			(xy 307.564536 -412.387034) (xy 307.57749 -412.358586) (xy 307.580961 -412.349843) (xy 307.582019 -412.331078)
			(xy 307.579522 -412.32201) (xy 307.571479 -412.295358) (xy 307.562805 -412.24037) (xy 307.56225 -412.212536)
			(xy 307.562748 -412.185887) (xy 307.570691 -412.133183) (xy 307.586401 -412.082253) (xy 307.609527 -412.034232)
			(xy 307.639551 -411.990195) (xy 307.675803 -411.951124) (xy 307.717474 -411.917893) (xy 307.763632 -411.891244)
			(xy 307.813246 -411.871772) (xy 307.865208 -411.859912) (xy 307.918358 -411.855929) (xy 307.971508 -411.859912)
			(xy 308.02347 -411.871772) (xy 308.073084 -411.891244) (xy 308.119242 -411.917893) (xy 308.160913 -411.951124)
			(xy 308.197165 -411.990195) (xy 308.227189 -412.034232) (xy 308.250315 -412.082253) (xy 308.266025 -412.133183)
			(xy 308.273968 -412.185887) (xy 308.274466 -412.212536) (xy 308.274106 -412.23599) (xy 308.267987 -412.282496)
			(xy 308.262274 -412.305246) (xy 308.259226 -412.316676) (xy 308.263798 -412.340044) (xy 308.319932 -412.41345)
			(xy 308.327528 -412.422408) (xy 308.348585 -412.43275) (xy 308.360318 -412.433262) (xy 309.280814 -412.433262)
			(xy 309.292526 -412.432667) (xy 309.313555 -412.422343) (xy 309.3212 -412.41345) (xy 309.377334 -412.340044)
			(xy 309.381906 -412.316676) (xy 309.378858 -412.305246) (xy 309.373128 -412.282499) (xy 309.367012 -412.235991)
			(xy 309.366666 -412.212536) (xy 309.367164 -412.185887) (xy 309.375107 -412.133183) (xy 309.390817 -412.082253)
			(xy 309.413943 -412.034232) (xy 309.443967 -411.990195) (xy 309.480219 -411.951124) (xy 309.52189 -411.917893)
			(xy 309.568048 -411.891244) (xy 309.617662 -411.871772) (xy 309.669624 -411.859912) (xy 309.722774 -411.855929)
			(xy 309.775924 -411.859912) (xy 309.827886 -411.871772) (xy 309.8775 -411.891244) (xy 309.923658 -411.917893)
			(xy 309.965329 -411.951124) (xy 310.001581 -411.990195) (xy 310.031605 -412.034232) (xy 310.054731 -412.082253)
			(xy 310.070441 -412.133183) (xy 310.078384 -412.185887) (xy 310.078882 -412.212536) (xy 310.078345 -412.240371)
			(xy 310.069664 -412.29536) (xy 310.06161 -412.32201) (xy 310.059042 -412.331072) (xy 310.060086 -412.349864)
			(xy 310.063642 -412.358586) (xy 310.076596 -412.387034) (xy 310.080854 -412.395542) (xy 310.094417 -412.408865)
			(xy 310.103012 -412.412942) (xy 310.134508 -412.427674) (xy 310.139934 -412.430262) (xy 310.151613 -412.433095)
			(xy 310.157622 -412.433262) (xy 310.54675 -412.433262) (xy 310.552759 -412.433094) (xy 310.564441 -412.430269)
			(xy 310.569864 -412.427674) (xy 310.60136 -412.412942) (xy 310.609962 -412.408871) (xy 310.623534 -412.395553)
			(xy 310.627776 -412.387034) (xy 310.64073 -412.358586) (xy 310.644204 -412.349843) (xy 310.645264 -412.331077)
			(xy 310.642762 -412.32201) (xy 310.634718 -412.295358) (xy 310.626043 -412.24037) (xy 310.62549 -412.212536)
			(xy 310.625988 -412.185887) (xy 310.633931 -412.133183) (xy 310.649641 -412.082253) (xy 310.672767 -412.034232)
			(xy 310.702791 -411.990195) (xy 310.739043 -411.951124) (xy 310.780714 -411.917893) (xy 310.826872 -411.891244)
			(xy 310.876486 -411.871772) (xy 310.928448 -411.859912) (xy 310.981598 -411.855929) (xy 311.034748 -411.859912)
			(xy 311.08671 -411.871772) (xy 311.136324 -411.891244) (xy 311.182482 -411.917893) (xy 311.224153 -411.951124)
			(xy 311.260405 -411.990195) (xy 311.290429 -412.034232) (xy 311.313555 -412.082253) (xy 311.329265 -412.133183)
			(xy 311.337208 -412.185887) (xy 311.337706 -412.212536) (xy 311.337346 -412.23599) (xy 311.331228 -412.282496)
			(xy 311.325514 -412.305246) (xy 311.322466 -412.316676) (xy 311.327038 -412.340044) (xy 311.383172 -412.41345)
			(xy 311.390771 -412.422401) (xy 311.411828 -412.432726) (xy 311.423558 -412.433262) (xy 312.344054 -412.433262)
			(xy 312.355762 -412.432659) (xy 312.376777 -412.422325) (xy 312.38444 -412.41345) (xy 312.440574 -412.340044)
			(xy 312.445146 -412.316676) (xy 312.442098 -412.305246) (xy 312.436368 -412.282499) (xy 312.43025 -412.235991)
			(xy 312.429906 -412.212536) (xy 312.430404 -412.185887) (xy 312.438347 -412.133183) (xy 312.454057 -412.082253)
			(xy 312.477183 -412.034232) (xy 312.507207 -411.990195) (xy 312.543459 -411.951124) (xy 312.58513 -411.917893)
			(xy 312.631288 -411.891244) (xy 312.680902 -411.871772) (xy 312.732864 -411.859912) (xy 312.786014 -411.855929)
			(xy 312.839164 -411.859912) (xy 312.891126 -411.871772) (xy 312.94074 -411.891244) (xy 312.986898 -411.917893)
			(xy 313.028569 -411.951124) (xy 313.064821 -411.990195) (xy 313.094845 -412.034232) (xy 313.117971 -412.082253)
			(xy 313.133681 -412.133183) (xy 313.141624 -412.185887) (xy 313.142122 -412.212536) (xy 313.141585 -412.240371)
			(xy 313.132906 -412.29536) (xy 313.12485 -412.32201) (xy 313.122284 -412.331072) (xy 313.123326 -412.349865)
			(xy 313.126882 -412.358586) (xy 313.139836 -412.387034) (xy 313.144097 -412.395538) (xy 313.157665 -412.408852)
			(xy 313.166252 -412.412942) (xy 313.197748 -412.427674) (xy 313.203175 -412.430258) (xy 313.214854 -412.433082)
			(xy 313.220862 -412.433262) (xy 313.60999 -412.433262) (xy 313.615998 -412.43309) (xy 313.627675 -412.430256)
			(xy 313.633104 -412.427674) (xy 313.6646 -412.412942) (xy 313.673197 -412.408867) (xy 313.686759 -412.395544)
			(xy 313.691016 -412.387034) (xy 313.70397 -412.358586) (xy 313.707441 -412.349843) (xy 313.708501 -412.331078)
			(xy 313.706002 -412.32201) (xy 313.697959 -412.295358) (xy 313.689286 -412.24037) (xy 313.68873 -412.212536)
			(xy 313.689228 -412.185887) (xy 313.697171 -412.133183) (xy 313.712881 -412.082253) (xy 313.736007 -412.034232)
			(xy 313.766031 -411.990195) (xy 313.802283 -411.951124) (xy 313.843954 -411.917893) (xy 313.890112 -411.891244)
			(xy 313.939726 -411.871772) (xy 313.991688 -411.859912) (xy 314.044838 -411.855929) (xy 314.097988 -411.859912)
			(xy 314.14995 -411.871772) (xy 314.199564 -411.891244) (xy 314.245722 -411.917893) (xy 314.287393 -411.951124)
			(xy 314.323645 -411.990195) (xy 314.353669 -412.034232) (xy 314.376795 -412.082253) (xy 314.392505 -412.133183)
			(xy 314.400448 -412.185887) (xy 314.400946 -412.212536) (xy 314.400586 -412.23599) (xy 314.394467 -412.282496)
			(xy 314.388754 -412.305246) (xy 314.385706 -412.316676) (xy 314.390278 -412.340044) (xy 314.446412 -412.41345)
			(xy 314.454007 -412.422411) (xy 314.475064 -412.432761) (xy 314.486798 -412.433262) (xy 315.407294 -412.433262)
			(xy 315.419008 -412.432671) (xy 315.440044 -412.422352) (xy 315.44768 -412.41345) (xy 315.503814 -412.340044)
			(xy 315.508386 -412.316676) (xy 315.505338 -412.305246) (xy 315.499608 -412.282499) (xy 315.49349 -412.235991)
			(xy 315.493146 -412.212536) (xy 315.493644 -412.185887) (xy 315.501587 -412.133183) (xy 315.517297 -412.082253)
			(xy 315.540423 -412.034232) (xy 315.570447 -411.990195) (xy 315.606699 -411.951124) (xy 315.64837 -411.917893)
			(xy 315.694528 -411.891244) (xy 315.744142 -411.871772) (xy 315.796104 -411.859912) (xy 315.849254 -411.855929)
			(xy 315.902404 -411.859912) (xy 315.954366 -411.871772) (xy 316.00398 -411.891244) (xy 316.050138 -411.917893)
			(xy 316.091809 -411.951124) (xy 316.128061 -411.990195) (xy 316.158085 -412.034232) (xy 316.181211 -412.082253)
			(xy 316.196921 -412.133183) (xy 316.204864 -412.185887) (xy 316.205362 -412.212536) (xy 316.204825 -412.240371)
			(xy 316.196147 -412.295361) (xy 316.18809 -412.32201) (xy 316.185522 -412.331072) (xy 316.186566 -412.349865)
			(xy 316.190122 -412.358586) (xy 316.203076 -412.387034) (xy 316.207333 -412.395543) (xy 316.220894 -412.408871)
			(xy 316.229492 -412.412942) (xy 316.260988 -412.427674) (xy 316.266416 -412.430254) (xy 316.278095 -412.433068)
			(xy 316.284102 -412.433262) (xy 316.67323 -412.433262) (xy 316.67924 -412.433097) (xy 316.690924 -412.430275)
			(xy 316.696344 -412.427674) (xy 316.72784 -412.412942) (xy 316.736444 -412.408874) (xy 316.750021 -412.395557)
			(xy 316.754256 -412.387034) (xy 316.76721 -412.358586) (xy 316.770679 -412.349843) (xy 316.771738 -412.331078)
			(xy 316.769242 -412.32201) (xy 316.761198 -412.295358) (xy 316.752524 -412.24037) (xy 316.75197 -412.212536)
			(xy 316.752468 -412.185887) (xy 316.760411 -412.133183) (xy 316.776121 -412.082253) (xy 316.799247 -412.034232)
			(xy 316.829271 -411.990195) (xy 316.865523 -411.951124) (xy 316.907194 -411.917893) (xy 316.953352 -411.891244)
			(xy 317.002966 -411.871772) (xy 317.054928 -411.859912) (xy 317.108078 -411.855929) (xy 317.161228 -411.859912)
			(xy 317.21319 -411.871772) (xy 317.262804 -411.891244) (xy 317.308962 -411.917893) (xy 317.350633 -411.951124)
			(xy 317.386885 -411.990195) (xy 317.416909 -412.034232) (xy 317.440035 -412.082253) (xy 317.455745 -412.133183)
			(xy 317.463688 -412.185887) (xy 317.464186 -412.212536) (xy 317.463826 -412.23599) (xy 317.457708 -412.282496)
			(xy 317.451994 -412.305246) (xy 317.448946 -412.316676) (xy 317.453518 -412.340044) (xy 317.509652 -412.41345)
			(xy 317.51725 -412.422405) (xy 317.538306 -412.432738) (xy 317.550038 -412.433262) (xy 318.470534 -412.433262)
			(xy 318.482244 -412.432663) (xy 318.503266 -412.422334) (xy 318.51092 -412.41345) (xy 318.567054 -412.340044)
			(xy 318.571626 -412.316676) (xy 318.568578 -412.305246) (xy 318.562848 -412.282499) (xy 318.556731 -412.235991)
			(xy 318.556386 -412.212536) (xy 318.556884 -412.185887) (xy 318.564827 -412.133183) (xy 318.580537 -412.082253)
			(xy 318.603663 -412.034232) (xy 318.633687 -411.990195) (xy 318.669939 -411.951124) (xy 318.71161 -411.917893)
			(xy 318.757768 -411.891244) (xy 318.807382 -411.871772) (xy 318.859344 -411.859912) (xy 318.912494 -411.855929)
			(xy 318.965644 -411.859912) (xy 319.017606 -411.871772) (xy 319.06722 -411.891244) (xy 319.113378 -411.917893)
			(xy 319.155049 -411.951124) (xy 319.191301 -411.990195) (xy 319.221325 -412.034232) (xy 319.244451 -412.082253)
			(xy 319.260161 -412.133183) (xy 319.268104 -412.185887) (xy 319.268602 -412.212536) (xy 319.268065 -412.240371)
			(xy 319.259385 -412.29536) (xy 319.25133 -412.32201) (xy 319.248761 -412.331072) (xy 319.249806 -412.349864)
			(xy 319.253362 -412.358586) (xy 319.266316 -412.387034) (xy 319.270576 -412.39554) (xy 319.284141 -412.408858)
			(xy 319.292732 -412.412942) (xy 319.324228 -412.427674) (xy 319.329654 -412.43026) (xy 319.341334 -412.433089)
			(xy 319.347342 -412.433262) (xy 319.73647 -412.433262) (xy 319.742479 -412.433092) (xy 319.754158 -412.430262)
			(xy 319.759584 -412.427674) (xy 319.79108 -412.412942) (xy 319.79968 -412.40887) (xy 319.813247 -412.395549)
			(xy 319.817496 -412.387034) (xy 319.83045 -412.358586) (xy 319.833922 -412.349843) (xy 319.834982 -412.331077)
			(xy 319.832482 -412.32201) (xy 319.824439 -412.295358) (xy 319.815767 -412.24037) (xy 319.81521 -412.212536)
			(xy 319.815708 -412.185887) (xy 319.823651 -412.133183) (xy 319.839361 -412.082253) (xy 319.862487 -412.034232)
			(xy 319.892511 -411.990195) (xy 319.928763 -411.951124) (xy 319.970434 -411.917893) (xy 320.016592 -411.891244)
			(xy 320.066206 -411.871772) (xy 320.118168 -411.859912) (xy 320.171318 -411.855929) (xy 320.224468 -411.859912)
			(xy 320.27643 -411.871772) (xy 320.326044 -411.891244) (xy 320.372202 -411.917893) (xy 320.413873 -411.951124)
			(xy 320.450125 -411.990195) (xy 320.480149 -412.034232) (xy 320.503275 -412.082253) (xy 320.518985 -412.133183)
			(xy 320.526928 -412.185887) (xy 320.527426 -412.212536) (xy 320.527067 -412.23599) (xy 320.520949 -412.282496)
			(xy 320.515234 -412.305246) (xy 320.512186 -412.316676) (xy 320.516758 -412.340044) (xy 320.572892 -412.41345)
			(xy 320.580492 -412.422398) (xy 320.601549 -412.432715) (xy 320.613278 -412.433262) (xy 321.533774 -412.433262)
			(xy 321.54549 -412.432676) (xy 321.566532 -412.422362) (xy 321.57416 -412.41345) (xy 321.630294 -412.340044)
			(xy 321.634866 -412.316676) (xy 321.631818 -412.305246) (xy 321.626088 -412.282499) (xy 321.61997 -412.235991)
			(xy 321.619626 -412.212536) (xy 321.620124 -412.185887) (xy 321.628067 -412.133183) (xy 321.643777 -412.082253)
			(xy 321.666903 -412.034232) (xy 321.696927 -411.990195) (xy 321.733179 -411.951124) (xy 321.77485 -411.917893)
			(xy 321.821008 -411.891244) (xy 321.870622 -411.871772) (xy 321.922584 -411.859912) (xy 321.975734 -411.855929)
			(xy 322.028884 -411.859912) (xy 322.080846 -411.871772) (xy 322.13046 -411.891244) (xy 322.176618 -411.917893)
			(xy 322.218289 -411.951124) (xy 322.254541 -411.990195) (xy 322.284565 -412.034232) (xy 322.307691 -412.082253)
			(xy 322.323401 -412.133183) (xy 322.331344 -412.185887) (xy 322.331842 -412.212536) (xy 322.331305 -412.240371)
			(xy 322.322626 -412.295361) (xy 322.31457 -412.32201) (xy 322.312003 -412.331072) (xy 322.313046 -412.349864)
			(xy 322.316602 -412.358586) (xy 322.329556 -412.387034) (xy 322.333818 -412.395537) (xy 322.347388 -412.408846)
			(xy 322.355972 -412.412942) (xy 322.387468 -412.427674) (xy 322.392895 -412.430256) (xy 322.404575 -412.433075)
			(xy 322.410582 -412.433262) (xy 322.79971 -412.433262) (xy 322.805721 -412.433099) (xy 322.817406 -412.430282)
			(xy 322.822824 -412.427674) (xy 322.85432 -412.412942) (xy 322.862915 -412.408865) (xy 322.876472 -412.39554)
			(xy 322.880736 -412.387034) (xy 322.89369 -412.358586) (xy 322.897161 -412.349843) (xy 322.898219 -412.331078)
			(xy 322.895722 -412.32201) (xy 322.887679 -412.295358) (xy 322.879005 -412.24037) (xy 322.87845 -412.212536)
			(xy 322.878948 -412.185887) (xy 322.886891 -412.133183) (xy 322.902601 -412.082253) (xy 322.925727 -412.034232)
			(xy 322.955751 -411.990195) (xy 322.992003 -411.951124) (xy 323.033674 -411.917893) (xy 323.079832 -411.891244)
			(xy 323.129446 -411.871772) (xy 323.181408 -411.859912) (xy 323.234558 -411.855929) (xy 323.287708 -411.859912)
			(xy 323.33967 -411.871772) (xy 323.389284 -411.891244) (xy 323.435442 -411.917893) (xy 323.477113 -411.951124)
			(xy 323.513365 -411.990195) (xy 323.543389 -412.034232) (xy 323.566515 -412.082253) (xy 323.582225 -412.133183)
			(xy 323.590168 -412.185887) (xy 323.590666 -412.212536) (xy 323.590306 -412.23599) (xy 323.584187 -412.282496)
			(xy 323.578474 -412.305246) (xy 323.575426 -412.316676) (xy 323.579998 -412.340044) (xy 323.636132 -412.41345)
			(xy 323.643728 -412.422408) (xy 323.664785 -412.43275) (xy 323.676518 -412.433262) (xy 324.597014 -412.433262)
			(xy 324.608726 -412.432667) (xy 324.629755 -412.422343) (xy 324.6374 -412.41345) (xy 324.693534 -412.340044)
			(xy 324.698106 -412.316676) (xy 324.695058 -412.305246) (xy 324.689328 -412.282499) (xy 324.683212 -412.235991)
			(xy 324.682866 -412.212536) (xy 324.683364 -412.185887) (xy 324.691307 -412.133183) (xy 324.707017 -412.082253)
			(xy 324.730143 -412.034232) (xy 324.760167 -411.990195) (xy 324.796419 -411.951124) (xy 324.83809 -411.917893)
			(xy 324.884248 -411.891244) (xy 324.933862 -411.871772) (xy 324.985824 -411.859912) (xy 325.038974 -411.855929)
			(xy 325.092124 -411.859912) (xy 325.144086 -411.871772) (xy 325.1937 -411.891244) (xy 325.239858 -411.917893)
			(xy 325.281529 -411.951124) (xy 325.317781 -411.990195) (xy 325.347805 -412.034232) (xy 325.370931 -412.082253)
			(xy 325.386641 -412.133183) (xy 325.394584 -412.185887) (xy 325.395082 -412.212536) (xy 325.394545 -412.240371)
			(xy 325.385864 -412.29536) (xy 325.37781 -412.32201) (xy 325.375242 -412.331072) (xy 325.376286 -412.349864)
			(xy 325.379842 -412.358586) (xy 325.392796 -412.387034) (xy 325.397054 -412.395542) (xy 325.410617 -412.408865)
			(xy 325.419212 -412.412942) (xy 325.450708 -412.427674) (xy 325.456134 -412.430262) (xy 325.467813 -412.433095)
			(xy 325.473822 -412.433262) (xy 325.86295 -412.433262) (xy 325.868959 -412.433094) (xy 325.880641 -412.430269)
			(xy 325.886064 -412.427674) (xy 325.91756 -412.412942) (xy 325.926162 -412.408871) (xy 325.939734 -412.395553)
			(xy 325.943976 -412.387034) (xy 325.95693 -412.358586) (xy 325.960404 -412.349843) (xy 325.961464 -412.331077)
			(xy 325.958962 -412.32201) (xy 325.950918 -412.295358) (xy 325.942243 -412.24037) (xy 325.94169 -412.212536)
			(xy 325.942188 -412.185887) (xy 325.950131 -412.133183) (xy 325.965841 -412.082253) (xy 325.988967 -412.034232)
			(xy 326.018991 -411.990195) (xy 326.055243 -411.951124) (xy 326.096914 -411.917893) (xy 326.143072 -411.891244)
			(xy 326.192686 -411.871772) (xy 326.244648 -411.859912) (xy 326.297798 -411.855929) (xy 326.350948 -411.859912)
			(xy 326.40291 -411.871772) (xy 326.452524 -411.891244) (xy 326.498682 -411.917893) (xy 326.540353 -411.951124)
			(xy 326.576605 -411.990195) (xy 326.606629 -412.034232) (xy 326.629755 -412.082253) (xy 326.645465 -412.133183)
			(xy 326.653408 -412.185887) (xy 326.653906 -412.212536) (xy 326.653546 -412.23599) (xy 326.647428 -412.282496)
			(xy 326.641714 -412.305246) (xy 326.638666 -412.316676) (xy 326.643238 -412.340044) (xy 326.699372 -412.41345)
			(xy 326.706971 -412.422401) (xy 326.728028 -412.432726) (xy 326.739758 -412.433262) (xy 327.660254 -412.433262)
			(xy 327.671962 -412.432659) (xy 327.692977 -412.422325) (xy 327.70064 -412.41345) (xy 327.756774 -412.340044)
			(xy 327.761346 -412.316676) (xy 327.758298 -412.305246) (xy 327.752568 -412.282499) (xy 327.74645 -412.235991)
			(xy 327.746106 -412.212536) (xy 327.746604 -412.185887) (xy 327.754547 -412.133183) (xy 327.770257 -412.082253)
			(xy 327.793383 -412.034232) (xy 327.823407 -411.990195) (xy 327.859659 -411.951124) (xy 327.90133 -411.917893)
			(xy 327.947488 -411.891244) (xy 327.997102 -411.871772) (xy 328.049064 -411.859912) (xy 328.102214 -411.855929)
			(xy 328.155364 -411.859912) (xy 328.207326 -411.871772) (xy 328.25694 -411.891244) (xy 328.303098 -411.917893)
			(xy 328.344769 -411.951124) (xy 328.381021 -411.990195) (xy 328.411045 -412.034232) (xy 328.434171 -412.082253)
			(xy 328.449881 -412.133183) (xy 328.457824 -412.185887) (xy 328.458322 -412.212536) (xy 328.457785 -412.240371)
			(xy 328.449106 -412.29536) (xy 328.44105 -412.32201) (xy 328.438484 -412.331072) (xy 328.439526 -412.349865)
			(xy 328.443082 -412.358586) (xy 328.456036 -412.387034) (xy 328.460297 -412.395538) (xy 328.473865 -412.408852)
			(xy 328.482452 -412.412942) (xy 328.513948 -412.427674) (xy 328.519375 -412.430258) (xy 328.531054 -412.433082)
			(xy 328.537062 -412.433262) (xy 328.92619 -412.433262) (xy 328.932198 -412.43309) (xy 328.943875 -412.430256)
			(xy 328.949304 -412.427674) (xy 328.9808 -412.412942) (xy 328.989397 -412.408867) (xy 329.002959 -412.395544)
			(xy 329.007216 -412.387034) (xy 329.02017 -412.358586) (xy 329.023641 -412.349843) (xy 329.024701 -412.331078)
			(xy 329.022202 -412.32201) (xy 329.014159 -412.295358) (xy 329.005486 -412.24037) (xy 329.00493 -412.212536)
			(xy 329.005428 -412.185887) (xy 329.013371 -412.133183) (xy 329.029081 -412.082253) (xy 329.052207 -412.034232)
			(xy 329.082231 -411.990195) (xy 329.118483 -411.951124) (xy 329.160154 -411.917893) (xy 329.206312 -411.891244)
			(xy 329.255926 -411.871772) (xy 329.307888 -411.859912) (xy 329.361038 -411.855929) (xy 329.414188 -411.859912)
			(xy 329.46615 -411.871772) (xy 329.515764 -411.891244) (xy 329.561922 -411.917893) (xy 329.603593 -411.951124)
			(xy 329.639845 -411.990195) (xy 329.669869 -412.034232) (xy 329.692995 -412.082253) (xy 329.708705 -412.133183)
			(xy 329.716648 -412.185887) (xy 329.717146 -412.212536) (xy 329.716786 -412.23599) (xy 329.710667 -412.282496)
			(xy 329.704954 -412.305246) (xy 329.701906 -412.316676) (xy 329.706478 -412.340044) (xy 329.762612 -412.41345)
			(xy 329.770207 -412.422411) (xy 329.791264 -412.432761) (xy 329.802998 -412.433262) (xy 330.723494 -412.433262)
			(xy 330.735208 -412.432671) (xy 330.756244 -412.422352) (xy 330.76388 -412.41345) (xy 330.820014 -412.340044)
			(xy 330.824586 -412.316676) (xy 330.821538 -412.305246) (xy 330.815808 -412.282499) (xy 330.80969 -412.235991)
			(xy 330.809346 -412.212536) (xy 330.809844 -412.185887) (xy 330.817787 -412.133183) (xy 330.833497 -412.082253)
			(xy 330.856623 -412.034232) (xy 330.886647 -411.990195) (xy 330.922899 -411.951124) (xy 330.96457 -411.917893)
			(xy 331.010728 -411.891244) (xy 331.060342 -411.871772) (xy 331.112304 -411.859912) (xy 331.165454 -411.855929)
			(xy 331.218604 -411.859912) (xy 331.270566 -411.871772) (xy 331.32018 -411.891244) (xy 331.366338 -411.917893)
			(xy 331.408009 -411.951124) (xy 331.444261 -411.990195) (xy 331.474285 -412.034232) (xy 331.497411 -412.082253)
			(xy 331.513121 -412.133183) (xy 331.521064 -412.185887) (xy 331.521562 -412.212536) (xy 331.521025 -412.240371)
			(xy 331.512347 -412.295361) (xy 331.50429 -412.32201) (xy 331.501722 -412.331072) (xy 331.502766 -412.349865)
			(xy 331.506322 -412.358586) (xy 331.519276 -412.387034) (xy 331.523533 -412.395543) (xy 331.537094 -412.408871)
			(xy 331.545692 -412.412942) (xy 331.577188 -412.427674) (xy 331.582616 -412.430254) (xy 331.594295 -412.433068)
			(xy 331.600302 -412.433262) (xy 331.98943 -412.433262) (xy 331.99544 -412.433097) (xy 332.007124 -412.430275)
			(xy 332.012544 -412.427674) (xy 332.04404 -412.412942) (xy 332.052644 -412.408874) (xy 332.066221 -412.395557)
			(xy 332.070456 -412.387034) (xy 332.08341 -412.358586) (xy 332.086879 -412.349843) (xy 332.087938 -412.331078)
			(xy 332.085442 -412.32201) (xy 332.077398 -412.295358) (xy 332.068724 -412.24037) (xy 332.06817 -412.212536)
			(xy 332.068668 -412.185887) (xy 332.076611 -412.133183) (xy 332.092321 -412.082253) (xy 332.115447 -412.034232)
			(xy 332.145471 -411.990195) (xy 332.181723 -411.951124) (xy 332.223394 -411.917893) (xy 332.269552 -411.891244)
			(xy 332.319166 -411.871772) (xy 332.371128 -411.859912) (xy 332.424278 -411.855929) (xy 332.477428 -411.859912)
			(xy 332.52939 -411.871772) (xy 332.579004 -411.891244) (xy 332.625162 -411.917893) (xy 332.666833 -411.951124)
			(xy 332.703085 -411.990195) (xy 332.733109 -412.034232) (xy 332.756235 -412.082253) (xy 332.771945 -412.133183)
			(xy 332.779888 -412.185887) (xy 332.780386 -412.212536) (xy 332.780026 -412.23599) (xy 332.773908 -412.282496)
			(xy 332.768194 -412.305246) (xy 332.765146 -412.316676) (xy 332.769718 -412.340044) (xy 332.825852 -412.41345)
			(xy 332.83345 -412.422405) (xy 332.854506 -412.432738) (xy 332.866238 -412.433262) (xy 333.786734 -412.433262)
			(xy 333.798444 -412.432663) (xy 333.819466 -412.422334) (xy 333.82712 -412.41345) (xy 333.883254 -412.340044)
			(xy 333.887826 -412.316676) (xy 333.884778 -412.305246) (xy 333.879048 -412.282499) (xy 333.872931 -412.235991)
			(xy 333.872586 -412.212536) (xy 333.873084 -412.185887) (xy 333.881027 -412.133183) (xy 333.896737 -412.082253)
			(xy 333.919863 -412.034232) (xy 333.949887 -411.990195) (xy 333.986139 -411.951124) (xy 334.02781 -411.917893)
			(xy 334.073968 -411.891244) (xy 334.123582 -411.871772) (xy 334.175544 -411.859912) (xy 334.228694 -411.855929)
			(xy 334.281844 -411.859912) (xy 334.333806 -411.871772) (xy 334.38342 -411.891244) (xy 334.429578 -411.917893)
			(xy 334.471249 -411.951124) (xy 334.507501 -411.990195) (xy 334.537525 -412.034232) (xy 334.560651 -412.082253)
			(xy 334.576361 -412.133183) (xy 334.584304 -412.185887) (xy 334.584802 -412.212536) (xy 334.584265 -412.240371)
			(xy 334.575585 -412.29536) (xy 334.56753 -412.32201) (xy 334.564961 -412.331072) (xy 334.566006 -412.349864)
			(xy 334.569562 -412.358586) (xy 334.582516 -412.387034) (xy 334.586776 -412.39554) (xy 334.600341 -412.408858)
			(xy 334.608932 -412.412942) (xy 334.640428 -412.427674) (xy 334.645854 -412.43026) (xy 334.657534 -412.433089)
			(xy 334.663542 -412.433262) (xy 335.05267 -412.433262) (xy 335.058679 -412.433092) (xy 335.070358 -412.430262)
			(xy 335.075784 -412.427674) (xy 335.10728 -412.412942) (xy 335.11588 -412.40887) (xy 335.129447 -412.395549)
			(xy 335.133696 -412.387034) (xy 335.14665 -412.358586) (xy 335.150122 -412.349843) (xy 335.151182 -412.331077)
			(xy 335.148682 -412.32201) (xy 335.140639 -412.295358) (xy 335.131967 -412.24037) (xy 335.13141 -412.212536)
			(xy 335.131908 -412.185887) (xy 335.139851 -412.133183) (xy 335.155561 -412.082253) (xy 335.178687 -412.034232)
			(xy 335.208711 -411.990195) (xy 335.244963 -411.951124) (xy 335.286634 -411.917893) (xy 335.332792 -411.891244)
			(xy 335.382406 -411.871772) (xy 335.434368 -411.859912) (xy 335.487518 -411.855929) (xy 335.540668 -411.859912)
			(xy 335.59263 -411.871772) (xy 335.642244 -411.891244) (xy 335.688402 -411.917893) (xy 335.730073 -411.951124)
			(xy 335.766325 -411.990195) (xy 335.796349 -412.034232) (xy 335.819475 -412.082253) (xy 335.835185 -412.133183)
			(xy 335.843128 -412.185887) (xy 335.843626 -412.212536) (xy 335.843267 -412.23599) (xy 335.837149 -412.282496)
			(xy 335.831434 -412.305246) (xy 335.828386 -412.316676) (xy 335.832958 -412.340044) (xy 335.889092 -412.41345)
			(xy 335.896692 -412.422398) (xy 335.917749 -412.432715) (xy 335.929478 -412.433262) (xy 336.849974 -412.433262)
			(xy 336.86169 -412.432676) (xy 336.882732 -412.422362) (xy 336.89036 -412.41345) (xy 336.946494 -412.340044)
			(xy 336.951066 -412.316676) (xy 336.948018 -412.305246) (xy 336.942288 -412.282499) (xy 336.93617 -412.235991)
			(xy 336.935826 -412.212536) (xy 336.936324 -412.185887) (xy 336.944267 -412.133183) (xy 336.959977 -412.082253)
			(xy 336.983103 -412.034232) (xy 337.013127 -411.990195) (xy 337.049379 -411.951124) (xy 337.09105 -411.917893)
			(xy 337.137208 -411.891244) (xy 337.186822 -411.871772) (xy 337.238784 -411.859912) (xy 337.291934 -411.855929)
			(xy 337.345084 -411.859912) (xy 337.397046 -411.871772) (xy 337.44666 -411.891244) (xy 337.492818 -411.917893)
			(xy 337.534489 -411.951124) (xy 337.570741 -411.990195) (xy 337.600765 -412.034232) (xy 337.623891 -412.082253)
			(xy 337.639601 -412.133183) (xy 337.647544 -412.185887) (xy 337.648042 -412.212536) (xy 337.647505 -412.240371)
			(xy 337.638826 -412.295361) (xy 337.63077 -412.32201) (xy 337.628203 -412.331072) (xy 337.629246 -412.349864)
			(xy 337.632802 -412.358586) (xy 337.645756 -412.387034) (xy 337.650018 -412.395537) (xy 337.663588 -412.408846)
			(xy 337.672172 -412.412942) (xy 337.703668 -412.427674) (xy 337.709095 -412.430256) (xy 337.720775 -412.433075)
			(xy 337.726782 -412.433262) (xy 338.11591 -412.433262) (xy 338.121921 -412.433099) (xy 338.133606 -412.430282)
			(xy 338.139024 -412.427674) (xy 338.17052 -412.412942) (xy 338.179115 -412.408865) (xy 338.192672 -412.39554)
			(xy 338.196936 -412.387034) (xy 338.20989 -412.358586) (xy 338.213361 -412.349843) (xy 338.214419 -412.331078)
			(xy 338.211922 -412.32201) (xy 338.203879 -412.295358) (xy 338.195205 -412.24037) (xy 338.19465 -412.212536)
			(xy 338.195148 -412.185887) (xy 338.203091 -412.133183) (xy 338.218801 -412.082253) (xy 338.241927 -412.034232)
			(xy 338.271951 -411.990195) (xy 338.308203 -411.951124) (xy 338.349874 -411.917893) (xy 338.396032 -411.891244)
			(xy 338.445646 -411.871772) (xy 338.497608 -411.859912) (xy 338.550758 -411.855929) (xy 338.603908 -411.859912)
			(xy 338.65587 -411.871772) (xy 338.705484 -411.891244) (xy 338.751642 -411.917893) (xy 338.793313 -411.951124)
			(xy 338.829565 -411.990195) (xy 338.859589 -412.034232) (xy 338.882715 -412.082253) (xy 338.898425 -412.133183)
			(xy 338.906368 -412.185887) (xy 338.906866 -412.212536) (xy 338.906506 -412.23599) (xy 338.900387 -412.282496)
			(xy 338.894674 -412.305246) (xy 338.891626 -412.316676) (xy 338.896198 -412.340044) (xy 338.952332 -412.41345)
			(xy 338.959928 -412.422408) (xy 338.980985 -412.43275) (xy 338.992718 -412.433262) (xy 339.913214 -412.433262)
			(xy 339.924926 -412.432667) (xy 339.945955 -412.422343) (xy 339.9536 -412.41345) (xy 340.009734 -412.340044)
			(xy 340.014306 -412.316676) (xy 340.011258 -412.305246) (xy 340.005528 -412.282499) (xy 339.999412 -412.235991)
			(xy 339.999066 -412.212536) (xy 339.999564 -412.185887) (xy 340.007507 -412.133183) (xy 340.023217 -412.082253)
			(xy 340.046343 -412.034232) (xy 340.076367 -411.990195) (xy 340.112619 -411.951124) (xy 340.15429 -411.917893)
			(xy 340.200448 -411.891244) (xy 340.250062 -411.871772) (xy 340.302024 -411.859912) (xy 340.355174 -411.855929)
			(xy 340.408324 -411.859912) (xy 340.460286 -411.871772) (xy 340.5099 -411.891244) (xy 340.556058 -411.917893)
			(xy 340.597729 -411.951124) (xy 340.633981 -411.990195) (xy 340.664005 -412.034232) (xy 340.687131 -412.082253)
			(xy 340.702841 -412.133183) (xy 340.710784 -412.185887) (xy 340.711282 -412.212536) (xy 340.710745 -412.240371)
			(xy 340.702064 -412.29536) (xy 340.69401 -412.32201) (xy 340.691442 -412.331072) (xy 340.692486 -412.349864)
			(xy 340.696042 -412.358586) (xy 340.708996 -412.387034) (xy 340.713254 -412.395542) (xy 340.726817 -412.408865)
			(xy 340.735412 -412.412942) (xy 340.766908 -412.427674) (xy 340.772334 -412.430262) (xy 340.784013 -412.433095)
			(xy 340.790022 -412.433262) (xy 341.17915 -412.433262) (xy 341.185159 -412.433094) (xy 341.196841 -412.430269)
			(xy 341.202264 -412.427674) (xy 341.23376 -412.412942) (xy 341.242362 -412.408871) (xy 341.255934 -412.395553)
			(xy 341.260176 -412.387034) (xy 341.27313 -412.358586) (xy 341.276604 -412.349843) (xy 341.277664 -412.331077)
			(xy 341.275162 -412.32201) (xy 341.267118 -412.295358) (xy 341.258443 -412.24037) (xy 341.25789 -412.212536)
			(xy 341.258388 -412.185887) (xy 341.266331 -412.133183) (xy 341.282041 -412.082253) (xy 341.305167 -412.034232)
			(xy 341.335191 -411.990195) (xy 341.371443 -411.951124) (xy 341.413114 -411.917893) (xy 341.459272 -411.891244)
			(xy 341.508886 -411.871772) (xy 341.560848 -411.859912) (xy 341.613998 -411.855929) (xy 341.667148 -411.859912)
			(xy 341.71911 -411.871772) (xy 341.768724 -411.891244) (xy 341.814882 -411.917893) (xy 341.856553 -411.951124)
			(xy 341.892805 -411.990195) (xy 341.922829 -412.034232) (xy 341.945955 -412.082253) (xy 341.961665 -412.133183)
			(xy 341.969608 -412.185887) (xy 341.970106 -412.212536) (xy 341.969746 -412.23599) (xy 341.963628 -412.282496)
			(xy 341.957914 -412.305246) (xy 341.954866 -412.316676) (xy 341.959438 -412.340044) (xy 342.015572 -412.41345)
			(xy 342.023171 -412.422401) (xy 342.044228 -412.432726) (xy 342.055958 -412.433262) (xy 342.976454 -412.433262)
			(xy 342.988162 -412.432659) (xy 343.009177 -412.422325) (xy 343.01684 -412.41345) (xy 343.072974 -412.340044)
			(xy 343.077546 -412.316676) (xy 343.074498 -412.305246) (xy 343.068768 -412.282499) (xy 343.06265 -412.235991)
			(xy 343.062306 -412.212536) (xy 343.062804 -412.185887) (xy 343.070747 -412.133183) (xy 343.086457 -412.082253)
			(xy 343.109583 -412.034232) (xy 343.139607 -411.990195) (xy 343.175859 -411.951124) (xy 343.21753 -411.917893)
			(xy 343.263688 -411.891244) (xy 343.313302 -411.871772) (xy 343.365264 -411.859912) (xy 343.418414 -411.855929)
			(xy 343.471564 -411.859912) (xy 343.523526 -411.871772) (xy 343.57314 -411.891244) (xy 343.619298 -411.917893)
			(xy 343.660969 -411.951124) (xy 343.697221 -411.990195) (xy 343.727245 -412.034232) (xy 343.750371 -412.082253)
			(xy 343.766081 -412.133183) (xy 343.774024 -412.185887) (xy 343.774522 -412.212536) (xy 343.773985 -412.240371)
			(xy 343.765306 -412.29536) (xy 343.75725 -412.32201) (xy 343.754684 -412.331072) (xy 343.755726 -412.349865)
			(xy 343.759282 -412.358586) (xy 343.772236 -412.387034) (xy 343.776497 -412.395538) (xy 343.790065 -412.408852)
			(xy 343.798652 -412.412942) (xy 343.830148 -412.427674) (xy 343.835575 -412.430258) (xy 343.847254 -412.433082)
			(xy 343.853262 -412.433262) (xy 344.24239 -412.433262) (xy 344.248398 -412.43309) (xy 344.260075 -412.430256)
			(xy 344.265504 -412.427674) (xy 344.297 -412.412942) (xy 344.305597 -412.408867) (xy 344.319159 -412.395544)
			(xy 344.323416 -412.387034) (xy 344.33637 -412.358586) (xy 344.339841 -412.349843) (xy 344.340901 -412.331078)
			(xy 344.338402 -412.32201) (xy 344.330359 -412.295358) (xy 344.321686 -412.24037) (xy 344.32113 -412.212536)
			(xy 344.321628 -412.185887) (xy 344.329571 -412.133183) (xy 344.345281 -412.082253) (xy 344.368407 -412.034232)
			(xy 344.398431 -411.990195) (xy 344.434683 -411.951124) (xy 344.476354 -411.917893) (xy 344.522512 -411.891244)
			(xy 344.572126 -411.871772) (xy 344.624088 -411.859912) (xy 344.677238 -411.855929) (xy 344.730388 -411.859912)
			(xy 344.78235 -411.871772) (xy 344.831964 -411.891244) (xy 344.878122 -411.917893) (xy 344.919793 -411.951124)
			(xy 344.956045 -411.990195) (xy 344.986069 -412.034232) (xy 345.009195 -412.082253) (xy 345.024905 -412.133183)
			(xy 345.032848 -412.185887) (xy 345.033346 -412.212536) (xy 345.032986 -412.23599) (xy 345.026867 -412.282496)
			(xy 345.021154 -412.305246) (xy 345.018106 -412.316676) (xy 345.022678 -412.340044) (xy 345.078812 -412.41345)
			(xy 345.086407 -412.422411) (xy 345.107464 -412.432761) (xy 345.119198 -412.433262) (xy 346.039694 -412.433262)
			(xy 346.051408 -412.432671) (xy 346.072444 -412.422352) (xy 346.08008 -412.41345) (xy 346.136214 -412.340044)
			(xy 346.140786 -412.316676) (xy 346.137738 -412.305246) (xy 346.132008 -412.282499) (xy 346.12589 -412.235991)
			(xy 346.125546 -412.212536) (xy 346.126044 -412.185887) (xy 346.133987 -412.133183) (xy 346.149697 -412.082253)
			(xy 346.172823 -412.034232) (xy 346.202847 -411.990195) (xy 346.239099 -411.951124) (xy 346.28077 -411.917893)
			(xy 346.326928 -411.891244) (xy 346.376542 -411.871772) (xy 346.428504 -411.859912) (xy 346.481654 -411.855929)
			(xy 346.534804 -411.859912) (xy 346.586766 -411.871772) (xy 346.63638 -411.891244) (xy 346.682538 -411.917893)
			(xy 346.724209 -411.951124) (xy 346.760461 -411.990195) (xy 346.790485 -412.034232) (xy 346.813611 -412.082253)
			(xy 346.829321 -412.133183) (xy 346.837264 -412.185887) (xy 346.837762 -412.212536) (xy 346.837225 -412.240371)
			(xy 346.828547 -412.295361) (xy 346.82049 -412.32201) (xy 346.817922 -412.331072) (xy 346.818966 -412.349865)
			(xy 346.822522 -412.358586) (xy 346.835476 -412.387034) (xy 346.839733 -412.395543) (xy 346.853294 -412.408871)
			(xy 346.861892 -412.412942) (xy 346.893388 -412.427674) (xy 346.898816 -412.430254) (xy 346.910495 -412.433068)
			(xy 346.916502 -412.433262) (xy 347.30563 -412.433262) (xy 347.31164 -412.433097) (xy 347.323324 -412.430275)
			(xy 347.328744 -412.427674) (xy 347.36024 -412.412942) (xy 347.368844 -412.408874) (xy 347.382421 -412.395557)
			(xy 347.386656 -412.387034) (xy 347.39961 -412.358586) (xy 347.403079 -412.349843) (xy 347.404138 -412.331078)
			(xy 347.401642 -412.32201) (xy 347.393598 -412.295358) (xy 347.384924 -412.24037) (xy 347.38437 -412.212536)
			(xy 347.384868 -412.185887) (xy 347.392811 -412.133183) (xy 347.408521 -412.082253) (xy 347.431647 -412.034232)
			(xy 347.461671 -411.990195) (xy 347.497923 -411.951124) (xy 347.539594 -411.917893) (xy 347.585752 -411.891244)
			(xy 347.635366 -411.871772) (xy 347.687328 -411.859912) (xy 347.740478 -411.855929) (xy 347.793628 -411.859912)
			(xy 347.84559 -411.871772) (xy 347.895204 -411.891244) (xy 347.941362 -411.917893) (xy 347.983033 -411.951124)
			(xy 348.019285 -411.990195) (xy 348.049309 -412.034232) (xy 348.072435 -412.082253) (xy 348.088145 -412.133183)
			(xy 348.096088 -412.185887) (xy 348.096586 -412.212536) (xy 348.096226 -412.23599) (xy 348.090108 -412.282496)
			(xy 348.084394 -412.305246) (xy 348.081346 -412.316676) (xy 348.085918 -412.340044) (xy 348.142052 -412.41345)
			(xy 348.14965 -412.422405) (xy 348.170706 -412.432738) (xy 348.182438 -412.433262) (xy 349.102934 -412.433262)
			(xy 349.114644 -412.432663) (xy 349.135666 -412.422334) (xy 349.14332 -412.41345) (xy 349.199454 -412.340044)
			(xy 349.204026 -412.316676) (xy 349.200978 -412.305246) (xy 349.195248 -412.282499) (xy 349.189131 -412.235991)
			(xy 349.188786 -412.212536) (xy 349.189284 -412.185887) (xy 349.197227 -412.133183) (xy 349.212937 -412.082253)
			(xy 349.236063 -412.034232) (xy 349.266087 -411.990195) (xy 349.302339 -411.951124) (xy 349.34401 -411.917893)
			(xy 349.390168 -411.891244) (xy 349.439782 -411.871772) (xy 349.491744 -411.859912) (xy 349.544894 -411.855929)
			(xy 349.598044 -411.859912) (xy 349.650006 -411.871772) (xy 349.69962 -411.891244) (xy 349.745778 -411.917893)
			(xy 349.787449 -411.951124) (xy 349.823701 -411.990195) (xy 349.853725 -412.034232) (xy 349.876851 -412.082253)
			(xy 349.892561 -412.133183) (xy 349.900504 -412.185887) (xy 349.901002 -412.212536) (xy 349.900465 -412.240371)
			(xy 349.891785 -412.29536) (xy 349.88373 -412.32201) (xy 349.881161 -412.331072) (xy 349.882206 -412.349864)
			(xy 349.885762 -412.358586) (xy 349.898716 -412.387034) (xy 349.902976 -412.39554) (xy 349.916541 -412.408858)
			(xy 349.925132 -412.412942) (xy 349.956628 -412.427674) (xy 349.962054 -412.43026) (xy 349.973734 -412.433089)
			(xy 349.979742 -412.433262) (xy 350.36887 -412.433262) (xy 350.374879 -412.433092) (xy 350.386558 -412.430262)
			(xy 350.391984 -412.427674) (xy 350.42348 -412.412942) (xy 350.43208 -412.40887) (xy 350.445647 -412.395549)
			(xy 350.449896 -412.387034) (xy 350.46285 -412.358586) (xy 350.466322 -412.349843) (xy 350.467382 -412.331077)
			(xy 350.464882 -412.32201) (xy 350.456839 -412.295358) (xy 350.448167 -412.24037) (xy 350.44761 -412.212536)
			(xy 350.448108 -412.185887) (xy 350.456051 -412.133183) (xy 350.471761 -412.082253) (xy 350.494887 -412.034232)
			(xy 350.524911 -411.990195) (xy 350.561163 -411.951124) (xy 350.602834 -411.917893) (xy 350.648992 -411.891244)
			(xy 350.698606 -411.871772) (xy 350.750568 -411.859912) (xy 350.803718 -411.855929) (xy 350.856868 -411.859912)
			(xy 350.90883 -411.871772) (xy 350.958444 -411.891244) (xy 351.004602 -411.917893) (xy 351.046273 -411.951124)
			(xy 351.082525 -411.990195) (xy 351.112549 -412.034232) (xy 351.135675 -412.082253) (xy 351.151385 -412.133183)
			(xy 351.159328 -412.185887) (xy 351.159826 -412.212536) (xy 351.159467 -412.23599) (xy 351.153349 -412.282496)
			(xy 351.147634 -412.305246) (xy 351.144586 -412.316676) (xy 351.149158 -412.340044) (xy 351.205292 -412.41345)
			(xy 351.212892 -412.422398) (xy 351.233949 -412.432715) (xy 351.245678 -412.433262) (xy 359.136696 -412.433262)
			(xy 359.14669 -412.432765) (xy 359.165164 -412.425127) (xy 359.179344 -412.411037) (xy 359.183686 -412.40202)
			(xy 359.189528 -412.387542) (xy 359.183686 -412.35757) (xy 358.500934 -411.674818) (xy 358.492966 -411.667693)
			(xy 358.473016 -411.66009) (xy 358.462326 -411.660086) (xy 358.375966 -411.664658) (xy 358.356916 -411.67431)
			(xy 358.350058 -411.682692) (xy 358.331852 -411.704379) (xy 358.290124 -411.742653) (xy 358.243194 -411.774336)
			(xy 358.192095 -411.798729) (xy 358.137951 -411.815298) (xy 358.081951 -411.823678) (xy 358.05364 -411.82417)
			(xy 358.028186 -411.82375) (xy 357.977731 -411.81698) (xy 357.928625 -411.803557) (xy 357.881743 -411.783719)
			(xy 357.837917 -411.757818) (xy 357.817674 -411.742382) (xy 357.8098 -411.736286) (xy 357.791258 -411.730952)
			(xy 357.702104 -411.739334) (xy 357.684832 -411.74797) (xy 357.678228 -411.75559) (xy 357.654386 -411.782118)
			(xy 357.601313 -411.82977) (xy 357.542836 -411.870612) (xy 357.479826 -411.904037) (xy 357.413217 -411.929548)
			(xy 357.344 -411.946766) (xy 357.273202 -411.955435) (xy 357.237538 -411.955996) (xy 357.202199 -411.955486)
			(xy 357.132037 -411.946971) (xy 357.063413 -411.93006) (xy 356.997328 -411.905001) (xy 356.934745 -411.872158)
			(xy 356.876578 -411.832011) (xy 356.823674 -411.785145) (xy 356.776805 -411.732243) (xy 356.736655 -411.674077)
			(xy 356.70381 -411.611496) (xy 356.678747 -411.545412) (xy 356.661834 -411.476788) (xy 356.653316 -411.406627)
			(xy 356.65283 -411.371288) (xy 356.653383 -411.33529) (xy 356.662225 -411.26384) (xy 356.679773 -411.194016)
			(xy 356.705762 -411.126875) (xy 356.739798 -411.063433) (xy 356.781367 -411.004651) (xy 356.829839 -410.951418)
			(xy 356.856792 -410.92755) (xy 356.863565 -410.921214) (xy 356.872404 -410.904927) (xy 356.874064 -410.8958)
			(xy 356.878128 -410.865574) (xy 356.87902 -410.856402) (xy 356.874974 -410.838438) (xy 356.870254 -410.830522)
			(xy 356.85399 -410.805395) (xy 356.826818 -410.75206) (xy 356.806102 -410.695902) (xy 356.792128 -410.637699)
			(xy 356.785091 -410.578257) (xy 356.784656 -410.548328) (xy 356.785118 -410.517595) (xy 356.792523 -410.456577)
			(xy 356.80723 -410.396896) (xy 356.829022 -410.339424) (xy 356.857584 -410.284997) (xy 356.892497 -410.234409)
			(xy 356.933254 -410.188399) (xy 356.979259 -410.147637) (xy 357.029842 -410.112717) (xy 357.084265 -410.084149)
			(xy 357.141735 -410.062349) (xy 357.201414 -410.047635) (xy 357.262431 -410.040222) (xy 357.293164 -410.03982)
			(xy 357.324964 -410.040315) (xy 357.388068 -410.048252) (xy 357.44969 -410.063993) (xy 357.508869 -410.087294)
			(xy 357.564681 -410.11779) (xy 357.616257 -410.155006) (xy 357.66279 -410.198362) (xy 357.683562 -410.222446)
			(xy 357.691154 -410.230577) (xy 357.711313 -410.239921) (xy 357.722424 -410.24048) (xy 357.809546 -410.24048)
			(xy 357.833737 -410.240934) (xy 357.881523 -410.24851) (xy 357.927535 -410.263468) (xy 357.97064 -410.28544)
			(xy 358.009778 -410.313885) (xy 358.027224 -410.33065) (xy 359.785666 -412.089092) (xy 359.802438 -412.106532)
			(xy 359.830881 -412.145672) (xy 359.85285 -412.188779) (xy 359.867806 -412.234792) (xy 359.875379 -412.282579)
			(xy 359.875836 -412.30677) (xy 359.875836 -412.382462) (xy 359.87625 -412.392486) (xy 359.883914 -412.411009)
			(xy 359.898089 -412.425185) (xy 359.916612 -412.43285) (xy 359.926636 -412.433262) (xy 359.960418 -412.433262)
			(xy 359.970434 -412.432839) (xy 359.988938 -412.425164) (xy 360.003096 -412.410991) (xy 360.01075 -412.392479)
			(xy 360.011218 -412.382462) (xy 360.011218 -412.372302) (xy 360.007408 -412.363158) (xy 359.998222 -412.339919)
			(xy 359.98532 -412.291642) (xy 359.978833 -412.242094) (xy 359.978452 -412.217108) (xy 359.978937 -412.189855)
			(xy 359.986693 -412.135905) (xy 360.002047 -412.083607) (xy 360.024687 -412.034026) (xy 360.054152 -411.988172)
			(xy 360.089843 -411.946977) (xy 360.131033 -411.911281) (xy 360.176884 -411.88181) (xy 360.226462 -411.859163)
			(xy 360.278758 -411.843803) (xy 360.332707 -411.836041) (xy 360.35996 -411.8356) (xy 360.387466 -411.836086)
			(xy 360.441908 -411.843996) (xy 360.468418 -411.851348) (xy 360.478324 -411.854142) (xy 360.49839 -411.85211)
			(xy 360.579162 -411.808422) (xy 360.591862 -411.792674) (xy 360.59491 -411.783022) (xy 360.603684 -411.75501)
			(xy 360.62743 -411.701328) (xy 360.65785 -411.651125) (xy 360.694443 -411.605226) (xy 360.736608 -411.564387)
			(xy 360.783651 -411.529279) (xy 360.8348 -411.500478) (xy 360.889214 -411.478458) (xy 360.945997 -411.463581)
			(xy 361.004218 -411.456092) (xy 361.033568 -411.455616) (xy 361.063538 -411.456083) (xy 361.122965 -411.463903)
			(xy 361.180863 -411.479414) (xy 361.236241 -411.50235) (xy 361.288151 -411.532318) (xy 361.335705 -411.568806)
			(xy 361.378089 -411.611189) (xy 361.414578 -411.658742) (xy 361.444547 -411.710652) (xy 361.467484 -411.766029)
			(xy 361.482995 -411.823927) (xy 361.490816 -411.883354) (xy 361.491276 -411.913324) (xy 361.490905 -411.939972)
			(xy 361.484713 -411.992907) (xy 361.472403 -412.044763) (xy 361.454144 -412.094833) (xy 361.442508 -412.11881)
			(xy 361.437487 -412.130452) (xy 361.438293 -412.155763) (xy 361.444032 -412.16707) (xy 361.459018 -412.193232)
			(xy 361.463798 -412.200725) (xy 361.477402 -412.21214) (xy 361.494082 -412.218237) (xy 361.50296 -412.218632)
			(xy 361.526328 -412.218632) (xy 361.536355 -412.218181) (xy 361.554914 -412.210591) (xy 361.562396 -412.2039)
			(xy 362.109766 -411.65653) (xy 362.116605 -411.649129) (xy 362.124319 -411.630531) (xy 362.124752 -411.620462)
			(xy 362.124752 -411.14472) (xy 362.124137 -411.133582) (xy 362.114668 -411.113413) (xy 362.106464 -411.105858)
			(xy 362.097237 -411.09804) (xy 362.07945 -411.08165) (xy 362.070904 -411.073092) (xy 362.0643 -411.066488)
			(xy 362.047536 -411.058868) (xy 361.961684 -411.05328) (xy 361.943904 -411.058614) (xy 361.936538 -411.064202)
			(xy 361.909727 -411.084296) (xy 361.851826 -411.118012) (xy 361.789996 -411.143825) (xy 361.72531 -411.161285)
			(xy 361.658889 -411.170091) (xy 361.625388 -411.170628) (xy 361.593831 -411.170151) (xy 361.531202 -411.162341)
			(xy 361.470021 -411.146842) (xy 361.411227 -411.123892) (xy 361.355725 -411.093845) (xy 361.304367 -411.057161)
			(xy 361.257942 -411.014405) (xy 361.217164 -410.966233) (xy 361.182659 -410.913386) (xy 361.154958 -410.856676)
			(xy 361.144312 -410.826966) (xy 361.139994 -410.814012) (xy 361.11942 -410.795978) (xy 361.005628 -410.774388)
			(xy 360.979974 -410.783532) (xy 360.97083 -410.793946) (xy 360.950098 -410.817553) (xy 360.903763 -410.859985)
			(xy 360.852549 -410.89638) (xy 360.797239 -410.926183) (xy 360.738676 -410.948939) (xy 360.677754 -410.964301)
			(xy 360.615403 -410.972033) (xy 360.583988 -410.972508) (xy 360.552027 -410.972005) (xy 360.488611 -410.963993)
			(xy 360.426698 -410.948095) (xy 360.367266 -410.924563) (xy 360.311252 -410.893768) (xy 360.259539 -410.856195)
			(xy 360.212943 -410.812437) (xy 360.172199 -410.763185) (xy 360.137949 -410.709214) (xy 360.110733 -410.651377)
			(xy 360.090981 -410.590584) (xy 360.079003 -410.527795) (xy 360.074989 -410.464) (xy 360.079003 -410.400205)
			(xy 360.090981 -410.337416) (xy 360.110733 -410.276623) (xy 360.137949 -410.218786) (xy 360.172199 -410.164815)
			(xy 360.212943 -410.115563) (xy 360.259539 -410.071805) (xy 360.311252 -410.034232) (xy 360.367266 -410.003437)
			(xy 360.426698 -409.979905) (xy 360.488611 -409.964007) (xy 360.552027 -409.955995) (xy 360.583988 -409.955492)
			(xy 360.615545 -409.955967) (xy 360.678176 -409.963775) (xy 360.739358 -409.979272) (xy 360.798154 -410.002221)
			(xy 360.853657 -410.032268) (xy 360.905017 -410.068952) (xy 360.951443 -410.111708) (xy 360.992221 -410.159881)
			(xy 361.026726 -410.212729) (xy 361.054427 -410.26944) (xy 361.065064 -410.299154) (xy 361.069382 -410.312108)
			(xy 361.089956 -410.330142) (xy 361.203748 -410.351732) (xy 361.229402 -410.342588) (xy 361.238546 -410.332174)
			(xy 361.259279 -410.308569) (xy 361.305617 -410.266141) (xy 361.356831 -410.22975) (xy 361.412142 -410.199949)
			(xy 361.470704 -410.177194) (xy 361.531624 -410.161832) (xy 361.593974 -410.154098) (xy 361.625388 -410.153612)
			(xy 361.658905 -410.154153) (xy 361.725357 -410.162973) (xy 361.790073 -410.180448) (xy 361.851933 -410.206275)
			(xy 361.909862 -410.240006) (xy 361.962857 -410.281057) (xy 361.98683 -410.304488) (xy 361.993434 -410.311092)
			(xy 362.010198 -410.318712) (xy 362.09605 -410.3243) (xy 362.11383 -410.318966) (xy 362.121196 -410.313378)
			(xy 362.148008 -410.293287) (xy 362.20591 -410.259576) (xy 362.26774 -410.233768) (xy 362.332426 -410.216313)
			(xy 362.398846 -410.207511) (xy 362.432346 -410.206952) (xy 362.463318 -410.207409) (xy 362.524803 -410.214928)
			(xy 362.58492 -410.229861) (xy 362.642777 -410.251986) (xy 362.697518 -410.280977) (xy 362.748331 -410.316404)
			(xy 362.77169 -410.336746) (xy 362.779071 -410.342799) (xy 362.796946 -410.349462) (xy 362.806488 -410.3497)
			(xy 362.837222 -410.348938) (xy 362.846839 -410.348335) (xy 362.864599 -410.340899) (xy 362.871766 -410.33446)
			(xy 362.881911 -410.324748) (xy 362.903001 -410.306197) (xy 362.91393 -410.297376) (xy 362.92155 -410.291026)
			(xy 362.930948 -410.274262) (xy 362.942632 -410.1846) (xy 362.937806 -410.166058) (xy 362.931964 -410.15793)
			(xy 362.914447 -410.133195) (xy 362.886646 -410.079341) (xy 362.867717 -410.021765) (xy 362.858139 -409.96192)
			(xy 362.857542 -409.931616) (xy 362.858028 -409.904365) (xy 362.865784 -409.850417) (xy 362.881139 -409.798122)
			(xy 362.903781 -409.748545) (xy 362.933247 -409.702695) (xy 362.968938 -409.661504) (xy 363.010129 -409.625813)
			(xy 363.055979 -409.596347) (xy 363.105556 -409.573705) (xy 363.157851 -409.55835) (xy 363.211799 -409.550594)
			(xy 363.266301 -409.550594) (xy 363.320249 -409.55835) (xy 363.372544 -409.573705) (xy 363.422121 -409.596347)
			(xy 363.467971 -409.625813) (xy 363.509162 -409.661504) (xy 363.544853 -409.702695) (xy 363.574319 -409.748545)
			(xy 363.596961 -409.798122) (xy 363.612316 -409.850417) (xy 363.620072 -409.904365) (xy 363.620558 -409.931616)
			(xy 363.620169 -409.957108) (xy 363.613407 -410.007641) (xy 363.599965 -410.056821) (xy 363.580084 -410.103769)
			(xy 363.567472 -410.125926) (xy 363.562392 -410.134562) (xy 363.559344 -410.153612) (xy 363.579918 -410.241496)
			(xy 363.591094 -410.257244) (xy 363.599476 -410.262832) (xy 363.62681 -410.281164) (xy 363.677582 -410.323047)
			(xy 363.723323 -410.370374) (xy 363.743748 -410.396182) (xy 363.751114 -410.405834) (xy 363.77245 -410.415994)
			(xy 363.87786 -410.414724) (xy 363.898942 -410.404056) (xy 363.906308 -410.39415) (xy 363.926895 -410.366984)
			(xy 363.97417 -410.317883) (xy 364.027585 -410.275541) (xy 364.086181 -410.24072) (xy 364.148905 -410.214044)
			(xy 364.214633 -410.195993) (xy 364.282183 -410.18689) (xy 364.316264 -410.186378) (xy 364.347285 -410.186827)
			(xy 364.408868 -410.194349) (xy 364.469078 -410.209311) (xy 364.52702 -410.23149) (xy 364.581832 -410.260555)
			(xy 364.632698 -410.296076) (xy 364.656116 -410.316426) (xy 364.663228 -410.32303) (xy 364.681008 -410.329634)
			(xy 364.770162 -410.327856) (xy 364.787434 -410.320744) (xy 364.794546 -410.313886) (xy 364.820251 -410.289747)
			(xy 364.877134 -410.248074) (xy 364.939235 -410.214673) (xy 364.972092 -410.201872) (xy 364.984792 -410.197046)
			(xy 365.00181 -410.17698) (xy 365.023146 -410.06522) (xy 365.014764 -410.040074) (xy 365.004604 -410.03093)
			(xy 364.97889 -410.007128) (xy 364.932747 -409.954396) (xy 364.893237 -409.896526) (xy 364.860927 -409.834349)
			(xy 364.836281 -409.768755) (xy 364.819652 -409.700686) (xy 364.811279 -409.631117) (xy 364.810802 -409.596082)
			(xy 364.811336 -409.560747) (xy 364.819857 -409.490592) (xy 364.836771 -409.421976) (xy 364.861833 -409.355899)
			(xy 364.894677 -409.293324) (xy 364.934824 -409.235165) (xy 364.981688 -409.182268) (xy 365.034587 -409.135406)
			(xy 365.092748 -409.095262) (xy 365.155324 -409.062422) (xy 365.221403 -409.037363) (xy 365.29002 -409.020452)
			(xy 365.360175 -409.011935) (xy 365.39551 -409.011374) (xy 365.430273 -409.011874) (xy 365.499308 -409.020121)
			(xy 365.566878 -409.036498) (xy 365.632029 -409.060774) (xy 365.69384 -409.092605) (xy 365.75144 -409.131544)
			(xy 365.804014 -409.177038) (xy 365.850822 -409.228448) (xy 365.891202 -409.285046) (xy 365.924584 -409.346034)
			(xy 365.950497 -409.410551) (xy 365.968575 -409.477686) (xy 365.974122 -409.512008) (xy 365.975745 -409.520606)
			(xy 365.983921 -409.536064) (xy 365.990124 -409.542234) (xy 366.011968 -409.562046) (xy 366.018661 -409.567664)
			(xy 366.034766 -409.574408) (xy 366.043464 -409.575254) (xy 366.075453 -409.577593) (xy 366.138511 -409.589323)
			(xy 366.199594 -409.608891) (xy 366.25773 -409.635987) (xy 366.311997 -409.67018) (xy 366.361531 -409.710927)
			(xy 366.405547 -409.757582) (xy 366.443345 -409.809402) (xy 366.474324 -409.865565) (xy 366.497994 -409.925178)
			(xy 366.513977 -409.987295) (xy 366.522019 -410.05093) (xy 366.522508 -410.083) (xy 366.648492 -410.083)
			(xy 366.648944 -410.050887) (xy 366.657038 -409.987173) (xy 366.673086 -409.924984) (xy 366.696832 -409.865308)
			(xy 366.727899 -409.809095) (xy 366.765792 -409.757239) (xy 366.80991 -409.710563) (xy 366.83442 -409.689808)
			(xy 366.842294 -409.683458) (xy 366.851438 -409.666694) (xy 366.86236 -409.577032) (xy 366.85728 -409.558236)
			(xy 366.851438 -409.550362) (xy 366.833466 -409.525384) (xy 366.804911 -409.470879) (xy 366.785455 -409.412504)
			(xy 366.7756 -409.351766) (xy 366.774984 -409.321) (xy 366.775471 -409.293712) (xy 366.783237 -409.239693)
			(xy 366.798613 -409.187329) (xy 366.821284 -409.137685) (xy 366.85079 -409.091774) (xy 366.886529 -409.050529)
			(xy 366.927774 -409.01479) (xy 366.973685 -408.985284) (xy 367.023329 -408.962613) (xy 367.075693 -408.947237)
			(xy 367.129712 -408.939471) (xy 367.184288 -408.939471) (xy 367.238307 -408.947237) (xy 367.290671 -408.962613)
			(xy 367.340315 -408.985284) (xy 367.386226 -409.01479) (xy 367.427471 -409.050529) (xy 367.46321 -409.091774)
			(xy 367.492716 -409.137685) (xy 367.515387 -409.187329) (xy 367.530763 -409.239693) (xy 367.538529 -409.293712)
			(xy 367.539016 -409.321) (xy 367.538391 -409.351765) (xy 367.528536 -409.412501) (xy 367.50908 -409.470875)
			(xy 367.480527 -409.525379) (xy 367.462562 -409.550362) (xy 367.45672 -409.558236) (xy 367.45164 -409.577032)
			(xy 367.462562 -409.666694) (xy 367.471706 -409.683458) (xy 367.47958 -409.689808) (xy 367.504087 -409.710564)
			(xy 367.548203 -409.757239) (xy 367.586094 -409.809096) (xy 367.617156 -409.865309) (xy 367.640895 -409.924985)
			(xy 367.656934 -409.987174) (xy 367.665018 -410.050888) (xy 367.665508 -410.083) (xy 367.665006 -410.114961)
			(xy 367.918994 -410.114961) (xy 367.918994 -410.051039) (xy 367.927005 -409.987621) (xy 367.942902 -409.925707)
			(xy 367.966434 -409.866274) (xy 367.997228 -409.810259) (xy 368.034801 -409.758544) (xy 368.078558 -409.711947)
			(xy 368.127811 -409.671202) (xy 368.181782 -409.636951) (xy 368.239621 -409.609734) (xy 368.300414 -409.589981)
			(xy 368.363204 -409.578003) (xy 368.427 -409.57399) (xy 368.490796 -409.578003) (xy 368.553586 -409.589981)
			(xy 368.614379 -409.609734) (xy 368.672218 -409.636951) (xy 368.726189 -409.671202) (xy 368.775442 -409.711947)
			(xy 368.819199 -409.758544) (xy 368.856772 -409.810259) (xy 368.887566 -409.866274) (xy 368.911098 -409.925707)
			(xy 368.926995 -409.987621) (xy 368.935006 -410.051039) (xy 368.935508 -410.083) (xy 368.935006 -410.114961)
			(xy 368.926995 -410.178379) (xy 368.911098 -410.240293) (xy 368.887566 -410.299726) (xy 368.856772 -410.355741)
			(xy 368.819199 -410.407456) (xy 368.775442 -410.454053) (xy 368.726189 -410.494798) (xy 368.672218 -410.529049)
			(xy 368.614379 -410.556266) (xy 368.553586 -410.576019) (xy 368.490796 -410.587997) (xy 368.427 -410.592011)
			(xy 368.363204 -410.587997) (xy 368.300414 -410.576019) (xy 368.239621 -410.556266) (xy 368.181782 -410.529049)
			(xy 368.127811 -410.494798) (xy 368.078558 -410.454053) (xy 368.034801 -410.407456) (xy 367.997228 -410.355741)
			(xy 367.966434 -410.299726) (xy 367.942902 -410.240293) (xy 367.927005 -410.178379) (xy 367.918994 -410.114961)
			(xy 367.665006 -410.114961) (xy 367.656995 -410.178379) (xy 367.641098 -410.240293) (xy 367.617566 -410.299726)
			(xy 367.586772 -410.355741) (xy 367.549199 -410.407456) (xy 367.505442 -410.454053) (xy 367.456189 -410.494798)
			(xy 367.402218 -410.529049) (xy 367.344379 -410.556266) (xy 367.283586 -410.576019) (xy 367.220796 -410.587997)
			(xy 367.157 -410.592011) (xy 367.093204 -410.587997) (xy 367.030414 -410.576019) (xy 366.969621 -410.556266)
			(xy 366.911782 -410.529049) (xy 366.857811 -410.494798) (xy 366.808558 -410.454053) (xy 366.764801 -410.407456)
			(xy 366.727228 -410.355741) (xy 366.696434 -410.299726) (xy 366.672902 -410.240293) (xy 366.657005 -410.178379)
			(xy 366.648994 -410.114961) (xy 366.648492 -410.083) (xy 366.522508 -410.083) (xy 366.522044 -410.113731)
			(xy 366.514635 -410.174745) (xy 366.499927 -410.234421) (xy 366.478132 -410.291889) (xy 366.449569 -410.346311)
			(xy 366.414655 -410.396893) (xy 366.373898 -410.442898) (xy 366.327893 -410.483655) (xy 366.277311 -410.518569)
			(xy 366.222889 -410.547132) (xy 366.165421 -410.568927) (xy 366.105745 -410.583635) (xy 366.044731 -410.591044)
			(xy 366.014 -410.591508) (xy 365.977202 -410.590868) (xy 365.904369 -410.580293) (xy 365.833815 -410.55935)
			(xy 365.800132 -410.544518) (xy 365.78794 -410.538676) (xy 365.76127 -410.540962) (xy 365.667036 -410.605986)
			(xy 365.655352 -410.630116) (xy 365.656114 -410.643578) (xy 365.657384 -410.67863) (xy 365.656918 -410.709359)
			(xy 365.649507 -410.770369) (xy 365.634795 -410.830041) (xy 365.612998 -410.887505) (xy 365.584434 -410.941922)
			(xy 365.549519 -410.9925) (xy 365.508762 -411.0385) (xy 365.462757 -411.079252) (xy 365.412176 -411.114162)
			(xy 365.357756 -411.142721) (xy 365.30029 -411.164511) (xy 365.240616 -411.179216) (xy 365.179605 -411.186621)
			(xy 365.148876 -411.187138) (xy 365.117854 -411.186691) (xy 365.056268 -411.179174) (xy 364.996055 -411.164216)
			(xy 364.93811 -411.142042) (xy 364.883294 -411.11298) (xy 364.832424 -411.077462) (xy 364.809024 -411.05709)
			(xy 364.801912 -411.050486) (xy 364.784132 -411.043882) (xy 364.694978 -411.04566) (xy 364.677706 -411.052772)
			(xy 364.670594 -411.05963) (xy 364.646801 -411.082039) (xy 364.594468 -411.121197) (xy 364.53755 -411.153328)
			(xy 364.476983 -411.177899) (xy 364.413767 -411.194507) (xy 364.348945 -411.202878) (xy 364.316264 -411.203394)
			(xy 364.286246 -411.202936) (xy 364.22663 -411.195829) (xy 364.168266 -411.181755) (xy 364.111964 -411.160907)
			(xy 364.058508 -411.133578) (xy 364.00864 -411.100145) (xy 363.963055 -411.061075) (xy 363.942376 -411.03931)
			(xy 363.933994 -411.03042) (xy 363.911896 -411.022038) (xy 363.806994 -411.032706) (xy 363.786928 -411.045152)
			(xy 363.780578 -411.055566) (xy 363.762913 -411.083858) (xy 363.72212 -411.136633) (xy 363.675583 -411.184418)
			(xy 363.623907 -411.226593) (xy 363.567764 -411.262609) (xy 363.507885 -411.291997) (xy 363.445049 -411.314375)
			(xy 363.380073 -411.329452) (xy 363.313803 -411.337031) (xy 363.280452 -411.337506) (xy 363.246639 -411.337021)
			(xy 363.179466 -411.329217) (xy 363.113641 -411.313718) (xy 363.050043 -411.29073) (xy 362.98952 -411.260562)
			(xy 362.93288 -411.223615) (xy 362.906564 -411.202378) (xy 362.895134 -411.192726) (xy 362.866178 -411.18917)
			(xy 362.769404 -411.234636) (xy 362.760843 -411.239084) (xy 362.747591 -411.253084) (xy 362.740408 -411.270974)
			(xy 362.73994 -411.28061) (xy 362.73994 -411.769052) (xy 362.739479 -411.793231) (xy 362.731946 -411.840998)
			(xy 362.717041 -411.887001) (xy 362.695131 -411.93011) (xy 362.666753 -411.969266) (xy 362.650024 -411.98673)
			(xy 362.290106 -412.346648) (xy 362.283273 -412.35401) (xy 362.27552 -412.372523) (xy 362.275464 -412.392594)
			(xy 362.27893 -412.40202) (xy 362.285026 -412.416244) (xy 362.310172 -412.433262) (xy 362.742988 -412.433262)
			(xy 362.752596 -412.432845) (xy 362.770472 -412.425791) (xy 362.777786 -412.419546) (xy 362.835698 -412.365444)
			(xy 362.843826 -412.348426) (xy 362.844334 -412.33852) (xy 362.846876 -412.30872) (xy 362.858727 -412.250097)
			(xy 362.878111 -412.193516) (xy 362.904699 -412.139942) (xy 362.938037 -412.090287) (xy 362.977558 -412.045396)
			(xy 363.022589 -412.006035) (xy 363.072363 -411.972873) (xy 363.126031 -411.946476) (xy 363.18268 -411.927293)
			(xy 363.241345 -411.915651) (xy 363.301026 -411.911748) (xy 363.360707 -411.915651) (xy 363.419372 -411.927293)
			(xy 363.476021 -411.946476) (xy 363.529689 -411.972873) (xy 363.579463 -412.006035) (xy 363.624494 -412.045396)
			(xy 363.664015 -412.090287) (xy 363.697353 -412.139942) (xy 363.723941 -412.193516) (xy 363.743325 -412.250097)
			(xy 363.755176 -412.30872) (xy 363.757718 -412.33852) (xy 363.758226 -412.348426) (xy 363.766354 -412.365444)
			(xy 363.824266 -412.419546) (xy 363.831554 -412.425837) (xy 363.849445 -412.432906) (xy 363.859064 -412.433262)
			(xy 367.897664 -412.433262) (xy 367.92535 -412.410656) (xy 367.92916 -412.392876) (xy 367.936037 -412.362039)
			(xy 367.95642 -412.302235) (xy 367.984056 -412.245418) (xy 368.01852 -412.192463) (xy 368.05928 -412.144187)
			(xy 368.105707 -412.101333) (xy 368.157087 -412.064563) (xy 368.212628 -412.034442) (xy 368.271472 -412.011436)
			(xy 368.332714 -411.995899) (xy 368.395409 -411.98807) (xy 368.458591 -411.98807) (xy 368.521286 -411.995899)
			(xy 368.582528 -412.011436) (xy 368.641372 -412.034442) (xy 368.696913 -412.064563) (xy 368.748293 -412.101333)
			(xy 368.79472 -412.144187) (xy 368.83548 -412.192463) (xy 368.869944 -412.245418) (xy 368.89758 -412.302235)
			(xy 368.917963 -412.362039) (xy 368.92484 -412.392876) (xy 368.92865 -412.410656) (xy 368.956336 -412.433262)
			(xy 370.25453 -412.433262) (xy 370.26624 -412.432664) (xy 370.287264 -412.422336) (xy 370.294916 -412.41345)
			(xy 370.35105 -412.340044) (xy 370.355622 -412.316676) (xy 370.352574 -412.305246) (xy 370.346844 -412.282499)
			(xy 370.340727 -412.235991) (xy 370.340382 -412.212536) (xy 370.34088 -412.185887) (xy 370.348823 -412.133183)
			(xy 370.364533 -412.082253) (xy 370.387659 -412.034232) (xy 370.417683 -411.990195) (xy 370.453935 -411.951124)
			(xy 370.495606 -411.917893) (xy 370.541764 -411.891244) (xy 370.591378 -411.871772) (xy 370.64334 -411.859912)
			(xy 370.69649 -411.855929) (xy 370.74964 -411.859912) (xy 370.801602 -411.871772) (xy 370.851216 -411.891244)
			(xy 370.897374 -411.917893) (xy 370.939045 -411.951124) (xy 370.975297 -411.990195) (xy 371.005321 -412.034232)
			(xy 371.028447 -412.082253) (xy 371.044157 -412.133183) (xy 371.0521 -412.185887) (xy 371.052598 -412.212536)
			(xy 371.052061 -412.240371) (xy 371.043381 -412.29536) (xy 371.035326 -412.32201) (xy 371.032757 -412.331072)
			(xy 371.033802 -412.349864) (xy 371.037358 -412.358586) (xy 371.050312 -412.387034) (xy 371.054572 -412.39554)
			(xy 371.068136 -412.40886) (xy 371.076728 -412.412942) (xy 371.108224 -412.427674) (xy 371.11365 -412.43026)
			(xy 371.12533 -412.43309) (xy 371.131338 -412.433262) (xy 371.520466 -412.433262) (xy 371.526475 -412.433093)
			(xy 371.538155 -412.430264) (xy 371.54358 -412.427674) (xy 371.575076 -412.412942) (xy 371.583676 -412.40887)
			(xy 371.597244 -412.39555) (xy 371.601492 -412.387034) (xy 371.614446 -412.358586) (xy 371.617919 -412.349843)
			(xy 371.618978 -412.331077) (xy 371.616478 -412.32201) (xy 371.608436 -412.295358) (xy 371.599763 -412.24037)
			(xy 371.599206 -412.212536) (xy 371.599704 -412.185887) (xy 371.607647 -412.133183) (xy 371.623357 -412.082253)
			(xy 371.646483 -412.034232) (xy 371.676507 -411.990195) (xy 371.712759 -411.951124) (xy 371.75443 -411.917893)
			(xy 371.800588 -411.891244) (xy 371.850202 -411.871772) (xy 371.902164 -411.859912) (xy 371.955314 -411.855929)
			(xy 372.008464 -411.859912) (xy 372.060426 -411.871772) (xy 372.11004 -411.891244) (xy 372.156198 -411.917893)
			(xy 372.197869 -411.951124) (xy 372.234121 -411.990195) (xy 372.264145 -412.034232) (xy 372.287271 -412.082253)
			(xy 372.302981 -412.133183) (xy 372.310924 -412.185887) (xy 372.311422 -412.212536) (xy 372.311063 -412.23599)
			(xy 372.304945 -412.282496) (xy 372.29923 -412.305246) (xy 372.296182 -412.316676) (xy 372.300754 -412.340044)
			(xy 372.356888 -412.41345) (xy 372.364488 -412.422399) (xy 372.385545 -412.432717) (xy 372.397274 -412.433262)
			(xy 373.31777 -412.433262) (xy 373.329487 -412.432676) (xy 373.35053 -412.422363) (xy 373.358156 -412.41345)
			(xy 373.41429 -412.340044) (xy 373.418862 -412.316676) (xy 373.415814 -412.305246) (xy 373.410084 -412.282499)
			(xy 373.403966 -412.235991) (xy 373.403622 -412.212536) (xy 373.40412 -412.185887) (xy 373.412063 -412.133183)
			(xy 373.427773 -412.082253) (xy 373.450899 -412.034232) (xy 373.480923 -411.990195) (xy 373.517175 -411.951124)
			(xy 373.558846 -411.917893) (xy 373.605004 -411.891244) (xy 373.654618 -411.871772) (xy 373.70658 -411.859912)
			(xy 373.75973 -411.855929) (xy 373.81288 -411.859912) (xy 373.864842 -411.871772) (xy 373.914456 -411.891244)
			(xy 373.960614 -411.917893) (xy 374.002285 -411.951124) (xy 374.038537 -411.990195) (xy 374.068561 -412.034232)
			(xy 374.091687 -412.082253) (xy 374.107397 -412.133183) (xy 374.11534 -412.185887) (xy 374.115838 -412.212536)
			(xy 374.115301 -412.240371) (xy 374.106622 -412.295361) (xy 374.098566 -412.32201) (xy 374.095999 -412.331072)
			(xy 374.097042 -412.349864) (xy 374.100598 -412.358586) (xy 374.113552 -412.387034) (xy 374.117814 -412.395537)
			(xy 374.131383 -412.408847) (xy 374.139968 -412.412942) (xy 374.171464 -412.427674) (xy 374.176891 -412.430256)
			(xy 374.188571 -412.433076) (xy 374.194578 -412.433262) (xy 374.583706 -412.433262) (xy 374.589717 -412.4331)
			(xy 374.601403 -412.430283) (xy 374.60682 -412.427674) (xy 374.638316 -412.412942) (xy 374.646911 -412.408865)
			(xy 374.660469 -412.395541) (xy 374.664732 -412.387034) (xy 374.677686 -412.358586) (xy 374.681157 -412.349843)
			(xy 374.682216 -412.331078) (xy 374.679718 -412.32201) (xy 374.671675 -412.295358) (xy 374.663001 -412.24037)
			(xy 374.662446 -412.212536) (xy 374.662944 -412.185887) (xy 374.670887 -412.133183) (xy 374.686597 -412.082253)
			(xy 374.709723 -412.034232) (xy 374.739747 -411.990195) (xy 374.775999 -411.951124) (xy 374.81767 -411.917893)
			(xy 374.863828 -411.891244) (xy 374.913442 -411.871772) (xy 374.965404 -411.859912) (xy 375.018554 -411.855929)
			(xy 375.071704 -411.859912) (xy 375.123666 -411.871772) (xy 375.17328 -411.891244) (xy 375.219438 -411.917893)
			(xy 375.261109 -411.951124) (xy 375.297361 -411.990195) (xy 375.327385 -412.034232) (xy 375.350511 -412.082253)
			(xy 375.366221 -412.133183) (xy 375.374164 -412.185887) (xy 375.374662 -412.212536) (xy 375.374302 -412.23599)
			(xy 375.368183 -412.282496) (xy 375.36247 -412.305246) (xy 375.359422 -412.316676) (xy 375.363994 -412.340044)
			(xy 375.420128 -412.41345) (xy 375.427724 -412.422409) (xy 375.448781 -412.432752) (xy 375.460514 -412.433262)
			(xy 376.38101 -412.433262) (xy 376.392722 -412.432668) (xy 376.413753 -412.422345) (xy 376.421396 -412.41345)
			(xy 376.47753 -412.340044) (xy 376.482102 -412.316676) (xy 376.479054 -412.305246) (xy 376.473323 -412.282499)
			(xy 376.467205 -412.235991) (xy 376.466862 -412.212536) (xy 376.46736 -412.185887) (xy 376.475303 -412.133183)
			(xy 376.491013 -412.082253) (xy 376.514139 -412.034232) (xy 376.544163 -411.990195) (xy 376.580415 -411.951124)
			(xy 376.622086 -411.917893) (xy 376.668244 -411.891244) (xy 376.717858 -411.871772) (xy 376.76982 -411.859912)
			(xy 376.82297 -411.855929) (xy 376.87612 -411.859912) (xy 376.928082 -411.871772) (xy 376.977696 -411.891244)
			(xy 377.023854 -411.917893) (xy 377.065525 -411.951124) (xy 377.101777 -411.990195) (xy 377.131801 -412.034232)
			(xy 377.154927 -412.082253) (xy 377.170637 -412.133183) (xy 377.17858 -412.185887) (xy 377.179078 -412.212536)
			(xy 377.178541 -412.240371) (xy 377.16986 -412.29536) (xy 377.161806 -412.32201) (xy 377.159238 -412.331072)
			(xy 377.160282 -412.349864) (xy 377.163838 -412.358586) (xy 377.176792 -412.387034) (xy 377.18105 -412.395542)
			(xy 377.194613 -412.408866) (xy 377.203208 -412.412942) (xy 377.234704 -412.427674) (xy 377.24013 -412.430262)
			(xy 377.251809 -412.433097) (xy 377.257818 -412.433262) (xy 377.646946 -412.433262) (xy 377.652956 -412.433095)
			(xy 377.664638 -412.43027) (xy 377.67006 -412.427674) (xy 377.701556 -412.412942) (xy 377.710158 -412.408872)
			(xy 377.723731 -412.395554) (xy 377.727972 -412.387034) (xy 377.740926 -412.358586) (xy 377.7444 -412.349843)
			(xy 377.74546 -412.331077) (xy 377.742958 -412.32201) (xy 377.734914 -412.295358) (xy 377.726239 -412.24037)
			(xy 377.725686 -412.212536) (xy 377.726184 -412.185887) (xy 377.734127 -412.133183) (xy 377.749837 -412.082253)
			(xy 377.772963 -412.034232) (xy 377.802987 -411.990195) (xy 377.839239 -411.951124) (xy 377.88091 -411.917893)
			(xy 377.927068 -411.891244) (xy 377.976682 -411.871772) (xy 378.028644 -411.859912) (xy 378.081794 -411.855929)
			(xy 378.134944 -411.859912) (xy 378.186906 -411.871772) (xy 378.23652 -411.891244) (xy 378.282678 -411.917893)
			(xy 378.324349 -411.951124) (xy 378.360601 -411.990195) (xy 378.390625 -412.034232) (xy 378.413751 -412.082253)
			(xy 378.429461 -412.133183) (xy 378.437404 -412.185887) (xy 378.437902 -412.212536) (xy 378.437542 -412.23599)
			(xy 378.431424 -412.282496) (xy 378.42571 -412.305246) (xy 378.422662 -412.316676) (xy 378.427234 -412.340044)
			(xy 378.483368 -412.41345) (xy 378.490967 -412.422402) (xy 378.512024 -412.432729) (xy 378.523754 -412.433262)
			(xy 379.44425 -412.433262) (xy 379.455958 -412.43266) (xy 379.476975 -412.422327) (xy 379.484636 -412.41345)
			(xy 379.54077 -412.340044) (xy 379.545342 -412.316676) (xy 379.542294 -412.305246) (xy 379.536564 -412.282499)
			(xy 379.530447 -412.235991) (xy 379.530102 -412.212536) (xy 379.5306 -412.185887) (xy 379.538543 -412.133183)
			(xy 379.554253 -412.082253) (xy 379.577379 -412.034232) (xy 379.607403 -411.990195) (xy 379.643655 -411.951124)
			(xy 379.685326 -411.917893) (xy 379.731484 -411.891244) (xy 379.781098 -411.871772) (xy 379.83306 -411.859912)
			(xy 379.88621 -411.855929) (xy 379.93936 -411.859912) (xy 379.991322 -411.871772) (xy 380.040936 -411.891244)
			(xy 380.087094 -411.917893) (xy 380.128765 -411.951124) (xy 380.165017 -411.990195) (xy 380.195041 -412.034232)
			(xy 380.218167 -412.082253) (xy 380.233877 -412.133183) (xy 380.24182 -412.185887) (xy 380.242318 -412.212536)
			(xy 380.241781 -412.240371) (xy 380.233101 -412.29536) (xy 380.225046 -412.32201) (xy 380.222477 -412.331072)
			(xy 380.223521 -412.349864) (xy 380.227078 -412.358586) (xy 380.240032 -412.387034) (xy 380.244293 -412.395539)
			(xy 380.25786 -412.408853) (xy 380.266448 -412.412942) (xy 380.297944 -412.427674) (xy 380.303371 -412.430258)
			(xy 380.31505 -412.433083) (xy 380.321058 -412.433262) (xy 380.710186 -412.433262) (xy 380.716194 -412.43309)
			(xy 380.727872 -412.430257) (xy 380.7333 -412.427674) (xy 380.764796 -412.412942) (xy 380.773394 -412.408868)
			(xy 380.786957 -412.395545) (xy 380.791212 -412.387034) (xy 380.804166 -412.358586) (xy 380.807637 -412.349843)
			(xy 380.808697 -412.331078) (xy 380.806198 -412.32201) (xy 380.798155 -412.295358) (xy 380.789482 -412.24037)
			(xy 380.788926 -412.212536) (xy 380.789424 -412.185887) (xy 380.797367 -412.133183) (xy 380.813077 -412.082253)
			(xy 380.836203 -412.034232) (xy 380.866227 -411.990195) (xy 380.902479 -411.951124) (xy 380.94415 -411.917893)
			(xy 380.990308 -411.891244) (xy 381.039922 -411.871772) (xy 381.091884 -411.859912) (xy 381.145034 -411.855929)
			(xy 381.198184 -411.859912) (xy 381.250146 -411.871772) (xy 381.29976 -411.891244) (xy 381.345918 -411.917893)
			(xy 381.387589 -411.951124) (xy 381.423841 -411.990195) (xy 381.453865 -412.034232) (xy 381.476991 -412.082253)
			(xy 381.492701 -412.133183) (xy 381.500644 -412.185887) (xy 381.501142 -412.212536) (xy 381.500782 -412.23599)
			(xy 381.494663 -412.282496) (xy 381.48895 -412.305246) (xy 381.485902 -412.316676) (xy 381.490474 -412.340044)
			(xy 381.546608 -412.41345) (xy 381.554203 -412.422412) (xy 381.575259 -412.432764) (xy 381.586994 -412.433262)
			(xy 382.50749 -412.433262) (xy 382.519204 -412.432672) (xy 382.540241 -412.422354) (xy 382.547876 -412.41345)
			(xy 382.60401 -412.340044) (xy 382.608582 -412.316676) (xy 382.605534 -412.305246) (xy 382.599804 -412.282499)
			(xy 382.593686 -412.235991) (xy 382.593342 -412.212536) (xy 382.59384 -412.185887) (xy 382.601783 -412.133183)
			(xy 382.617493 -412.082253) (xy 382.640619 -412.034232) (xy 382.670643 -411.990195) (xy 382.706895 -411.951124)
			(xy 382.748566 -411.917893) (xy 382.794724 -411.891244) (xy 382.844338 -411.871772) (xy 382.8963 -411.859912)
			(xy 382.94945 -411.855929) (xy 383.0026 -411.859912) (xy 383.054562 -411.871772) (xy 383.104176 -411.891244)
			(xy 383.150334 -411.917893) (xy 383.192005 -411.951124) (xy 383.228257 -411.990195) (xy 383.258281 -412.034232)
			(xy 383.281407 -412.082253) (xy 383.297117 -412.133183) (xy 383.30506 -412.185887) (xy 383.305558 -412.212536)
			(xy 383.305021 -412.240371) (xy 383.296342 -412.295361) (xy 383.288286 -412.32201) (xy 383.285719 -412.331072)
			(xy 383.286762 -412.349865) (xy 383.290318 -412.358586) (xy 383.303272 -412.387034) (xy 383.307529 -412.395543)
			(xy 383.321089 -412.408872) (xy 383.329688 -412.412942) (xy 383.361184 -412.427674) (xy 383.366611 -412.430254)
			(xy 383.378291 -412.43307) (xy 383.384298 -412.433262) (xy 383.773426 -412.433262) (xy 383.779436 -412.433097)
			(xy 383.79112 -412.430276) (xy 383.79654 -412.427674) (xy 383.828036 -412.412942) (xy 383.836641 -412.408874)
			(xy 383.850219 -412.395558) (xy 383.854452 -412.387034) (xy 383.867406 -412.358586) (xy 383.870876 -412.349843)
			(xy 383.871934 -412.331078) (xy 383.869438 -412.32201) (xy 383.861394 -412.295358) (xy 383.85272 -412.24037)
			(xy 383.852166 -412.212536) (xy 383.852664 -412.185887) (xy 383.860607 -412.133183) (xy 383.876317 -412.082253)
			(xy 383.899443 -412.034232) (xy 383.929467 -411.990195) (xy 383.965719 -411.951124) (xy 384.00739 -411.917893)
			(xy 384.053548 -411.891244) (xy 384.103162 -411.871772) (xy 384.155124 -411.859912) (xy 384.208274 -411.855929)
			(xy 384.261424 -411.859912) (xy 384.313386 -411.871772) (xy 384.363 -411.891244) (xy 384.409158 -411.917893)
			(xy 384.450829 -411.951124) (xy 384.487081 -411.990195) (xy 384.517105 -412.034232) (xy 384.540231 -412.082253)
			(xy 384.555941 -412.133183) (xy 384.563884 -412.185887) (xy 384.564382 -412.212536) (xy 384.564022 -412.23599)
			(xy 384.557904 -412.282496) (xy 384.55219 -412.305246) (xy 384.549142 -412.316676) (xy 384.553714 -412.340044)
			(xy 384.609848 -412.41345) (xy 384.617445 -412.422406) (xy 384.638502 -412.432741) (xy 384.650234 -412.433262)
			(xy 385.57073 -412.433262) (xy 385.58244 -412.432664) (xy 385.603464 -412.422336) (xy 385.611116 -412.41345)
			(xy 385.66725 -412.340044) (xy 385.671822 -412.316676) (xy 385.668774 -412.305246) (xy 385.663044 -412.282499)
			(xy 385.656927 -412.235991) (xy 385.656582 -412.212536) (xy 385.65708 -412.185887) (xy 385.665023 -412.133183)
			(xy 385.680733 -412.082253) (xy 385.703859 -412.034232) (xy 385.733883 -411.990195) (xy 385.770135 -411.951124)
			(xy 385.811806 -411.917893) (xy 385.857964 -411.891244) (xy 385.907578 -411.871772) (xy 385.95954 -411.859912)
			(xy 386.01269 -411.855929) (xy 386.06584 -411.859912) (xy 386.117802 -411.871772) (xy 386.167416 -411.891244)
			(xy 386.213574 -411.917893) (xy 386.255245 -411.951124) (xy 386.291497 -411.990195) (xy 386.321521 -412.034232)
			(xy 386.344647 -412.082253) (xy 386.360357 -412.133183) (xy 386.3683 -412.185887) (xy 386.368798 -412.212536)
			(xy 386.368261 -412.240371) (xy 386.359581 -412.29536) (xy 386.351526 -412.32201) (xy 386.348957 -412.331072)
			(xy 386.350002 -412.349864) (xy 386.353558 -412.358586) (xy 386.366512 -412.387034) (xy 386.370772 -412.39554)
			(xy 386.384336 -412.40886) (xy 386.392928 -412.412942) (xy 386.424424 -412.427674) (xy 386.42985 -412.43026)
			(xy 386.44153 -412.43309) (xy 386.447538 -412.433262) (xy 386.836666 -412.433262) (xy 386.842675 -412.433093)
			(xy 386.854355 -412.430264) (xy 386.85978 -412.427674) (xy 386.891276 -412.412942) (xy 386.899876 -412.40887)
			(xy 386.913444 -412.39555) (xy 386.917692 -412.387034) (xy 386.930646 -412.358586) (xy 386.934119 -412.349843)
			(xy 386.935178 -412.331077) (xy 386.932678 -412.32201) (xy 386.924636 -412.295358) (xy 386.915963 -412.24037)
			(xy 386.915406 -412.212536) (xy 386.915904 -412.185887) (xy 386.923847 -412.133183) (xy 386.939557 -412.082253)
			(xy 386.962683 -412.034232) (xy 386.992707 -411.990195) (xy 387.028959 -411.951124) (xy 387.07063 -411.917893)
			(xy 387.116788 -411.891244) (xy 387.166402 -411.871772) (xy 387.218364 -411.859912) (xy 387.271514 -411.855929)
			(xy 387.324664 -411.859912) (xy 387.376626 -411.871772) (xy 387.42624 -411.891244) (xy 387.472398 -411.917893)
			(xy 387.514069 -411.951124) (xy 387.550321 -411.990195) (xy 387.580345 -412.034232) (xy 387.603471 -412.082253)
			(xy 387.619181 -412.133183) (xy 387.627124 -412.185887) (xy 387.627622 -412.212536) (xy 387.627263 -412.23599)
			(xy 387.621145 -412.282496) (xy 387.61543 -412.305246) (xy 387.612382 -412.316676) (xy 387.616954 -412.340044)
			(xy 387.673088 -412.41345) (xy 387.680688 -412.422399) (xy 387.701745 -412.432717) (xy 387.713474 -412.433262)
			(xy 388.63397 -412.433262) (xy 388.645687 -412.432676) (xy 388.66673 -412.422363) (xy 388.674356 -412.41345)
			(xy 388.73049 -412.340044) (xy 388.735062 -412.316676) (xy 388.732014 -412.305246) (xy 388.726284 -412.282499)
			(xy 388.720166 -412.235991) (xy 388.719822 -412.212536) (xy 388.72032 -412.185887) (xy 388.728263 -412.133183)
			(xy 388.743973 -412.082253) (xy 388.767099 -412.034232) (xy 388.797123 -411.990195) (xy 388.833375 -411.951124)
			(xy 388.875046 -411.917893) (xy 388.921204 -411.891244) (xy 388.970818 -411.871772) (xy 389.02278 -411.859912)
			(xy 389.07593 -411.855929) (xy 389.12908 -411.859912) (xy 389.181042 -411.871772) (xy 389.230656 -411.891244)
			(xy 389.276814 -411.917893) (xy 389.318485 -411.951124) (xy 389.354737 -411.990195) (xy 389.384761 -412.034232)
			(xy 389.407887 -412.082253) (xy 389.423597 -412.133183) (xy 389.43154 -412.185887) (xy 389.432038 -412.212536)
			(xy 389.431501 -412.240371) (xy 389.422822 -412.295361) (xy 389.414766 -412.32201) (xy 389.412199 -412.331072)
			(xy 389.413242 -412.349864) (xy 389.416798 -412.358586) (xy 389.429752 -412.387034) (xy 389.434014 -412.395537)
			(xy 389.447583 -412.408847) (xy 389.456168 -412.412942) (xy 389.487664 -412.427674) (xy 389.493091 -412.430256)
			(xy 389.504771 -412.433076) (xy 389.510778 -412.433262) (xy 389.899906 -412.433262) (xy 389.905917 -412.4331)
			(xy 389.917603 -412.430283) (xy 389.92302 -412.427674) (xy 389.954516 -412.412942) (xy 389.963111 -412.408865)
			(xy 389.976669 -412.395541) (xy 389.980932 -412.387034) (xy 389.993886 -412.358586) (xy 389.997357 -412.349843)
			(xy 389.998416 -412.331078) (xy 389.995918 -412.32201) (xy 389.987875 -412.295358) (xy 389.979201 -412.24037)
			(xy 389.978646 -412.212536) (xy 389.979144 -412.185887) (xy 389.987087 -412.133183) (xy 390.002797 -412.082253)
			(xy 390.025923 -412.034232) (xy 390.055947 -411.990195) (xy 390.092199 -411.951124) (xy 390.13387 -411.917893)
			(xy 390.180028 -411.891244) (xy 390.229642 -411.871772) (xy 390.281604 -411.859912) (xy 390.334754 -411.855929)
			(xy 390.387904 -411.859912) (xy 390.439866 -411.871772) (xy 390.48948 -411.891244) (xy 390.535638 -411.917893)
			(xy 390.577309 -411.951124) (xy 390.613561 -411.990195) (xy 390.643585 -412.034232) (xy 390.666711 -412.082253)
			(xy 390.682421 -412.133183) (xy 390.690364 -412.185887) (xy 390.690862 -412.212536) (xy 390.690502 -412.23599)
			(xy 390.684383 -412.282496) (xy 390.67867 -412.305246) (xy 390.675622 -412.316676) (xy 390.680194 -412.340044)
			(xy 390.736328 -412.41345) (xy 390.743924 -412.422409) (xy 390.764981 -412.432752) (xy 390.776714 -412.433262)
			(xy 391.69721 -412.433262) (xy 391.708922 -412.432668) (xy 391.729953 -412.422345) (xy 391.737596 -412.41345)
			(xy 391.79373 -412.340044) (xy 391.798302 -412.316676) (xy 391.795254 -412.305246) (xy 391.789523 -412.282499)
			(xy 391.783405 -412.235991) (xy 391.783062 -412.212536) (xy 391.78356 -412.185887) (xy 391.791503 -412.133183)
			(xy 391.807213 -412.082253) (xy 391.830339 -412.034232) (xy 391.860363 -411.990195) (xy 391.896615 -411.951124)
			(xy 391.938286 -411.917893) (xy 391.984444 -411.891244) (xy 392.034058 -411.871772) (xy 392.08602 -411.859912)
			(xy 392.13917 -411.855929) (xy 392.19232 -411.859912) (xy 392.244282 -411.871772) (xy 392.293896 -411.891244)
			(xy 392.340054 -411.917893) (xy 392.381725 -411.951124) (xy 392.417977 -411.990195) (xy 392.448001 -412.034232)
			(xy 392.471127 -412.082253) (xy 392.486837 -412.133183) (xy 392.49478 -412.185887) (xy 392.495278 -412.212536)
			(xy 392.494741 -412.240371) (xy 392.48606 -412.29536) (xy 392.478006 -412.32201) (xy 392.475438 -412.331072)
			(xy 392.476482 -412.349864) (xy 392.480038 -412.358586) (xy 392.492992 -412.387034) (xy 392.49725 -412.395542)
			(xy 392.510813 -412.408866) (xy 392.519408 -412.412942) (xy 392.550904 -412.427674) (xy 392.55633 -412.430262)
			(xy 392.568009 -412.433097) (xy 392.574018 -412.433262) (xy 392.963146 -412.433262) (xy 392.969156 -412.433095)
			(xy 392.980838 -412.43027) (xy 392.98626 -412.427674) (xy 393.017756 -412.412942) (xy 393.026358 -412.408872)
			(xy 393.039931 -412.395554) (xy 393.044172 -412.387034) (xy 393.057126 -412.358586) (xy 393.0606 -412.349843)
			(xy 393.06166 -412.331077) (xy 393.059158 -412.32201) (xy 393.051114 -412.295358) (xy 393.042439 -412.24037)
			(xy 393.041886 -412.212536) (xy 393.042384 -412.185887) (xy 393.050327 -412.133183) (xy 393.066037 -412.082253)
			(xy 393.089163 -412.034232) (xy 393.119187 -411.990195) (xy 393.155439 -411.951124) (xy 393.19711 -411.917893)
			(xy 393.243268 -411.891244) (xy 393.292882 -411.871772) (xy 393.344844 -411.859912) (xy 393.397994 -411.855929)
			(xy 393.451144 -411.859912) (xy 393.503106 -411.871772) (xy 393.55272 -411.891244) (xy 393.598878 -411.917893)
			(xy 393.640549 -411.951124) (xy 393.676801 -411.990195) (xy 393.706825 -412.034232) (xy 393.729951 -412.082253)
			(xy 393.745661 -412.133183) (xy 393.753604 -412.185887) (xy 393.754102 -412.212536) (xy 393.753742 -412.23599)
			(xy 393.747624 -412.282496) (xy 393.74191 -412.305246) (xy 393.738862 -412.316676) (xy 393.743434 -412.340044)
			(xy 393.799568 -412.41345) (xy 393.807167 -412.422402) (xy 393.828224 -412.432729) (xy 393.839954 -412.433262)
			(xy 394.538454 -412.433262) (xy 394.548519 -412.432828) (xy 394.567106 -412.425096) (xy 394.574522 -412.418276)
			(xy 394.848588 -412.14421) (xy 394.855446 -412.132272) (xy 394.85697 -412.125414) (xy 394.863697 -412.100589)
			(xy 394.883316 -412.053046) (xy 394.909571 -412.008819) (xy 394.941914 -411.968829) (xy 394.979674 -411.933907)
			(xy 395.022064 -411.90478) (xy 395.04493 -411.893004) (xy 395.058138 -411.886654) (xy 395.073378 -411.862016)
			(xy 395.073378 -402.508974) (xy 395.073805 -402.498905) (xy 395.081524 -402.480306) (xy 395.088364 -402.472906)
			(xy 395.122654 -402.438616) (xy 395.129457 -402.431269) (xy 395.137166 -402.412805) (xy 395.13764 -402.402802)
			(xy 395.13764 -402.39823) (xy 395.16177 -402.3741) (xy 395.16558 -402.364194) (xy 395.176902 -402.336589)
			(xy 395.205096 -402.284005) (xy 395.239251 -402.235081) (xy 395.278896 -402.190491) (xy 395.323487 -402.150846)
			(xy 395.372412 -402.116692) (xy 395.424996 -402.088498) (xy 395.4526 -402.077174) (xy 395.462506 -402.073364)
			(xy 395.578838 -401.957032) (xy 395.585681 -401.949633) (xy 395.5934 -401.931034) (xy 395.593824 -401.920964)
			(xy 395.593824 -401.224242) (xy 395.594309 -401.21428) (xy 395.601897 -401.195855) (xy 395.608556 -401.188428)
			(xy 395.798548 -400.998436) (xy 395.80947 -400.998436) (xy 395.850618 -400.957288) (xy 395.858013 -400.950435)
			(xy 395.876612 -400.942693) (xy 395.886686 -400.942302) (xy 396.143226 -400.942302) (xy 396.153294 -400.941874)
			(xy 396.171892 -400.934153) (xy 396.179294 -400.927316) (xy 396.352014 -400.754596) (xy 396.358869 -400.747201)
			(xy 396.366616 -400.728602) (xy 396.367 -400.718528) (xy 396.367 -399.663412) (xy 396.366465 -399.653424)
			(xy 396.358754 -399.634988) (xy 396.352014 -399.627598) (xy 396.35176 -399.62709) (xy 396.345082 -399.619678)
			(xy 396.33751 -399.601242) (xy 396.337028 -399.591276) (xy 396.337028 -398.558766) (xy 396.336485 -398.548781)
			(xy 396.328766 -398.530355) (xy 396.322042 -398.522952) (xy 396.211044 -398.411954) (xy 396.203645 -398.40511)
			(xy 396.185046 -398.397388) (xy 396.174976 -398.396968) (xy 395.038834 -398.396968) (xy 395.028782 -398.397471)
			(xy 395.010217 -398.405188) (xy 395.002766 -398.411954) (xy 394.62583 -398.78889) (xy 394.619015 -398.796233)
			(xy 394.611274 -398.814696) (xy 394.610844 -398.824704) (xy 394.610844 -400.8501) (xy 394.610371 -400.860068)
			(xy 394.602805 -400.878514) (xy 394.596112 -400.885914) (xy 394.428218 -401.053808) (xy 394.420809 -401.060494)
			(xy 394.402373 -401.068081) (xy 394.392404 -401.06854) (xy 393.210796 -401.06854) (xy 393.200828 -401.068066)
			(xy 393.182384 -401.060499) (xy 393.174982 -401.053808) (xy 393.160504 -401.039584) (xy 393.153163 -401.032764)
			(xy 393.1347 -401.025017) (xy 393.12469 -401.024598) (xy 392.80084 -401.024598) (xy 392.790849 -401.025128)
			(xy 392.772407 -401.032831) (xy 392.765026 -401.039584) (xy 392.658092 -401.146264) (xy 392.651309 -401.153687)
			(xy 392.643704 -401.172284) (xy 392.64336 -401.182332) (xy 392.64336 -403.811232) (xy 392.642815 -403.821216)
			(xy 392.63509 -403.839636) (xy 392.628374 -403.847046) (xy 392.573764 -403.901656) (xy 392.573764 -403.90191)
			(xy 389.68045 -406.795224) (xy 389.673053 -406.802071) (xy 389.654453 -406.809799) (xy 389.644382 -406.81021)
			(xy 369.057936 -406.81021) (xy 369.032282 -406.827736) (xy 369.02644 -406.842214) (xy 369.014817 -406.870212)
			(xy 368.985849 -406.923465) (xy 368.950753 -406.972896) (xy 368.910028 -407.017803) (xy 368.864252 -407.057548)
			(xy 368.814075 -407.091567) (xy 368.760208 -407.119378) (xy 368.703416 -407.140587) (xy 368.644505 -407.154891)
			(xy 368.584311 -407.162088) (xy 368.554 -407.162508) (xy 368.5235 -407.162058) (xy 368.462938 -407.154759)
			(xy 368.403685 -407.140265) (xy 368.346592 -407.118786) (xy 368.292479 -407.090629) (xy 368.242124 -407.0562)
			(xy 368.196251 -407.015993) (xy 368.17554 -406.993598) (xy 368.167314 -406.985303) (xy 368.145669 -406.976585)
			(xy 368.122395 -406.978287) (xy 368.11204 -406.983692) (xy 368.089991 -406.996116) (xy 368.043318 -407.015683)
			(xy 367.994471 -407.028921) (xy 367.944305 -407.035598) (xy 367.919 -407.036016) (xy 367.89205 -407.035575)
			(xy 367.838681 -407.02804) (xy 367.7869 -407.013079) (xy 367.737736 -406.990989) (xy 367.692165 -406.962207)
			(xy 367.67135 -406.945084) (xy 367.664765 -406.939899) (xy 367.649215 -406.933671) (xy 367.64087 -406.932892)
			(xy 367.611406 -406.931622) (xy 367.602875 -406.931512) (xy 367.586515 -406.936311) (xy 367.579402 -406.94102)
			(xy 367.553453 -406.958931) (xy 367.497978 -406.988901) (xy 367.439226 -407.01179) (xy 367.378097 -407.027247)
			(xy 367.315527 -407.035035) (xy 367.284 -407.035508) (xy 367.253269 -407.035044) (xy 367.192255 -407.027635)
			(xy 367.132579 -407.012927) (xy 367.075111 -406.991132) (xy 367.020689 -406.962569) (xy 366.970107 -406.927655)
			(xy 366.924102 -406.886898) (xy 366.883345 -406.840893) (xy 366.848431 -406.790311) (xy 366.819868 -406.735889)
			(xy 366.798073 -406.678421) (xy 366.783365 -406.618745) (xy 366.775956 -406.557731) (xy 366.775492 -406.527)
			(xy 366.775945 -406.496451) (xy 366.783269 -406.435793) (xy 366.797812 -406.376451) (xy 366.819363 -406.31928)
			(xy 366.847612 -406.265105) (xy 366.882151 -406.214706) (xy 366.901984 -406.191466) (xy 366.907787 -406.184121)
			(xy 366.914156 -406.166534) (xy 366.91443 -406.157176) (xy 366.914176 -406.127204) (xy 366.913567 -406.117346)
			(xy 366.90586 -406.099182) (xy 366.89919 -406.091898) (xy 364.747302 -403.94001) (xy 364.739904 -403.933162)
			(xy 364.721306 -403.925425) (xy 364.711234 -403.925024) (xy 363.072426 -403.925024) (xy 363.062375 -403.924519)
			(xy 363.043813 -403.916799) (xy 363.036358 -403.910038) (xy 362.550202 -403.423882) (xy 362.543358 -403.416482)
			(xy 362.53563 -403.397885) (xy 362.535216 -403.387814) (xy 362.535216 -402.456142) (xy 362.53565 -402.446077)
			(xy 362.543381 -402.427489) (xy 362.550202 -402.420074) (xy 362.666026 -402.30425) (xy 362.669328 -402.298408)
			(xy 362.686903 -402.268751) (xy 362.728834 -402.21403) (xy 362.777774 -402.165478) (xy 362.832825 -402.123982)
			(xy 362.892978 -402.090306) (xy 362.924852 -402.077174) (xy 362.934758 -402.073364) (xy 363.05109 -401.957032)
			(xy 363.057927 -401.94963) (xy 363.065638 -401.931032) (xy 363.066076 -401.920964) (xy 363.066076 -401.224242)
			(xy 363.06656 -401.214279) (xy 363.074143 -401.19585) (xy 363.080808 -401.188428) (xy 363.2708 -400.998436)
			(xy 363.281722 -400.998436) (xy 363.32287 -400.957288) (xy 363.330268 -400.950443) (xy 363.348867 -400.94272)
			(xy 363.358938 -400.942302) (xy 363.615478 -400.942302) (xy 363.625542 -400.941864) (xy 363.644126 -400.93413)
			(xy 363.651546 -400.927316) (xy 363.824266 -400.754596) (xy 363.831115 -400.747199) (xy 363.838854 -400.728601)
			(xy 363.839252 -400.718528) (xy 363.839252 -398.588992) (xy 363.838826 -398.578924) (xy 363.831104 -398.560326)
			(xy 363.824266 -398.552924) (xy 363.683296 -398.411954) (xy 363.6759 -398.405102) (xy 363.657301 -398.397361)
			(xy 363.647228 -398.396968) (xy 361.43692 -398.396968) (xy 361.426869 -398.397474) (xy 361.408308 -398.405194)
			(xy 361.400852 -398.411954) (xy 361.307888 -398.504918) (xy 361.301035 -398.512313) (xy 361.293293 -398.530912)
			(xy 361.292902 -398.540986) (xy 361.292902 -398.76476) (xy 361.292648 -398.765014) (xy 361.292648 -400.556984)
			(xy 361.292208 -400.567046) (xy 361.284466 -400.585624) (xy 361.277662 -400.593052) (xy 360.533442 -401.337272)
			(xy 360.526042 -401.344112) (xy 360.507443 -401.35183) (xy 360.497374 -401.352258) (xy 359.393236 -401.352258)
			(xy 359.383172 -401.352694) (xy 359.36459 -401.360432) (xy 359.357168 -401.367244) (xy 358.641151 -402.083261)
			(xy 359.298735 -402.083261) (xy 359.298735 -402.015207) (xy 359.306635 -401.947614) (xy 359.322329 -401.881396)
			(xy 359.345605 -401.817447) (xy 359.376147 -401.756632) (xy 359.413543 -401.699775) (xy 359.457286 -401.647643)
			(xy 359.506786 -401.600942) (xy 359.561373 -401.560304) (xy 359.620309 -401.526277) (xy 359.682797 -401.499323)
			(xy 359.747991 -401.479805) (xy 359.81501 -401.467987) (xy 359.882948 -401.464031) (xy 359.950886 -401.467987)
			(xy 360.017905 -401.479805) (xy 360.083099 -401.499323) (xy 360.145587 -401.526277) (xy 360.204523 -401.560304)
			(xy 360.25911 -401.600942) (xy 360.30861 -401.647643) (xy 360.352353 -401.699775) (xy 360.389749 -401.756632)
			(xy 360.420291 -401.817447) (xy 360.443567 -401.881396) (xy 360.459261 -401.947614) (xy 360.467161 -402.015207)
			(xy 360.467656 -402.049234) (xy 360.467161 -402.083261) (xy 360.459261 -402.150854) (xy 360.443567 -402.217072)
			(xy 360.420291 -402.281021) (xy 360.389749 -402.341836) (xy 360.352353 -402.398693) (xy 360.30861 -402.450825)
			(xy 360.25911 -402.497526) (xy 360.204523 -402.538164) (xy 360.145587 -402.572191) (xy 360.083099 -402.599145)
			(xy 360.017905 -402.618663) (xy 359.950886 -402.630481) (xy 359.882948 -402.634438) (xy 359.81501 -402.630481)
			(xy 359.747991 -402.618663) (xy 359.682797 -402.599145) (xy 359.620309 -402.572191) (xy 359.561373 -402.538164)
			(xy 359.506786 -402.497526) (xy 359.457286 -402.450825) (xy 359.413543 -402.398693) (xy 359.376147 -402.341836)
			(xy 359.345605 -402.281021) (xy 359.322329 -402.217072) (xy 359.306635 -402.150854) (xy 359.298735 -402.083261)
			(xy 358.641151 -402.083261) (xy 358.196388 -402.528024) (xy 358.189536 -402.53542) (xy 358.181796 -402.554019)
			(xy 358.181402 -402.564092) (xy 358.181402 -403.117803) (xy 358.530131 -403.117803) (xy 358.530131 -403.049749)
			(xy 358.538031 -402.982156) (xy 358.553725 -402.915938) (xy 358.577001 -402.851989) (xy 358.607543 -402.791174)
			(xy 358.644939 -402.734317) (xy 358.688682 -402.682185) (xy 358.738182 -402.635484) (xy 358.792769 -402.594846)
			(xy 358.851705 -402.560819) (xy 358.914193 -402.533865) (xy 358.979387 -402.514347) (xy 359.046406 -402.502529)
			(xy 359.114344 -402.498573) (xy 359.182282 -402.502529) (xy 359.249301 -402.514347) (xy 359.314495 -402.533865)
			(xy 359.376983 -402.560819) (xy 359.435919 -402.594846) (xy 359.490506 -402.635484) (xy 359.540006 -402.682185)
			(xy 359.583749 -402.734317) (xy 359.621145 -402.791174) (xy 359.651687 -402.851989) (xy 359.674963 -402.915938)
			(xy 359.690657 -402.982156) (xy 359.698557 -403.049749) (xy 359.699052 -403.083776) (xy 359.698557 -403.117803)
			(xy 359.690657 -403.185396) (xy 359.674963 -403.251614) (xy 359.651687 -403.315563) (xy 359.621145 -403.376378)
			(xy 359.583749 -403.433235) (xy 359.540006 -403.485367) (xy 359.490506 -403.532068) (xy 359.435919 -403.572706)
			(xy 359.376983 -403.606733) (xy 359.314495 -403.633687) (xy 359.249301 -403.653205) (xy 359.182282 -403.665023)
			(xy 359.114344 -403.66898) (xy 359.046406 -403.665023) (xy 358.979387 -403.653205) (xy 358.914193 -403.633687)
			(xy 358.851705 -403.606733) (xy 358.792769 -403.572706) (xy 358.738182 -403.532068) (xy 358.688682 -403.485367)
			(xy 358.644939 -403.433235) (xy 358.607543 -403.376378) (xy 358.577001 -403.315563) (xy 358.553725 -403.251614)
			(xy 358.538031 -403.185396) (xy 358.530131 -403.117803) (xy 358.181402 -403.117803) (xy 358.181402 -403.330918)
			(xy 358.180975 -403.340987) (xy 358.173257 -403.359587) (xy 358.166416 -403.366986) (xy 356.923349 -404.610053)
			(xy 359.259873 -404.610053) (xy 359.259873 -404.541999) (xy 359.267773 -404.474406) (xy 359.283467 -404.408188)
			(xy 359.306743 -404.344239) (xy 359.337285 -404.283424) (xy 359.374681 -404.226567) (xy 359.418424 -404.174435)
			(xy 359.467924 -404.127734) (xy 359.522511 -404.087096) (xy 359.581447 -404.053069) (xy 359.643935 -404.026115)
			(xy 359.709129 -404.006597) (xy 359.776148 -403.994779) (xy 359.844086 -403.990823) (xy 359.912024 -403.994779)
			(xy 359.979043 -404.006597) (xy 360.044237 -404.026115) (xy 360.106725 -404.053069) (xy 360.165661 -404.087096)
			(xy 360.220248 -404.127734) (xy 360.269748 -404.174435) (xy 360.313491 -404.226567) (xy 360.350887 -404.283424)
			(xy 360.381429 -404.344239) (xy 360.404705 -404.408188) (xy 360.420399 -404.474406) (xy 360.428299 -404.541999)
			(xy 360.428794 -404.576026) (xy 360.428299 -404.610053) (xy 360.420399 -404.677646) (xy 360.404705 -404.743864)
			(xy 360.381429 -404.807813) (xy 360.350887 -404.868628) (xy 360.313491 -404.925485) (xy 360.269748 -404.977617)
			(xy 360.220248 -405.024318) (xy 360.165661 -405.064956) (xy 360.106725 -405.098983) (xy 360.044237 -405.125937)
			(xy 359.979043 -405.145455) (xy 359.912024 -405.157273) (xy 359.844086 -405.16123) (xy 359.776148 -405.157273)
			(xy 359.709129 -405.145455) (xy 359.643935 -405.125937) (xy 359.581447 -405.098983) (xy 359.522511 -405.064956)
			(xy 359.467924 -405.024318) (xy 359.418424 -404.977617) (xy 359.374681 -404.925485) (xy 359.337285 -404.868628)
			(xy 359.306743 -404.807813) (xy 359.283467 -404.743864) (xy 359.267773 -404.677646) (xy 359.259873 -404.610053)
			(xy 356.923349 -404.610053) (xy 355.981004 -405.552398) (xy 364.181118 -405.552398) (xy 364.181118 -405.492462)
			(xy 364.188941 -405.43304) (xy 364.204454 -405.375147) (xy 364.22739 -405.319774) (xy 364.257357 -405.267868)
			(xy 364.293844 -405.220318) (xy 364.336224 -405.177938) (xy 364.383774 -405.141451) (xy 364.43568 -405.111484)
			(xy 364.491053 -405.088548) (xy 364.548946 -405.073035) (xy 364.608368 -405.065212) (xy 364.668304 -405.065212)
			(xy 364.727726 -405.073035) (xy 364.785619 -405.088548) (xy 364.840992 -405.111484) (xy 364.892898 -405.141451)
			(xy 364.940448 -405.177938) (xy 364.982828 -405.220318) (xy 365.019315 -405.267868) (xy 365.049282 -405.319774)
			(xy 365.072218 -405.375147) (xy 365.087731 -405.43304) (xy 365.095554 -405.492462) (xy 365.096044 -405.52243)
			(xy 365.095554 -405.552398) (xy 365.087731 -405.61182) (xy 365.072218 -405.669713) (xy 365.049282 -405.725086)
			(xy 365.019315 -405.776992) (xy 364.982828 -405.824542) (xy 364.940448 -405.866922) (xy 364.892898 -405.903409)
			(xy 364.840992 -405.933376) (xy 364.785619 -405.956312) (xy 364.727726 -405.971825) (xy 364.668304 -405.979648)
			(xy 364.608368 -405.979648) (xy 364.548946 -405.971825) (xy 364.491053 -405.956312) (xy 364.43568 -405.933376)
			(xy 364.383774 -405.903409) (xy 364.336224 -405.866922) (xy 364.293844 -405.824542) (xy 364.257357 -405.776992)
			(xy 364.22739 -405.725086) (xy 364.204454 -405.669713) (xy 364.188941 -405.61182) (xy 364.181118 -405.552398)
			(xy 355.981004 -405.552398) (xy 354.738178 -406.795224) (xy 354.730782 -406.802075) (xy 354.712183 -406.809814)
			(xy 354.70211 -406.81021) (xy 331.128624 -406.81021) (xy 331.11856 -406.809773) (xy 331.099974 -406.802041)
			(xy 331.092556 -406.795224) (xy 327.98639 -403.689058) (xy 327.97954 -403.681662) (xy 327.971807 -403.663062)
			(xy 327.971404 -403.65299) (xy 327.971404 -402.510752) (xy 327.971836 -402.500686) (xy 327.979563 -402.482094)
			(xy 327.98639 -402.474684) (xy 328.022458 -402.438616) (xy 328.02926 -402.431268) (xy 328.036969 -402.412805)
			(xy 328.037444 -402.402802) (xy 328.037444 -402.39823) (xy 328.061574 -402.3741) (xy 328.065384 -402.364194)
			(xy 328.076706 -402.336589) (xy 328.104901 -402.284005) (xy 328.139055 -402.235082) (xy 328.178701 -402.190492)
			(xy 328.223292 -402.150847) (xy 328.272216 -402.116694) (xy 328.324801 -402.0885) (xy 328.352404 -402.077174)
			(xy 328.36231 -402.073364) (xy 328.478642 -401.957032) (xy 328.485484 -401.949633) (xy 328.493203 -401.931034)
			(xy 328.493628 -401.920964) (xy 328.493628 -401.224242) (xy 328.494113 -401.21428) (xy 328.501702 -401.195856)
			(xy 328.50836 -401.188428) (xy 328.698352 -400.998436) (xy 328.709274 -400.998436) (xy 328.750422 -400.957288)
			(xy 328.757817 -400.950435) (xy 328.776417 -400.942695) (xy 328.78649 -400.942302) (xy 329.04303 -400.942302)
			(xy 329.053098 -400.941873) (xy 329.071694 -400.934151) (xy 329.079098 -400.927316) (xy 329.251818 -400.754596)
			(xy 329.258673 -400.747201) (xy 329.266419 -400.728602) (xy 329.266804 -400.718528) (xy 329.266804 -399.663412)
			(xy 329.266269 -399.653423) (xy 329.258559 -399.634988) (xy 329.251818 -399.627598) (xy 329.251564 -399.62709)
			(xy 329.244885 -399.619678) (xy 329.237312 -399.601242) (xy 329.236832 -399.591276) (xy 329.236832 -398.558766)
			(xy 329.236289 -398.548781) (xy 329.228571 -398.530354) (xy 329.221846 -398.522952) (xy 329.110848 -398.411954)
			(xy 329.103449 -398.40511) (xy 329.08485 -398.397386) (xy 329.07478 -398.396968) (xy 327.938892 -398.396968)
			(xy 327.928822 -398.397392) (xy 327.910216 -398.405105) (xy 327.902824 -398.411954) (xy 327.525634 -398.789144)
			(xy 327.518827 -398.79649) (xy 327.511105 -398.814953) (xy 327.510648 -398.824958) (xy 327.510648 -400.8501)
			(xy 327.510172 -400.860066) (xy 327.502596 -400.878503) (xy 327.495916 -400.885914) (xy 327.328022 -401.053808)
			(xy 327.320613 -401.060495) (xy 327.302177 -401.068083) (xy 327.292208 -401.06854) (xy 326.1106 -401.06854)
			(xy 326.100632 -401.068067) (xy 326.082186 -401.0605) (xy 326.074786 -401.053808) (xy 326.060308 -401.039584)
			(xy 326.052967 -401.032763) (xy 326.034504 -401.025015) (xy 326.024494 -401.024598) (xy 325.700898 -401.024598)
			(xy 325.690911 -401.025136) (xy 325.672479 -401.03285) (xy 325.665084 -401.039584) (xy 325.55815 -401.146264)
			(xy 325.551308 -401.153664) (xy 325.543589 -401.172262) (xy 325.543164 -401.182332) (xy 325.543164 -403.495002)
			(xy 325.542688 -403.504969) (xy 325.535113 -403.523406) (xy 325.528432 -403.530816) (xy 325.473822 -403.585426)
			(xy 325.473822 -403.587204) (xy 322.265802 -406.795224) (xy 322.258407 -406.802079) (xy 322.239808 -406.809826)
			(xy 322.229734 -406.81021) (xy 303.651666 -406.81021) (xy 303.641599 -406.81064) (xy 303.623004 -406.818364)
			(xy 303.615598 -406.825196) (xy 303.441397 -406.999397) (xy 358.258612 -406.999397) (xy 358.258612 -406.935475)
			(xy 358.266623 -406.872057) (xy 358.28252 -406.810143) (xy 358.306052 -406.75071) (xy 358.336846 -406.694695)
			(xy 358.374419 -406.64298) (xy 358.418176 -406.596383) (xy 358.467429 -406.555638) (xy 358.5214 -406.521387)
			(xy 358.579239 -406.49417) (xy 358.640032 -406.474417) (xy 358.702822 -406.462439) (xy 358.766618 -406.458426)
			(xy 358.830414 -406.462439) (xy 358.893204 -406.474417) (xy 358.953997 -406.49417) (xy 359.011836 -406.521387)
			(xy 359.065807 -406.555638) (xy 359.11506 -406.596383) (xy 359.158817 -406.64298) (xy 359.19639 -406.694695)
			(xy 359.227184 -406.75071) (xy 359.250716 -406.810143) (xy 359.266613 -406.872057) (xy 359.274624 -406.935475)
			(xy 359.275126 -406.967436) (xy 359.274624 -406.999397) (xy 359.266613 -407.062815) (xy 359.250716 -407.124729)
			(xy 359.227184 -407.184162) (xy 359.19639 -407.240177) (xy 359.158817 -407.291892) (xy 359.11506 -407.338489)
			(xy 359.065807 -407.379234) (xy 359.011836 -407.413485) (xy 358.953997 -407.440702) (xy 358.893204 -407.460455)
			(xy 358.830414 -407.472433) (xy 358.766618 -407.476447) (xy 358.702822 -407.472433) (xy 358.640032 -407.460455)
			(xy 358.579239 -407.440702) (xy 358.5214 -407.413485) (xy 358.467429 -407.379234) (xy 358.418176 -407.338489)
			(xy 358.374419 -407.291892) (xy 358.336846 -407.240177) (xy 358.306052 -407.184162) (xy 358.28252 -407.124729)
			(xy 358.266623 -407.062815) (xy 358.258612 -406.999397) (xy 303.441397 -406.999397) (xy 303.263554 -407.17724)
			(xy 303.256708 -407.184638) (xy 303.24898 -407.203237) (xy 303.248568 -407.213308) (xy 303.248568 -407.906211)
			(xy 357.374431 -407.906211) (xy 357.374431 -407.838157) (xy 357.382331 -407.770564) (xy 357.398025 -407.704346)
			(xy 357.421301 -407.640397) (xy 357.451843 -407.579582) (xy 357.489239 -407.522725) (xy 357.532982 -407.470593)
			(xy 357.582482 -407.423892) (xy 357.637069 -407.383254) (xy 357.696005 -407.349227) (xy 357.758493 -407.322273)
			(xy 357.823687 -407.302755) (xy 357.890706 -407.290937) (xy 357.958644 -407.286981) (xy 358.026582 -407.290937)
			(xy 358.093601 -407.302755) (xy 358.158795 -407.322273) (xy 358.221283 -407.349227) (xy 358.280219 -407.383254)
			(xy 358.334806 -407.423892) (xy 358.384306 -407.470593) (xy 358.428049 -407.522725) (xy 358.465445 -407.579582)
			(xy 358.495987 -407.640397) (xy 358.519263 -407.704346) (xy 358.534957 -407.770564) (xy 358.542857 -407.838157)
			(xy 358.543352 -407.872184) (xy 358.542857 -407.906211) (xy 358.534957 -407.973804) (xy 358.519263 -408.040022)
			(xy 358.495987 -408.103971) (xy 358.465445 -408.164786) (xy 358.428049 -408.221643) (xy 358.384306 -408.273775)
			(xy 358.35121 -408.305) (xy 359.586797 -408.305) (xy 359.590753 -408.237062) (xy 359.602571 -408.170043)
			(xy 359.622089 -408.104849) (xy 359.649043 -408.042361) (xy 359.68307 -407.983425) (xy 359.723708 -407.928838)
			(xy 359.770409 -407.879338) (xy 359.822541 -407.835595) (xy 359.879398 -407.798199) (xy 359.940213 -407.767657)
			(xy 360.004162 -407.744381) (xy 360.07038 -407.728687) (xy 360.137973 -407.720787) (xy 360.172 -407.720292)
			(xy 360.207255 -407.720832) (xy 360.277248 -407.729348) (xy 360.345713 -407.746208) (xy 360.411657 -407.771168)
			(xy 360.474127 -407.803867) (xy 360.50347 -407.823416) (xy 360.512614 -407.829512) (xy 360.53395 -407.833322)
			(xy 360.629962 -407.808684) (xy 360.646726 -407.795222) (xy 360.651806 -407.785062) (xy 360.664506 -407.761694)
			(xy 360.67111 -407.750772) (xy 360.672126 -407.725372) (xy 360.623866 -407.626058) (xy 360.603292 -407.611072)
			(xy 360.590592 -407.609294) (xy 360.557724 -407.60432) (xy 360.493547 -407.586993) (xy 360.432177 -407.561449)
			(xy 360.374659 -407.528123) (xy 360.321977 -407.487584) (xy 360.275027 -407.440525) (xy 360.234612 -407.387747)
			(xy 360.201422 -407.330151) (xy 360.176022 -407.268721) (xy 360.158846 -407.204503) (xy 360.150186 -407.138595)
			(xy 360.149648 -407.105358) (xy 360.150088 -407.074671) (xy 360.15747 -407.013743) (xy 360.172135 -406.954147)
			(xy 360.193867 -406.89675) (xy 360.222352 -406.842387) (xy 360.257175 -406.791849) (xy 360.277156 -406.768554)
			(xy 360.284014 -406.76068) (xy 360.290618 -406.741376) (xy 360.28249 -406.647142) (xy 360.272838 -406.628854)
			(xy 360.26471 -406.62225) (xy 360.239623 -406.601442) (xy 360.193769 -406.555116) (xy 360.153353 -406.503976)
			(xy 360.118878 -406.448658) (xy 360.090771 -406.389847) (xy 360.069382 -406.328275) (xy 360.054975 -406.264705)
			(xy 360.047731 -406.199927) (xy 360.047286 -406.167336) (xy 360.047781 -406.133309) (xy 360.055681 -406.065716)
			(xy 360.071375 -405.999498) (xy 360.094651 -405.935549) (xy 360.125193 -405.874734) (xy 360.162589 -405.817877)
			(xy 360.206332 -405.765745) (xy 360.255832 -405.719044) (xy 360.310419 -405.678406) (xy 360.369355 -405.644379)
			(xy 360.431843 -405.617425) (xy 360.497037 -405.597907) (xy 360.564056 -405.586089) (xy 360.631994 -405.582133)
			(xy 360.699932 -405.586089) (xy 360.766951 -405.597907) (xy 360.832145 -405.617425) (xy 360.894633 -405.644379)
			(xy 360.953569 -405.678406) (xy 361.008156 -405.719044) (xy 361.057656 -405.765745) (xy 361.101399 -405.817877)
			(xy 361.138795 -405.874734) (xy 361.169337 -405.935549) (xy 361.192613 -405.999498) (xy 361.208307 -406.065716)
			(xy 361.216207 -406.133309) (xy 361.216702 -406.167336) (xy 361.216037 -406.208205) (xy 361.204696 -406.28915)
			(xy 361.194096 -406.328626) (xy 361.190032 -406.342088) (xy 361.19689 -406.368504) (xy 361.278932 -406.451308)
			(xy 361.305094 -406.45842) (xy 361.318556 -406.45461) (xy 361.343463 -406.448186) (xy 361.394437 -406.4413)
			(xy 361.420156 -406.440894) (xy 361.447411 -406.44135) (xy 361.501367 -406.449102) (xy 361.55367 -406.464455)
			(xy 361.603256 -406.487095) (xy 361.649115 -406.516562) (xy 361.690313 -406.552255) (xy 361.726012 -406.59345)
			(xy 361.755484 -406.639305) (xy 361.77813 -406.688888) (xy 361.793488 -406.74119) (xy 361.801247 -406.795145)
			(xy 361.801247 -406.849655) (xy 361.793488 -406.90361) (xy 361.77813 -406.955912) (xy 361.755484 -407.005495)
			(xy 361.726012 -407.05135) (xy 361.690313 -407.092545) (xy 361.649115 -407.128238) (xy 361.603256 -407.157705)
			(xy 361.55367 -407.180345) (xy 361.501367 -407.195698) (xy 361.447411 -407.20345) (xy 361.420156 -407.20391)
			(xy 361.396541 -407.203553) (xy 361.349667 -407.197757) (xy 361.303867 -407.186222) (xy 361.281726 -407.178002)
			(xy 361.27182 -407.173938) (xy 361.250484 -407.174954) (xy 361.16387 -407.21788) (xy 361.150154 -407.23439)
			(xy 361.147106 -407.244804) (xy 361.13704 -407.278078) (xy 361.109083 -407.341725) (xy 361.07271 -407.400967)
			(xy 361.051094 -407.428192) (xy 361.042966 -407.438098) (xy 361.037886 -407.46299) (xy 361.070398 -407.5684)
			(xy 361.088432 -407.586434) (xy 361.100878 -407.58999) (xy 361.126866 -407.598136) (xy 361.176377 -407.620821)
			(xy 361.22216 -407.650315) (xy 361.263283 -407.68602) (xy 361.298911 -407.72721) (xy 361.328321 -407.773048)
			(xy 361.350913 -407.822601) (xy 361.36623 -407.874864) (xy 361.373959 -407.928773) (xy 361.374436 -407.956004)
			(xy 361.373926 -407.983254) (xy 361.36617 -408.037199) (xy 361.350815 -408.089492) (xy 361.328176 -408.139067)
			(xy 361.298712 -408.184916) (xy 361.263023 -408.226106) (xy 361.221836 -408.261797) (xy 361.175989 -408.291264)
			(xy 361.126415 -408.313907) (xy 361.074123 -408.329265) (xy 361.020178 -408.337024) (xy 360.992928 -408.337512)
			(xy 360.964093 -408.336983) (xy 360.907078 -408.328311) (xy 360.87939 -408.32024) (xy 360.868722 -408.316938)
			(xy 360.847132 -408.319478) (xy 360.762804 -408.371548) (xy 360.750612 -408.389582) (xy 360.748834 -408.400504)
			(xy 360.742771 -408.434249) (xy 360.723737 -408.500119) (xy 360.69713 -408.56331) (xy 360.663314 -408.622955)
			(xy 360.622755 -408.678236) (xy 360.576008 -408.728394) (xy 360.523716 -408.77274) (xy 360.466596 -408.810666)
			(xy 360.405432 -408.841651) (xy 360.341065 -408.86527) (xy 360.274376 -408.881198) (xy 360.206282 -408.889218)
			(xy 360.172 -408.889708) (xy 360.137973 -408.889213) (xy 360.07038 -408.881313) (xy 360.004162 -408.865619)
			(xy 359.940213 -408.842343) (xy 359.879398 -408.811801) (xy 359.822541 -408.774405) (xy 359.770409 -408.730662)
			(xy 359.723708 -408.681162) (xy 359.68307 -408.626575) (xy 359.649043 -408.567639) (xy 359.622089 -408.505151)
			(xy 359.602571 -408.439957) (xy 359.590753 -408.372938) (xy 359.586797 -408.305) (xy 358.35121 -408.305)
			(xy 358.334806 -408.320476) (xy 358.280219 -408.361114) (xy 358.221283 -408.395141) (xy 358.158795 -408.422095)
			(xy 358.093601 -408.441613) (xy 358.026582 -408.453431) (xy 357.958644 -408.457388) (xy 357.890706 -408.453431)
			(xy 357.823687 -408.441613) (xy 357.758493 -408.422095) (xy 357.696005 -408.395141) (xy 357.637069 -408.361114)
			(xy 357.582482 -408.320476) (xy 357.532982 -408.273775) (xy 357.489239 -408.221643) (xy 357.451843 -408.164786)
			(xy 357.421301 -408.103971) (xy 357.398025 -408.040022) (xy 357.382331 -407.973804) (xy 357.374431 -407.906211)
			(xy 303.248568 -407.906211) (xy 303.248568 -408.73807) (xy 303.248131 -408.748134) (xy 303.240396 -408.766717)
			(xy 303.233582 -408.774138) (xy 303.044395 -408.963325) (xy 362.77397 -408.963325) (xy 362.77397 -408.899403)
			(xy 362.781981 -408.835985) (xy 362.797878 -408.774071) (xy 362.82141 -408.714638) (xy 362.852204 -408.658623)
			(xy 362.889777 -408.606908) (xy 362.933534 -408.560311) (xy 362.982787 -408.519566) (xy 363.036758 -408.485315)
			(xy 363.094597 -408.458098) (xy 363.15539 -408.438345) (xy 363.21818 -408.426367) (xy 363.281976 -408.422354)
			(xy 363.345772 -408.426367) (xy 363.408562 -408.438345) (xy 363.469355 -408.458098) (xy 363.527194 -408.485315)
			(xy 363.581165 -408.519566) (xy 363.630418 -408.560311) (xy 363.674175 -408.606908) (xy 363.711748 -408.658623)
			(xy 363.742542 -408.714638) (xy 363.766074 -408.774071) (xy 363.781971 -408.835985) (xy 363.789982 -408.899403)
			(xy 363.790484 -408.931364) (xy 363.789982 -408.963325) (xy 363.781971 -409.026743) (xy 363.766074 -409.088657)
			(xy 363.742542 -409.14809) (xy 363.711748 -409.204105) (xy 363.674175 -409.25582) (xy 363.630418 -409.302417)
			(xy 363.581165 -409.343162) (xy 363.527194 -409.377413) (xy 363.469355 -409.40463) (xy 363.408562 -409.424383)
			(xy 363.345772 -409.436361) (xy 363.281976 -409.440375) (xy 363.21818 -409.436361) (xy 363.15539 -409.424383)
			(xy 363.094597 -409.40463) (xy 363.036758 -409.377413) (xy 362.982787 -409.343162) (xy 362.933534 -409.302417)
			(xy 362.889777 -409.25582) (xy 362.852204 -409.204105) (xy 362.82141 -409.14809) (xy 362.797878 -409.088657)
			(xy 362.781981 -409.026743) (xy 362.77397 -408.963325) (xy 303.044395 -408.963325) (xy 302.816768 -409.190952)
			(xy 302.798226 -409.198572) (xy 302.792384 -409.198572) (xy 302.616362 -409.374594) (xy 302.609015 -409.381399)
			(xy 302.590552 -409.389119) (xy 302.580548 -409.38958) (xy 301.552864 -409.38958) (xy 301.54288 -409.389036)
			(xy 301.524459 -409.381311) (xy 301.51705 -409.374594) (xy 301.129446 -408.987244) (xy 301.126821 -408.984656)
			(xy 301.120956 -408.980194) (xy 301.117762 -408.978354) (xy 301.092031 -408.963962) (xy 301.043755 -408.930114)
			(xy 300.999719 -408.89091) (xy 300.960511 -408.846876) (xy 300.926659 -408.798604) (xy 300.912276 -408.772868)
			(xy 300.910433 -408.769677) (xy 300.905971 -408.763811) (xy 300.903386 -408.761184) (xy 300.691042 -408.548586)
			(xy 300.683168 -408.530044) (xy 300.683168 -408.522678) (xy 299.939202 -407.778458) (xy 299.932362 -407.771057)
			(xy 299.924642 -407.752459) (xy 299.924216 -407.74239) (xy 299.924216 -405.28367) (xy 299.923788 -405.273602)
			(xy 299.916068 -405.255004) (xy 299.90923 -405.247602) (xy 299.594016 -404.932388) (xy 299.586607 -404.925703)
			(xy 299.568171 -404.918117) (xy 299.558202 -404.917656) (xy 296.913046 -404.917656) (xy 296.903056 -404.917126)
			(xy 296.884616 -404.909419) (xy 296.877232 -404.90267) (xy 296.874184 -404.899622) (xy 296.850054 -404.899622)
			(xy 296.839988 -404.900054) (xy 296.821398 -404.907783) (xy 296.813986 -404.914608) (xy 296.461942 -405.266652)
			(xy 296.455099 -405.274051) (xy 296.447377 -405.29265) (xy 296.446956 -405.30272) (xy 296.446956 -408.375104)
			(xy 296.447381 -408.385173) (xy 296.455103 -408.403771) (xy 296.461942 -408.411172) (xy 296.89044 -408.83967)
			(xy 296.897839 -408.846514) (xy 296.916438 -408.854238) (xy 296.926508 -408.854656) (xy 299.272706 -408.854656)
			(xy 299.282774 -408.855082) (xy 299.301372 -408.862804) (xy 299.308774 -408.869642) (xy 301.200312 -410.76118)
			(xy 354.274374 -410.76118) (xy 354.274837 -410.730449) (xy 354.282248 -410.669436) (xy 354.296958 -410.609761)
			(xy 354.318754 -410.552294) (xy 354.347317 -410.497873) (xy 354.382232 -410.447292) (xy 354.422989 -410.401287)
			(xy 354.468993 -410.360531) (xy 354.519575 -410.325616) (xy 354.573996 -410.297053) (xy 354.631463 -410.275257)
			(xy 354.691138 -410.260547) (xy 354.752151 -410.253137) (xy 354.782882 -410.252672) (xy 354.820858 -410.253349)
			(xy 354.895975 -410.264566) (xy 354.932488 -410.275024) (xy 354.941886 -410.278072) (xy 354.96119 -410.276548)
			(xy 355.041454 -410.236416) (xy 355.054408 -410.221938) (xy 355.05771 -410.212794) (xy 355.070426 -410.179367)
			(xy 355.102834 -410.115611) (xy 355.142776 -410.056283) (xy 355.189656 -410.002271) (xy 355.242774 -409.954379)
			(xy 355.301336 -409.913324) (xy 355.364469 -409.879718) (xy 355.43123 -409.854064) (xy 355.500621 -409.836743)
			(xy 355.571606 -409.828016) (xy 355.607366 -409.827476) (xy 355.641394 -409.827982) (xy 355.70899 -409.835879)
			(xy 355.775213 -409.85157) (xy 355.839165 -409.874844) (xy 355.899984 -409.905385) (xy 355.956845 -409.94278)
			(xy 356.00898 -409.986524) (xy 356.055684 -410.036025) (xy 356.096326 -410.090613) (xy 356.130355 -410.149551)
			(xy 356.157312 -410.21204) (xy 356.176831 -410.277237) (xy 356.188649 -410.344259) (xy 356.192607 -410.4122)
			(xy 356.188649 -410.480141) (xy 356.176831 -410.547163) (xy 356.157312 -410.61236) (xy 356.130355 -410.674849)
			(xy 356.096326 -410.733787) (xy 356.055684 -410.788375) (xy 356.00898 -410.837876) (xy 355.956845 -410.88162)
			(xy 355.899984 -410.919015) (xy 355.839165 -410.949556) (xy 355.775213 -410.97283) (xy 355.70899 -410.988521)
			(xy 355.641394 -410.996418) (xy 355.607366 -410.996892) (xy 355.573383 -410.996387) (xy 355.505875 -410.988514)
			(xy 355.439732 -410.972879) (xy 355.375844 -410.949692) (xy 355.345238 -410.934916) (xy 355.335813 -410.930708)
			(xy 355.315237 -410.929383) (xy 355.30536 -410.932376) (xy 355.254814 -410.950664) (xy 355.248464 -410.96565)
			(xy 355.244938 -410.974667) (xy 355.244294 -410.994003) (xy 355.247194 -411.003242) (xy 355.257608 -411.032706)
			(xy 355.261248 -411.041568) (xy 355.273908 -411.055927) (xy 355.282246 -411.060646) (xy 355.305214 -411.072992)
			(xy 355.347808 -411.103075) (xy 355.385909 -411.138677) (xy 355.418807 -411.179136) (xy 355.445891 -411.223697)
			(xy 355.466655 -411.271531) (xy 355.480712 -411.321747) (xy 355.487801 -411.373409) (xy 355.48824 -411.399482)
			(xy 355.487754 -411.426733) (xy 355.479998 -411.480681) (xy 355.464643 -411.532976) (xy 355.442001 -411.582553)
			(xy 355.412535 -411.628403) (xy 355.376844 -411.669594) (xy 355.335653 -411.705285) (xy 355.289803 -411.734751)
			(xy 355.240226 -411.757393) (xy 355.187931 -411.772748) (xy 355.133983 -411.780504) (xy 355.079481 -411.780504)
			(xy 355.025533 -411.772748) (xy 354.973238 -411.757393) (xy 354.923661 -411.734751) (xy 354.877811 -411.705285)
			(xy 354.83662 -411.669594) (xy 354.800929 -411.628403) (xy 354.771463 -411.582553) (xy 354.748821 -411.532976)
			(xy 354.733466 -411.480681) (xy 354.72571 -411.426733) (xy 354.725224 -411.399482) (xy 354.727256 -411.361128)
			(xy 354.728018 -411.351984) (xy 354.723446 -411.334458) (xy 354.675694 -411.26537) (xy 354.660962 -411.254956)
			(xy 354.652326 -411.25267) (xy 354.620226 -411.243605) (xy 354.558553 -411.218197) (xy 354.500731 -411.184943)
			(xy 354.447752 -411.144415) (xy 354.400527 -411.097309) (xy 354.359867 -411.044432) (xy 354.326468 -410.986694)
			(xy 354.300904 -410.925084) (xy 354.283615 -410.860661) (xy 354.274897 -410.794531) (xy 354.274374 -410.76118)
			(xy 301.200312 -410.76118) (xy 302.857408 -412.418276) (xy 302.864806 -412.425124) (xy 302.883404 -412.432859)
			(xy 302.893476 -412.433262)
		)
		(stroke
			(width 0)
			(type solid)
		)
		(fill yes)
		(layer "B.Cu")
		(net "P0V9_CPU0_RT_2D")
	)
	(gr_poly
		(pts
			(xy 322.13804 -406.540462) (xy 322.147917 -406.539999) (xy 322.166215 -406.532557) (xy 322.1736 -406.525984)
			(xy 322.173854 -406.52573) (xy 325.273924 -403.42566) (xy 325.274432 -403.425152) (xy 325.281017 -403.417772)
			(xy 325.288473 -403.399473) (xy 325.28891 -403.389592) (xy 325.28891 -402.16709) (xy 325.287386 -402.154644)
			(xy 325.283068 -402.137626) (xy 325.280528 -402.132546) (xy 325.267484 -402.105802) (xy 325.24703 -402.049924)
			(xy 325.233249 -401.992037) (xy 325.22633 -401.932936) (xy 325.225918 -401.903184) (xy 325.225918 -401.902422)
			(xy 325.226363 -401.87199) (xy 325.233629 -401.811562) (xy 325.248059 -401.752433) (xy 325.269447 -401.695451)
			(xy 325.283068 -401.668234) (xy 325.285862 -401.6629) (xy 325.28891 -401.650962) (xy 325.28891 -401.519898)
			(xy 325.285862 -401.50796) (xy 325.283068 -401.502626) (xy 325.269451 -401.475408) (xy 325.248072 -401.418424)
			(xy 325.233647 -401.359296) (xy 325.22638 -401.298869) (xy 325.225918 -401.268438) (xy 325.225918 -401.26793)
			(xy 325.226445 -401.234508) (xy 325.235198 -401.168241) (xy 325.252556 -401.103691) (xy 325.278221 -401.041971)
			(xy 325.311749 -400.984146) (xy 325.352564 -400.93121) (xy 325.399962 -400.884078) (xy 325.453126 -400.843561)
			(xy 325.511139 -400.810358) (xy 325.541894 -400.797268) (xy 325.551292 -400.793458) (xy 325.601838 -400.742912)
			(xy 325.602346 -400.742404) (xy 325.608922 -400.735021) (xy 325.616358 -400.716722) (xy 325.616824 -400.706844)
			(xy 325.616824 -397.895572) (xy 325.616396 -397.885504) (xy 325.608678 -397.866904) (xy 325.601838 -397.859504)
			(xy 325.572628 -397.830294) (xy 325.565225 -397.823459) (xy 325.546627 -397.815752) (xy 325.53656 -397.815308)
			(xy 324.560184 -397.815308) (xy 324.550115 -397.814882) (xy 324.531514 -397.807165) (xy 324.524116 -397.800322)
			(xy 324.290436 -397.566642) (xy 324.289928 -397.566134) (xy 324.2818 -397.557752) (xy 324.259702 -397.550132)
			(xy 324.156832 -397.562832) (xy 324.137528 -397.575278) (xy 324.131432 -397.585184) (xy 324.1171 -397.607692)
			(xy 324.08235 -397.648182) (xy 324.041546 -397.682561) (xy 324.01891 -397.69669) (xy 324.013322 -397.700246)
			(xy 324.005487 -397.707042) (xy 323.995636 -397.725271) (xy 323.994272 -397.735552) (xy 323.994018 -397.740378)
			(xy 323.994018 -397.825722) (xy 323.994479 -397.835598) (xy 324.001925 -397.853894) (xy 324.008496 -397.861282)
			(xy 324.00875 -397.861536) (xy 324.018402 -397.871188) (xy 324.023482 -397.87449) (xy 324.02399 -397.874744)
			(xy 324.044074 -397.887764) (xy 324.080616 -397.918676) (xy 324.112318 -397.954534) (xy 324.138518 -397.994589)
			(xy 324.158668 -398.038003) (xy 324.172347 -398.083869) (xy 324.179268 -398.131229) (xy 324.179692 -398.15516)
			(xy 324.179276 -398.178932) (xy 324.172458 -398.225986) (xy 324.158972 -398.271578) (xy 324.139096 -398.314769)
			(xy 324.113239 -398.354668) (xy 324.097904 -398.372838) (xy 324.091808 -398.379696) (xy 324.085458 -398.396714)
			(xy 324.085458 -398.437608) (xy 324.085838 -398.44671) (xy 324.092225 -398.463757) (xy 324.097904 -398.470882)
			(xy 324.11325 -398.489043) (xy 324.139111 -398.52894) (xy 324.158984 -398.572133) (xy 324.172457 -398.61773)
			(xy 324.179252 -398.664787) (xy 324.179692 -398.68856) (xy 324.179149 -398.716075) (xy 324.170046 -398.770347)
			(xy 324.152085 -398.822364) (xy 324.125761 -398.870689) (xy 324.091801 -398.913991) (xy 324.051141 -398.951073)
			(xy 324.028308 -398.966436) (xy 324.027292 -398.966944) (xy 324.02526 -398.968214) (xy 324.01847 -398.973541)
			(xy 324.008599 -398.987685) (xy 324.005956 -398.9959) (xy 323.998082 -399.023078) (xy 323.996526 -399.029116)
			(xy 323.996005 -399.041572) (xy 323.997066 -399.047716) (xy 324.000114 -399.061432) (xy 324.0024 -399.066258)
			(xy 324.011424 -399.0875) (xy 324.024175 -399.131855) (xy 324.030661 -399.177549) (xy 324.031102 -399.200624)
			(xy 324.031102 -399.201132) (xy 324.030592 -399.227119) (xy 324.022462 -399.278454) (xy 324.006401 -399.327884)
			(xy 323.982805 -399.374194) (xy 323.952255 -399.416242) (xy 323.915504 -399.452993) (xy 323.873456 -399.483543)
			(xy 323.827146 -399.507139) (xy 323.777716 -399.5232) (xy 323.726381 -399.53133) (xy 323.674407 -399.53133)
			(xy 323.623072 -399.5232) (xy 323.573642 -399.507139) (xy 323.527332 -399.483543) (xy 323.485284 -399.452993)
			(xy 323.448533 -399.416242) (xy 323.417983 -399.374194) (xy 323.394387 -399.327884) (xy 323.378326 -399.278454)
			(xy 323.370196 -399.227119) (xy 323.369686 -399.201132) (xy 323.37023 -399.173617) (xy 323.379333 -399.119345)
			(xy 323.397295 -399.067329) (xy 323.423618 -399.019003) (xy 323.457577 -398.975701) (xy 323.498236 -398.938617)
			(xy 323.52107 -398.923256) (xy 323.522086 -398.922748) (xy 323.524118 -398.921478) (xy 323.53091 -398.916152)
			(xy 323.540783 -398.902008) (xy 323.543422 -398.893792) (xy 323.551296 -398.866614) (xy 323.552852 -398.860576)
			(xy 323.553371 -398.848121) (xy 323.552312 -398.841976) (xy 323.549264 -398.82826) (xy 323.546978 -398.823434)
			(xy 323.537953 -398.802192) (xy 323.525199 -398.757837) (xy 323.518713 -398.712143) (xy 323.518276 -398.689068)
			(xy 323.518276 -398.68856) (xy 323.518691 -398.664787) (xy 323.525505 -398.617731) (xy 323.538988 -398.572137)
			(xy 323.558861 -398.528943) (xy 323.584714 -398.48904) (xy 323.600064 -398.470882) (xy 323.605741 -398.463759)
			(xy 323.612116 -398.446709) (xy 323.61251 -398.437608) (xy 323.61251 -398.396714) (xy 323.60616 -398.379696)
			(xy 323.600064 -398.372838) (xy 323.584714 -398.354679) (xy 323.558845 -398.314784) (xy 323.538966 -398.271591)
			(xy 323.525487 -398.225993) (xy 323.518687 -398.178934) (xy 323.518276 -398.15516) (xy 323.518715 -398.130779)
			(xy 323.525887 -398.082548) (xy 323.54007 -398.035894) (xy 323.560955 -397.991831) (xy 323.588089 -397.951316)
			(xy 323.620883 -397.915229) (xy 323.658625 -397.884353) (xy 323.679312 -397.871442) (xy 323.68669 -397.866643)
			(xy 323.697898 -397.853091) (xy 323.703863 -397.836547) (xy 323.704204 -397.827754) (xy 323.704204 -397.74241)
			(xy 323.703783 -397.732339) (xy 323.696071 -397.713732) (xy 323.689218 -397.706342) (xy 323.67982 -397.696944)
			(xy 323.67474 -397.693642) (xy 323.674232 -397.693388) (xy 323.654145 -397.68037) (xy 323.617598 -397.64946)
			(xy 323.585891 -397.613603) (xy 323.559685 -397.573548) (xy 323.53953 -397.530134) (xy 323.525845 -397.484266)
			(xy 323.518918 -397.436904) (xy 323.51853 -397.412972) (xy 323.519087 -397.385352) (xy 323.528266 -397.330879)
			(xy 323.546363 -397.278688) (xy 323.572877 -397.230226) (xy 323.607071 -397.186841) (xy 323.647996 -397.149737)
			(xy 323.67093 -397.134334) (xy 323.68236 -397.127222) (xy 323.694806 -397.103346) (xy 323.69125 -396.9893)
			(xy 323.677534 -396.966694) (xy 323.665596 -396.96009) (xy 323.643906 -396.947454) (xy 323.604272 -396.916654)
			(xy 323.569745 -396.88022) (xy 323.541119 -396.838989) (xy 323.51905 -396.793906) (xy 323.504045 -396.746006)
			(xy 323.496448 -396.696389) (xy 323.495924 -396.671292) (xy 323.495924 -396.670784) (xy 323.496247 -396.65031)
			(xy 323.501344 -396.609679) (xy 323.506084 -396.589758) (xy 323.507608 -396.583662) (xy 323.507608 -396.583408)
			(xy 323.509491 -396.575378) (xy 323.508595 -396.558919) (xy 323.50583 -396.55115) (xy 323.495162 -396.523972)
			(xy 323.491771 -396.516372) (xy 323.48101 -396.50369) (xy 323.47408 -396.49908) (xy 323.44872 -396.483207)
			(xy 323.402526 -396.445191) (xy 323.362399 -396.400817) (xy 323.329207 -396.351043) (xy 323.303665 -396.296944)
			(xy 323.286325 -396.239686) (xy 323.277562 -396.180505) (xy 323.276976 -396.150592) (xy 323.277495 -396.121526)
			(xy 323.285769 -396.063987) (xy 323.302147 -396.008211) (xy 323.326296 -395.955333) (xy 323.357724 -395.90643)
			(xy 323.395791 -395.862497) (xy 323.439723 -395.824428) (xy 323.488626 -395.792999) (xy 323.541503 -395.76885)
			(xy 323.597279 -395.752471) (xy 323.654818 -395.744196) (xy 323.683884 -395.743684) (xy 323.75856 -395.743684)
			(xy 323.768585 -395.743271) (xy 323.787113 -395.735608) (xy 323.801294 -395.721434) (xy 323.808967 -395.702909)
			(xy 323.80936 -395.692884) (xy 323.80936 -395.232382) (xy 323.808932 -395.222314) (xy 323.801209 -395.203718)
			(xy 323.794374 -395.196314) (xy 322.785486 -394.187426) (xy 322.778642 -394.180028) (xy 322.770921 -394.161428)
			(xy 322.7705 -394.151358) (xy 322.7705 -392.100562) (xy 322.77007 -392.090495) (xy 322.762346 -392.071901)
			(xy 322.755514 -392.064494) (xy 322.482718 -391.791698) (xy 322.47587 -391.7843) (xy 322.468134 -391.765702)
			(xy 322.467732 -391.75563) (xy 322.467732 -391.001504) (xy 322.468155 -390.991434) (xy 322.475872 -390.972832)
			(xy 322.482718 -390.965436) (xy 322.596256 -390.851898) (xy 322.596764 -390.85139) (xy 322.603352 -390.844011)
			(xy 322.610816 -390.825712) (xy 322.611242 -390.81583) (xy 322.611242 -388.006082) (xy 322.610814 -387.996015)
			(xy 322.603089 -387.97742) (xy 322.596256 -387.970014) (xy 322.382388 -387.756146) (xy 322.374991 -387.749296)
			(xy 322.356393 -387.741559) (xy 322.34632 -387.74116) (xy 316.665864 -387.74116) (xy 316.655798 -387.741591)
			(xy 316.637209 -387.749322) (xy 316.629796 -387.756146) (xy 316.517528 -387.868414) (xy 316.510681 -387.875812)
			(xy 316.502947 -387.89441) (xy 316.502542 -387.904482) (xy 316.502542 -391.001758) (xy 316.502107 -391.011822)
			(xy 316.494371 -391.030406) (xy 316.487556 -391.037826) (xy 316.264465 -391.260917) (xy 316.686186 -391.260917)
			(xy 316.686186 -391.208943) (xy 316.694316 -391.157608) (xy 316.710377 -391.108178) (xy 316.733973 -391.061868)
			(xy 316.764523 -391.01982) (xy 316.801274 -390.983069) (xy 316.843322 -390.952519) (xy 316.889632 -390.928923)
			(xy 316.939062 -390.912862) (xy 316.990397 -390.904732) (xy 317.042371 -390.904732) (xy 317.093706 -390.912862)
			(xy 317.143136 -390.928923) (xy 317.189446 -390.952519) (xy 317.231494 -390.983069) (xy 317.268245 -391.01982)
			(xy 317.298795 -391.061868) (xy 317.322391 -391.108178) (xy 317.338452 -391.157608) (xy 317.346582 -391.208943)
			(xy 317.347092 -391.23493) (xy 317.346582 -391.260917) (xy 317.886082 -391.260917) (xy 317.886082 -391.208943)
			(xy 317.894212 -391.157608) (xy 317.910273 -391.108178) (xy 317.933869 -391.061868) (xy 317.964419 -391.01982)
			(xy 318.00117 -390.983069) (xy 318.043218 -390.952519) (xy 318.089528 -390.928923) (xy 318.138958 -390.912862)
			(xy 318.190293 -390.904732) (xy 318.242267 -390.904732) (xy 318.293602 -390.912862) (xy 318.343032 -390.928923)
			(xy 318.389342 -390.952519) (xy 318.43139 -390.983069) (xy 318.468141 -391.01982) (xy 318.498691 -391.061868)
			(xy 318.522287 -391.108178) (xy 318.538348 -391.157608) (xy 318.546478 -391.208943) (xy 318.546988 -391.23493)
			(xy 318.546478 -391.260917) (xy 319.085978 -391.260917) (xy 319.085978 -391.208943) (xy 319.094108 -391.157608)
			(xy 319.110169 -391.108178) (xy 319.133765 -391.061868) (xy 319.164315 -391.01982) (xy 319.201066 -390.983069)
			(xy 319.243114 -390.952519) (xy 319.289424 -390.928923) (xy 319.338854 -390.912862) (xy 319.390189 -390.904732)
			(xy 319.442163 -390.904732) (xy 319.493498 -390.912862) (xy 319.542928 -390.928923) (xy 319.589238 -390.952519)
			(xy 319.631286 -390.983069) (xy 319.668037 -391.01982) (xy 319.698587 -391.061868) (xy 319.722183 -391.108178)
			(xy 319.738244 -391.157608) (xy 319.746374 -391.208943) (xy 319.746884 -391.23493) (xy 319.746374 -391.260917)
			(xy 320.286128 -391.260917) (xy 320.286128 -391.208943) (xy 320.294258 -391.157608) (xy 320.310319 -391.108178)
			(xy 320.333915 -391.061868) (xy 320.364465 -391.01982) (xy 320.401216 -390.983069) (xy 320.443264 -390.952519)
			(xy 320.489574 -390.928923) (xy 320.539004 -390.912862) (xy 320.590339 -390.904732) (xy 320.642313 -390.904732)
			(xy 320.693648 -390.912862) (xy 320.743078 -390.928923) (xy 320.789388 -390.952519) (xy 320.831436 -390.983069)
			(xy 320.868187 -391.01982) (xy 320.898737 -391.061868) (xy 320.922333 -391.108178) (xy 320.938394 -391.157608)
			(xy 320.946524 -391.208943) (xy 320.947034 -391.23493) (xy 320.946524 -391.260917) (xy 321.486024 -391.260917)
			(xy 321.486024 -391.208943) (xy 321.494154 -391.157608) (xy 321.510215 -391.108178) (xy 321.533811 -391.061868)
			(xy 321.564361 -391.01982) (xy 321.601112 -390.983069) (xy 321.64316 -390.952519) (xy 321.68947 -390.928923)
			(xy 321.7389 -390.912862) (xy 321.790235 -390.904732) (xy 321.842209 -390.904732) (xy 321.893544 -390.912862)
			(xy 321.942974 -390.928923) (xy 321.989284 -390.952519) (xy 322.031332 -390.983069) (xy 322.068083 -391.01982)
			(xy 322.098633 -391.061868) (xy 322.122229 -391.108178) (xy 322.13829 -391.157608) (xy 322.14642 -391.208943)
			(xy 322.14693 -391.23493) (xy 322.14642 -391.260917) (xy 322.13829 -391.312252) (xy 322.122229 -391.361682)
			(xy 322.098633 -391.407992) (xy 322.068083 -391.45004) (xy 322.031332 -391.486791) (xy 321.989284 -391.517341)
			(xy 321.942974 -391.540937) (xy 321.893544 -391.556998) (xy 321.842209 -391.565128) (xy 321.790235 -391.565128)
			(xy 321.7389 -391.556998) (xy 321.68947 -391.540937) (xy 321.64316 -391.517341) (xy 321.601112 -391.486791)
			(xy 321.564361 -391.45004) (xy 321.533811 -391.407992) (xy 321.510215 -391.361682) (xy 321.494154 -391.312252)
			(xy 321.486024 -391.260917) (xy 320.946524 -391.260917) (xy 320.938394 -391.312252) (xy 320.922333 -391.361682)
			(xy 320.898737 -391.407992) (xy 320.868187 -391.45004) (xy 320.831436 -391.486791) (xy 320.789388 -391.517341)
			(xy 320.743078 -391.540937) (xy 320.693648 -391.556998) (xy 320.642313 -391.565128) (xy 320.590339 -391.565128)
			(xy 320.539004 -391.556998) (xy 320.489574 -391.540937) (xy 320.443264 -391.517341) (xy 320.401216 -391.486791)
			(xy 320.364465 -391.45004) (xy 320.333915 -391.407992) (xy 320.310319 -391.361682) (xy 320.294258 -391.312252)
			(xy 320.286128 -391.260917) (xy 319.746374 -391.260917) (xy 319.738244 -391.312252) (xy 319.722183 -391.361682)
			(xy 319.698587 -391.407992) (xy 319.668037 -391.45004) (xy 319.631286 -391.486791) (xy 319.589238 -391.517341)
			(xy 319.542928 -391.540937) (xy 319.493498 -391.556998) (xy 319.442163 -391.565128) (xy 319.390189 -391.565128)
			(xy 319.338854 -391.556998) (xy 319.289424 -391.540937) (xy 319.243114 -391.517341) (xy 319.201066 -391.486791)
			(xy 319.164315 -391.45004) (xy 319.133765 -391.407992) (xy 319.110169 -391.361682) (xy 319.094108 -391.312252)
			(xy 319.085978 -391.260917) (xy 318.546478 -391.260917) (xy 318.538348 -391.312252) (xy 318.522287 -391.361682)
			(xy 318.498691 -391.407992) (xy 318.468141 -391.45004) (xy 318.43139 -391.486791) (xy 318.389342 -391.517341)
			(xy 318.343032 -391.540937) (xy 318.293602 -391.556998) (xy 318.242267 -391.565128) (xy 318.190293 -391.565128)
			(xy 318.138958 -391.556998) (xy 318.089528 -391.540937) (xy 318.043218 -391.517341) (xy 318.00117 -391.486791)
			(xy 317.964419 -391.45004) (xy 317.933869 -391.407992) (xy 317.910273 -391.361682) (xy 317.894212 -391.312252)
			(xy 317.886082 -391.260917) (xy 317.346582 -391.260917) (xy 317.338452 -391.312252) (xy 317.322391 -391.361682)
			(xy 317.298795 -391.407992) (xy 317.268245 -391.45004) (xy 317.231494 -391.486791) (xy 317.189446 -391.517341)
			(xy 317.143136 -391.540937) (xy 317.093706 -391.556998) (xy 317.042371 -391.565128) (xy 316.990397 -391.565128)
			(xy 316.939062 -391.556998) (xy 316.889632 -391.540937) (xy 316.843322 -391.517341) (xy 316.801274 -391.486791)
			(xy 316.764523 -391.45004) (xy 316.733973 -391.407992) (xy 316.710377 -391.361682) (xy 316.694316 -391.312252)
			(xy 316.686186 -391.260917) (xy 316.264465 -391.260917) (xy 315.943488 -391.581894) (xy 315.936089 -391.588739)
			(xy 315.917491 -391.59647) (xy 315.90742 -391.59688) (xy 309.658004 -391.59688) (xy 309.647934 -391.596457)
			(xy 309.62933 -391.588742) (xy 309.621936 -391.581894) (xy 309.611522 -391.57148) (xy 309.611522 -391.56894)
			(xy 309.471568 -391.428986) (xy 309.464717 -391.42159) (xy 309.456976 -391.402991) (xy 309.456582 -391.392918)
			(xy 309.456582 -387.861302) (xy 309.456159 -387.851232) (xy 309.448443 -387.832629) (xy 309.441596 -387.825234)
			(xy 309.336948 -387.720586) (xy 309.329551 -387.713739) (xy 309.310952 -387.70601) (xy 309.30088 -387.7056)
			(xy 308.81447 -387.7056) (xy 308.796182 -387.69798) (xy 308.790086 -387.69544) (xy 302.634142 -387.69544)
			(xy 302.624077 -387.695875) (xy 302.605492 -387.703609) (xy 302.598074 -387.710426) (xy 301.909988 -388.398512)
			(xy 301.903134 -388.405907) (xy 301.89539 -388.424506) (xy 301.895002 -388.43458) (xy 301.895002 -390.888728)
			(xy 301.895444 -390.898149) (xy 301.902223 -390.915731) (xy 301.90821 -390.923018) (xy 301.908464 -390.923272)
			(xy 301.922942 -390.938766) (xy 301.926015 -390.941942) (xy 301.933041 -390.947302) (xy 301.936912 -390.949434)
			(xy 301.952152 -390.957308) (xy 301.955839 -390.959048) (xy 301.963623 -390.961471) (xy 301.967646 -390.962134)
			(xy 301.990904 -390.966122) (xy 302.036062 -390.979816) (xy 302.07882 -390.999776) (xy 302.118317 -391.025597)
			(xy 302.136302 -391.040874) (xy 302.14316 -391.04697) (xy 302.159924 -391.053574) (xy 302.234346 -391.054844)
			(xy 302.243368 -391.054712) (xy 302.260417 -391.048849) (xy 302.26762 -391.043414) (xy 302.289034 -391.026687)
			(xy 302.336382 -391.000037) (xy 302.387572 -390.981826) (xy 302.441114 -390.972585) (xy 302.46828 -390.97204)
			(xy 302.493268 -390.972503) (xy 302.54263 -390.980319) (xy 302.590162 -390.99576) (xy 302.634693 -391.018447)
			(xy 302.675126 -391.047821) (xy 302.710466 -391.083159) (xy 302.739843 -391.12359) (xy 302.762532 -391.168119)
			(xy 302.777977 -391.21565) (xy 302.784988 -391.259919) (xy 303.49874 -391.259919) (xy 303.49874 -391.209941)
			(xy 303.506559 -391.160578) (xy 303.522003 -391.113046) (xy 303.544693 -391.068514) (xy 303.574069 -391.028081)
			(xy 303.609409 -390.992741) (xy 303.649842 -390.963365) (xy 303.694374 -390.940675) (xy 303.741906 -390.925231)
			(xy 303.791269 -390.917412) (xy 303.841247 -390.917412) (xy 303.89061 -390.925231) (xy 303.938142 -390.940675)
			(xy 303.982674 -390.963365) (xy 304.023107 -390.992741) (xy 304.058447 -391.028081) (xy 304.087823 -391.068514)
			(xy 304.110513 -391.113046) (xy 304.125957 -391.160578) (xy 304.133776 -391.209941) (xy 304.134266 -391.23493)
			(xy 304.133776 -391.259919) (xy 304.133618 -391.260917) (xy 304.68621 -391.260917) (xy 304.68621 -391.208943)
			(xy 304.69434 -391.157608) (xy 304.710401 -391.108178) (xy 304.733997 -391.061868) (xy 304.764547 -391.01982)
			(xy 304.801298 -390.983069) (xy 304.843346 -390.952519) (xy 304.889656 -390.928923) (xy 304.939086 -390.912862)
			(xy 304.990421 -390.904732) (xy 305.042395 -390.904732) (xy 305.09373 -390.912862) (xy 305.14316 -390.928923)
			(xy 305.18947 -390.952519) (xy 305.231518 -390.983069) (xy 305.268269 -391.01982) (xy 305.298819 -391.061868)
			(xy 305.322415 -391.108178) (xy 305.338476 -391.157608) (xy 305.346606 -391.208943) (xy 305.347116 -391.23493)
			(xy 305.346606 -391.260917) (xy 305.886106 -391.260917) (xy 305.886106 -391.208943) (xy 305.894236 -391.157608)
			(xy 305.910297 -391.108178) (xy 305.933893 -391.061868) (xy 305.964443 -391.01982) (xy 306.001194 -390.983069)
			(xy 306.043242 -390.952519) (xy 306.089552 -390.928923) (xy 306.138982 -390.912862) (xy 306.190317 -390.904732)
			(xy 306.242291 -390.904732) (xy 306.293626 -390.912862) (xy 306.343056 -390.928923) (xy 306.389366 -390.952519)
			(xy 306.431414 -390.983069) (xy 306.468165 -391.01982) (xy 306.498715 -391.061868) (xy 306.522311 -391.108178)
			(xy 306.538372 -391.157608) (xy 306.546502 -391.208943) (xy 306.547012 -391.23493) (xy 306.546502 -391.260917)
			(xy 307.086002 -391.260917) (xy 307.086002 -391.208943) (xy 307.094132 -391.157608) (xy 307.110193 -391.108178)
			(xy 307.133789 -391.061868) (xy 307.164339 -391.01982) (xy 307.20109 -390.983069) (xy 307.243138 -390.952519)
			(xy 307.289448 -390.928923) (xy 307.338878 -390.912862) (xy 307.390213 -390.904732) (xy 307.442187 -390.904732)
			(xy 307.493522 -390.912862) (xy 307.542952 -390.928923) (xy 307.589262 -390.952519) (xy 307.63131 -390.983069)
			(xy 307.668061 -391.01982) (xy 307.698611 -391.061868) (xy 307.722207 -391.108178) (xy 307.738268 -391.157608)
			(xy 307.746398 -391.208943) (xy 307.746908 -391.23493) (xy 307.746398 -391.260917) (xy 308.286152 -391.260917)
			(xy 308.286152 -391.208943) (xy 308.294282 -391.157608) (xy 308.310343 -391.108178) (xy 308.333939 -391.061868)
			(xy 308.364489 -391.01982) (xy 308.40124 -390.983069) (xy 308.443288 -390.952519) (xy 308.489598 -390.928923)
			(xy 308.539028 -390.912862) (xy 308.590363 -390.904732) (xy 308.642337 -390.904732) (xy 308.693672 -390.912862)
			(xy 308.743102 -390.928923) (xy 308.789412 -390.952519) (xy 308.83146 -390.983069) (xy 308.868211 -391.01982)
			(xy 308.898761 -391.061868) (xy 308.922357 -391.108178) (xy 308.938418 -391.157608) (xy 308.946548 -391.208943)
			(xy 308.947058 -391.23493) (xy 308.946548 -391.260917) (xy 308.938418 -391.312252) (xy 308.922357 -391.361682)
			(xy 308.898761 -391.407992) (xy 308.868211 -391.45004) (xy 308.83146 -391.486791) (xy 308.789412 -391.517341)
			(xy 308.743102 -391.540937) (xy 308.693672 -391.556998) (xy 308.642337 -391.565128) (xy 308.590363 -391.565128)
			(xy 308.539028 -391.556998) (xy 308.489598 -391.540937) (xy 308.443288 -391.517341) (xy 308.40124 -391.486791)
			(xy 308.364489 -391.45004) (xy 308.333939 -391.407992) (xy 308.310343 -391.361682) (xy 308.294282 -391.312252)
			(xy 308.286152 -391.260917) (xy 307.746398 -391.260917) (xy 307.738268 -391.312252) (xy 307.722207 -391.361682)
			(xy 307.698611 -391.407992) (xy 307.668061 -391.45004) (xy 307.63131 -391.486791) (xy 307.589262 -391.517341)
			(xy 307.542952 -391.540937) (xy 307.493522 -391.556998) (xy 307.442187 -391.565128) (xy 307.390213 -391.565128)
			(xy 307.338878 -391.556998) (xy 307.289448 -391.540937) (xy 307.243138 -391.517341) (xy 307.20109 -391.486791)
			(xy 307.164339 -391.45004) (xy 307.133789 -391.407992) (xy 307.110193 -391.361682) (xy 307.094132 -391.312252)
			(xy 307.086002 -391.260917) (xy 306.546502 -391.260917) (xy 306.538372 -391.312252) (xy 306.522311 -391.361682)
			(xy 306.498715 -391.407992) (xy 306.468165 -391.45004) (xy 306.431414 -391.486791) (xy 306.389366 -391.517341)
			(xy 306.343056 -391.540937) (xy 306.293626 -391.556998) (xy 306.242291 -391.565128) (xy 306.190317 -391.565128)
			(xy 306.138982 -391.556998) (xy 306.089552 -391.540937) (xy 306.043242 -391.517341) (xy 306.001194 -391.486791)
			(xy 305.964443 -391.45004) (xy 305.933893 -391.407992) (xy 305.910297 -391.361682) (xy 305.894236 -391.312252)
			(xy 305.886106 -391.260917) (xy 305.346606 -391.260917) (xy 305.338476 -391.312252) (xy 305.322415 -391.361682)
			(xy 305.298819 -391.407992) (xy 305.268269 -391.45004) (xy 305.231518 -391.486791) (xy 305.18947 -391.517341)
			(xy 305.14316 -391.540937) (xy 305.09373 -391.556998) (xy 305.042395 -391.565128) (xy 304.990421 -391.565128)
			(xy 304.939086 -391.556998) (xy 304.889656 -391.540937) (xy 304.843346 -391.517341) (xy 304.801298 -391.486791)
			(xy 304.764547 -391.45004) (xy 304.733997 -391.407992) (xy 304.710401 -391.361682) (xy 304.69434 -391.312252)
			(xy 304.68621 -391.260917) (xy 304.133618 -391.260917) (xy 304.125957 -391.309282) (xy 304.110513 -391.356814)
			(xy 304.087823 -391.401346) (xy 304.058447 -391.441779) (xy 304.023107 -391.477119) (xy 303.982674 -391.506495)
			(xy 303.938142 -391.529185) (xy 303.89061 -391.544629) (xy 303.841247 -391.552448) (xy 303.791269 -391.552448)
			(xy 303.741906 -391.544629) (xy 303.694374 -391.529185) (xy 303.649842 -391.506495) (xy 303.609409 -391.477119)
			(xy 303.574069 -391.441779) (xy 303.544693 -391.401346) (xy 303.522003 -391.356814) (xy 303.506559 -391.309282)
			(xy 303.49874 -391.259919) (xy 302.784988 -391.259919) (xy 302.785795 -391.265012) (xy 302.785795 -391.314988)
			(xy 302.777977 -391.36435) (xy 302.762532 -391.41188) (xy 302.739843 -391.45641) (xy 302.710466 -391.496841)
			(xy 302.675126 -391.532179) (xy 302.634693 -391.561553) (xy 302.590162 -391.58424) (xy 302.54263 -391.599681)
			(xy 302.493268 -391.607497) (xy 302.46828 -391.608056) (xy 302.440955 -391.607488) (xy 302.387109 -391.598143)
			(xy 302.335653 -391.579733) (xy 302.288101 -391.552799) (xy 302.266604 -391.53592) (xy 302.259746 -391.530332)
			(xy 302.24349 -391.52449) (xy 302.233584 -391.52449) (xy 302.176942 -391.525506) (xy 302.172515 -391.525741)
			(xy 302.163834 -391.527538) (xy 302.15967 -391.529062) (xy 302.135794 -391.538206) (xy 302.129444 -391.54354)
			(xy 302.106016 -391.562238) (xy 302.053824 -391.591705) (xy 301.997173 -391.611274) (xy 301.967646 -391.616438)
			(xy 301.963619 -391.617082) (xy 301.955832 -391.619505) (xy 301.952152 -391.621264) (xy 301.936912 -391.629138)
			(xy 301.933025 -391.631245) (xy 301.925998 -391.63661) (xy 301.922942 -391.639806) (xy 301.908718 -391.655046)
			(xy 301.902443 -391.662339) (xy 301.895408 -391.68023) (xy 301.895002 -391.689844) (xy 301.895002 -392.243056)
			(xy 301.887382 -392.261598) (xy 301.883318 -392.265662) (xy 301.882302 -392.266932) (xy 301.88027 -392.268964)
			(xy 301.723806 -392.425174) (xy 301.720175 -392.429) (xy 301.71442 -392.437837) (xy 301.712376 -392.4427)
			(xy 301.70882 -392.451844) (xy 301.70882 -392.61796) (xy 301.711868 -392.626342) (xy 301.721083 -392.653557)
			(xy 301.73104 -392.710139) (xy 301.73168 -392.738864) (xy 301.73168 -392.739372) (xy 301.731199 -392.765362)
			(xy 301.723071 -392.816702) (xy 301.707011 -392.866139) (xy 301.683414 -392.912454) (xy 301.652862 -392.954507)
			(xy 301.616107 -392.991262) (xy 301.574054 -393.021814) (xy 301.568368 -393.024711) (xy 303.144664 -393.024711)
			(xy 303.144664 -392.974733) (xy 303.152483 -392.92537) (xy 303.167927 -392.877838) (xy 303.190617 -392.833306)
			(xy 303.219993 -392.792873) (xy 303.255333 -392.757533) (xy 303.295766 -392.728157) (xy 303.340298 -392.705467)
			(xy 303.38783 -392.690023) (xy 303.437193 -392.682204) (xy 303.487171 -392.682204) (xy 303.536534 -392.690023)
			(xy 303.584066 -392.705467) (xy 303.628598 -392.728157) (xy 303.669031 -392.757533) (xy 303.704371 -392.792873)
			(xy 303.733747 -392.833306) (xy 303.756437 -392.877838) (xy 303.771881 -392.92537) (xy 303.7797 -392.974733)
			(xy 303.78019 -392.999722) (xy 303.7797 -393.024711) (xy 303.779542 -393.025709) (xy 304.33188 -393.025709)
			(xy 304.33188 -392.973735) (xy 304.34001 -392.9224) (xy 304.356071 -392.87297) (xy 304.379667 -392.82666)
			(xy 304.410217 -392.784612) (xy 304.446968 -392.747861) (xy 304.489016 -392.717311) (xy 304.535326 -392.693715)
			(xy 304.584756 -392.677654) (xy 304.636091 -392.669524) (xy 304.688065 -392.669524) (xy 304.7394 -392.677654)
			(xy 304.78883 -392.693715) (xy 304.83514 -392.717311) (xy 304.877188 -392.747861) (xy 304.913939 -392.784612)
			(xy 304.944489 -392.82666) (xy 304.968085 -392.87297) (xy 304.984146 -392.9224) (xy 304.992276 -392.973735)
			(xy 304.992786 -392.999722) (xy 304.992276 -393.025709) (xy 305.53203 -393.025709) (xy 305.53203 -392.973735)
			(xy 305.54016 -392.9224) (xy 305.556221 -392.87297) (xy 305.579817 -392.82666) (xy 305.610367 -392.784612)
			(xy 305.647118 -392.747861) (xy 305.689166 -392.717311) (xy 305.735476 -392.693715) (xy 305.784906 -392.677654)
			(xy 305.836241 -392.669524) (xy 305.888215 -392.669524) (xy 305.93955 -392.677654) (xy 305.98898 -392.693715)
			(xy 306.03529 -392.717311) (xy 306.077338 -392.747861) (xy 306.114089 -392.784612) (xy 306.144639 -392.82666)
			(xy 306.168235 -392.87297) (xy 306.184296 -392.9224) (xy 306.192426 -392.973735) (xy 306.192936 -392.999722)
			(xy 306.192426 -393.025709) (xy 306.731926 -393.025709) (xy 306.731926 -392.973735) (xy 306.740056 -392.9224)
			(xy 306.756117 -392.87297) (xy 306.779713 -392.82666) (xy 306.810263 -392.784612) (xy 306.847014 -392.747861)
			(xy 306.889062 -392.717311) (xy 306.935372 -392.693715) (xy 306.984802 -392.677654) (xy 307.036137 -392.669524)
			(xy 307.088111 -392.669524) (xy 307.139446 -392.677654) (xy 307.188876 -392.693715) (xy 307.235186 -392.717311)
			(xy 307.277234 -392.747861) (xy 307.313985 -392.784612) (xy 307.344535 -392.82666) (xy 307.368131 -392.87297)
			(xy 307.384192 -392.9224) (xy 307.392322 -392.973735) (xy 307.392832 -392.999722) (xy 307.392322 -393.025709)
			(xy 307.932076 -393.025709) (xy 307.932076 -392.973735) (xy 307.940206 -392.9224) (xy 307.956267 -392.87297)
			(xy 307.979863 -392.82666) (xy 308.010413 -392.784612) (xy 308.047164 -392.747861) (xy 308.089212 -392.717311)
			(xy 308.135522 -392.693715) (xy 308.184952 -392.677654) (xy 308.236287 -392.669524) (xy 308.288261 -392.669524)
			(xy 308.339596 -392.677654) (xy 308.389026 -392.693715) (xy 308.435336 -392.717311) (xy 308.477384 -392.747861)
			(xy 308.514135 -392.784612) (xy 308.544685 -392.82666) (xy 308.568281 -392.87297) (xy 308.584342 -392.9224)
			(xy 308.592472 -392.973735) (xy 308.592982 -392.999722) (xy 308.592472 -393.025709) (xy 309.131972 -393.025709)
			(xy 309.131972 -392.973735) (xy 309.140102 -392.9224) (xy 309.156163 -392.87297) (xy 309.179759 -392.82666)
			(xy 309.210309 -392.784612) (xy 309.24706 -392.747861) (xy 309.289108 -392.717311) (xy 309.335418 -392.693715)
			(xy 309.384848 -392.677654) (xy 309.436183 -392.669524) (xy 309.488157 -392.669524) (xy 309.539492 -392.677654)
			(xy 309.588922 -392.693715) (xy 309.635232 -392.717311) (xy 309.67728 -392.747861) (xy 309.714031 -392.784612)
			(xy 309.744581 -392.82666) (xy 309.768177 -392.87297) (xy 309.784238 -392.9224) (xy 309.792368 -392.973735)
			(xy 309.792878 -392.999722) (xy 309.792368 -393.025709) (xy 310.331868 -393.025709) (xy 310.331868 -392.973735)
			(xy 310.339998 -392.9224) (xy 310.356059 -392.87297) (xy 310.379655 -392.82666) (xy 310.410205 -392.784612)
			(xy 310.446956 -392.747861) (xy 310.489004 -392.717311) (xy 310.535314 -392.693715) (xy 310.584744 -392.677654)
			(xy 310.636079 -392.669524) (xy 310.688053 -392.669524) (xy 310.739388 -392.677654) (xy 310.788818 -392.693715)
			(xy 310.835128 -392.717311) (xy 310.877176 -392.747861) (xy 310.913927 -392.784612) (xy 310.944477 -392.82666)
			(xy 310.968073 -392.87297) (xy 310.984134 -392.9224) (xy 310.992264 -392.973735) (xy 310.992774 -392.999722)
			(xy 310.992264 -393.025709) (xy 311.532018 -393.025709) (xy 311.532018 -392.973735) (xy 311.540148 -392.9224)
			(xy 311.556209 -392.87297) (xy 311.579805 -392.82666) (xy 311.610355 -392.784612) (xy 311.647106 -392.747861)
			(xy 311.689154 -392.717311) (xy 311.735464 -392.693715) (xy 311.784894 -392.677654) (xy 311.836229 -392.669524)
			(xy 311.888203 -392.669524) (xy 311.939538 -392.677654) (xy 311.988968 -392.693715) (xy 312.035278 -392.717311)
			(xy 312.077326 -392.747861) (xy 312.114077 -392.784612) (xy 312.144627 -392.82666) (xy 312.168223 -392.87297)
			(xy 312.184284 -392.9224) (xy 312.192414 -392.973735) (xy 312.192924 -392.999722) (xy 312.192414 -393.025709)
			(xy 312.731914 -393.025709) (xy 312.731914 -392.973735) (xy 312.740044 -392.9224) (xy 312.756105 -392.87297)
			(xy 312.779701 -392.82666) (xy 312.810251 -392.784612) (xy 312.847002 -392.747861) (xy 312.88905 -392.717311)
			(xy 312.93536 -392.693715) (xy 312.98479 -392.677654) (xy 313.036125 -392.669524) (xy 313.088099 -392.669524)
			(xy 313.139434 -392.677654) (xy 313.188864 -392.693715) (xy 313.235174 -392.717311) (xy 313.277222 -392.747861)
			(xy 313.313973 -392.784612) (xy 313.344523 -392.82666) (xy 313.368119 -392.87297) (xy 313.38418 -392.9224)
			(xy 313.39231 -392.973735) (xy 313.39282 -392.999722) (xy 313.39231 -393.025709) (xy 313.932064 -393.025709)
			(xy 313.932064 -392.973735) (xy 313.940194 -392.9224) (xy 313.956255 -392.87297) (xy 313.979851 -392.82666)
			(xy 314.010401 -392.784612) (xy 314.047152 -392.747861) (xy 314.0892 -392.717311) (xy 314.13551 -392.693715)
			(xy 314.18494 -392.677654) (xy 314.236275 -392.669524) (xy 314.288249 -392.669524) (xy 314.339584 -392.677654)
			(xy 314.389014 -392.693715) (xy 314.435324 -392.717311) (xy 314.477372 -392.747861) (xy 314.514123 -392.784612)
			(xy 314.544673 -392.82666) (xy 314.568269 -392.87297) (xy 314.58433 -392.9224) (xy 314.59246 -392.973735)
			(xy 314.59297 -392.999722) (xy 314.59246 -393.025709) (xy 315.13196 -393.025709) (xy 315.13196 -392.973735)
			(xy 315.14009 -392.9224) (xy 315.156151 -392.87297) (xy 315.179747 -392.82666) (xy 315.210297 -392.784612)
			(xy 315.247048 -392.747861) (xy 315.289096 -392.717311) (xy 315.335406 -392.693715) (xy 315.384836 -392.677654)
			(xy 315.436171 -392.669524) (xy 315.488145 -392.669524) (xy 315.53948 -392.677654) (xy 315.58891 -392.693715)
			(xy 315.63522 -392.717311) (xy 315.677268 -392.747861) (xy 315.714019 -392.784612) (xy 315.744569 -392.82666)
			(xy 315.768165 -392.87297) (xy 315.784226 -392.9224) (xy 315.792356 -392.973735) (xy 315.792866 -392.999722)
			(xy 315.792356 -393.025709) (xy 316.331856 -393.025709) (xy 316.331856 -392.973735) (xy 316.339986 -392.9224)
			(xy 316.356047 -392.87297) (xy 316.379643 -392.82666) (xy 316.410193 -392.784612) (xy 316.446944 -392.747861)
			(xy 316.488992 -392.717311) (xy 316.535302 -392.693715) (xy 316.584732 -392.677654) (xy 316.636067 -392.669524)
			(xy 316.688041 -392.669524) (xy 316.739376 -392.677654) (xy 316.788806 -392.693715) (xy 316.835116 -392.717311)
			(xy 316.877164 -392.747861) (xy 316.913915 -392.784612) (xy 316.944465 -392.82666) (xy 316.968061 -392.87297)
			(xy 316.984122 -392.9224) (xy 316.992252 -392.973735) (xy 316.992762 -392.999722) (xy 316.992252 -393.025709)
			(xy 317.532006 -393.025709) (xy 317.532006 -392.973735) (xy 317.540136 -392.9224) (xy 317.556197 -392.87297)
			(xy 317.579793 -392.82666) (xy 317.610343 -392.784612) (xy 317.647094 -392.747861) (xy 317.689142 -392.717311)
			(xy 317.735452 -392.693715) (xy 317.784882 -392.677654) (xy 317.836217 -392.669524) (xy 317.888191 -392.669524)
			(xy 317.939526 -392.677654) (xy 317.988956 -392.693715) (xy 318.035266 -392.717311) (xy 318.077314 -392.747861)
			(xy 318.114065 -392.784612) (xy 318.144615 -392.82666) (xy 318.168211 -392.87297) (xy 318.184272 -392.9224)
			(xy 318.192402 -392.973735) (xy 318.192912 -392.999722) (xy 318.192402 -393.025709) (xy 318.731902 -393.025709)
			(xy 318.731902 -392.973735) (xy 318.740032 -392.9224) (xy 318.756093 -392.87297) (xy 318.779689 -392.82666)
			(xy 318.810239 -392.784612) (xy 318.84699 -392.747861) (xy 318.889038 -392.717311) (xy 318.935348 -392.693715)
			(xy 318.984778 -392.677654) (xy 319.036113 -392.669524) (xy 319.088087 -392.669524) (xy 319.139422 -392.677654)
			(xy 319.188852 -392.693715) (xy 319.235162 -392.717311) (xy 319.27721 -392.747861) (xy 319.313961 -392.784612)
			(xy 319.344511 -392.82666) (xy 319.368107 -392.87297) (xy 319.384168 -392.9224) (xy 319.392298 -392.973735)
			(xy 319.392808 -392.999722) (xy 319.392298 -393.025709) (xy 319.932052 -393.025709) (xy 319.932052 -392.973735)
			(xy 319.940182 -392.9224) (xy 319.956243 -392.87297) (xy 319.979839 -392.82666) (xy 320.010389 -392.784612)
			(xy 320.04714 -392.747861) (xy 320.089188 -392.717311) (xy 320.135498 -392.693715) (xy 320.184928 -392.677654)
			(xy 320.236263 -392.669524) (xy 320.288237 -392.669524) (xy 320.339572 -392.677654) (xy 320.389002 -392.693715)
			(xy 320.435312 -392.717311) (xy 320.47736 -392.747861) (xy 320.514111 -392.784612) (xy 320.544661 -392.82666)
			(xy 320.568257 -392.87297) (xy 320.584318 -392.9224) (xy 320.592448 -392.973735) (xy 320.592958 -392.999722)
			(xy 320.592448 -393.025709) (xy 321.131948 -393.025709) (xy 321.131948 -392.973735) (xy 321.140078 -392.9224)
			(xy 321.156139 -392.87297) (xy 321.179735 -392.82666) (xy 321.210285 -392.784612) (xy 321.247036 -392.747861)
			(xy 321.289084 -392.717311) (xy 321.335394 -392.693715) (xy 321.384824 -392.677654) (xy 321.436159 -392.669524)
			(xy 321.488133 -392.669524) (xy 321.539468 -392.677654) (xy 321.588898 -392.693715) (xy 321.635208 -392.717311)
			(xy 321.677256 -392.747861) (xy 321.714007 -392.784612) (xy 321.744557 -392.82666) (xy 321.768153 -392.87297)
			(xy 321.784214 -392.9224) (xy 321.792344 -392.973735) (xy 321.792854 -392.999722) (xy 321.792344 -393.025709)
			(xy 321.784214 -393.077044) (xy 321.768153 -393.126474) (xy 321.744557 -393.172784) (xy 321.714007 -393.214832)
			(xy 321.677256 -393.251583) (xy 321.635208 -393.282133) (xy 321.588898 -393.305729) (xy 321.539468 -393.32179)
			(xy 321.488133 -393.32992) (xy 321.436159 -393.32992) (xy 321.384824 -393.32179) (xy 321.335394 -393.305729)
			(xy 321.289084 -393.282133) (xy 321.247036 -393.251583) (xy 321.210285 -393.214832) (xy 321.179735 -393.172784)
			(xy 321.156139 -393.126474) (xy 321.140078 -393.077044) (xy 321.131948 -393.025709) (xy 320.592448 -393.025709)
			(xy 320.584318 -393.077044) (xy 320.568257 -393.126474) (xy 320.544661 -393.172784) (xy 320.514111 -393.214832)
			(xy 320.47736 -393.251583) (xy 320.435312 -393.282133) (xy 320.389002 -393.305729) (xy 320.339572 -393.32179)
			(xy 320.288237 -393.32992) (xy 320.236263 -393.32992) (xy 320.184928 -393.32179) (xy 320.135498 -393.305729)
			(xy 320.089188 -393.282133) (xy 320.04714 -393.251583) (xy 320.010389 -393.214832) (xy 319.979839 -393.172784)
			(xy 319.956243 -393.126474) (xy 319.940182 -393.077044) (xy 319.932052 -393.025709) (xy 319.392298 -393.025709)
			(xy 319.384168 -393.077044) (xy 319.368107 -393.126474) (xy 319.344511 -393.172784) (xy 319.313961 -393.214832)
			(xy 319.27721 -393.251583) (xy 319.235162 -393.282133) (xy 319.188852 -393.305729) (xy 319.139422 -393.32179)
			(xy 319.088087 -393.32992) (xy 319.036113 -393.32992) (xy 318.984778 -393.32179) (xy 318.935348 -393.305729)
			(xy 318.889038 -393.282133) (xy 318.84699 -393.251583) (xy 318.810239 -393.214832) (xy 318.779689 -393.172784)
			(xy 318.756093 -393.126474) (xy 318.740032 -393.077044) (xy 318.731902 -393.025709) (xy 318.192402 -393.025709)
			(xy 318.184272 -393.077044) (xy 318.168211 -393.126474) (xy 318.144615 -393.172784) (xy 318.114065 -393.214832)
			(xy 318.077314 -393.251583) (xy 318.035266 -393.282133) (xy 317.988956 -393.305729) (xy 317.939526 -393.32179)
			(xy 317.888191 -393.32992) (xy 317.836217 -393.32992) (xy 317.784882 -393.32179) (xy 317.735452 -393.305729)
			(xy 317.689142 -393.282133) (xy 317.647094 -393.251583) (xy 317.610343 -393.214832) (xy 317.579793 -393.172784)
			(xy 317.556197 -393.126474) (xy 317.540136 -393.077044) (xy 317.532006 -393.025709) (xy 316.992252 -393.025709)
			(xy 316.984122 -393.077044) (xy 316.968061 -393.126474) (xy 316.944465 -393.172784) (xy 316.913915 -393.214832)
			(xy 316.877164 -393.251583) (xy 316.835116 -393.282133) (xy 316.788806 -393.305729) (xy 316.739376 -393.32179)
			(xy 316.688041 -393.32992) (xy 316.636067 -393.32992) (xy 316.584732 -393.32179) (xy 316.535302 -393.305729)
			(xy 316.488992 -393.282133) (xy 316.446944 -393.251583) (xy 316.410193 -393.214832) (xy 316.379643 -393.172784)
			(xy 316.356047 -393.126474) (xy 316.339986 -393.077044) (xy 316.331856 -393.025709) (xy 315.792356 -393.025709)
			(xy 315.784226 -393.077044) (xy 315.768165 -393.126474) (xy 315.744569 -393.172784) (xy 315.714019 -393.214832)
			(xy 315.677268 -393.251583) (xy 315.63522 -393.282133) (xy 315.58891 -393.305729) (xy 315.53948 -393.32179)
			(xy 315.488145 -393.32992) (xy 315.436171 -393.32992) (xy 315.384836 -393.32179) (xy 315.335406 -393.305729)
			(xy 315.289096 -393.282133) (xy 315.247048 -393.251583) (xy 315.210297 -393.214832) (xy 315.179747 -393.172784)
			(xy 315.156151 -393.126474) (xy 315.14009 -393.077044) (xy 315.13196 -393.025709) (xy 314.59246 -393.025709)
			(xy 314.58433 -393.077044) (xy 314.568269 -393.126474) (xy 314.544673 -393.172784) (xy 314.514123 -393.214832)
			(xy 314.477372 -393.251583) (xy 314.435324 -393.282133) (xy 314.389014 -393.305729) (xy 314.339584 -393.32179)
			(xy 314.288249 -393.32992) (xy 314.236275 -393.32992) (xy 314.18494 -393.32179) (xy 314.13551 -393.305729)
			(xy 314.0892 -393.282133) (xy 314.047152 -393.251583) (xy 314.010401 -393.214832) (xy 313.979851 -393.172784)
			(xy 313.956255 -393.126474) (xy 313.940194 -393.077044) (xy 313.932064 -393.025709) (xy 313.39231 -393.025709)
			(xy 313.38418 -393.077044) (xy 313.368119 -393.126474) (xy 313.344523 -393.172784) (xy 313.313973 -393.214832)
			(xy 313.277222 -393.251583) (xy 313.235174 -393.282133) (xy 313.188864 -393.305729) (xy 313.139434 -393.32179)
			(xy 313.088099 -393.32992) (xy 313.036125 -393.32992) (xy 312.98479 -393.32179) (xy 312.93536 -393.305729)
			(xy 312.88905 -393.282133) (xy 312.847002 -393.251583) (xy 312.810251 -393.214832) (xy 312.779701 -393.172784)
			(xy 312.756105 -393.126474) (xy 312.740044 -393.077044) (xy 312.731914 -393.025709) (xy 312.192414 -393.025709)
			(xy 312.184284 -393.077044) (xy 312.168223 -393.126474) (xy 312.144627 -393.172784) (xy 312.114077 -393.214832)
			(xy 312.077326 -393.251583) (xy 312.035278 -393.282133) (xy 311.988968 -393.305729) (xy 311.939538 -393.32179)
			(xy 311.888203 -393.32992) (xy 311.836229 -393.32992) (xy 311.784894 -393.32179) (xy 311.735464 -393.305729)
			(xy 311.689154 -393.282133) (xy 311.647106 -393.251583) (xy 311.610355 -393.214832) (xy 311.579805 -393.172784)
			(xy 311.556209 -393.126474) (xy 311.540148 -393.077044) (xy 311.532018 -393.025709) (xy 310.992264 -393.025709)
			(xy 310.984134 -393.077044) (xy 310.968073 -393.126474) (xy 310.944477 -393.172784) (xy 310.913927 -393.214832)
			(xy 310.877176 -393.251583) (xy 310.835128 -393.282133) (xy 310.788818 -393.305729) (xy 310.739388 -393.32179)
			(xy 310.688053 -393.32992) (xy 310.636079 -393.32992) (xy 310.584744 -393.32179) (xy 310.535314 -393.305729)
			(xy 310.489004 -393.282133) (xy 310.446956 -393.251583) (xy 310.410205 -393.214832) (xy 310.379655 -393.172784)
			(xy 310.356059 -393.126474) (xy 310.339998 -393.077044) (xy 310.331868 -393.025709) (xy 309.792368 -393.025709)
			(xy 309.784238 -393.077044) (xy 309.768177 -393.126474) (xy 309.744581 -393.172784) (xy 309.714031 -393.214832)
			(xy 309.67728 -393.251583) (xy 309.635232 -393.282133) (xy 309.588922 -393.305729) (xy 309.539492 -393.32179)
			(xy 309.488157 -393.32992) (xy 309.436183 -393.32992) (xy 309.384848 -393.32179) (xy 309.335418 -393.305729)
			(xy 309.289108 -393.282133) (xy 309.24706 -393.251583) (xy 309.210309 -393.214832) (xy 309.179759 -393.172784)
			(xy 309.156163 -393.126474) (xy 309.140102 -393.077044) (xy 309.131972 -393.025709) (xy 308.592472 -393.025709)
			(xy 308.584342 -393.077044) (xy 308.568281 -393.126474) (xy 308.544685 -393.172784) (xy 308.514135 -393.214832)
			(xy 308.477384 -393.251583) (xy 308.435336 -393.282133) (xy 308.389026 -393.305729) (xy 308.339596 -393.32179)
			(xy 308.288261 -393.32992) (xy 308.236287 -393.32992) (xy 308.184952 -393.32179) (xy 308.135522 -393.305729)
			(xy 308.089212 -393.282133) (xy 308.047164 -393.251583) (xy 308.010413 -393.214832) (xy 307.979863 -393.172784)
			(xy 307.956267 -393.126474) (xy 307.940206 -393.077044) (xy 307.932076 -393.025709) (xy 307.392322 -393.025709)
			(xy 307.384192 -393.077044) (xy 307.368131 -393.126474) (xy 307.344535 -393.172784) (xy 307.313985 -393.214832)
			(xy 307.277234 -393.251583) (xy 307.235186 -393.282133) (xy 307.188876 -393.305729) (xy 307.139446 -393.32179)
			(xy 307.088111 -393.32992) (xy 307.036137 -393.32992) (xy 306.984802 -393.32179) (xy 306.935372 -393.305729)
			(xy 306.889062 -393.282133) (xy 306.847014 -393.251583) (xy 306.810263 -393.214832) (xy 306.779713 -393.172784)
			(xy 306.756117 -393.126474) (xy 306.740056 -393.077044) (xy 306.731926 -393.025709) (xy 306.192426 -393.025709)
			(xy 306.184296 -393.077044) (xy 306.168235 -393.126474) (xy 306.144639 -393.172784) (xy 306.114089 -393.214832)
			(xy 306.077338 -393.251583) (xy 306.03529 -393.282133) (xy 305.98898 -393.305729) (xy 305.93955 -393.32179)
			(xy 305.888215 -393.32992) (xy 305.836241 -393.32992) (xy 305.784906 -393.32179) (xy 305.735476 -393.305729)
			(xy 305.689166 -393.282133) (xy 305.647118 -393.251583) (xy 305.610367 -393.214832) (xy 305.579817 -393.172784)
			(xy 305.556221 -393.126474) (xy 305.54016 -393.077044) (xy 305.53203 -393.025709) (xy 304.992276 -393.025709)
			(xy 304.984146 -393.077044) (xy 304.968085 -393.126474) (xy 304.944489 -393.172784) (xy 304.913939 -393.214832)
			(xy 304.877188 -393.251583) (xy 304.83514 -393.282133) (xy 304.78883 -393.305729) (xy 304.7394 -393.32179)
			(xy 304.688065 -393.32992) (xy 304.636091 -393.32992) (xy 304.584756 -393.32179) (xy 304.535326 -393.305729)
			(xy 304.489016 -393.282133) (xy 304.446968 -393.251583) (xy 304.410217 -393.214832) (xy 304.379667 -393.172784)
			(xy 304.356071 -393.126474) (xy 304.34001 -393.077044) (xy 304.33188 -393.025709) (xy 303.779542 -393.025709)
			(xy 303.771881 -393.074074) (xy 303.756437 -393.121606) (xy 303.733747 -393.166138) (xy 303.704371 -393.206571)
			(xy 303.669031 -393.241911) (xy 303.628598 -393.271287) (xy 303.584066 -393.293977) (xy 303.536534 -393.309421)
			(xy 303.487171 -393.31724) (xy 303.437193 -393.31724) (xy 303.38783 -393.309421) (xy 303.340298 -393.293977)
			(xy 303.295766 -393.271287) (xy 303.255333 -393.241911) (xy 303.219993 -393.206571) (xy 303.190617 -393.166138)
			(xy 303.167927 -393.121606) (xy 303.152483 -393.074074) (xy 303.144664 -393.024711) (xy 301.568368 -393.024711)
			(xy 301.527739 -393.045411) (xy 301.478302 -393.061471) (xy 301.426962 -393.069599) (xy 301.400972 -393.07008)
			(xy 301.393606 -393.07008) (xy 301.383192 -393.069826) (xy 301.364396 -393.077192) (xy 301.30496 -393.135358)
			(xy 301.298011 -393.142784) (xy 301.290145 -393.161519) (xy 301.28972 -393.17168) (xy 301.28972 -393.869164)
			(xy 301.292514 -393.877038) (xy 301.300812 -393.903055) (xy 301.309748 -393.956923) (xy 301.310294 -393.984226)
			(xy 301.310294 -393.985242) (xy 301.309753 -394.012545) (xy 301.300811 -394.066412) (xy 301.292514 -394.09243)
			(xy 301.28972 -394.100304) (xy 301.28972 -394.25753) (xy 302.833786 -394.25753) (xy 302.834349 -394.22995)
			(xy 302.843547 -394.175561) (xy 302.852074 -394.149326) (xy 302.854868 -394.141452) (xy 302.854868 -393.99718)
			(xy 302.855417 -393.980487) (xy 302.86405 -393.948237) (xy 302.880725 -393.919314) (xy 302.904308 -393.895683)
			(xy 302.933198 -393.878949) (xy 302.96543 -393.870251) (xy 302.982122 -393.869672) (xy 303.363122 -393.869672)
			(xy 303.373028 -393.87018) (xy 303.384803 -393.870497) (xy 303.406649 -393.861781) (xy 303.414938 -393.853416)
			(xy 303.47666 -393.784836) (xy 303.48301 -393.761976) (xy 303.482248 -393.758166) (xy 303.482248 -393.757404)
			(xy 303.479123 -393.741331) (xy 303.475814 -393.708753) (xy 303.475644 -393.69238) (xy 303.4761 -393.667589)
			(xy 303.483859 -393.618619) (xy 303.499183 -393.571465) (xy 303.521695 -393.527288) (xy 303.550841 -393.487178)
			(xy 303.585902 -393.45212) (xy 303.626016 -393.422978) (xy 303.670194 -393.400471) (xy 303.71735 -393.385151)
			(xy 303.766321 -393.377397) (xy 303.791112 -393.376912) (xy 303.814725 -393.377336) (xy 303.861424 -393.384385)
			(xy 303.906551 -393.39831) (xy 303.949102 -393.4188) (xy 303.988127 -393.445398) (xy 304.022756 -393.477511)
			(xy 304.052217 -393.514423) (xy 304.064416 -393.534646) (xy 304.073636 -393.551159) (xy 304.08854 -393.585921)
			(xy 304.094134 -393.603988) (xy 304.094642 -393.60602) (xy 304.095658 -393.610084) (xy 304.143577 -393.692888)
			(xy 304.67554 -393.692888) (xy 304.67554 -393.69238) (xy 304.676 -393.667589) (xy 304.683759 -393.618619)
			(xy 304.699083 -393.571465) (xy 304.721594 -393.52729) (xy 304.750739 -393.487179) (xy 304.7858 -393.452121)
			(xy 304.825913 -393.42298) (xy 304.870091 -393.400472) (xy 304.917246 -393.385152) (xy 304.966217 -393.377397)
			(xy 304.991008 -393.376912) (xy 305.016403 -393.377388) (xy 305.066539 -393.385521) (xy 305.114726 -393.401575)
			(xy 305.159722 -393.425136) (xy 305.200365 -393.455597) (xy 305.235607 -393.492172) (xy 305.264539 -393.533917)
			(xy 305.286415 -393.579756) (xy 305.29403 -393.603988) (xy 305.295554 -393.60983) (xy 305.343304 -393.69238)
			(xy 305.875436 -393.69238) (xy 305.875898 -393.667602) (xy 305.88365 -393.618657) (xy 305.898958 -393.571525)
			(xy 305.921447 -393.527367) (xy 305.950564 -393.487267) (xy 305.985592 -393.452213) (xy 306.02567 -393.423067)
			(xy 306.069812 -393.400546) (xy 306.116933 -393.385203) (xy 306.165873 -393.377417) (xy 306.19065 -393.376912)
			(xy 306.191158 -393.376912) (xy 306.216552 -393.377432) (xy 306.266686 -393.385557) (xy 306.314872 -393.401604)
			(xy 306.359867 -393.425159) (xy 306.40051 -393.455614) (xy 306.435754 -393.492183) (xy 306.464687 -393.533923)
			(xy 306.486564 -393.579758) (xy 306.49418 -393.603988) (xy 306.495704 -393.60983) (xy 306.816252 -394.164312)
			(xy 306.820316 -394.16863) (xy 306.836409 -394.186275) (xy 306.863635 -394.225509) (xy 306.884637 -394.268398)
			(xy 306.898935 -394.313962) (xy 306.906201 -394.361161) (xy 306.906676 -394.385038) (xy 306.906676 -394.385546)
			(xy 306.905914 -394.405866) (xy 306.905152 -394.415772) (xy 306.911502 -394.434822) (xy 306.972208 -394.504164)
			(xy 306.989988 -394.513054) (xy 307.000148 -394.513816) (xy 307.025123 -394.516026) (xy 307.073981 -394.527275)
			(xy 307.120468 -394.546052) (xy 307.163433 -394.57189) (xy 307.201812 -394.604149) (xy 307.218588 -394.622782)
			(xy 307.221046 -394.625558) (xy 307.226662 -394.630402) (xy 307.229764 -394.632434) (xy 307.24184 -394.640475)
			(xy 307.261795 -394.661525) (xy 307.275865 -394.686888) (xy 307.283162 -394.71496) (xy 307.283612 -394.729462)
			(xy 307.283612 -394.7414) (xy 307.285136 -394.748004) (xy 307.290328 -394.768376) (xy 307.295938 -394.810042)
			(xy 307.296312 -394.831062) (xy 307.29593 -394.852082) (xy 307.29033 -394.893748) (xy 307.285136 -394.91412)
			(xy 307.283612 -394.920724) (xy 307.283612 -395.034262) (xy 307.283133 -395.04926) (xy 307.275387 -395.078237)
			(xy 307.260411 -395.104226) (xy 307.239225 -395.125458) (xy 307.213269 -395.140491) (xy 307.184308 -395.1483)
			(xy 307.169312 -395.148816) (xy 306.987194 -395.148816) (xy 306.986686 -395.14907) (xy 306.969922 -395.14907)
			(xy 306.969414 -395.148816) (xy 306.787804 -395.148816) (xy 306.772776 -395.148317) (xy 306.74374 -395.140549)
			(xy 306.717699 -395.125542) (xy 306.696421 -395.104313) (xy 306.681353 -395.078307) (xy 306.673518 -395.049289)
			(xy 306.672996 -395.034262) (xy 306.672996 -394.920724) (xy 306.671472 -394.91412) (xy 306.666266 -394.893751)
			(xy 306.660665 -394.852083) (xy 306.660296 -394.831062) (xy 306.661058 -394.808456) (xy 306.66182 -394.79855)
			(xy 306.65547 -394.779246) (xy 306.595272 -394.709904) (xy 306.577238 -394.70076) (xy 306.567332 -394.699998)
			(xy 306.543462 -394.69772) (xy 306.496737 -394.686973) (xy 306.452176 -394.669277) (xy 306.410807 -394.645042)
			(xy 306.373582 -394.614824) (xy 306.34136 -394.57932) (xy 306.314882 -394.539348) (xy 306.29476 -394.495829)
			(xy 306.287678 -394.472922) (xy 306.286154 -394.46708) (xy 305.966368 -393.914122) (xy 305.962304 -393.909804)
			(xy 305.946077 -393.892116) (xy 305.918656 -393.85272) (xy 305.897517 -393.809625) (xy 305.883149 -393.763827)
			(xy 305.875883 -393.71638) (xy 305.875436 -393.69238) (xy 305.343304 -393.69238) (xy 305.615848 -394.16355)
			(xy 305.619912 -394.167868) (xy 305.636113 -394.185545) (xy 305.663512 -394.224893) (xy 305.684644 -394.267933)
			(xy 305.699021 -394.313675) (xy 305.706314 -394.361064) (xy 305.70678 -394.385038) (xy 305.70678 -394.385546)
			(xy 305.706018 -394.405866) (xy 305.705256 -394.415772) (xy 305.711606 -394.434822) (xy 305.772312 -394.504164)
			(xy 305.790092 -394.513054) (xy 305.800252 -394.513816) (xy 305.825227 -394.516023) (xy 305.874085 -394.527274)
			(xy 305.920572 -394.546051) (xy 305.963537 -394.571889) (xy 306.001916 -394.604149) (xy 306.018692 -394.622782)
			(xy 306.02115 -394.625559) (xy 306.026765 -394.630402) (xy 306.029868 -394.632434) (xy 306.041945 -394.640474)
			(xy 306.061899 -394.661524) (xy 306.07597 -394.686888) (xy 306.083266 -394.71496) (xy 306.083716 -394.729462)
			(xy 306.083716 -394.7414) (xy 306.08524 -394.748004) (xy 306.090432 -394.768376) (xy 306.096042 -394.810042)
			(xy 306.096416 -394.831062) (xy 306.096034 -394.852082) (xy 306.090434 -394.893748) (xy 306.08524 -394.91412)
			(xy 306.083716 -394.920724) (xy 306.083716 -395.034262) (xy 306.083233 -395.049259) (xy 306.075487 -395.078236)
			(xy 306.060512 -395.104224) (xy 306.039327 -395.125457) (xy 306.013372 -395.14049) (xy 305.984412 -395.1483)
			(xy 305.969416 -395.148816) (xy 305.787298 -395.148816) (xy 305.78679 -395.14907) (xy 305.770026 -395.14907)
			(xy 305.769518 -395.148816) (xy 305.587908 -395.148816) (xy 305.57288 -395.148313) (xy 305.543845 -395.140547)
			(xy 305.517803 -395.12554) (xy 305.496525 -395.104312) (xy 305.481457 -395.078306) (xy 305.473622 -395.049289)
			(xy 305.4731 -395.034262) (xy 305.4731 -394.920724) (xy 305.471576 -394.91412) (xy 305.46637 -394.893751)
			(xy 305.460769 -394.852083) (xy 305.4604 -394.831062) (xy 305.461162 -394.808456) (xy 305.461924 -394.79855)
			(xy 305.455574 -394.779246) (xy 305.395376 -394.709904) (xy 305.377342 -394.70076) (xy 305.367436 -394.699998)
			(xy 305.343612 -394.697774) (xy 305.296983 -394.687051) (xy 305.252508 -394.669409) (xy 305.211207 -394.645254)
			(xy 305.174028 -394.615139) (xy 305.141822 -394.579755) (xy 305.115329 -394.539913) (xy 305.095156 -394.496527)
			(xy 305.088036 -394.473684) (xy 305.086512 -394.467842) (xy 304.766218 -393.914122) (xy 304.762154 -393.909804)
			(xy 304.746002 -393.892131) (xy 304.718682 -393.852815) (xy 304.697613 -393.809825) (xy 304.683278 -393.764146)
			(xy 304.676005 -393.716825) (xy 304.67554 -393.692888) (xy 304.143577 -393.692888) (xy 304.415952 -394.16355)
			(xy 304.420016 -394.167868) (xy 304.436217 -394.185545) (xy 304.463616 -394.224893) (xy 304.484748 -394.267933)
			(xy 304.499125 -394.313674) (xy 304.506418 -394.361064) (xy 304.506884 -394.385038) (xy 304.506884 -394.385546)
			(xy 304.506122 -394.405866) (xy 304.50536 -394.415772) (xy 304.51171 -394.434822) (xy 304.572416 -394.504164)
			(xy 304.590196 -394.513054) (xy 304.600356 -394.513816) (xy 304.625303 -394.51606) (xy 304.674102 -394.527334)
			(xy 304.720532 -394.546115) (xy 304.763445 -394.571939) (xy 304.801782 -394.604169) (xy 304.818542 -394.622782)
			(xy 304.821006 -394.625553) (xy 304.826617 -394.630401) (xy 304.829718 -394.632434) (xy 304.841756 -394.640501)
			(xy 304.861646 -394.661565) (xy 304.875651 -394.686925) (xy 304.882888 -394.714977) (xy 304.883312 -394.729462)
			(xy 304.883312 -394.7414) (xy 304.88509 -394.748004) (xy 304.890281 -394.768377) (xy 304.895892 -394.810042)
			(xy 304.896266 -394.831062) (xy 304.895886 -394.852082) (xy 304.890285 -394.893749) (xy 304.88509 -394.91412)
			(xy 304.883312 -394.920724) (xy 304.883312 -395.034262) (xy 304.882874 -395.049286) (xy 304.875103 -395.078313)
			(xy 304.860082 -395.104337) (xy 304.838834 -395.125584) (xy 304.812809 -395.140605) (xy 304.783782 -395.148375)
			(xy 304.768758 -395.148816) (xy 304.587148 -395.148816) (xy 304.58664 -395.14907) (xy 304.569876 -395.14907)
			(xy 304.569368 -395.148816) (xy 304.387758 -395.148816) (xy 304.372736 -395.1484) (xy 304.343719 -395.140614)
			(xy 304.317705 -395.125583) (xy 304.296468 -395.104331) (xy 304.281455 -395.078307) (xy 304.273689 -395.049284)
			(xy 304.273204 -395.034262) (xy 304.273204 -394.920724) (xy 304.271426 -394.91412) (xy 304.266219 -394.893751)
			(xy 304.260619 -394.852083) (xy 304.26025 -394.831062) (xy 304.261012 -394.808456) (xy 304.261774 -394.798296)
			(xy 304.255678 -394.7795) (xy 304.202084 -394.717524) (xy 304.195163 -394.710255) (xy 304.177246 -394.701246)
			(xy 304.167286 -394.699998) (xy 304.143473 -394.697816) (xy 304.09688 -394.687053) (xy 304.052444 -394.669384)
			(xy 304.011183 -394.645212) (xy 303.974042 -394.615091) (xy 303.94187 -394.579711) (xy 303.915405 -394.539882)
			(xy 303.895253 -394.496516) (xy 303.88814 -394.473684) (xy 303.886616 -394.467842) (xy 303.569116 -393.919202)
			(xy 303.562258 -393.909804) (xy 303.553876 -393.90066) (xy 303.51349 -393.924028) (xy 303.504838 -393.929631)
			(xy 303.492496 -393.946113) (xy 303.487627 -393.966119) (xy 303.488852 -393.976352) (xy 303.490376 -393.996926)
			(xy 303.490376 -393.997434) (xy 303.490376 -394.201904) (xy 303.491138 -394.205714) (xy 303.493041 -394.21852)
			(xy 303.495079 -394.24433) (xy 303.495202 -394.257276) (xy 303.495202 -394.25753) (xy 303.495032 -394.273119)
			(xy 303.492106 -394.30416) (xy 303.48936 -394.319506) (xy 303.488852 -394.321538) (xy 303.485296 -394.338048)
			(xy 303.484788 -394.339572) (xy 303.480297 -394.356211) (xy 303.468338 -394.388535) (xy 303.460912 -394.404088)
			(xy 303.460912 -394.404342) (xy 303.456911 -394.413623) (xy 303.455716 -394.433781) (xy 303.458626 -394.443458)
			(xy 303.486566 -394.522198) (xy 303.500536 -394.537184) (xy 303.509934 -394.541502) (xy 303.530517 -394.551334)
			(xy 303.568903 -394.575973) (xy 303.603393 -394.605822) (xy 303.618646 -394.622782) (xy 303.621109 -394.625554)
			(xy 303.626721 -394.630401) (xy 303.629822 -394.632434) (xy 303.641861 -394.6405) (xy 303.66175 -394.661564)
			(xy 303.675756 -394.686925) (xy 303.682992 -394.714977) (xy 303.683416 -394.729462) (xy 303.683416 -394.7414)
			(xy 303.685194 -394.748004) (xy 303.690385 -394.768377) (xy 303.695996 -394.810042) (xy 303.69637 -394.831062)
			(xy 303.69599 -394.852082) (xy 303.690389 -394.893749) (xy 303.685194 -394.91412) (xy 303.683416 -394.920724)
			(xy 303.683416 -395.034262) (xy 303.682974 -395.049286) (xy 303.675204 -395.078312) (xy 303.660183 -395.104336)
			(xy 303.638936 -395.125583) (xy 303.612912 -395.140604) (xy 303.583886 -395.148374) (xy 303.568862 -395.148816)
			(xy 303.387252 -395.148816) (xy 303.386744 -395.14907) (xy 303.36998 -395.14907) (xy 303.369472 -395.148816)
			(xy 303.187862 -395.148816) (xy 303.17284 -395.148397) (xy 303.143823 -395.140611) (xy 303.117809 -395.125581)
			(xy 303.096573 -395.10433) (xy 303.081559 -395.078306) (xy 303.073793 -395.049284) (xy 303.073308 -395.034262)
			(xy 303.073308 -394.920724) (xy 303.07153 -394.91412) (xy 303.066323 -394.893751) (xy 303.060723 -394.852083)
			(xy 303.060354 -394.831062) (xy 303.060722 -394.810041) (xy 303.066332 -394.768375) (xy 303.07153 -394.748004)
			(xy 303.073308 -394.7414) (xy 303.073308 -394.729462) (xy 303.073506 -394.718867) (xy 303.077338 -394.698029)
			(xy 303.080928 -394.68806) (xy 303.084484 -394.678916) (xy 303.08423 -394.659612) (xy 303.050194 -394.576554)
			(xy 303.03724 -394.562838) (xy 303.028096 -394.558774) (xy 303.003636 -394.547144) (xy 302.958594 -394.51707)
			(xy 302.919056 -394.480057) (xy 302.886079 -394.437094) (xy 302.860546 -394.389332) (xy 302.843139 -394.338046)
			(xy 302.834323 -394.28461) (xy 302.833786 -394.25753) (xy 301.28972 -394.25753) (xy 301.28972 -394.59154)
			(xy 301.289839 -394.597044) (xy 301.29214 -394.607809) (xy 301.294292 -394.612876) (xy 301.29861 -394.62202)
			(xy 301.30623 -394.628878) (xy 301.325852 -394.647796) (xy 301.359235 -394.690879) (xy 301.385092 -394.738857)
			(xy 301.402722 -394.79043) (xy 301.411645 -394.844197) (xy 301.412148 -394.871448) (xy 301.412148 -394.871956)
			(xy 301.411579 -394.899093) (xy 301.402668 -394.952632) (xy 301.385128 -395.003995) (xy 301.372778 -395.028166)
			(xy 301.368714 -395.035532) (xy 301.36592 -395.051788) (xy 301.37862 -395.129258) (xy 301.38624 -395.14399)
			(xy 301.392082 -395.149578) (xy 301.404108 -395.161885) (xy 301.421724 -395.191427) (xy 301.430875 -395.224583)
			(xy 301.431452 -395.24178) (xy 301.431452 -395.377162) (xy 301.432468 -395.384274) (xy 301.432468 -395.384528)
			(xy 301.433896 -395.395713) (xy 301.43542 -395.418211) (xy 301.435516 -395.429486) (xy 301.435516 -395.429994)
			(xy 301.435431 -395.441269) (xy 301.433903 -395.463768) (xy 301.432468 -395.474952) (xy 301.432468 -395.475206)
			(xy 301.431452 -395.482318) (xy 301.431452 -395.62278) (xy 301.430909 -395.639499) (xy 301.422261 -395.671799)
			(xy 301.405549 -395.70076) (xy 301.381911 -395.72441) (xy 301.352958 -395.741137) (xy 301.320663 -395.749801)
			(xy 301.303944 -395.750288) (xy 301.18685 -395.750288) (xy 301.181008 -395.751558) (xy 301.155942 -395.756993)
			(xy 301.104808 -395.760961) (xy 301.053674 -395.756993) (xy 301.028608 -395.751558) (xy 301.022766 -395.750288)
			(xy 300.999144 -395.750288) (xy 300.98184 -395.7497) (xy 300.948507 -395.740391) (xy 300.918898 -395.722474)
			(xy 300.895189 -395.697263) (xy 300.886622 -395.682216) (xy 300.884625 -395.678636) (xy 300.879651 -395.672123)
			(xy 300.876716 -395.669262) (xy 300.85653 -395.649191) (xy 300.82267 -395.603438) (xy 300.797138 -395.552566)
			(xy 300.788324 -395.525498) (xy 300.784768 -395.51356) (xy 300.767496 -395.49578) (xy 300.664372 -395.461998)
			(xy 300.639988 -395.466062) (xy 300.630082 -395.473428) (xy 300.606262 -395.490723) (xy 300.555028 -395.519708)
			(xy 300.500497 -395.541879) (xy 300.443572 -395.556869) (xy 300.385195 -395.564431) (xy 300.355762 -395.564868)
			(xy 300.326464 -395.564401) (xy 300.268347 -395.556931) (xy 300.211656 -395.542116) (xy 300.157314 -395.520199)
			(xy 300.106208 -395.491536) (xy 300.05917 -395.456595) (xy 300.037754 -395.436598) (xy 300.030896 -395.429994)
			(xy 300.003972 -395.418818) (xy 299.999285 -395.417022) (xy 299.989433 -395.415108) (xy 299.984414 -395.415008)
			(xy 299.734732 -395.415008) (xy 299.726604 -395.417802) (xy 299.716453 -395.421174) (xy 299.695387 -395.424874)
			(xy 299.684694 -395.425168) (xy 299.40885 -395.425168) (xy 299.404174 -395.425251) (xy 299.394971 -395.426912)
			(xy 299.390562 -395.42847) (xy 299.380402 -395.432534) (xy 299.214286 -395.598904) (xy 299.206876 -395.605586)
			(xy 299.188439 -395.613162) (xy 299.178472 -395.613636) (xy 299.014134 -395.613636) (xy 299.00407 -395.614072)
			(xy 298.985486 -395.621807) (xy 298.978066 -395.628622) (xy 298.748704 -395.857984) (xy 298.74187 -395.865387)
			(xy 298.734166 -395.883985) (xy 298.733718 -395.894052) (xy 298.733718 -396.679674) (xy 299.808644 -396.679674)
			(xy 299.812715 -396.624052) (xy 299.824841 -396.569615) (xy 299.844764 -396.517524) (xy 299.87206 -396.468889)
			(xy 299.906146 -396.424746) (xy 299.946295 -396.386037) (xy 299.991653 -396.353586) (xy 300.041253 -396.328085)
			(xy 300.094037 -396.310078) (xy 300.14888 -396.299948) (xy 300.204614 -396.297911) (xy 300.260051 -396.304011)
			(xy 300.314008 -396.318117) (xy 300.365337 -396.339929) (xy 300.412943 -396.368983) (xy 300.455811 -396.404658)
			(xy 300.493028 -396.446195) (xy 300.523801 -396.492708) (xy 300.547473 -396.543205) (xy 300.563541 -396.596612)
			(xy 300.571661 -396.651788) (xy 300.572142 -396.67815) (xy 300.7741 -396.67815) (xy 300.774275 -396.661462)
			(xy 300.777587 -396.628251) (xy 300.780704 -396.611856) (xy 300.78172 -396.606776) (xy 300.78172 -396.571978)
			(xy 300.782336 -396.554052) (xy 300.792291 -396.519609) (xy 300.811412 -396.489281) (xy 300.838199 -396.465449)
			(xy 300.85411 -396.45717) (xy 300.856142 -396.456154) (xy 300.859562 -396.454242) (xy 300.865818 -396.449526)
			(xy 300.868588 -396.446756) (xy 300.88739 -396.428318) (xy 300.92972 -396.397) (xy 300.976481 -396.37279)
			(xy 301.026489 -396.356302) (xy 301.07848 -396.347953) (xy 301.104808 -396.347442) (xy 301.13263 -396.348013)
			(xy 301.187488 -396.357334) (xy 301.24001 -396.375711) (xy 301.288713 -396.402625) (xy 301.332219 -396.437316)
			(xy 301.351188 -396.457678) (xy 301.36084 -396.46606) (xy 301.37285 -396.474592) (xy 301.392927 -396.496141)
			(xy 301.407552 -396.521706) (xy 301.41595 -396.549935) (xy 301.417228 -396.564612) (xy 301.417482 -396.567914)
			(xy 301.419514 -396.577312) (xy 301.426936 -396.601861) (xy 301.434974 -396.65251) (xy 301.435516 -396.67815)
			(xy 301.435007 -396.703515) (xy 301.433898 -396.710662) (xy 303.200308 -396.710662) (xy 303.200674 -396.689641)
			(xy 303.206285 -396.647975) (xy 303.211484 -396.627604) (xy 303.213008 -396.621) (xy 303.213008 -396.507462)
			(xy 303.213499 -396.492468) (xy 303.221256 -396.463499) (xy 303.236235 -396.437519) (xy 303.257417 -396.41629)
			(xy 303.283364 -396.401254) (xy 303.312315 -396.393433) (xy 303.327308 -396.392908) (xy 303.509426 -396.392908)
			(xy 303.509934 -396.392654) (xy 303.526698 -396.392654) (xy 303.527206 -396.392908) (xy 303.708816 -396.392908)
			(xy 303.723847 -396.393366) (xy 303.752887 -396.40114) (xy 303.778931 -396.416156) (xy 303.800208 -396.437393)
			(xy 303.815274 -396.463407) (xy 303.823105 -396.492432) (xy 303.823624 -396.507462) (xy 303.823624 -396.621)
			(xy 303.825148 -396.627604) (xy 303.83034 -396.647976) (xy 303.83595 -396.689642) (xy 303.836324 -396.710662)
			(xy 304.400204 -396.710662) (xy 304.40057 -396.689641) (xy 304.406181 -396.647975) (xy 304.41138 -396.627604)
			(xy 304.412904 -396.621) (xy 304.412904 -396.507462) (xy 304.413399 -396.492468) (xy 304.421156 -396.4635)
			(xy 304.436134 -396.43752) (xy 304.457315 -396.416291) (xy 304.483261 -396.401255) (xy 304.512211 -396.393433)
			(xy 304.527204 -396.392908) (xy 304.709322 -396.392908) (xy 304.70983 -396.392654) (xy 304.726594 -396.392654)
			(xy 304.727102 -396.392908) (xy 304.908712 -396.392908) (xy 304.923743 -396.39337) (xy 304.952783 -396.401143)
			(xy 304.978826 -396.416158) (xy 305.000104 -396.437394) (xy 305.01517 -396.463408) (xy 305.023001 -396.492432)
			(xy 305.02352 -396.507462) (xy 305.02352 -396.621) (xy 305.025044 -396.627604) (xy 305.030236 -396.647976)
			(xy 305.035846 -396.689642) (xy 305.03622 -396.710662) (xy 305.600354 -396.710662) (xy 305.600722 -396.689641)
			(xy 305.606332 -396.647975) (xy 305.61153 -396.627604) (xy 305.613308 -396.621) (xy 305.613308 -396.507462)
			(xy 305.613802 -396.492447) (xy 305.621581 -396.463441) (xy 305.6366 -396.437435) (xy 305.657835 -396.4162)
			(xy 305.683841 -396.401181) (xy 305.712847 -396.393402) (xy 305.727862 -396.392908) (xy 305.909472 -396.392908)
			(xy 305.90998 -396.392654) (xy 305.926744 -396.392654) (xy 305.927252 -396.392908) (xy 306.108862 -396.392908)
			(xy 306.123874 -396.393469) (xy 306.152877 -396.40123) (xy 306.178883 -396.416233) (xy 306.20012 -396.437456)
			(xy 306.215141 -396.463452) (xy 306.222921 -396.49245) (xy 306.223416 -396.507462) (xy 306.223416 -396.621)
			(xy 306.225194 -396.627604) (xy 306.230385 -396.647977) (xy 306.235996 -396.689642) (xy 306.23637 -396.710662)
			(xy 306.80025 -396.710662) (xy 306.800618 -396.689641) (xy 306.806228 -396.647975) (xy 306.811426 -396.627604)
			(xy 306.813204 -396.621) (xy 306.813204 -396.507462) (xy 306.813702 -396.492447) (xy 306.821481 -396.463442)
			(xy 306.836499 -396.437436) (xy 306.857733 -396.416201) (xy 306.883738 -396.401182) (xy 306.912743 -396.393403)
			(xy 306.927758 -396.392908) (xy 307.109368 -396.392908) (xy 307.109876 -396.392654) (xy 307.12664 -396.392654)
			(xy 307.127148 -396.392908) (xy 307.308758 -396.392908) (xy 307.323776 -396.393428) (xy 307.35279 -396.401191)
			(xy 307.378806 -396.4162) (xy 307.400051 -396.43743) (xy 307.415078 -396.463436) (xy 307.422861 -396.492445)
			(xy 307.423312 -396.507462) (xy 307.423312 -396.621) (xy 307.42509 -396.627604) (xy 307.430281 -396.647977)
			(xy 307.435892 -396.689642) (xy 307.436266 -396.710662) (xy 307.436266 -396.71117) (xy 307.436096 -396.725795)
			(xy 307.433429 -396.754924) (xy 307.430932 -396.769336) (xy 307.429564 -396.77851) (xy 307.432839 -396.796753)
			(xy 307.437282 -396.804896) (xy 307.453792 -396.83182) (xy 307.458944 -396.839612) (xy 307.473682 -396.851067)
			(xy 307.482494 -396.854172) (xy 307.507373 -396.862243) (xy 307.554253 -396.88543) (xy 307.596665 -396.916032)
			(xy 307.633449 -396.953211) (xy 307.663597 -396.995949) (xy 307.686282 -397.043073) (xy 307.694076 -397.06804)
			(xy 307.6956 -397.073882) (xy 307.830474 -397.307308) (xy 307.835177 -397.314703) (xy 307.848516 -397.326048)
			(xy 307.864905 -397.332212) (xy 307.873654 -397.332708) (xy 307.960776 -397.333978) (xy 307.969521 -397.333748)
			(xy 307.986086 -397.328174) (xy 307.999792 -397.317329) (xy 308.004718 -397.310102) (xy 308.016896 -397.291349)
			(xy 308.045889 -397.25731) (xy 308.079535 -397.227859) (xy 308.117113 -397.203627) (xy 308.137306 -397.194024)
			(xy 308.26202 -397.137636) (xy 308.277514 -397.117316) (xy 308.279546 -397.10487) (xy 308.280308 -397.100552)
			(xy 308.281669 -397.091212) (xy 308.27813 -397.072682) (xy 308.27345 -397.064484) (xy 308.25694 -397.037814)
			(xy 308.25173 -397.030117) (xy 308.23701 -397.01879) (xy 308.228238 -397.015716) (xy 308.206658 -397.008976)
			(xy 308.165534 -396.990198) (xy 308.127481 -396.965788) (xy 308.093267 -396.936238) (xy 308.078124 -396.91945)
			(xy 308.075661 -396.916678) (xy 308.070049 -396.911831) (xy 308.066948 -396.909798) (xy 308.054813 -396.901704)
			(xy 308.034723 -396.880569) (xy 308.020574 -396.855072) (xy 308.013271 -396.826842) (xy 308.012846 -396.812262)
			(xy 308.012846 -396.799816) (xy 308.011068 -396.793466) (xy 308.00594 -396.773151) (xy 308.000462 -396.731612)
			(xy 308.000146 -396.710662) (xy 308.000482 -396.689714) (xy 308.005956 -396.648176) (xy 308.011068 -396.627858)
			(xy 308.012846 -396.621508) (xy 308.012846 -396.164816) (xy 308.011068 -396.158466) (xy 308.00594 -396.138151)
			(xy 308.000462 -396.096612) (xy 308.000146 -396.075662) (xy 308.000482 -396.054714) (xy 308.005956 -396.013176)
			(xy 308.011068 -395.992858) (xy 308.012846 -395.986508) (xy 308.012846 -395.974062) (xy 308.01333 -395.958598)
			(xy 308.021557 -395.928784) (xy 308.037388 -395.902213) (xy 308.05969 -395.880784) (xy 308.073044 -395.87297)
			(xy 308.0766 -395.868906) (xy 308.083954 -395.859384) (xy 308.089651 -395.836044) (xy 308.087522 -395.824202)
			(xy 308.08041 -395.792706) (xy 308.077123 -395.781199) (xy 308.061887 -395.762785) (xy 308.0512 -395.7574)
			(xy 308.029717 -395.747579) (xy 307.989651 -395.722561) (xy 307.953733 -395.691886) (xy 307.937916 -395.674342)
			(xy 307.935455 -395.671568) (xy 307.929842 -395.666723) (xy 307.92674 -395.66469) (xy 307.914676 -395.656633)
			(xy 307.89472 -395.635588) (xy 307.880646 -395.61023) (xy 307.873345 -395.582162) (xy 307.872892 -395.567662)
			(xy 307.872892 -395.555724) (xy 307.871368 -395.54912) (xy 307.866162 -395.528751) (xy 307.860561 -395.487083)
			(xy 307.860192 -395.466062) (xy 307.860559 -395.445041) (xy 307.866169 -395.403375) (xy 307.871368 -395.383004)
			(xy 307.872892 -395.3764) (xy 307.872892 -395.262862) (xy 307.873559 -395.244744) (xy 307.884809 -395.210299)
			(xy 307.89499 -395.195298) (xy 307.89949 -395.188629) (xy 307.904535 -395.173363) (xy 307.904896 -395.165326)
			(xy 307.904896 -395.131798) (xy 307.904601 -395.123749) (xy 307.899549 -395.108466) (xy 307.89499 -395.101826)
			(xy 307.884907 -395.086774) (xy 307.873649 -395.052363) (xy 307.872892 -395.034262) (xy 307.872892 -394.920724)
			(xy 307.871368 -394.91412) (xy 307.866162 -394.893751) (xy 307.860561 -394.852083) (xy 307.860192 -394.831062)
			(xy 307.860954 -394.808456) (xy 307.861716 -394.798296) (xy 307.85562 -394.7795) (xy 307.802026 -394.717524)
			(xy 307.79509 -394.710272) (xy 307.777184 -394.701253) (xy 307.767228 -394.699998) (xy 307.743418 -394.697782)
			(xy 307.696826 -394.687026) (xy 307.652391 -394.669362) (xy 307.61113 -394.645195) (xy 307.573988 -394.615079)
			(xy 307.541815 -394.579703) (xy 307.515349 -394.539877) (xy 307.495195 -394.496514) (xy 307.488082 -394.473684)
			(xy 307.486558 -394.467842) (xy 307.166264 -393.914122) (xy 307.1622 -393.909804) (xy 307.145972 -393.892117)
			(xy 307.118551 -393.85272) (xy 307.097413 -393.809626) (xy 307.083045 -393.763827) (xy 307.075779 -393.71638)
			(xy 307.075332 -393.69238) (xy 307.075798 -393.667603) (xy 307.083549 -393.618657) (xy 307.098858 -393.571526)
			(xy 307.121346 -393.527368) (xy 307.150463 -393.487269) (xy 307.18549 -393.452215) (xy 307.225568 -393.423069)
			(xy 307.26971 -393.400547) (xy 307.31683 -393.385204) (xy 307.365769 -393.377417) (xy 307.390546 -393.376912)
			(xy 307.391054 -393.376912) (xy 307.416448 -393.377436) (xy 307.466581 -393.38556) (xy 307.514767 -393.401606)
			(xy 307.559763 -393.42516) (xy 307.600406 -393.455615) (xy 307.635649 -393.492184) (xy 307.664583 -393.533924)
			(xy 307.68646 -393.579758) (xy 307.694076 -393.603988) (xy 307.6956 -393.60983) (xy 308.015894 -394.16355)
			(xy 308.019958 -394.167868) (xy 308.036115 -394.18557) (xy 308.063458 -394.22493) (xy 308.084537 -394.26797)
			(xy 308.098869 -394.313702) (xy 308.106122 -394.361076) (xy 308.106572 -394.385038) (xy 308.106572 -394.385546)
			(xy 308.106064 -394.405866) (xy 308.105302 -394.415772) (xy 308.111652 -394.434822) (xy 308.172358 -394.504164)
			(xy 308.190138 -394.513054) (xy 308.200298 -394.513816) (xy 308.225247 -394.516035) (xy 308.274047 -394.527315)
			(xy 308.320477 -394.546102) (xy 308.36339 -394.571932) (xy 308.401725 -394.604167) (xy 308.418484 -394.622782)
			(xy 308.420943 -394.625558) (xy 308.426558 -394.630402) (xy 308.42966 -394.632434) (xy 308.441735 -394.640476)
			(xy 308.46169 -394.661525) (xy 308.475761 -394.686888) (xy 308.483058 -394.71496) (xy 308.483508 -394.729462)
			(xy 308.483508 -394.7414) (xy 308.485032 -394.748004) (xy 308.490224 -394.768376) (xy 308.495834 -394.810042)
			(xy 308.496208 -394.831062) (xy 308.495826 -394.852082) (xy 308.490226 -394.893748) (xy 308.485032 -394.91412)
			(xy 308.483508 -394.920724) (xy 308.483508 -394.981176) (xy 308.48394 -394.991197) (xy 308.491603 -395.009715)
			(xy 308.505772 -395.023888) (xy 308.524287 -395.031557) (xy 308.534308 -395.031976) (xy 308.538118 -395.031976)
			(xy 308.542182 -395.031214) (xy 308.553851 -395.02946) (xy 308.577373 -395.027553) (xy 308.589172 -395.027404)
			(xy 309.022496 -395.027404) (xy 309.032503 -395.026909) (xy 309.050994 -395.019251) (xy 309.065147 -395.005101)
			(xy 309.072807 -394.986611) (xy 309.073296 -394.976604) (xy 309.073296 -394.920724) (xy 309.071518 -394.91412)
			(xy 309.066311 -394.893751) (xy 309.060711 -394.852083) (xy 309.060342 -394.831062) (xy 309.061104 -394.808456)
			(xy 309.061866 -394.79855) (xy 309.055516 -394.779246) (xy 308.995318 -394.709904) (xy 308.977284 -394.70076)
			(xy 308.967378 -394.699998) (xy 308.943549 -394.697821) (xy 308.896919 -394.68709) (xy 308.852443 -394.66944)
			(xy 308.811143 -394.645278) (xy 308.773964 -394.615156) (xy 308.74176 -394.579766) (xy 308.715268 -394.539919)
			(xy 308.695097 -394.496529) (xy 308.687978 -394.473684) (xy 308.686454 -394.467842) (xy 308.36616 -393.914122)
			(xy 308.362096 -393.909804) (xy 308.345867 -393.892118) (xy 308.318447 -393.852721) (xy 308.297309 -393.809626)
			(xy 308.282941 -393.763827) (xy 308.275675 -393.71638) (xy 308.275228 -393.69238) (xy 308.275698 -393.667603)
			(xy 308.283449 -393.618658) (xy 308.298757 -393.571527) (xy 308.321246 -393.527369) (xy 308.350362 -393.48727)
			(xy 308.385389 -393.452216) (xy 308.425466 -393.42307) (xy 308.469607 -393.400548) (xy 308.516726 -393.385205)
			(xy 308.565665 -393.377417) (xy 308.590442 -393.376912) (xy 308.59095 -393.376912) (xy 308.616344 -393.377439)
			(xy 308.666477 -393.385563) (xy 308.714663 -393.401609) (xy 308.759658 -393.425162) (xy 308.800302 -393.455616)
			(xy 308.835545 -393.492185) (xy 308.864479 -393.533924) (xy 308.886356 -393.579758) (xy 308.893972 -393.603988)
			(xy 308.895496 -393.60983) (xy 309.21579 -394.16355) (xy 309.219854 -394.167868) (xy 309.23601 -394.185571)
			(xy 309.263354 -394.22493) (xy 309.284433 -394.26797) (xy 309.298765 -394.313703) (xy 309.306018 -394.361076)
			(xy 309.306468 -394.385038) (xy 309.306468 -394.385546) (xy 309.30596 -394.405866) (xy 309.305198 -394.415772)
			(xy 309.311548 -394.434822) (xy 309.372254 -394.504164) (xy 309.390034 -394.513054) (xy 309.400194 -394.513816)
			(xy 309.425172 -394.515998) (xy 309.47403 -394.527255) (xy 309.520517 -394.546038) (xy 309.563482 -394.571882)
			(xy 309.601859 -394.604147) (xy 309.618634 -394.622782) (xy 309.621099 -394.625552) (xy 309.62671 -394.6304)
			(xy 309.62981 -394.632434) (xy 309.641846 -394.640503) (xy 309.661737 -394.661566) (xy 309.675743 -394.686925)
			(xy 309.68298 -394.714977) (xy 309.683404 -394.729462) (xy 309.683404 -394.7414) (xy 309.685182 -394.748004)
			(xy 309.690375 -394.768376) (xy 309.695984 -394.810042) (xy 309.696358 -394.831062) (xy 309.695975 -394.852082)
			(xy 309.690375 -394.893748) (xy 309.685182 -394.91412) (xy 309.683404 -394.920724) (xy 309.683404 -394.976604)
			(xy 309.683885 -394.986612) (xy 309.691547 -395.005105) (xy 309.705702 -395.019258) (xy 309.724196 -395.026917)
			(xy 309.734204 -395.027404) (xy 309.811166 -395.027404) (xy 309.840626 -395.028125) (xy 309.898438 -395.039513)
			(xy 309.925974 -395.05001) (xy 309.935372 -395.05382) (xy 310.23687 -395.05382) (xy 310.243247 -395.05363)
			(xy 310.25559 -395.050408) (xy 310.261254 -395.04747) (xy 310.273192 -395.041374) (xy 310.273192 -394.920724)
			(xy 310.271414 -394.91412) (xy 310.266207 -394.893751) (xy 310.260607 -394.852083) (xy 310.260238 -394.831062)
			(xy 310.261 -394.808456) (xy 310.261762 -394.798296) (xy 310.255666 -394.7795) (xy 310.202072 -394.717524)
			(xy 310.195155 -394.71025) (xy 310.177235 -394.701244) (xy 310.167274 -394.699998) (xy 310.14346 -394.697826)
			(xy 310.096866 -394.687061) (xy 310.052431 -394.66939) (xy 310.01117 -394.645217) (xy 309.974029 -394.615094)
			(xy 309.941857 -394.579713) (xy 309.915393 -394.539883) (xy 309.895241 -394.496516) (xy 309.888128 -394.473684)
			(xy 309.886604 -394.467842) (xy 309.56631 -393.914122) (xy 309.562246 -393.909804) (xy 309.546093 -393.892132)
			(xy 309.518774 -393.852816) (xy 309.497705 -393.809825) (xy 309.48337 -393.764146) (xy 309.476097 -393.716826)
			(xy 309.475632 -393.692888) (xy 309.475632 -393.69238) (xy 309.4761 -393.66759) (xy 309.483858 -393.61862)
			(xy 309.499182 -393.571467) (xy 309.521693 -393.527292) (xy 309.550837 -393.487182) (xy 309.585897 -393.452124)
			(xy 309.626009 -393.422983) (xy 309.670186 -393.400474) (xy 309.71734 -393.385154) (xy 309.76631 -393.377398)
			(xy 309.7911 -393.376912) (xy 309.816495 -393.377395) (xy 309.866631 -393.385527) (xy 309.914818 -393.40158)
			(xy 309.959813 -393.42514) (xy 310.000456 -393.4556) (xy 310.035698 -393.492174) (xy 310.064631 -393.533918)
			(xy 310.086507 -393.579756) (xy 310.094122 -393.603988) (xy 310.095646 -393.60983) (xy 310.41594 -394.16355)
			(xy 310.420004 -394.167868) (xy 310.436203 -394.185546) (xy 310.463603 -394.224894) (xy 310.484735 -394.267934)
			(xy 310.499113 -394.313675) (xy 310.506406 -394.361065) (xy 310.506872 -394.385038) (xy 310.506872 -394.385546)
			(xy 310.50611 -394.405866) (xy 310.505348 -394.415772) (xy 310.511698 -394.434822) (xy 310.572404 -394.504164)
			(xy 310.590184 -394.513054) (xy 310.600344 -394.513816) (xy 310.625296 -394.516007) (xy 310.674097 -394.527294)
			(xy 310.720527 -394.546088) (xy 310.763438 -394.571924) (xy 310.801772 -394.604164) (xy 310.81853 -394.622782)
			(xy 310.820995 -394.625552) (xy 310.826606 -394.6304) (xy 310.829706 -394.632434) (xy 310.841742 -394.640505)
			(xy 310.861632 -394.661567) (xy 310.875639 -394.686926) (xy 310.882876 -394.714977) (xy 310.8833 -394.729462)
			(xy 310.8833 -394.7414) (xy 310.885078 -394.748004) (xy 310.89027 -394.768376) (xy 310.89588 -394.810042)
			(xy 310.896254 -394.831062) (xy 310.895871 -394.852082) (xy 310.890271 -394.893748) (xy 310.885078 -394.91412)
			(xy 310.8833 -394.920724) (xy 310.8833 -394.958824) (xy 310.883768 -394.968833) (xy 310.891436 -394.987326)
			(xy 310.905595 -395.001478) (xy 310.924091 -395.009136) (xy 310.9341 -395.009624) (xy 311.422288 -395.009624)
			(xy 311.432292 -395.009103) (xy 311.450779 -395.001452) (xy 311.464931 -394.987309) (xy 311.472596 -394.968828)
			(xy 311.473088 -394.958824) (xy 311.473088 -394.920724) (xy 311.471564 -394.91412) (xy 311.466358 -394.893751)
			(xy 311.460757 -394.852083) (xy 311.460388 -394.831062) (xy 311.46115 -394.808456) (xy 311.461912 -394.79855)
			(xy 311.455562 -394.779246) (xy 311.395364 -394.709904) (xy 311.37733 -394.70076) (xy 311.367424 -394.699998)
			(xy 311.343599 -394.697784) (xy 311.29697 -394.687059) (xy 311.252495 -394.669416) (xy 311.211194 -394.645259)
			(xy 311.174014 -394.615142) (xy 311.141809 -394.579757) (xy 311.115316 -394.539914) (xy 311.095144 -394.496528)
			(xy 311.088024 -394.473684) (xy 311.0865 -394.467842) (xy 310.766206 -393.914122) (xy 310.762142 -393.909804)
			(xy 310.745988 -393.892133) (xy 310.718669 -393.852816) (xy 310.697601 -393.809825) (xy 310.683266 -393.764146)
			(xy 310.675993 -393.716826) (xy 310.675528 -393.692888) (xy 310.675528 -393.69238) (xy 310.676 -393.66759)
			(xy 310.683758 -393.618621) (xy 310.699082 -393.571468) (xy 310.721592 -393.527293) (xy 310.750736 -393.487183)
			(xy 310.785795 -393.452126) (xy 310.825907 -393.422984) (xy 310.870083 -393.400475) (xy 310.917236 -393.385155)
			(xy 310.966206 -393.377398) (xy 310.990996 -393.376912) (xy 311.016391 -393.377399) (xy 311.066526 -393.38553)
			(xy 311.114713 -393.401582) (xy 311.159708 -393.425142) (xy 311.200352 -393.455601) (xy 311.235594 -393.492175)
			(xy 311.264527 -393.533919) (xy 311.286403 -393.579756) (xy 311.294018 -393.603988) (xy 311.295542 -393.60983)
			(xy 311.615836 -394.16355) (xy 311.6199 -394.167868) (xy 311.636099 -394.185547) (xy 311.663499 -394.224894)
			(xy 311.684631 -394.267934) (xy 311.699009 -394.313675) (xy 311.706302 -394.361065) (xy 311.706768 -394.385038)
			(xy 311.706768 -394.385546) (xy 311.706006 -394.405866) (xy 311.705244 -394.415772) (xy 311.711594 -394.434822)
			(xy 311.7723 -394.504164) (xy 311.79008 -394.513054) (xy 311.80024 -394.513816) (xy 311.825215 -394.516031)
			(xy 311.874072 -394.527279) (xy 311.920559 -394.546054) (xy 311.963524 -394.571891) (xy 312.001904 -394.60415)
			(xy 312.01868 -394.622782) (xy 312.021139 -394.625557) (xy 312.026754 -394.630402) (xy 312.029856 -394.632434)
			(xy 312.04193 -394.640478) (xy 312.061886 -394.661526) (xy 312.075957 -394.686889) (xy 312.083254 -394.714961)
			(xy 312.083704 -394.729462) (xy 312.083704 -394.7414) (xy 312.085228 -394.748004) (xy 312.090419 -394.768376)
			(xy 312.09603 -394.810042) (xy 312.096404 -394.831062) (xy 312.096023 -394.852082) (xy 312.090422 -394.893748)
			(xy 312.085228 -394.91412) (xy 312.083704 -394.920724) (xy 312.083704 -394.958824) (xy 312.084168 -394.968834)
			(xy 312.091837 -394.987327) (xy 312.105997 -395.001479) (xy 312.124494 -395.009137) (xy 312.134504 -395.009624)
			(xy 312.622184 -395.009624) (xy 312.632188 -395.009099) (xy 312.650675 -395.00145) (xy 312.664827 -394.987308)
			(xy 312.672492 -394.968827) (xy 312.672984 -394.958824) (xy 312.672984 -394.920724) (xy 312.67146 -394.91412)
			(xy 312.666254 -394.893751) (xy 312.660653 -394.852083) (xy 312.660284 -394.831062) (xy 312.661046 -394.808456)
			(xy 312.661808 -394.79855) (xy 312.655458 -394.779246) (xy 312.59526 -394.709904) (xy 312.577226 -394.70076)
			(xy 312.56732 -394.699998) (xy 312.543449 -394.69773) (xy 312.496723 -394.686981) (xy 312.452162 -394.669284)
			(xy 312.410793 -394.645046) (xy 312.373569 -394.614827) (xy 312.341347 -394.579322) (xy 312.31487 -394.539349)
			(xy 312.294747 -394.49583) (xy 312.287666 -394.472922) (xy 312.286142 -394.46708) (xy 311.966356 -393.914122)
			(xy 311.962292 -393.909804) (xy 311.946063 -393.892118) (xy 311.918642 -393.852721) (xy 311.897504 -393.809626)
			(xy 311.883137 -393.763827) (xy 311.875871 -393.71638) (xy 311.875424 -393.69238) (xy 311.875898 -393.667603)
			(xy 311.883649 -393.618659) (xy 311.898957 -393.571528) (xy 311.921445 -393.52737) (xy 311.95056 -393.487271)
			(xy 311.985587 -393.452218) (xy 312.025664 -393.423072) (xy 312.069804 -393.40055) (xy 312.116923 -393.385206)
			(xy 312.165861 -393.377418) (xy 312.190638 -393.376912) (xy 312.191146 -393.376912) (xy 312.216543 -393.377355)
			(xy 312.26668 -393.385493) (xy 312.314868 -393.401553) (xy 312.359863 -393.425119) (xy 312.400506 -393.455585)
			(xy 312.435747 -393.492164) (xy 312.464678 -393.533913) (xy 312.486553 -393.579754) (xy 312.494168 -393.603988)
			(xy 312.495692 -393.60983) (xy 312.81624 -394.164312) (xy 312.820304 -394.16863) (xy 312.836395 -394.186277)
			(xy 312.863622 -394.22551) (xy 312.884624 -394.268398) (xy 312.898922 -394.313962) (xy 312.906189 -394.361161)
			(xy 312.906664 -394.385038) (xy 312.906664 -394.385546) (xy 312.905902 -394.405866) (xy 312.90514 -394.415772)
			(xy 312.91149 -394.434822) (xy 312.972196 -394.504164) (xy 312.989976 -394.513054) (xy 313.000136 -394.513816)
			(xy 313.02511 -394.516033) (xy 313.073968 -394.527281) (xy 313.120455 -394.546056) (xy 313.16342 -394.571892)
			(xy 313.201799 -394.60415) (xy 313.218576 -394.622782) (xy 313.221036 -394.625557) (xy 313.22665 -394.630402)
			(xy 313.229752 -394.632434) (xy 313.241825 -394.640479) (xy 313.261781 -394.661527) (xy 313.275853 -394.686889)
			(xy 313.28315 -394.714961) (xy 313.2836 -394.729462) (xy 313.2836 -394.7414) (xy 313.285124 -394.748004)
			(xy 313.290315 -394.768377) (xy 313.295926 -394.810042) (xy 313.2963 -394.831062) (xy 313.295919 -394.852082)
			(xy 313.290318 -394.893748) (xy 313.285124 -394.91412) (xy 313.2836 -394.920724) (xy 313.2836 -394.958824)
			(xy 313.284068 -394.968833) (xy 313.291736 -394.987326) (xy 313.305895 -395.001478) (xy 313.324391 -395.009136)
			(xy 313.3344 -395.009624) (xy 313.835542 -395.009624) (xy 313.8449 -395.009701) (xy 313.863582 -395.010845)
			(xy 313.87288 -395.01191) (xy 313.87288 -394.920724) (xy 313.871356 -394.91412) (xy 313.86615 -394.893751)
			(xy 313.860549 -394.852083) (xy 313.86018 -394.831062) (xy 313.860942 -394.808456) (xy 313.861704 -394.798296)
			(xy 313.855608 -394.7795) (xy 313.802014 -394.717524) (xy 313.795082 -394.710267) (xy 313.777174 -394.701251)
			(xy 313.767216 -394.699998) (xy 313.743405 -394.697792) (xy 313.696813 -394.687034) (xy 313.652378 -394.669368)
			(xy 313.611116 -394.6452) (xy 313.573975 -394.615082) (xy 313.541802 -394.579705) (xy 313.515337 -394.539879)
			(xy 313.495183 -394.496515) (xy 313.48807 -394.473684) (xy 313.486546 -394.467842) (xy 313.166252 -393.914122)
			(xy 313.162188 -393.909804) (xy 313.145958 -393.892119) (xy 313.118538 -393.852722) (xy 313.0974 -393.809626)
			(xy 313.083033 -393.763827) (xy 313.075767 -393.71638) (xy 313.07532 -393.69238) (xy 313.075798 -393.667603)
			(xy 313.083549 -393.618659) (xy 313.098856 -393.571529) (xy 313.121344 -393.527371) (xy 313.150459 -393.487273)
			(xy 313.185485 -393.452219) (xy 313.225561 -393.423073) (xy 313.269701 -393.400551) (xy 313.31682 -393.385207)
			(xy 313.365757 -393.377418) (xy 313.390534 -393.376912) (xy 313.391042 -393.376912) (xy 313.416439 -393.377358)
			(xy 313.466576 -393.385496) (xy 313.514763 -393.401555) (xy 313.559759 -393.425121) (xy 313.600401 -393.455586)
			(xy 313.635643 -393.492165) (xy 313.664574 -393.533913) (xy 313.686449 -393.579755) (xy 313.694064 -393.603988)
			(xy 313.695588 -393.60983) (xy 314.015882 -394.16355) (xy 314.019946 -394.167868) (xy 314.036101 -394.185572)
			(xy 314.063445 -394.224931) (xy 314.084525 -394.267971) (xy 314.098856 -394.313703) (xy 314.10611 -394.361076)
			(xy 314.10656 -394.385038) (xy 314.10656 -394.385546) (xy 314.106052 -394.405866) (xy 314.10529 -394.415772)
			(xy 314.11164 -394.434822) (xy 314.172346 -394.504164) (xy 314.190126 -394.513054) (xy 314.200286 -394.513816)
			(xy 314.225235 -394.516042) (xy 314.274034 -394.52732) (xy 314.320464 -394.546106) (xy 314.363377 -394.571934)
			(xy 314.401713 -394.604168) (xy 314.418472 -394.622782) (xy 314.420932 -394.625556) (xy 314.426546 -394.630402)
			(xy 314.429648 -394.632434) (xy 314.44172 -394.64048) (xy 314.461677 -394.661527) (xy 314.475749 -394.686889)
			(xy 314.483046 -394.714961) (xy 314.483496 -394.729462) (xy 314.483496 -394.7414) (xy 314.48502 -394.748004)
			(xy 314.490211 -394.768377) (xy 314.495822 -394.810042) (xy 314.496196 -394.831062) (xy 314.495815 -394.852082)
			(xy 314.490214 -394.893748) (xy 314.48502 -394.91412) (xy 314.483496 -394.920724) (xy 314.483496 -395.00302)
			(xy 314.483971 -395.013028) (xy 314.491637 -395.03152) (xy 314.505793 -395.045672) (xy 314.524287 -395.053332)
			(xy 314.534296 -395.05382) (xy 314.87364 -395.05382) (xy 314.886086 -395.050518) (xy 314.891674 -395.04747)
			(xy 314.918673 -395.033319) (xy 314.976771 -395.014897) (xy 315.00699 -395.010894) (xy 315.015833 -395.009595)
			(xy 315.031831 -395.00164) (xy 315.038232 -394.9954) (xy 315.059314 -394.973302) (xy 315.065673 -394.965967)
			(xy 315.072855 -394.947948) (xy 315.073284 -394.93825) (xy 315.073284 -394.920724) (xy 315.071506 -394.91412)
			(xy 315.066301 -394.893751) (xy 315.060699 -394.852083) (xy 315.06033 -394.831062) (xy 315.061092 -394.808456)
			(xy 315.061854 -394.79855) (xy 315.055504 -394.779246) (xy 314.995306 -394.709904) (xy 314.977272 -394.70076)
			(xy 314.967366 -394.699998) (xy 314.943545 -394.69775) (xy 314.896917 -394.687031) (xy 314.852442 -394.669394)
			(xy 314.811141 -394.645242) (xy 314.77396 -394.61513) (xy 314.741754 -394.579749) (xy 314.71526 -394.53991)
			(xy 314.695087 -394.496526) (xy 314.687966 -394.473684) (xy 314.686442 -394.467842) (xy 314.366148 -393.914122)
			(xy 314.362084 -393.909804) (xy 314.345853 -393.892119) (xy 314.318433 -393.852722) (xy 314.297296 -393.809626)
			(xy 314.282929 -393.763827) (xy 314.275663 -393.71638) (xy 314.275216 -393.69238) (xy 314.275698 -393.667603)
			(xy 314.283449 -393.61866) (xy 314.298756 -393.57153) (xy 314.321243 -393.527373) (xy 314.350358 -393.487274)
			(xy 314.385384 -393.452221) (xy 314.425459 -393.423074) (xy 314.469598 -393.400552) (xy 314.516716 -393.385207)
			(xy 314.565654 -393.377418) (xy 314.59043 -393.376912) (xy 314.590938 -393.376912) (xy 314.616334 -393.377362)
			(xy 314.666471 -393.385499) (xy 314.714659 -393.401558) (xy 314.759654 -393.425123) (xy 314.800297 -393.455588)
			(xy 314.835539 -393.492166) (xy 314.86447 -393.533914) (xy 314.886345 -393.579755) (xy 314.89396 -393.603988)
			(xy 314.895484 -393.60983) (xy 314.943528 -393.692888) (xy 315.47562 -393.692888) (xy 315.47562 -393.69238)
			(xy 315.476099 -393.66759) (xy 315.483858 -393.618622) (xy 315.499181 -393.57147) (xy 315.521691 -393.527295)
			(xy 315.550834 -393.487186) (xy 315.585892 -393.452128) (xy 315.626002 -393.422987) (xy 315.670178 -393.400478)
			(xy 315.71733 -393.385156) (xy 315.766298 -393.377399) (xy 315.791088 -393.376912) (xy 315.816483 -393.377406)
			(xy 315.866618 -393.385535) (xy 315.914804 -393.401587) (xy 315.9598 -393.425145) (xy 316.000443 -393.455604)
			(xy 316.035685 -393.492177) (xy 316.064618 -393.53392) (xy 316.086495 -393.579757) (xy 316.09411 -393.603988)
			(xy 316.095634 -393.60983) (xy 316.143678 -393.692888) (xy 316.675516 -393.692888) (xy 316.675516 -393.69238)
			(xy 316.675999 -393.667591) (xy 316.683758 -393.618623) (xy 316.69908 -393.571471) (xy 316.72159 -393.527297)
			(xy 316.750732 -393.487187) (xy 316.78579 -393.45213) (xy 316.8259 -393.422988) (xy 316.870075 -393.400479)
			(xy 316.917227 -393.385157) (xy 316.966195 -393.377399) (xy 316.990984 -393.376912) (xy 317.016379 -393.377409)
			(xy 317.066513 -393.385538) (xy 317.1147 -393.401589) (xy 317.159695 -393.425147) (xy 317.200339 -393.455605)
			(xy 317.235581 -393.492177) (xy 317.264514 -393.53392) (xy 317.286391 -393.579757) (xy 317.294006 -393.603988)
			(xy 317.29553 -393.60983) (xy 317.34328 -393.69238) (xy 317.875412 -393.69238) (xy 317.875898 -393.667604)
			(xy 317.883649 -393.61866) (xy 317.898956 -393.571531) (xy 317.921443 -393.527374) (xy 317.950557 -393.487275)
			(xy 317.985582 -393.452222) (xy 318.025657 -393.423076) (xy 318.069796 -393.400553) (xy 318.116913 -393.385208)
			(xy 318.16585 -393.377418) (xy 318.190626 -393.376912) (xy 318.191134 -393.376912) (xy 318.21653 -393.377365)
			(xy 318.266667 -393.385502) (xy 318.314855 -393.40156) (xy 318.35985 -393.425125) (xy 318.400493 -393.455589)
			(xy 318.435734 -393.492167) (xy 318.464666 -393.533914) (xy 318.486541 -393.579755) (xy 318.494156 -393.603988)
			(xy 318.49568 -393.60983) (xy 318.543402 -393.69238) (xy 319.075308 -393.69238) (xy 319.075798 -393.667604)
			(xy 319.083549 -393.618661) (xy 319.098855 -393.571532) (xy 319.121342 -393.527375) (xy 319.150456 -393.487277)
			(xy 319.18548 -393.452223) (xy 319.225555 -393.423077) (xy 319.269693 -393.400554) (xy 319.31681 -393.385209)
			(xy 319.365746 -393.377419) (xy 319.390522 -393.376912) (xy 319.39103 -393.376912) (xy 319.416426 -393.377369)
			(xy 319.466563 -393.385505) (xy 319.51475 -393.401562) (xy 319.559746 -393.425127) (xy 319.600388 -393.45559)
			(xy 319.63563 -393.492167) (xy 319.664562 -393.533915) (xy 319.686437 -393.579755) (xy 319.694052 -393.603988)
			(xy 319.695576 -393.60983) (xy 319.74362 -393.692888) (xy 320.275712 -393.692888) (xy 320.275712 -393.69238)
			(xy 320.276199 -393.667591) (xy 320.283958 -393.618623) (xy 320.29928 -393.571472) (xy 320.321789 -393.527298)
			(xy 320.350931 -393.487188) (xy 320.385988 -393.452131) (xy 320.426098 -393.422989) (xy 320.470272 -393.40048)
			(xy 320.517423 -393.385158) (xy 320.566391 -393.377399) (xy 320.59118 -393.376912) (xy 320.616575 -393.377413)
			(xy 320.666709 -393.385541) (xy 320.714896 -393.401591) (xy 320.759891 -393.425149) (xy 320.800534 -393.455606)
			(xy 320.835777 -393.492178) (xy 320.86471 -393.533921) (xy 320.886587 -393.579757) (xy 320.894202 -393.603988)
			(xy 320.895726 -393.60983) (xy 320.943742 -393.692888) (xy 321.475608 -393.692888) (xy 321.475608 -393.69238)
			(xy 321.476099 -393.667591) (xy 321.483858 -393.618624) (xy 321.49918 -393.571473) (xy 321.521689 -393.527299)
			(xy 321.55083 -393.48719) (xy 321.585887 -393.452133) (xy 321.625996 -393.422991) (xy 321.670169 -393.400481)
			(xy 321.71732 -393.385159) (xy 321.766287 -393.3774) (xy 321.791076 -393.376912) (xy 321.816471 -393.377416)
			(xy 321.866605 -393.385544) (xy 321.914791 -393.401593) (xy 321.959787 -393.425151) (xy 322.00043 -393.455608)
			(xy 322.035673 -393.492179) (xy 322.064606 -393.533921) (xy 322.086482 -393.579757) (xy 322.094098 -393.603988)
			(xy 322.095622 -393.60983) (xy 322.415916 -394.16355) (xy 322.41998 -394.167868) (xy 322.436175 -394.18555)
			(xy 322.463577 -394.224896) (xy 322.48471 -394.267935) (xy 322.499089 -394.313675) (xy 322.506382 -394.361065)
			(xy 322.506848 -394.385038) (xy 322.506848 -394.385546) (xy 322.506086 -394.405612) (xy 322.505907 -394.415661)
			(xy 322.512442 -394.434649) (xy 322.518786 -394.442442) (xy 322.573396 -394.504164) (xy 322.59143 -394.513054)
			(xy 322.60159 -394.513562) (xy 322.626967 -394.51554) (xy 322.676674 -394.526488) (xy 322.724002 -394.545211)
			(xy 322.767746 -394.57123) (xy 322.806789 -394.603883) (xy 322.82384 -394.622782) (xy 322.826304 -394.625553)
			(xy 322.831915 -394.6304) (xy 322.835016 -394.632434) (xy 322.847081 -394.64049) (xy 322.86704 -394.661533)
			(xy 322.881115 -394.686892) (xy 322.888413 -394.714961) (xy 322.888864 -394.729462) (xy 322.888864 -394.7414)
			(xy 322.890388 -394.748004) (xy 322.895579 -394.768377) (xy 322.90119 -394.810042) (xy 322.901564 -394.831062)
			(xy 322.901184 -394.852082) (xy 322.895583 -394.893749) (xy 322.890388 -394.91412) (xy 322.888864 -394.920724)
			(xy 322.888864 -395.034262) (xy 322.888334 -395.049255) (xy 322.880592 -395.078225) (xy 322.865625 -395.104208)
			(xy 322.844449 -395.12544) (xy 322.818505 -395.140476) (xy 322.789556 -395.148294) (xy 322.774564 -395.148816)
			(xy 322.592446 -395.148816) (xy 322.591938 -395.14907) (xy 322.575174 -395.14907) (xy 322.574666 -395.148816)
			(xy 322.393056 -395.148816) (xy 322.378026 -395.148359) (xy 322.348988 -395.14058) (xy 322.322947 -395.125563)
			(xy 322.301671 -395.104326) (xy 322.286604 -395.078314) (xy 322.27877 -395.049291) (xy 322.278248 -395.034262)
			(xy 322.278248 -394.920724) (xy 322.276724 -394.91412) (xy 322.271517 -394.893751) (xy 322.265917 -394.852083)
			(xy 322.265548 -394.831062) (xy 322.26631 -394.80871) (xy 322.267072 -394.79855) (xy 322.260722 -394.7795)
			(xy 322.199508 -394.70965) (xy 322.181474 -394.70076) (xy 322.171314 -394.700252) (xy 322.147226 -394.698317)
			(xy 322.100019 -394.687981) (xy 322.054941 -394.670568) (xy 322.013045 -394.646485) (xy 321.975312 -394.616294)
			(xy 321.942625 -394.580702) (xy 321.915747 -394.540541) (xy 321.895308 -394.496752) (xy 321.888104 -394.473684)
			(xy 321.88658 -394.467842) (xy 321.566286 -393.914122) (xy 321.562222 -393.909804) (xy 321.546065 -393.892136)
			(xy 321.518747 -393.852818) (xy 321.49768 -393.809826) (xy 321.483345 -393.764146) (xy 321.476073 -393.716826)
			(xy 321.475608 -393.692888) (xy 320.943742 -393.692888) (xy 321.216274 -394.164312) (xy 321.220338 -394.16863)
			(xy 321.236383 -394.186304) (xy 321.263555 -394.225547) (xy 321.284506 -394.268436) (xy 321.298758 -394.313991)
			(xy 321.305986 -394.361172) (xy 321.306444 -394.385038) (xy 321.306444 -394.385546) (xy 321.305936 -394.405866)
			(xy 321.305174 -394.415772) (xy 321.311524 -394.434822) (xy 321.37223 -394.504164) (xy 321.39001 -394.513054)
			(xy 321.40017 -394.513816) (xy 321.425147 -394.516013) (xy 321.474004 -394.527266) (xy 321.520491 -394.546045)
			(xy 321.563456 -394.571886) (xy 321.601834 -394.604148) (xy 321.61861 -394.622782) (xy 321.621078 -394.625549)
			(xy 321.626686 -394.630399) (xy 321.629786 -394.632434) (xy 321.641817 -394.640511) (xy 321.66171 -394.66157)
			(xy 321.675718 -394.686927) (xy 321.682956 -394.714978) (xy 321.68338 -394.729462) (xy 321.68338 -394.7414)
			(xy 321.685158 -394.748004) (xy 321.69035 -394.768376) (xy 321.69596 -394.810042) (xy 321.696334 -394.831062)
			(xy 321.695952 -394.852082) (xy 321.690352 -394.893748) (xy 321.685158 -394.91412) (xy 321.68338 -394.920724)
			(xy 321.68338 -395.034262) (xy 321.682875 -395.049281) (xy 321.67511 -395.078297) (xy 321.660099 -395.104314)
			(xy 321.638865 -395.12556) (xy 321.612856 -395.140585) (xy 321.583845 -395.148367) (xy 321.568826 -395.148816)
			(xy 321.387216 -395.148816) (xy 321.386708 -395.14907) (xy 321.369944 -395.14907) (xy 321.369436 -395.148816)
			(xy 321.187826 -395.148816) (xy 321.172801 -395.148385) (xy 321.143775 -395.140611) (xy 321.117751 -395.125588)
			(xy 321.096505 -395.104339) (xy 321.081484 -395.078314) (xy 321.073714 -395.049287) (xy 321.073272 -395.034262)
			(xy 321.073272 -394.920724) (xy 321.071494 -394.91412) (xy 321.066288 -394.893751) (xy 321.060687 -394.852083)
			(xy 321.060318 -394.831062) (xy 321.06108 -394.808456) (xy 321.061842 -394.79855) (xy 321.055492 -394.779246)
			(xy 320.995294 -394.709904) (xy 320.97726 -394.70076) (xy 320.967354 -394.699998) (xy 320.943478 -394.697783)
			(xy 320.89675 -394.687024) (xy 320.852189 -394.669318) (xy 320.81082 -394.645073) (xy 320.773597 -394.614846)
			(xy 320.741377 -394.579335) (xy 320.714901 -394.539356) (xy 320.694781 -394.495832) (xy 320.6877 -394.472922)
			(xy 320.686176 -394.46708) (xy 320.36639 -393.914122) (xy 320.362326 -393.909804) (xy 320.346169 -393.892135)
			(xy 320.318851 -393.852818) (xy 320.297784 -393.809826) (xy 320.283449 -393.764146) (xy 320.276177 -393.716826)
			(xy 320.275712 -393.692888) (xy 319.74362 -393.692888) (xy 320.01587 -394.16355) (xy 320.019934 -394.167868)
			(xy 320.036087 -394.185574) (xy 320.063431 -394.224932) (xy 320.084512 -394.267971) (xy 320.098844 -394.313703)
			(xy 320.106098 -394.361076) (xy 320.106548 -394.385038) (xy 320.106548 -394.385546) (xy 320.10604 -394.405866)
			(xy 320.105278 -394.415772) (xy 320.111628 -394.434822) (xy 320.172334 -394.504164) (xy 320.190114 -394.513054)
			(xy 320.200274 -394.513816) (xy 320.225251 -394.51601) (xy 320.274109 -394.527264) (xy 320.320596 -394.546044)
			(xy 320.36356 -394.571885) (xy 320.401938 -394.604148) (xy 320.418714 -394.622782) (xy 320.421181 -394.62555)
			(xy 320.42679 -394.630399) (xy 320.42989 -394.632434) (xy 320.441922 -394.640509) (xy 320.461814 -394.661569)
			(xy 320.475822 -394.686927) (xy 320.48306 -394.714977) (xy 320.483484 -394.729462) (xy 320.483484 -394.7414)
			(xy 320.485262 -394.748004) (xy 320.490454 -394.768376) (xy 320.496064 -394.810042) (xy 320.496438 -394.831062)
			(xy 320.496055 -394.852082) (xy 320.490456 -394.893748) (xy 320.485262 -394.91412) (xy 320.483484 -394.920724)
			(xy 320.483484 -395.034262) (xy 320.482975 -395.04928) (xy 320.47521 -395.078296) (xy 320.4602 -395.104313)
			(xy 320.438967 -395.125558) (xy 320.412959 -395.140584) (xy 320.383948 -395.148366) (xy 320.36893 -395.148816)
			(xy 320.18732 -395.148816) (xy 320.186812 -395.14907) (xy 320.170048 -395.14907) (xy 320.16954 -395.148816)
			(xy 319.98793 -395.148816) (xy 319.972906 -395.148381) (xy 319.94388 -395.140609) (xy 319.917856 -395.125586)
			(xy 319.896609 -395.104338) (xy 319.881588 -395.078313) (xy 319.873818 -395.049286) (xy 319.873376 -395.034262)
			(xy 319.873376 -394.920724) (xy 319.871598 -394.91412) (xy 319.866392 -394.893751) (xy 319.860791 -394.852083)
			(xy 319.860422 -394.831062) (xy 319.861184 -394.808456) (xy 319.861946 -394.79855) (xy 319.855596 -394.779246)
			(xy 319.795398 -394.709904) (xy 319.777364 -394.70076) (xy 319.767458 -394.699998) (xy 319.743636 -394.697756)
			(xy 319.697008 -394.687036) (xy 319.652533 -394.669398) (xy 319.611232 -394.645245) (xy 319.574052 -394.615133)
			(xy 319.541845 -394.57975) (xy 319.515352 -394.53991) (xy 319.495179 -394.496526) (xy 319.488058 -394.473684)
			(xy 319.486534 -394.467842) (xy 319.16624 -393.914122) (xy 319.162176 -393.909804) (xy 319.145944 -393.892121)
			(xy 319.118525 -393.852723) (xy 319.097388 -393.809627) (xy 319.08302 -393.763827) (xy 319.075755 -393.71638)
			(xy 319.075308 -393.69238) (xy 318.543402 -393.69238) (xy 318.816228 -394.164312) (xy 318.820292 -394.16863)
			(xy 318.836381 -394.186278) (xy 318.863609 -394.225511) (xy 318.884612 -394.268399) (xy 318.89891 -394.313963)
			(xy 318.906177 -394.361161) (xy 318.906652 -394.385038) (xy 318.906652 -394.385546) (xy 318.90589 -394.405866)
			(xy 318.905128 -394.415772) (xy 318.911478 -394.434822) (xy 318.972184 -394.504164) (xy 318.989964 -394.513054)
			(xy 319.000124 -394.513816) (xy 319.025104 -394.51598) (xy 319.073963 -394.527241) (xy 319.12045 -394.546029)
			(xy 319.163413 -394.571877) (xy 319.201789 -394.604145) (xy 319.218564 -394.622782) (xy 319.221025 -394.625556)
			(xy 319.226638 -394.630402) (xy 319.22974 -394.632434) (xy 319.241811 -394.640482) (xy 319.261768 -394.661529)
			(xy 319.27584 -394.68689) (xy 319.283138 -394.714961) (xy 319.283588 -394.729462) (xy 319.283588 -394.7414)
			(xy 319.285112 -394.748004) (xy 319.290303 -394.768377) (xy 319.295914 -394.810042) (xy 319.296288 -394.831062)
			(xy 319.295907 -394.852082) (xy 319.290306 -394.893748) (xy 319.285112 -394.91412) (xy 319.283588 -394.920724)
			(xy 319.283588 -395.034262) (xy 319.283034 -395.049253) (xy 319.275294 -395.078219) (xy 319.260331 -395.104201)
			(xy 319.23916 -395.125431) (xy 319.213222 -395.140469) (xy 319.184278 -395.148291) (xy 319.169288 -395.148816)
			(xy 318.98717 -395.148816) (xy 318.986662 -395.14907) (xy 318.969898 -395.14907) (xy 318.96939 -395.148816)
			(xy 318.78778 -395.148816) (xy 318.772751 -395.148338) (xy 318.743714 -395.140565) (xy 318.717673 -395.125552)
			(xy 318.696396 -395.10432) (xy 318.681328 -395.07831) (xy 318.673494 -395.04929) (xy 318.672972 -395.034262)
			(xy 318.672972 -394.920724) (xy 318.671448 -394.91412) (xy 318.666241 -394.893751) (xy 318.660641 -394.852083)
			(xy 318.660272 -394.831062) (xy 318.661034 -394.808456) (xy 318.661796 -394.79855) (xy 318.655446 -394.779246)
			(xy 318.595248 -394.709904) (xy 318.577214 -394.70076) (xy 318.567308 -394.699998) (xy 318.543436 -394.69774)
			(xy 318.49671 -394.686989) (xy 318.452149 -394.66929) (xy 318.41078 -394.645051) (xy 318.373556 -394.61483)
			(xy 318.341334 -394.579324) (xy 318.314857 -394.539351) (xy 318.294735 -394.49583) (xy 318.287654 -394.472922)
			(xy 318.28613 -394.46708) (xy 317.966344 -393.914122) (xy 317.96228 -393.909804) (xy 317.946049 -393.89212)
			(xy 317.918629 -393.852722) (xy 317.897492 -393.809627) (xy 317.883124 -393.763827) (xy 317.875859 -393.71638)
			(xy 317.875412 -393.69238) (xy 317.34328 -393.69238) (xy 317.615824 -394.16355) (xy 317.619888 -394.167868)
			(xy 317.636085 -394.185549) (xy 317.663485 -394.224895) (xy 317.684618 -394.267934) (xy 317.698997 -394.313675)
			(xy 317.70629 -394.361065) (xy 317.706756 -394.385038) (xy 317.706756 -394.385546) (xy 317.705994 -394.405866)
			(xy 317.705232 -394.415772) (xy 317.711582 -394.434822) (xy 317.772288 -394.504164) (xy 317.790068 -394.513054)
			(xy 317.800228 -394.513816) (xy 317.825202 -394.516038) (xy 317.874059 -394.527284) (xy 317.920546 -394.546058)
			(xy 317.963512 -394.571893) (xy 318.001891 -394.60415) (xy 318.018668 -394.622782) (xy 318.021129 -394.625556)
			(xy 318.026742 -394.630402) (xy 318.029844 -394.632434) (xy 318.041916 -394.640481) (xy 318.061872 -394.661528)
			(xy 318.075945 -394.68689) (xy 318.083242 -394.714961) (xy 318.083692 -394.729462) (xy 318.083692 -394.7414)
			(xy 318.085216 -394.748004) (xy 318.090407 -394.768377) (xy 318.096018 -394.810042) (xy 318.096392 -394.831062)
			(xy 318.096011 -394.852082) (xy 318.09041 -394.893748) (xy 318.085216 -394.91412) (xy 318.083692 -394.920724)
			(xy 318.083692 -395.034262) (xy 318.083134 -395.049253) (xy 318.075395 -395.078218) (xy 318.060432 -395.104199)
			(xy 318.039262 -395.12543) (xy 318.013324 -395.140468) (xy 317.984381 -395.148291) (xy 317.969392 -395.148816)
			(xy 317.787274 -395.148816) (xy 317.786766 -395.14907) (xy 317.770002 -395.14907) (xy 317.769494 -395.148816)
			(xy 317.587884 -395.148816) (xy 317.572855 -395.148334) (xy 317.543819 -395.140562) (xy 317.517777 -395.12555)
			(xy 317.4965 -395.104319) (xy 317.481433 -395.07831) (xy 317.473598 -395.04929) (xy 317.473076 -395.034262)
			(xy 317.473076 -394.920724) (xy 317.471552 -394.91412) (xy 317.466346 -394.893751) (xy 317.460745 -394.852083)
			(xy 317.460376 -394.831062) (xy 317.461138 -394.808456) (xy 317.4619 -394.79855) (xy 317.45555 -394.779246)
			(xy 317.395352 -394.709904) (xy 317.377318 -394.70076) (xy 317.367412 -394.699998) (xy 317.343586 -394.697793)
			(xy 317.296957 -394.687067) (xy 317.252481 -394.669422) (xy 317.211181 -394.645264) (xy 317.174001 -394.615146)
			(xy 317.141796 -394.579759) (xy 317.115304 -394.539915) (xy 317.095132 -394.496528) (xy 317.088012 -394.473684)
			(xy 317.086488 -394.467842) (xy 316.766194 -393.914122) (xy 316.76213 -393.909804) (xy 316.745974 -393.892135)
			(xy 316.718656 -393.852818) (xy 316.697588 -393.809826) (xy 316.683253 -393.764146) (xy 316.675981 -393.716826)
			(xy 316.675516 -393.692888) (xy 316.143678 -393.692888) (xy 316.415928 -394.16355) (xy 316.419992 -394.167868)
			(xy 316.436189 -394.185548) (xy 316.46359 -394.224895) (xy 316.484723 -394.267934) (xy 316.499101 -394.313675)
			(xy 316.506394 -394.361065) (xy 316.50686 -394.385038) (xy 316.50686 -394.385546) (xy 316.506098 -394.405866)
			(xy 316.505336 -394.415772) (xy 316.511686 -394.434822) (xy 316.572392 -394.504164) (xy 316.590172 -394.513054)
			(xy 316.600332 -394.513816) (xy 316.625284 -394.516014) (xy 316.674084 -394.5273) (xy 316.720514 -394.546092)
			(xy 316.763426 -394.571926) (xy 316.80176 -394.604165) (xy 316.818518 -394.622782) (xy 316.820985 -394.62555)
			(xy 316.826594 -394.630399) (xy 316.829694 -394.632434) (xy 316.841727 -394.640508) (xy 316.861619 -394.661569)
			(xy 316.875626 -394.686927) (xy 316.882864 -394.714977) (xy 316.883288 -394.729462) (xy 316.883288 -394.7414)
			(xy 316.885066 -394.748004) (xy 316.890258 -394.768376) (xy 316.895868 -394.810042) (xy 316.896242 -394.831062)
			(xy 316.895859 -394.852082) (xy 316.89026 -394.893748) (xy 316.885066 -394.91412) (xy 316.883288 -394.920724)
			(xy 316.883288 -395.034262) (xy 316.882635 -395.052382) (xy 316.871376 -395.086827) (xy 316.86119 -395.101826)
			(xy 316.856709 -395.108492) (xy 316.851782 -395.12377) (xy 316.851538 -395.131798) (xy 316.851538 -395.165326)
			(xy 316.851841 -395.173345) (xy 316.856755 -395.188611) (xy 316.86119 -395.195298) (xy 316.87128 -395.210346)
			(xy 316.882534 -395.24476) (xy 316.883288 -395.262862) (xy 316.883288 -395.3764) (xy 316.885066 -395.383004)
			(xy 316.890258 -395.403376) (xy 316.895868 -395.445042) (xy 316.896242 -395.466062) (xy 316.895859 -395.487082)
			(xy 316.89026 -395.528748) (xy 316.885066 -395.54912) (xy 316.883288 -395.555724) (xy 316.883288 -395.567662)
			(xy 316.882821 -395.583034) (xy 316.874689 -395.612683) (xy 316.858995 -395.63912) (xy 316.83686 -395.660457)
			(xy 316.823598 -395.668246) (xy 316.819788 -395.672818) (xy 316.812476 -395.682283) (xy 316.806795 -395.705487)
			(xy 316.808866 -395.717268) (xy 316.815978 -395.749018) (xy 316.81926 -395.760528) (xy 316.834497 -395.778945)
			(xy 316.845188 -395.784324) (xy 316.866617 -395.794056) (xy 316.906569 -395.818935) (xy 316.942417 -395.849431)
			(xy 316.958218 -395.866874) (xy 316.960686 -395.869642) (xy 316.966294 -395.874491) (xy 316.969394 -395.876526)
			(xy 316.981549 -395.884593) (xy 317.001635 -395.905738) (xy 317.015778 -395.931243) (xy 317.023074 -395.95948)
			(xy 317.023496 -395.974062) (xy 317.023496 -395.986508) (xy 317.025274 -395.992858) (xy 317.030408 -396.013172)
			(xy 317.035882 -396.054712) (xy 317.036196 -396.075662) (xy 317.035863 -396.096611) (xy 317.030387 -396.138148)
			(xy 317.025274 -396.158466) (xy 317.023496 -396.164816) (xy 317.023496 -396.621508) (xy 317.025274 -396.627858)
			(xy 317.030408 -396.648172) (xy 317.035882 -396.689712) (xy 317.036196 -396.710662) (xy 317.60033 -396.710662)
			(xy 317.600696 -396.689641) (xy 317.606306 -396.647975) (xy 317.611506 -396.627604) (xy 317.613284 -396.621)
			(xy 317.613284 -396.507462) (xy 317.613703 -396.49244) (xy 317.621489 -396.463423) (xy 317.636519 -396.437409)
			(xy 317.65777 -396.416173) (xy 317.683794 -396.401159) (xy 317.712816 -396.393393) (xy 317.727838 -396.392908)
			(xy 317.909448 -396.392908) (xy 317.909956 -396.392654) (xy 317.92672 -396.392654) (xy 317.927228 -396.392908)
			(xy 318.108838 -396.392908) (xy 318.123853 -396.393402) (xy 318.152859 -396.401181) (xy 318.178865 -396.4162)
			(xy 318.2001 -396.437435) (xy 318.215119 -396.463441) (xy 318.222898 -396.492447) (xy 318.223392 -396.507462)
			(xy 318.223392 -396.621) (xy 318.22517 -396.627604) (xy 318.230362 -396.647976) (xy 318.235972 -396.689642)
			(xy 318.236346 -396.710662) (xy 318.800226 -396.710662) (xy 318.800592 -396.689641) (xy 318.806203 -396.647975)
			(xy 318.811402 -396.627604) (xy 318.81318 -396.621) (xy 318.81318 -396.507462) (xy 318.813603 -396.492441)
			(xy 318.821388 -396.463424) (xy 318.836418 -396.437411) (xy 318.857668 -396.416174) (xy 318.883691 -396.40116)
			(xy 318.912712 -396.393394) (xy 318.927734 -396.392908) (xy 319.109344 -396.392908) (xy 319.109852 -396.392654)
			(xy 319.126616 -396.392654) (xy 319.127124 -396.392908) (xy 319.308734 -396.392908) (xy 319.323749 -396.393406)
			(xy 319.352755 -396.401184) (xy 319.378761 -396.416201) (xy 319.399996 -396.437436) (xy 319.415015 -396.463441)
			(xy 319.422794 -396.492447) (xy 319.423288 -396.507462) (xy 319.423288 -396.621) (xy 319.425066 -396.627604)
			(xy 319.430258 -396.647976) (xy 319.435868 -396.689642) (xy 319.436242 -396.710662) (xy 320.000376 -396.710662)
			(xy 320.000743 -396.689641) (xy 320.006353 -396.647975) (xy 320.011552 -396.627604) (xy 320.013076 -396.621)
			(xy 320.013076 -396.507462) (xy 320.0135 -396.492462) (xy 320.021263 -396.463484) (xy 320.036252 -396.437496)
			(xy 320.057448 -396.416266) (xy 320.083411 -396.401235) (xy 320.112377 -396.393425) (xy 320.127376 -396.392908)
			(xy 320.309494 -396.392908) (xy 320.310002 -396.392654) (xy 320.326766 -396.392654) (xy 320.327274 -396.392908)
			(xy 320.508884 -396.392908) (xy 320.523914 -396.393394) (xy 320.552952 -396.401161) (xy 320.578996 -396.41617)
			(xy 320.600275 -396.437401) (xy 320.615342 -396.463412) (xy 320.623172 -396.492433) (xy 320.623692 -396.507462)
			(xy 320.623692 -396.621) (xy 320.625216 -396.627604) (xy 320.630407 -396.647977) (xy 320.636018 -396.689642)
			(xy 320.636392 -396.710662) (xy 321.200272 -396.710662) (xy 321.200639 -396.689641) (xy 321.206249 -396.647975)
			(xy 321.211448 -396.627604) (xy 321.212972 -396.621) (xy 321.212972 -396.507462) (xy 321.2134 -396.492462)
			(xy 321.221163 -396.463485) (xy 321.236151 -396.437498) (xy 321.257346 -396.416267) (xy 321.283308 -396.401236)
			(xy 321.312273 -396.393425) (xy 321.327272 -396.392908) (xy 321.50939 -396.392908) (xy 321.509898 -396.392654)
			(xy 321.526662 -396.392654) (xy 321.52717 -396.392908) (xy 321.70878 -396.392908) (xy 321.72381 -396.393398)
			(xy 321.752848 -396.401163) (xy 321.778892 -396.416172) (xy 321.800171 -396.437403) (xy 321.815238 -396.463413)
			(xy 321.823068 -396.492434) (xy 321.823588 -396.507462) (xy 321.823588 -396.621) (xy 321.825112 -396.627604)
			(xy 321.830303 -396.647977) (xy 321.835914 -396.689642) (xy 321.836288 -396.710662) (xy 321.836288 -396.71117)
			(xy 321.836118 -396.725795) (xy 321.833451 -396.754924) (xy 321.830954 -396.769336) (xy 321.829583 -396.77851)
			(xy 321.832859 -396.796753) (xy 321.837304 -396.804896) (xy 321.853814 -396.83182) (xy 321.858994 -396.83959)
			(xy 321.873713 -396.851056) (xy 321.882516 -396.854172) (xy 321.907399 -396.86223) (xy 321.954278 -396.885421)
			(xy 321.99669 -396.916026) (xy 322.033473 -396.953207) (xy 322.06362 -396.995946) (xy 322.086304 -397.043072)
			(xy 322.094098 -397.06804) (xy 322.095622 -397.073882) (xy 322.415916 -397.627602) (xy 322.41998 -397.63192)
			(xy 322.436168 -397.649642) (xy 322.463596 -397.689028) (xy 322.484742 -397.732114) (xy 322.499119 -397.777906)
			(xy 322.506396 -397.825346) (xy 322.506848 -397.849344) (xy 322.506424 -397.874123) (xy 322.498668 -397.923071)
			(xy 322.483356 -397.970204) (xy 322.460862 -398.014364) (xy 322.431741 -398.054464) (xy 322.396709 -398.089518)
			(xy 322.356626 -398.118663) (xy 322.31248 -398.141183) (xy 322.265356 -398.156524) (xy 322.216413 -398.164309)
			(xy 322.191634 -398.164812) (xy 322.191126 -398.164812) (xy 322.165732 -398.164289) (xy 322.1156 -398.156162)
			(xy 322.067415 -398.140114) (xy 322.02242 -398.11656) (xy 321.981777 -398.086105) (xy 321.946534 -398.049537)
			(xy 321.9176 -398.007798) (xy 321.895721 -397.961966) (xy 321.888104 -397.937736) (xy 321.88658 -397.931894)
			(xy 321.566286 -397.378174) (xy 321.562222 -397.373856) (xy 321.546057 -397.356127) (xy 321.518691 -397.316723)
			(xy 321.497602 -397.273632) (xy 321.483276 -397.227846) (xy 321.476042 -397.18042) (xy 321.475608 -397.156432)
			(xy 321.475789 -397.142384) (xy 321.478329 -397.114402) (xy 321.480688 -397.100552) (xy 321.482012 -397.091273)
			(xy 321.478484 -397.072875) (xy 321.47383 -397.064738) (xy 321.457066 -397.037814) (xy 321.451847 -397.030124)
			(xy 321.437134 -397.018793) (xy 321.428364 -397.015716) (xy 321.40674 -397.00891) (xy 321.365525 -396.99003)
			(xy 321.327404 -396.965496) (xy 321.293148 -396.935805) (xy 321.277996 -396.918942) (xy 321.275537 -396.916166)
			(xy 321.269922 -396.911322) (xy 321.26682 -396.90929) (xy 321.254752 -396.901239) (xy 321.234797 -396.880192)
			(xy 321.220725 -396.854832) (xy 321.213425 -396.826762) (xy 321.212972 -396.812262) (xy 321.212972 -396.800324)
			(xy 321.211448 -396.79372) (xy 321.206241 -396.773351) (xy 321.200641 -396.731683) (xy 321.200272 -396.710662)
			(xy 320.636392 -396.710662) (xy 320.636392 -396.71117) (xy 320.636222 -396.725795) (xy 320.633555 -396.754924)
			(xy 320.631058 -396.769336) (xy 320.6297 -396.77851) (xy 320.63297 -396.796751) (xy 320.637408 -396.804896)
			(xy 320.653918 -396.83182) (xy 320.659097 -396.839591) (xy 320.673816 -396.851057) (xy 320.68262 -396.854172)
			(xy 320.707543 -396.86231) (xy 320.754509 -396.885602) (xy 320.796989 -396.916323) (xy 320.833818 -396.953631)
			(xy 320.863989 -396.996504) (xy 320.886673 -397.043767) (xy 320.894456 -397.068802) (xy 320.89598 -397.074644)
			(xy 321.215766 -397.627602) (xy 321.21983 -397.63192) (xy 321.235991 -397.649585) (xy 321.26331 -397.688903)
			(xy 321.284377 -397.731895) (xy 321.298711 -397.777576) (xy 321.305981 -397.824898) (xy 321.306444 -397.848836)
			(xy 321.306444 -397.849344) (xy 321.305947 -397.874793) (xy 321.297775 -397.92503) (xy 321.281652 -397.973306)
			(xy 321.257993 -398.01837) (xy 321.227412 -398.059056) (xy 321.190701 -398.09431) (xy 321.170046 -398.109186)
			(xy 321.161516 -398.115635) (xy 321.150307 -398.133823) (xy 321.147463 -398.154996) (xy 321.153476 -398.175496)
			(xy 321.167306 -398.19178) (xy 321.186563 -398.201031) (xy 321.197224 -398.201896) (xy 321.206876 -398.201388)
			(xy 321.21539 -398.200099) (xy 321.232555 -398.198697) (xy 321.241166 -398.198594) (xy 321.24142 -398.198848)
			(xy 321.540632 -398.198848) (xy 321.540886 -398.198594) (xy 321.561931 -398.199046) (xy 321.603249 -398.207033)
			(xy 321.642204 -398.222955) (xy 321.677286 -398.246198) (xy 321.707138 -398.27586) (xy 321.730604 -398.310794)
			(xy 321.746774 -398.349646) (xy 321.755024 -398.390913) (xy 321.755516 -398.411954) (xy 321.755516 -398.666716)
			(xy 322.380356 -398.666716) (xy 322.380356 -398.411954) (xy 322.380898 -398.390743) (xy 322.389323 -398.349164)
			(xy 322.405774 -398.31006) (xy 322.429606 -398.274963) (xy 322.459886 -398.245249) (xy 322.495425 -398.222082)
			(xy 322.534833 -398.20637) (xy 322.576563 -398.19873) (xy 322.59778 -398.198594) (xy 322.598288 -398.198848)
			(xy 322.891912 -398.198848) (xy 322.89242 -398.198594) (xy 322.913652 -398.198687) (xy 322.955423 -398.206257)
			(xy 322.994875 -398.221932) (xy 323.030452 -398.245092) (xy 323.060751 -398.274825) (xy 323.084579 -398.309958)
			(xy 323.100995 -398.349107) (xy 323.109353 -398.390728) (xy 323.109844 -398.411954) (xy 323.109844 -398.666716)
			(xy 323.097144 -398.666716) (xy 323.087615 -398.667799) (xy 323.070326 -398.676062) (xy 323.057275 -398.690093)
			(xy 323.050283 -398.707934) (xy 323.0499 -398.717516) (xy 323.0499 -398.881092) (xy 323.049474 -398.891113)
			(xy 323.041807 -398.90963) (xy 323.027636 -398.923802) (xy 323.009121 -398.931472) (xy 322.9991 -398.931892)
			(xy 322.4911 -398.931892) (xy 322.481078 -398.93148) (xy 322.462559 -398.923809) (xy 322.448387 -398.909634)
			(xy 322.440718 -398.891114) (xy 322.4403 -398.881092) (xy 322.4403 -398.717516) (xy 322.439868 -398.707496)
			(xy 322.432203 -398.688979) (xy 322.418034 -398.674806) (xy 322.39952 -398.667136) (xy 322.3895 -398.666716)
			(xy 322.380356 -398.666716) (xy 321.755516 -398.666716) (xy 321.746372 -398.666716) (xy 321.736361 -398.667165)
			(xy 321.717865 -398.674837) (xy 321.703712 -398.689002) (xy 321.696057 -398.707504) (xy 321.695572 -398.717516)
			(xy 321.695572 -398.881092) (xy 321.695173 -398.891116) (xy 321.687501 -398.909638) (xy 321.673322 -398.923812)
			(xy 321.654796 -398.931477) (xy 321.644772 -398.931892) (xy 321.13728 -398.931892) (xy 321.12727 -398.931428)
			(xy 321.108776 -398.923761) (xy 321.094624 -398.9096) (xy 321.086966 -398.891102) (xy 321.08648 -398.881092)
			(xy 321.08648 -398.717516) (xy 321.086067 -398.707493) (xy 321.078399 -398.688973) (xy 321.064224 -398.674799)
			(xy 321.045703 -398.667132) (xy 321.03568 -398.666716) (xy 321.026536 -398.666716) (xy 321.026536 -398.411446)
			(xy 321.027319 -398.385724) (xy 321.039653 -398.335777) (xy 321.05092 -398.31264) (xy 321.056762 -398.30121)
			(xy 321.056508 -398.27581) (xy 321.002914 -398.178782) (xy 320.981324 -398.165066) (xy 320.96837 -398.16405)
			(xy 320.944477 -398.161895) (xy 320.897691 -398.151301) (xy 320.853051 -398.13374) (xy 320.811586 -398.109618)
			(xy 320.774255 -398.079492) (xy 320.74192 -398.044057) (xy 320.715327 -398.004132) (xy 320.695091 -397.960639)
			(xy 320.687954 -397.937736) (xy 320.68643 -397.931894) (xy 320.365882 -397.377412) (xy 320.361818 -397.373094)
			(xy 320.345713 -397.355438) (xy 320.318527 -397.316137) (xy 320.297577 -397.273187) (xy 320.283342 -397.227569)
			(xy 320.276147 -397.180326) (xy 320.275712 -397.156432) (xy 320.275893 -397.142384) (xy 320.278433 -397.114402)
			(xy 320.280792 -397.100552) (xy 320.282116 -397.091273) (xy 320.278588 -397.072875) (xy 320.273934 -397.064738)
			(xy 320.25717 -397.037814) (xy 320.251949 -397.030125) (xy 320.237237 -397.018794) (xy 320.228468 -397.015716)
			(xy 320.206844 -397.008909) (xy 320.16563 -396.990029) (xy 320.127509 -396.965496) (xy 320.093252 -396.935804)
			(xy 320.0781 -396.918942) (xy 320.075641 -396.916167) (xy 320.070026 -396.911322) (xy 320.066924 -396.90929)
			(xy 320.054857 -396.901238) (xy 320.034902 -396.880191) (xy 320.020829 -396.854831) (xy 320.013529 -396.826762)
			(xy 320.013076 -396.812262) (xy 320.013076 -396.800324) (xy 320.011552 -396.79372) (xy 320.006346 -396.773351)
			(xy 320.000745 -396.731683) (xy 320.000376 -396.710662) (xy 319.436242 -396.710662) (xy 319.436242 -396.71117)
			(xy 319.436072 -396.725795) (xy 319.433405 -396.754924) (xy 319.430908 -396.769336) (xy 319.429544 -396.77851)
			(xy 319.432817 -396.796752) (xy 319.437258 -396.804896) (xy 319.453768 -396.83182) (xy 319.458929 -396.839605)
			(xy 319.473661 -396.851064) (xy 319.48247 -396.854172) (xy 319.507345 -396.862256) (xy 319.554224 -396.88544)
			(xy 319.596638 -396.916039) (xy 319.633423 -396.953216) (xy 319.663571 -396.995951) (xy 319.686257 -397.043074)
			(xy 319.694052 -397.06804) (xy 319.695576 -397.073882) (xy 320.01587 -397.627602) (xy 320.019934 -397.63192)
			(xy 320.036095 -397.649585) (xy 320.063414 -397.688902) (xy 320.084482 -397.731895) (xy 320.098815 -397.777576)
			(xy 320.106085 -397.824898) (xy 320.106548 -397.848836) (xy 320.106548 -397.849344) (xy 320.106049 -397.874793)
			(xy 320.097878 -397.92503) (xy 320.081754 -397.973306) (xy 320.058096 -398.01837) (xy 320.027515 -398.059056)
			(xy 319.990804 -398.09431) (xy 319.97015 -398.109186) (xy 319.961618 -398.115634) (xy 319.950407 -398.133821)
			(xy 319.947563 -398.154996) (xy 319.953576 -398.175497) (xy 319.967408 -398.191781) (xy 319.986666 -398.201032)
			(xy 319.997328 -398.201896) (xy 320.00698 -398.201388) (xy 320.015494 -398.200098) (xy 320.032659 -398.198697)
			(xy 320.04127 -398.198594) (xy 320.041524 -398.198848) (xy 320.340736 -398.198848) (xy 320.34099 -398.198594)
			(xy 320.362035 -398.199042) (xy 320.403353 -398.20703) (xy 320.442308 -398.222953) (xy 320.47739 -398.246196)
			(xy 320.507242 -398.275859) (xy 320.530708 -398.310793) (xy 320.546878 -398.349645) (xy 320.555128 -398.390912)
			(xy 320.55562 -398.411954) (xy 320.55562 -398.666716) (xy 320.546476 -398.666716) (xy 320.536465 -398.667169)
			(xy 320.517969 -398.674839) (xy 320.503817 -398.689003) (xy 320.496161 -398.707504) (xy 320.495676 -398.717516)
			(xy 320.495676 -398.881092) (xy 320.495273 -398.891116) (xy 320.487602 -398.909637) (xy 320.473424 -398.923811)
			(xy 320.4549 -398.931477) (xy 320.444876 -398.931892) (xy 319.937384 -398.931892) (xy 319.927374 -398.931425)
			(xy 319.908881 -398.923759) (xy 319.894728 -398.909599) (xy 319.88707 -398.891102) (xy 319.886584 -398.881092)
			(xy 319.886584 -398.717516) (xy 319.886167 -398.707494) (xy 319.878499 -398.688974) (xy 319.864326 -398.674801)
			(xy 319.845806 -398.667133) (xy 319.835784 -398.666716) (xy 319.82664 -398.666716) (xy 319.82664 -398.411446)
			(xy 319.827422 -398.385724) (xy 319.839757 -398.335777) (xy 319.851024 -398.31264) (xy 319.856866 -398.30121)
			(xy 319.856612 -398.27581) (xy 319.803018 -398.178782) (xy 319.781428 -398.165066) (xy 319.768474 -398.16405)
			(xy 319.744573 -398.161972) (xy 319.697785 -398.151364) (xy 319.653143 -398.13379) (xy 319.61168 -398.109657)
			(xy 319.574351 -398.07952) (xy 319.542018 -398.044076) (xy 319.515427 -398.004143) (xy 319.495194 -397.960642)
			(xy 319.488058 -397.937736) (xy 319.486534 -397.931894) (xy 319.16624 -397.378174) (xy 319.162176 -397.373856)
			(xy 319.145969 -397.356151) (xy 319.118546 -397.316759) (xy 319.097404 -397.273669) (xy 319.083031 -397.227874)
			(xy 319.075758 -397.180431) (xy 319.075308 -397.156432) (xy 319.075487 -397.142384) (xy 319.07803 -397.114402)
			(xy 319.080388 -397.100552) (xy 319.081679 -397.091296) (xy 319.078281 -397.072932) (xy 319.073784 -397.064738)
			(xy 319.05702 -397.037814) (xy 319.051817 -397.030111) (xy 319.037092 -397.018788) (xy 319.028318 -397.015716)
			(xy 319.006687 -397.008928) (xy 318.965474 -396.990042) (xy 318.927355 -396.965503) (xy 318.893101 -396.935807)
			(xy 318.87795 -396.918942) (xy 318.875484 -396.916173) (xy 318.869874 -396.911324) (xy 318.866774 -396.90929)
			(xy 318.854745 -396.901211) (xy 318.834855 -396.88015) (xy 318.820848 -396.854794) (xy 318.813607 -396.826746)
			(xy 318.81318 -396.812262) (xy 318.81318 -396.800324) (xy 318.811402 -396.79372) (xy 318.806196 -396.773351)
			(xy 318.800595 -396.731683) (xy 318.800226 -396.710662) (xy 318.236346 -396.710662) (xy 318.236346 -396.71117)
			(xy 318.236176 -396.725795) (xy 318.233509 -396.754924) (xy 318.231012 -396.769336) (xy 318.229647 -396.77851)
			(xy 318.23292 -396.796752) (xy 318.237362 -396.804896) (xy 318.253872 -396.83182) (xy 318.259031 -396.839606)
			(xy 318.273765 -396.851064) (xy 318.282574 -396.854172) (xy 318.307507 -396.862279) (xy 318.354472 -396.88558)
			(xy 318.39695 -396.916308) (xy 318.433777 -396.953621) (xy 318.463946 -396.996499) (xy 318.486628 -397.043765)
			(xy 318.49441 -397.068802) (xy 318.495934 -397.074644) (xy 318.81572 -397.627602) (xy 318.819784 -397.63192)
			(xy 318.835973 -397.649641) (xy 318.8634 -397.689028) (xy 318.884546 -397.732114) (xy 318.898923 -397.777906)
			(xy 318.9062 -397.825346) (xy 318.906652 -397.849344) (xy 318.906151 -397.874806) (xy 318.897953 -397.925065)
			(xy 318.881793 -397.973357) (xy 318.858091 -398.018428) (xy 318.82746 -398.05911) (xy 318.790696 -398.094347)
			(xy 318.77 -398.109186) (xy 318.761493 -398.115657) (xy 318.7503 -398.133838) (xy 318.747462 -398.154999)
			(xy 318.753469 -398.175487) (xy 318.767285 -398.191765) (xy 318.786524 -398.201023) (xy 318.797178 -398.201896)
			(xy 318.80683 -398.201388) (xy 318.815344 -398.200093) (xy 318.832509 -398.198695) (xy 318.84112 -398.198594)
			(xy 318.841374 -398.198848) (xy 319.140586 -398.198848) (xy 319.14084 -398.198594) (xy 319.161901 -398.199017)
			(xy 319.203259 -398.206968) (xy 319.242258 -398.222869) (xy 319.277384 -398.246104) (xy 319.307276 -398.275772)
			(xy 319.330774 -398.310722) (xy 319.346968 -398.349599) (xy 319.35523 -398.390896) (xy 319.355724 -398.411954)
			(xy 319.355724 -398.666716) (xy 319.34658 -398.666716) (xy 319.336569 -398.667172) (xy 319.318074 -398.674841)
			(xy 319.303921 -398.689004) (xy 319.296265 -398.707505) (xy 319.29578 -398.717516) (xy 319.29578 -398.881092)
			(xy 319.295374 -398.891115) (xy 319.287702 -398.909636) (xy 319.273526 -398.923809) (xy 319.255003 -398.931476)
			(xy 319.24498 -398.931892) (xy 318.73698 -398.931892) (xy 318.72697 -398.931428) (xy 318.708476 -398.923761)
			(xy 318.694324 -398.9096) (xy 318.686666 -398.891102) (xy 318.68618 -398.881092) (xy 318.68618 -398.666716)
			(xy 318.677036 -398.666716) (xy 318.667019 -398.666251) (xy 318.648506 -398.658596) (xy 318.634333 -398.644438)
			(xy 318.626659 -398.625933) (xy 318.626236 -398.615916) (xy 318.626236 -398.411954) (xy 318.626579 -398.394721)
			(xy 318.63215 -398.360708) (xy 318.643123 -398.328035) (xy 318.650874 -398.31264) (xy 318.656716 -398.30121)
			(xy 318.656462 -398.27581) (xy 318.602868 -398.178782) (xy 318.581278 -398.165066) (xy 318.568324 -398.16405)
			(xy 318.544427 -398.161932) (xy 318.49764 -398.151331) (xy 318.452999 -398.133764) (xy 318.411535 -398.109636)
			(xy 318.374205 -398.079505) (xy 318.341871 -398.044066) (xy 318.31528 -398.004137) (xy 318.295044 -397.960641)
			(xy 318.287908 -397.937736) (xy 318.286384 -397.931894) (xy 317.965836 -397.377412) (xy 317.961772 -397.373094)
			(xy 317.945672 -397.355421) (xy 317.918423 -397.316143) (xy 317.897411 -397.273204) (xy 317.883118 -397.227586)
			(xy 317.875871 -397.180334) (xy 317.875412 -397.156432) (xy 317.875591 -397.142384) (xy 317.878134 -397.114402)
			(xy 317.880492 -397.100552) (xy 317.881783 -397.091296) (xy 317.878385 -397.072932) (xy 317.873888 -397.064738)
			(xy 317.857124 -397.037814) (xy 317.851919 -397.030113) (xy 317.837196 -397.018788) (xy 317.828422 -397.015716)
			(xy 317.806792 -397.008927) (xy 317.765578 -396.990041) (xy 317.727459 -396.965503) (xy 317.693205 -396.935807)
			(xy 317.678054 -396.918942) (xy 317.675588 -396.916173) (xy 317.669978 -396.911324) (xy 317.666878 -396.90929)
			(xy 317.65485 -396.901209) (xy 317.63496 -396.880149) (xy 317.620952 -396.854794) (xy 317.613711 -396.826746)
			(xy 317.613284 -396.812262) (xy 317.613284 -396.800324) (xy 317.611506 -396.79372) (xy 317.606301 -396.773351)
			(xy 317.600699 -396.731683) (xy 317.60033 -396.710662) (xy 317.036196 -396.710662) (xy 317.036055 -396.725415)
			(xy 317.03338 -396.754799) (xy 317.030862 -396.769336) (xy 317.029504 -396.77851) (xy 317.032774 -396.796751)
			(xy 317.037212 -396.804896) (xy 317.053722 -396.83182) (xy 317.0589 -396.839592) (xy 317.07362 -396.851057)
			(xy 317.082424 -396.854172) (xy 317.107309 -396.862225) (xy 317.154188 -396.885417) (xy 317.1966 -396.916023)
			(xy 317.233382 -396.953206) (xy 317.263529 -396.995945) (xy 317.286213 -397.043072) (xy 317.294006 -397.06804)
			(xy 317.29553 -397.073882) (xy 317.615824 -397.627602) (xy 317.619888 -397.63192) (xy 317.636078 -397.64964)
			(xy 317.663504 -397.689028) (xy 317.68465 -397.732114) (xy 317.699027 -397.777906) (xy 317.706304 -397.825346)
			(xy 317.706756 -397.849344) (xy 317.706253 -397.874806) (xy 317.698055 -397.925065) (xy 317.681896 -397.973356)
			(xy 317.658194 -398.018428) (xy 317.627564 -398.059109) (xy 317.5908 -398.094347) (xy 317.570104 -398.109186)
			(xy 317.561595 -398.115655) (xy 317.5504 -398.133837) (xy 317.547562 -398.154999) (xy 317.55357 -398.175488)
			(xy 317.567387 -398.191766) (xy 317.586627 -398.201024) (xy 317.597282 -398.201896) (xy 317.606934 -398.201388)
			(xy 317.615447 -398.200092) (xy 317.632613 -398.198695) (xy 317.641224 -398.198594) (xy 317.641478 -398.198848)
			(xy 317.94069 -398.198848) (xy 317.940944 -398.198594) (xy 317.962005 -398.199013) (xy 318.003364 -398.206965)
			(xy 318.042362 -398.222867) (xy 318.077488 -398.246102) (xy 318.10738 -398.275771) (xy 318.130878 -398.310721)
			(xy 318.147072 -398.349599) (xy 318.155334 -398.390896) (xy 318.155828 -398.411954) (xy 318.155828 -398.666716)
			(xy 318.146684 -398.666716) (xy 318.136673 -398.667175) (xy 318.118178 -398.674843) (xy 318.104025 -398.689005)
			(xy 318.096369 -398.707505) (xy 318.095884 -398.717516) (xy 318.095884 -398.881092) (xy 318.095474 -398.891115)
			(xy 318.087803 -398.909635) (xy 318.073628 -398.923808) (xy 318.055107 -398.931475) (xy 318.045084 -398.931892)
			(xy 317.537084 -398.931892) (xy 317.527074 -398.931425) (xy 317.508581 -398.923759) (xy 317.494428 -398.909599)
			(xy 317.48677 -398.891102) (xy 317.486284 -398.881092) (xy 317.486284 -398.666716) (xy 317.47714 -398.666716)
			(xy 317.467123 -398.666248) (xy 317.44861 -398.658594) (xy 317.434437 -398.644437) (xy 317.426763 -398.625932)
			(xy 317.42634 -398.615916) (xy 317.42634 -398.411954) (xy 317.426682 -398.394721) (xy 317.432254 -398.360708)
			(xy 317.443227 -398.328035) (xy 317.450978 -398.31264) (xy 317.45682 -398.30121) (xy 317.456566 -398.27581)
			(xy 317.402972 -398.178782) (xy 317.381382 -398.165066) (xy 317.368428 -398.16405) (xy 317.344532 -398.161929)
			(xy 317.297745 -398.151328) (xy 317.253104 -398.133762) (xy 317.21164 -398.109635) (xy 317.174309 -398.079504)
			(xy 317.141975 -398.044065) (xy 317.115384 -398.004137) (xy 317.095148 -397.960641) (xy 317.088012 -397.937736)
			(xy 317.086488 -397.931894) (xy 316.766194 -397.378174) (xy 316.76213 -397.373856) (xy 316.745967 -397.356126)
			(xy 316.7186 -397.316722) (xy 316.69751 -397.273631) (xy 316.683184 -397.227846) (xy 316.67595 -397.18042)
			(xy 316.675516 -397.156432) (xy 316.675696 -397.142384) (xy 316.678237 -397.114402) (xy 316.680596 -397.100552)
			(xy 316.681919 -397.091273) (xy 316.678391 -397.072875) (xy 316.673738 -397.064738) (xy 316.656974 -397.037814)
			(xy 316.651787 -397.030098) (xy 316.637051 -397.018781) (xy 316.628272 -397.015716) (xy 316.606697 -397.008963)
			(xy 316.565571 -396.990189) (xy 316.527518 -396.965783) (xy 316.493302 -396.936236) (xy 316.478158 -396.91945)
			(xy 316.47569 -396.916682) (xy 316.470082 -396.911833) (xy 316.466982 -396.909798) (xy 316.454833 -396.901724)
			(xy 316.434748 -396.88058) (xy 316.420604 -396.855077) (xy 316.413304 -396.826843) (xy 316.41288 -396.812262)
			(xy 316.41288 -396.799816) (xy 316.411102 -396.793466) (xy 316.405972 -396.773151) (xy 316.400496 -396.731612)
			(xy 316.40018 -396.710662) (xy 316.400518 -396.689714) (xy 316.405991 -396.648176) (xy 316.411102 -396.627858)
			(xy 316.41288 -396.621508) (xy 316.41288 -396.164816) (xy 316.411102 -396.158466) (xy 316.405972 -396.138151)
			(xy 316.400496 -396.096612) (xy 316.40018 -396.075662) (xy 316.400518 -396.054714) (xy 316.405991 -396.013176)
			(xy 316.411102 -395.992858) (xy 316.41288 -395.986508) (xy 316.41288 -395.974062) (xy 316.413346 -395.958597)
			(xy 316.421577 -395.92878) (xy 316.437412 -395.902209) (xy 316.459721 -395.880782) (xy 316.473078 -395.87297)
			(xy 316.476634 -395.868906) (xy 316.483991 -395.859386) (xy 316.489685 -395.836044) (xy 316.487556 -395.824202)
			(xy 316.480444 -395.792706) (xy 316.477188 -395.781187) (xy 316.461931 -395.762776) (xy 316.451234 -395.7574)
			(xy 316.429742 -395.747597) (xy 316.38968 -395.722571) (xy 316.353765 -395.691889) (xy 316.33795 -395.674342)
			(xy 316.335484 -395.671573) (xy 316.329874 -395.666724) (xy 316.326774 -395.66469) (xy 316.314745 -395.656611)
			(xy 316.294855 -395.63555) (xy 316.280848 -395.610194) (xy 316.273607 -395.582146) (xy 316.27318 -395.567662)
			(xy 316.27318 -395.555724) (xy 316.271402 -395.54912) (xy 316.266196 -395.528751) (xy 316.260595 -395.487083)
			(xy 316.260226 -395.466062) (xy 316.260592 -395.445041) (xy 316.266203 -395.403375) (xy 316.271402 -395.383004)
			(xy 316.27318 -395.3764) (xy 316.27318 -395.262862) (xy 316.273831 -395.244742) (xy 316.28509 -395.210296)
			(xy 316.295278 -395.195298) (xy 316.299747 -395.188624) (xy 316.304682 -395.173352) (xy 316.30493 -395.165326)
			(xy 316.30493 -395.131798) (xy 316.304604 -395.123781) (xy 316.299705 -395.108516) (xy 316.295278 -395.101826)
			(xy 316.285194 -395.086775) (xy 316.273937 -395.052363) (xy 316.27318 -395.034262) (xy 316.27318 -394.920724)
			(xy 316.271402 -394.91412) (xy 316.266196 -394.893751) (xy 316.260595 -394.852083) (xy 316.260226 -394.831062)
			(xy 316.260988 -394.808456) (xy 316.26175 -394.798296) (xy 316.255654 -394.7795) (xy 316.20206 -394.717524)
			(xy 316.195111 -394.710285) (xy 316.177215 -394.701259) (xy 316.167262 -394.699998) (xy 316.143456 -394.697754)
			(xy 316.096864 -394.687003) (xy 316.052429 -394.669343) (xy 316.011168 -394.645181) (xy 315.974025 -394.615069)
			(xy 315.941852 -394.579696) (xy 315.915385 -394.539874) (xy 315.89523 -394.496513) (xy 315.888116 -394.473684)
			(xy 315.886592 -394.467842) (xy 315.566298 -393.914122) (xy 315.562234 -393.909804) (xy 315.546079 -393.892134)
			(xy 315.51876 -393.852817) (xy 315.497692 -393.809826) (xy 315.483358 -393.764146) (xy 315.476085 -393.716826)
			(xy 315.47562 -393.692888) (xy 314.943528 -393.692888) (xy 315.215778 -394.16355) (xy 315.219842 -394.167868)
			(xy 315.235996 -394.185573) (xy 315.26334 -394.224931) (xy 315.28442 -394.267971) (xy 315.298752 -394.313703)
			(xy 315.306006 -394.361076) (xy 315.306456 -394.385038) (xy 315.306456 -394.385546) (xy 315.305948 -394.405866)
			(xy 315.305186 -394.415772) (xy 315.311536 -394.434822) (xy 315.372242 -394.504164) (xy 315.390022 -394.513054)
			(xy 315.400182 -394.513816) (xy 315.425159 -394.516005) (xy 315.474017 -394.52726) (xy 315.520504 -394.546041)
			(xy 315.563469 -394.571884) (xy 315.601846 -394.604147) (xy 315.618622 -394.622782) (xy 315.621088 -394.625551)
			(xy 315.626698 -394.6304) (xy 315.629798 -394.632434) (xy 315.641832 -394.640507) (xy 315.661723 -394.661568)
			(xy 315.67573 -394.686926) (xy 315.682968 -394.714977) (xy 315.683392 -394.729462) (xy 315.683392 -394.7414)
			(xy 315.68517 -394.748004) (xy 315.690362 -394.768376) (xy 315.695972 -394.810042) (xy 315.696346 -394.831062)
			(xy 315.695963 -394.852082) (xy 315.690364 -394.893748) (xy 315.68517 -394.91412) (xy 315.683392 -394.920724)
			(xy 315.683392 -394.979398) (xy 315.71311 -395.009116) (xy 315.719968 -395.009116) (xy 315.730036 -395.009554)
			(xy 315.748634 -395.017265) (xy 315.756036 -395.024102) (xy 315.979302 -395.247114) (xy 315.986141 -395.254515)
			(xy 315.993861 -395.273114) (xy 315.994288 -395.283182) (xy 315.994288 -396.892272) (xy 315.994732 -396.902522)
			(xy 316.002728 -396.921397) (xy 316.009782 -396.928848) (xy 316.029172 -396.948291) (xy 316.061595 -396.992599)
			(xy 316.085857 -397.041851) (xy 316.09411 -397.06804) (xy 316.095634 -397.073628) (xy 316.255146 -397.349472)
			(xy 316.263274 -397.36014) (xy 316.414912 -397.511778) (xy 316.421583 -397.519198) (xy 316.429175 -397.537628)
			(xy 316.429177 -397.557561) (xy 316.421589 -397.575992) (xy 316.414912 -397.583406) (xy 316.414658 -397.58366)
			(xy 316.41034 -397.61795) (xy 316.412118 -397.621252) (xy 316.41796 -397.62938) (xy 316.42685 -397.639286)
			(xy 316.441812 -397.656748) (xy 316.467104 -397.69515) (xy 316.486558 -397.736813) (xy 316.499764 -397.780858)
			(xy 316.506441 -397.826353) (xy 316.50686 -397.849344) (xy 316.506331 -397.874072) (xy 316.498595 -397.922919)
			(xy 316.483335 -397.969961) (xy 316.460924 -398.014048) (xy 316.431912 -398.0541) (xy 316.397007 -398.089136)
			(xy 316.37732 -398.104106) (xy 316.36802 -398.111684) (xy 316.35714 -398.133022) (xy 316.356492 -398.145)
			(xy 316.356492 -398.149826) (xy 316.356966 -398.159834) (xy 316.364633 -398.178325) (xy 316.37879 -398.192477)
			(xy 316.397283 -398.200137) (xy 316.407292 -398.200626) (xy 316.410594 -398.200626) (xy 316.413642 -398.200372)
			(xy 316.441074 -398.198594) (xy 316.441328 -398.198848) (xy 316.74054 -398.198848) (xy 316.740794 -398.198594)
			(xy 316.761839 -398.199039) (xy 316.803158 -398.207027) (xy 316.842112 -398.222951) (xy 316.877195 -398.246194)
			(xy 316.907046 -398.275858) (xy 316.930512 -398.310792) (xy 316.946682 -398.349645) (xy 316.954932 -398.390912)
			(xy 316.955424 -398.411954) (xy 316.955424 -398.666716) (xy 316.94628 -398.666716) (xy 316.936269 -398.667172)
			(xy 316.917774 -398.674841) (xy 316.903621 -398.689004) (xy 316.895965 -398.707505) (xy 316.89548 -398.717516)
			(xy 316.89548 -398.881092) (xy 316.895074 -398.891115) (xy 316.887402 -398.909636) (xy 316.873226 -398.923809)
			(xy 316.854703 -398.931476) (xy 316.84468 -398.931892) (xy 316.39129 -398.931892) (xy 316.381283 -398.93238)
			(xy 316.362792 -398.940041) (xy 316.34864 -398.954194) (xy 316.340979 -398.972685) (xy 316.34049 -398.982692)
			(xy 316.34049 -401.675346) (xy 316.634876 -401.675346) (xy 316.634876 -400.81073) (xy 316.635323 -400.785263)
			(xy 316.642125 -400.734783) (xy 316.655585 -400.685659) (xy 316.675464 -400.638763) (xy 316.701407 -400.59493)
			(xy 316.732954 -400.55494) (xy 316.750954 -400.536918) (xy 316.757558 -400.530568) (xy 316.765432 -400.513804)
			(xy 316.77229 -400.42846) (xy 316.76721 -400.41068) (xy 316.761622 -400.403314) (xy 316.74677 -400.382567)
			(xy 316.723135 -400.337353) (xy 316.707034 -400.288941) (xy 316.698882 -400.238578) (xy 316.698376 -400.213068)
			(xy 316.698376 -400.212814) (xy 316.698866 -400.187825) (xy 316.706685 -400.138462) (xy 316.722129 -400.09093)
			(xy 316.744819 -400.046398) (xy 316.774195 -400.005965) (xy 316.809535 -399.970625) (xy 316.849968 -399.941249)
			(xy 316.8945 -399.918559) (xy 316.942032 -399.903115) (xy 316.991395 -399.895296) (xy 317.041373 -399.895296)
			(xy 317.090736 -399.903115) (xy 317.138268 -399.918559) (xy 317.1828 -399.941249) (xy 317.223233 -399.970625)
			(xy 317.258573 -400.005965) (xy 317.287949 -400.046398) (xy 317.310639 -400.09093) (xy 317.326083 -400.138462)
			(xy 317.333902 -400.187825) (xy 317.334392 -400.212814) (xy 317.334392 -400.213068) (xy 317.333901 -400.238577)
			(xy 317.325723 -400.288937) (xy 317.309621 -400.337348) (xy 317.286005 -400.382572) (xy 317.271146 -400.403314)
			(xy 317.265558 -400.41068) (xy 317.260478 -400.42846) (xy 317.267336 -400.513804) (xy 317.27521 -400.530568)
			(xy 317.281814 -400.536918) (xy 317.299824 -400.554929) (xy 317.331362 -400.594927) (xy 317.3573 -400.638763)
			(xy 317.377178 -400.68566) (xy 317.390641 -400.734784) (xy 317.397451 -400.785262) (xy 317.397892 -400.81073)
			(xy 317.397892 -401.675346) (xy 317.834772 -401.675346) (xy 317.834772 -400.81073) (xy 317.83522 -400.785263)
			(xy 317.842022 -400.734784) (xy 317.855482 -400.685659) (xy 317.875361 -400.638763) (xy 317.901304 -400.59493)
			(xy 317.93285 -400.55494) (xy 317.95085 -400.536918) (xy 317.957454 -400.530568) (xy 317.965328 -400.513804)
			(xy 317.972186 -400.42846) (xy 317.967106 -400.41068) (xy 317.961518 -400.403314) (xy 317.946666 -400.382567)
			(xy 317.923031 -400.337353) (xy 317.90693 -400.288941) (xy 317.898778 -400.238578) (xy 317.898272 -400.213068)
			(xy 317.898272 -400.212814) (xy 317.898762 -400.187825) (xy 317.906581 -400.138462) (xy 317.922025 -400.09093)
			(xy 317.944715 -400.046398) (xy 317.974091 -400.005965) (xy 318.009431 -399.970625) (xy 318.049864 -399.941249)
			(xy 318.094396 -399.918559) (xy 318.141928 -399.903115) (xy 318.191291 -399.895296) (xy 318.241269 -399.895296)
			(xy 318.290632 -399.903115) (xy 318.338164 -399.918559) (xy 318.382696 -399.941249) (xy 318.423129 -399.970625)
			(xy 318.458469 -400.005965) (xy 318.487845 -400.046398) (xy 318.510535 -400.09093) (xy 318.525979 -400.138462)
			(xy 318.533798 -400.187825) (xy 318.534288 -400.212814) (xy 318.534288 -400.213068) (xy 318.533778 -400.238576)
			(xy 318.525603 -400.288934) (xy 318.509505 -400.337345) (xy 318.485897 -400.382571) (xy 318.471042 -400.403314)
			(xy 318.465454 -400.41068) (xy 318.460374 -400.42846) (xy 318.467232 -400.513804) (xy 318.475106 -400.530568)
			(xy 318.48171 -400.536918) (xy 318.49972 -400.55493) (xy 318.531258 -400.594927) (xy 318.557196 -400.638763)
			(xy 318.577074 -400.68566) (xy 318.590537 -400.734784) (xy 318.597347 -400.785263) (xy 318.597788 -400.81073)
			(xy 318.597788 -401.674838) (xy 319.034668 -401.674838) (xy 319.034668 -400.81073) (xy 319.035118 -400.785263)
			(xy 319.041919 -400.734784) (xy 319.055379 -400.685659) (xy 319.075257 -400.638763) (xy 319.1012 -400.59493)
			(xy 319.132746 -400.55494) (xy 319.150746 -400.536918) (xy 319.15735 -400.530568) (xy 319.165224 -400.513804)
			(xy 319.172082 -400.42846) (xy 319.167002 -400.41068) (xy 319.161414 -400.403314) (xy 319.146561 -400.382567)
			(xy 319.122927 -400.337353) (xy 319.106826 -400.288941) (xy 319.098674 -400.238578) (xy 319.098168 -400.213068)
			(xy 319.098168 -400.212814) (xy 319.098658 -400.187825) (xy 319.106477 -400.138462) (xy 319.121921 -400.09093)
			(xy 319.144611 -400.046398) (xy 319.173987 -400.005965) (xy 319.209327 -399.970625) (xy 319.24976 -399.941249)
			(xy 319.294292 -399.918559) (xy 319.341824 -399.903115) (xy 319.391187 -399.895296) (xy 319.441165 -399.895296)
			(xy 319.490528 -399.903115) (xy 319.53806 -399.918559) (xy 319.582592 -399.941249) (xy 319.623025 -399.970625)
			(xy 319.658365 -400.005965) (xy 319.687741 -400.046398) (xy 319.710431 -400.09093) (xy 319.725875 -400.138462)
			(xy 319.733694 -400.187825) (xy 319.734184 -400.212814) (xy 319.734184 -400.213068) (xy 319.733675 -400.238576)
			(xy 319.7255 -400.288934) (xy 319.709402 -400.337345) (xy 319.685793 -400.382571) (xy 319.670938 -400.403314)
			(xy 319.66535 -400.41068) (xy 319.66027 -400.42846) (xy 319.667128 -400.513804) (xy 319.675002 -400.530568)
			(xy 319.681606 -400.536918) (xy 319.699615 -400.554931) (xy 319.731153 -400.594927) (xy 319.757092 -400.638764)
			(xy 319.776969 -400.68566) (xy 319.790433 -400.734784) (xy 319.797243 -400.785263) (xy 319.797684 -400.81073)
			(xy 319.797684 -401.674838) (xy 320.234564 -401.674838) (xy 320.234564 -400.811238) (xy 320.234982 -400.785718)
			(xy 320.241772 -400.735131) (xy 320.25525 -400.685902) (xy 320.275175 -400.638911) (xy 320.30119 -400.594998)
			(xy 320.33283 -400.554948) (xy 320.350896 -400.536918) (xy 320.3575 -400.530568) (xy 320.365374 -400.513804)
			(xy 320.372232 -400.42846) (xy 320.367152 -400.41068) (xy 320.361564 -400.403314) (xy 320.346718 -400.382563)
			(xy 320.32308 -400.337351) (xy 320.306977 -400.28894) (xy 320.298824 -400.238577) (xy 320.298318 -400.213068)
			(xy 320.298318 -400.212814) (xy 320.298808 -400.187825) (xy 320.306627 -400.138462) (xy 320.322071 -400.09093)
			(xy 320.344761 -400.046398) (xy 320.374137 -400.005965) (xy 320.409477 -399.970625) (xy 320.44991 -399.941249)
			(xy 320.494442 -399.918559) (xy 320.541974 -399.903115) (xy 320.591337 -399.895296) (xy 320.641315 -399.895296)
			(xy 320.690678 -399.903115) (xy 320.73821 -399.918559) (xy 320.782742 -399.941249) (xy 320.823175 -399.970625)
			(xy 320.858515 -400.005965) (xy 320.887891 -400.046398) (xy 320.910581 -400.09093) (xy 320.926025 -400.138462)
			(xy 320.933844 -400.187825) (xy 320.934334 -400.212814) (xy 320.934334 -400.213068) (xy 320.933834 -400.238577)
			(xy 320.925658 -400.288936) (xy 320.909558 -400.337347) (xy 320.885945 -400.382572) (xy 320.871088 -400.403314)
			(xy 320.8655 -400.41068) (xy 320.86042 -400.42846) (xy 320.867278 -400.513804) (xy 320.875152 -400.530568)
			(xy 320.881756 -400.536918) (xy 320.89979 -400.554976) (xy 320.931421 -400.595028) (xy 320.957432 -400.638937)
			(xy 320.97736 -400.685921) (xy 320.990849 -400.735141) (xy 320.997658 -400.78572) (xy 320.998088 -400.811238)
			(xy 320.998088 -401.674838) (xy 321.43446 -401.674838) (xy 321.43446 -400.811238) (xy 321.434879 -400.785718)
			(xy 321.441669 -400.735131) (xy 321.455147 -400.685902) (xy 321.475071 -400.638911) (xy 321.501086 -400.594998)
			(xy 321.532726 -400.554948) (xy 321.550792 -400.536918) (xy 321.557396 -400.530568) (xy 321.56527 -400.513804)
			(xy 321.572128 -400.42846) (xy 321.567048 -400.41068) (xy 321.56146 -400.403314) (xy 321.546613 -400.382563)
			(xy 321.522976 -400.337351) (xy 321.506873 -400.28894) (xy 321.49872 -400.238577) (xy 321.498214 -400.213068)
			(xy 321.498214 -400.212814) (xy 321.498704 -400.187825) (xy 321.506523 -400.138462) (xy 321.521967 -400.09093)
			(xy 321.544657 -400.046398) (xy 321.574033 -400.005965) (xy 321.609373 -399.970625) (xy 321.649806 -399.941249)
			(xy 321.694338 -399.918559) (xy 321.74187 -399.903115) (xy 321.791233 -399.895296) (xy 321.841211 -399.895296)
			(xy 321.890574 -399.903115) (xy 321.938106 -399.918559) (xy 321.982638 -399.941249) (xy 322.023071 -399.970625)
			(xy 322.058411 -400.005965) (xy 322.087787 -400.046398) (xy 322.110477 -400.09093) (xy 322.125921 -400.138462)
			(xy 322.13374 -400.187825) (xy 322.13423 -400.212814) (xy 322.13423 -400.213068) (xy 322.133731 -400.238577)
			(xy 322.125555 -400.288936) (xy 322.109454 -400.337347) (xy 322.085841 -400.382572) (xy 322.070984 -400.403314)
			(xy 322.065396 -400.41068) (xy 322.060316 -400.42846) (xy 322.067174 -400.513804) (xy 322.075048 -400.530568)
			(xy 322.081652 -400.536918) (xy 322.099686 -400.554977) (xy 322.131316 -400.595028) (xy 322.157328 -400.638937)
			(xy 322.177256 -400.685921) (xy 322.190745 -400.735142) (xy 322.197554 -400.78572) (xy 322.197984 -400.811238)
			(xy 322.197984 -401.197826) (xy 323.511162 -401.197826) (xy 323.515233 -401.142204) (xy 323.527359 -401.087767)
			(xy 323.547282 -401.035676) (xy 323.574578 -400.987041) (xy 323.608664 -400.942898) (xy 323.648813 -400.904189)
			(xy 323.694171 -400.871738) (xy 323.743771 -400.846237) (xy 323.796555 -400.82823) (xy 323.851398 -400.8181)
			(xy 323.907132 -400.816063) (xy 323.962569 -400.822163) (xy 324.016526 -400.836269) (xy 324.067855 -400.858081)
			(xy 324.115461 -400.887135) (xy 324.158329 -400.92281) (xy 324.195546 -400.964347) (xy 324.226319 -401.01086)
			(xy 324.249991 -401.061357) (xy 324.266059 -401.114764) (xy 324.274179 -401.16994) (xy 324.274688 -401.197826)
			(xy 324.274179 -401.225712) (xy 324.266059 -401.280888) (xy 324.249991 -401.334295) (xy 324.226319 -401.384792)
			(xy 324.195546 -401.431305) (xy 324.158329 -401.472842) (xy 324.115461 -401.508517) (xy 324.067855 -401.537571)
			(xy 324.016526 -401.559383) (xy 323.962569 -401.573489) (xy 323.907132 -401.579589) (xy 323.851398 -401.577552)
			(xy 323.796555 -401.567422) (xy 323.743771 -401.549415) (xy 323.694171 -401.523914) (xy 323.648813 -401.491463)
			(xy 323.608664 -401.452754) (xy 323.574578 -401.408611) (xy 323.547282 -401.359976) (xy 323.527359 -401.307885)
			(xy 323.515233 -401.253448) (xy 323.511162 -401.197826) (xy 322.197984 -401.197826) (xy 322.197984 -401.674838)
			(xy 322.196968 -401.703794) (xy 322.19664 -401.716396) (xy 322.196906 -401.717002) (xy 324.23303 -401.717002)
			(xy 324.237101 -401.66138) (xy 324.249227 -401.606943) (xy 324.26915 -401.554852) (xy 324.296446 -401.506217)
			(xy 324.330532 -401.462074) (xy 324.370681 -401.423365) (xy 324.416039 -401.390914) (xy 324.465639 -401.365413)
			(xy 324.518423 -401.347406) (xy 324.573266 -401.337276) (xy 324.629 -401.335239) (xy 324.684437 -401.341339)
			(xy 324.738394 -401.355445) (xy 324.789723 -401.377257) (xy 324.837329 -401.406311) (xy 324.880197 -401.441986)
			(xy 324.917414 -401.483523) (xy 324.948187 -401.530036) (xy 324.971859 -401.580533) (xy 324.987927 -401.63394)
			(xy 324.996047 -401.689116) (xy 324.996556 -401.717002) (xy 324.996047 -401.744888) (xy 324.987927 -401.800064)
			(xy 324.971859 -401.853471) (xy 324.948187 -401.903968) (xy 324.917414 -401.950481) (xy 324.880197 -401.992018)
			(xy 324.837329 -402.027693) (xy 324.789723 -402.056747) (xy 324.738394 -402.078559) (xy 324.684437 -402.092665)
			(xy 324.629 -402.098765) (xy 324.573266 -402.096728) (xy 324.518423 -402.086598) (xy 324.465639 -402.068591)
			(xy 324.416039 -402.04309) (xy 324.370681 -402.010639) (xy 324.330532 -401.97193) (xy 324.296446 -401.927787)
			(xy 324.26915 -401.879152) (xy 324.249227 -401.827061) (xy 324.237101 -401.772624) (xy 324.23303 -401.717002)
			(xy 322.196906 -401.717002) (xy 322.206774 -401.739446) (xy 322.216272 -401.747736) (xy 322.241164 -401.76704)
			(xy 322.251488 -401.774242) (xy 322.276269 -401.778502) (xy 322.288408 -401.775168) (xy 322.316687 -401.766396)
			(xy 322.375137 -401.756959) (xy 322.40474 -401.756372) (xy 322.432336 -401.756931) (xy 322.486912 -401.765162)
			(xy 322.539651 -401.781435) (xy 322.589376 -401.805386) (xy 322.634976 -401.83648) (xy 322.675433 -401.874023)
			(xy 322.709843 -401.917176) (xy 322.737437 -401.964975) (xy 322.7576 -402.016353) (xy 322.769881 -402.070162)
			(xy 322.774005 -402.1252) (xy 322.769881 -402.180238) (xy 322.7576 -402.234047) (xy 322.737437 -402.285425)
			(xy 322.709843 -402.333224) (xy 322.675433 -402.376377) (xy 322.634976 -402.41392) (xy 322.589376 -402.445014)
			(xy 322.539651 -402.468965) (xy 322.486912 -402.485238) (xy 322.432336 -402.493469) (xy 322.40474 -402.493988)
			(xy 322.376379 -402.493456) (xy 322.320329 -402.48475) (xy 322.266277 -402.467553) (xy 322.240656 -402.45538)
			(xy 322.232341 -402.451674) (xy 322.214239 -402.449857) (xy 322.20535 -402.451824) (xy 322.131944 -402.47062)
			(xy 322.116958 -402.481034) (xy 322.111878 -402.488654) (xy 322.094971 -402.51217) (xy 322.054855 -402.553943)
			(xy 322.008558 -402.588738) (xy 321.957278 -402.615657) (xy 321.902345 -402.634001) (xy 321.84518 -402.643295)
			(xy 321.816222 -402.643848) (xy 321.790552 -402.643332) (xy 321.739733 -402.636029) (xy 321.69047 -402.621568)
			(xy 321.643767 -402.600243) (xy 321.600575 -402.572489) (xy 321.561771 -402.538871) (xy 321.528147 -402.500073)
			(xy 321.500386 -402.456885) (xy 321.479053 -402.410186) (xy 321.464584 -402.360926) (xy 321.457273 -402.310108)
			(xy 321.456812 -402.284438) (xy 321.457211 -402.260235) (xy 321.463713 -402.212267) (xy 321.476603 -402.165609)
			(xy 321.495648 -402.121106) (xy 321.520502 -402.079568) (xy 321.535298 -402.06041) (xy 321.535552 -402.060156)
			(xy 321.540826 -402.05297) (xy 321.546408 -402.03605) (xy 321.546474 -402.027136) (xy 321.544442 -401.952714)
			(xy 321.537584 -401.93595) (xy 321.531742 -401.929346) (xy 321.513533 -401.908236) (xy 321.48279 -401.861732)
			(xy 321.45914 -401.81125) (xy 321.443086 -401.757865) (xy 321.43497 -401.702712) (xy 321.43446 -401.674838)
			(xy 320.998088 -401.674838) (xy 320.997518 -401.704001) (xy 320.988598 -401.761642) (xy 320.971016 -401.817256)
			(xy 320.945182 -401.86955) (xy 320.911697 -401.917307) (xy 320.891916 -401.938744) (xy 320.885749 -401.94582)
			(xy 320.878598 -401.963161) (xy 320.877946 -401.972526) (xy 320.876168 -402.041106) (xy 320.876319 -402.050362)
			(xy 320.882448 -402.067814) (xy 320.888106 -402.075142) (xy 320.888614 -402.07565) (xy 320.904965 -402.095265)
			(xy 320.932499 -402.138273) (xy 320.953657 -402.18475) (xy 320.968012 -402.233758) (xy 320.975275 -402.284305)
			(xy 320.975736 -402.309838) (xy 320.975234 -402.336734) (xy 320.967216 -402.389926) (xy 320.95136 -402.441329)
			(xy 320.928021 -402.489795) (xy 320.897718 -402.534241) (xy 320.86113 -402.573674) (xy 320.819073 -402.607213)
			(xy 320.772487 -402.634109) (xy 320.722413 -402.653762) (xy 320.669968 -402.665732) (xy 320.616326 -402.669752)
			(xy 320.562684 -402.665732) (xy 320.510239 -402.653762) (xy 320.460165 -402.634109) (xy 320.413579 -402.607213)
			(xy 320.371522 -402.573674) (xy 320.334934 -402.534241) (xy 320.304631 -402.489795) (xy 320.281292 -402.441329)
			(xy 320.265436 -402.389926) (xy 320.257418 -402.336734) (xy 320.256916 -402.309838) (xy 320.257401 -402.284271)
			(xy 320.264676 -402.233656) (xy 320.279071 -402.184589) (xy 320.300292 -402.138066) (xy 320.327909 -402.09503)
			(xy 320.344292 -402.075396) (xy 320.344546 -402.075142) (xy 320.350207 -402.067819) (xy 320.35632 -402.050362)
			(xy 320.356484 -402.041106) (xy 320.354452 -401.962874) (xy 320.34734 -401.945856) (xy 320.340736 -401.938744)
			(xy 320.320956 -401.917306) (xy 320.287463 -401.869553) (xy 320.261625 -401.81726) (xy 320.244046 -401.761644)
			(xy 320.235135 -401.704002) (xy 320.234564 -401.674838) (xy 319.797684 -401.674838) (xy 319.797142 -401.703992)
			(xy 319.788271 -401.761621) (xy 319.77074 -401.817231) (xy 319.744957 -401.869529) (xy 319.711523 -401.917298)
			(xy 319.691766 -401.938744) (xy 319.685606 -401.945825) (xy 319.67845 -401.963162) (xy 319.677796 -401.972526)
			(xy 319.676018 -402.041106) (xy 319.676158 -402.050363) (xy 319.682294 -402.067816) (xy 319.687956 -402.075142)
			(xy 319.688464 -402.07565) (xy 319.704774 -402.095286) (xy 319.732249 -402.138307) (xy 319.753353 -402.184785)
			(xy 319.767662 -402.233784) (xy 319.774886 -402.284315) (xy 319.775332 -402.309838) (xy 319.77483 -402.336715)
			(xy 319.766818 -402.38987) (xy 319.750974 -402.441236) (xy 319.72765 -402.489668) (xy 319.697369 -402.534082)
			(xy 319.660807 -402.573487) (xy 319.618779 -402.607003) (xy 319.572226 -402.63388) (xy 319.522187 -402.653519)
			(xy 319.46978 -402.66548) (xy 319.416176 -402.669498) (xy 319.362572 -402.66548) (xy 319.310165 -402.653519)
			(xy 319.260126 -402.63388) (xy 319.213573 -402.607003) (xy 319.171545 -402.573487) (xy 319.134983 -402.534082)
			(xy 319.104702 -402.489668) (xy 319.081378 -402.441236) (xy 319.065534 -402.38987) (xy 319.057522 -402.336715)
			(xy 319.05702 -402.309838) (xy 319.0575 -402.284281) (xy 319.064735 -402.233682) (xy 319.079079 -402.184623)
			(xy 319.100241 -402.138096) (xy 319.127793 -402.095044) (xy 319.144142 -402.075396) (xy 319.144396 -402.075142)
			(xy 319.150063 -402.067823) (xy 319.156171 -402.050362) (xy 319.156334 -402.041106) (xy 319.154302 -401.962874)
			(xy 319.14719 -401.945856) (xy 319.140586 -401.938744) (xy 319.120848 -401.917282) (xy 319.087411 -401.869517)
			(xy 319.061627 -401.817223) (xy 319.044095 -401.761617) (xy 319.035223 -401.70399) (xy 319.034668 -401.674838)
			(xy 318.597788 -401.674838) (xy 318.597788 -401.675346) (xy 318.597213 -401.705084) (xy 318.587932 -401.763831)
			(xy 318.56965 -401.820428) (xy 318.542808 -401.873502) (xy 318.508057 -401.92177) (xy 318.487552 -401.943316)
			(xy 318.481223 -401.950273) (xy 318.473668 -401.967477) (xy 318.47282 -401.976844) (xy 318.47155 -402.008086)
			(xy 318.471546 -402.017335) (xy 318.477268 -402.034909) (xy 318.482726 -402.042376) (xy 318.500741 -402.065524)
			(xy 318.529479 -402.116651) (xy 318.549117 -402.171916) (xy 318.559087 -402.229713) (xy 318.559688 -402.259038)
			(xy 318.559208 -402.284737) (xy 318.551547 -402.335561) (xy 318.536398 -402.384675) (xy 318.514097 -402.430983)
			(xy 318.485144 -402.47345) (xy 318.450184 -402.511127) (xy 318.41 -402.543173) (xy 318.365488 -402.568872)
			(xy 318.317643 -402.587649) (xy 318.267534 -402.599087) (xy 318.21628 -402.602928) (xy 318.165026 -402.599087)
			(xy 318.114917 -402.587649) (xy 318.067072 -402.568872) (xy 318.02256 -402.543173) (xy 317.982376 -402.511127)
			(xy 317.947416 -402.47345) (xy 317.918463 -402.430983) (xy 317.896162 -402.384675) (xy 317.881013 -402.335561)
			(xy 317.873352 -402.284737) (xy 317.872872 -402.259038) (xy 317.873462 -402.229711) (xy 317.88342 -402.171908)
			(xy 317.903054 -402.116637) (xy 317.931793 -402.065506) (xy 317.949834 -402.042376) (xy 317.955336 -402.034929)
			(xy 317.961075 -402.017344) (xy 317.96101 -402.008086) (xy 317.95974 -401.976844) (xy 317.958866 -401.967483)
			(xy 317.951318 -401.950284) (xy 317.945008 -401.943316) (xy 317.924516 -401.921758) (xy 317.889757 -401.873498)
			(xy 317.862913 -401.820426) (xy 317.844633 -401.76383) (xy 317.835361 -401.705083) (xy 317.834772 -401.675346)
			(xy 317.397892 -401.675346) (xy 317.397278 -401.705696) (xy 317.387628 -401.765624) (xy 317.368608 -401.823268)
			(xy 317.340701 -401.877173) (xy 317.30461 -401.925978) (xy 317.283338 -401.947634) (xy 317.27648 -401.954492)
			(xy 317.268352 -401.972018) (xy 317.264542 -402.060664) (xy 317.270892 -402.078952) (xy 317.277242 -402.086318)
			(xy 317.292749 -402.105058) (xy 317.318864 -402.146094) (xy 317.33892 -402.190407) (xy 317.352514 -402.237109)
			(xy 317.359374 -402.285264) (xy 317.359792 -402.309584) (xy 317.359792 -402.309838) (xy 317.359312 -402.335537)
			(xy 317.351651 -402.386361) (xy 317.336502 -402.435475) (xy 317.314201 -402.481783) (xy 317.285248 -402.52425)
			(xy 317.250288 -402.561927) (xy 317.210104 -402.593973) (xy 317.165592 -402.619672) (xy 317.117747 -402.638449)
			(xy 317.067638 -402.649887) (xy 317.016384 -402.653728) (xy 316.96513 -402.649887) (xy 316.915021 -402.638449)
			(xy 316.867176 -402.619672) (xy 316.822664 -402.593973) (xy 316.78248 -402.561927) (xy 316.74752 -402.52425)
			(xy 316.718567 -402.481783) (xy 316.696266 -402.435475) (xy 316.681117 -402.386361) (xy 316.673456 -402.335537)
			(xy 316.672976 -402.309838) (xy 316.672976 -402.309584) (xy 316.673398 -402.285266) (xy 316.680284 -402.237119)
			(xy 316.693888 -402.190424) (xy 316.713939 -402.146112) (xy 316.740035 -402.105069) (xy 316.755526 -402.086318)
			(xy 316.761876 -402.078952) (xy 316.768226 -402.060664) (xy 316.764416 -401.972018) (xy 316.756288 -401.954492)
			(xy 316.74943 -401.947634) (xy 316.728165 -401.925971) (xy 316.692069 -401.877169) (xy 316.664157 -401.823267)
			(xy 316.645135 -401.765624) (xy 316.635483 -401.705696) (xy 316.634876 -401.675346) (xy 316.34049 -401.675346)
			(xy 316.34049 -402.810218) (xy 316.340076 -402.820289) (xy 316.332348 -402.838886) (xy 316.325504 -402.846286)
			(xy 316.039754 -403.132036) (xy 316.032295 -403.138792) (xy 316.013736 -403.146515) (xy 316.003686 -403.147022)
			(xy 309.186834 -403.147022) (xy 309.176764 -403.1466) (xy 309.158165 -403.138879) (xy 309.150766 -403.132036)
			(xy 308.850538 -402.831808) (xy 308.850538 -402.831554) (xy 308.75351 -402.734526) (xy 308.7403 -402.72098)
			(xy 308.716987 -402.691178) (xy 308.707028 -402.67509) (xy 308.701621 -402.666956) (xy 308.686063 -402.655176)
			(xy 308.667241 -402.650026) (xy 308.657498 -402.650706) (xy 308.647252 -402.651886) (xy 308.626664 -402.653155)
			(xy 308.61635 -402.653246) (xy 308.589365 -402.652725) (xy 308.536062 -402.644276) (xy 308.484735 -402.627594)
			(xy 308.43665 -402.603089) (xy 308.392989 -402.571365) (xy 308.354828 -402.533202) (xy 308.323105 -402.48954)
			(xy 308.298602 -402.441454) (xy 308.281921 -402.390127) (xy 308.273474 -402.336823) (xy 308.272942 -402.309838)
			(xy 308.272942 -402.309584) (xy 308.273372 -402.285266) (xy 308.280258 -402.23712) (xy 308.29386 -402.190425)
			(xy 308.313909 -402.146113) (xy 308.340003 -402.10507) (xy 308.355492 -402.086318) (xy 308.361842 -402.078952)
			(xy 308.368192 -402.060664) (xy 308.364382 -401.972018) (xy 308.356254 -401.954492) (xy 308.349396 -401.947634)
			(xy 308.331583 -401.929609) (xy 308.300354 -401.8897) (xy 308.274683 -401.846008) (xy 308.255023 -401.799302)
			(xy 308.241719 -401.750404) (xy 308.235005 -401.700176) (xy 308.234588 -401.674838) (xy 308.234588 -400.811238)
			(xy 308.235029 -400.785719) (xy 308.241818 -400.735134) (xy 308.255293 -400.685906) (xy 308.275213 -400.638916)
			(xy 308.301223 -400.595002) (xy 308.332857 -400.554949) (xy 308.35092 -400.536918) (xy 308.357524 -400.530568)
			(xy 308.365398 -400.513804) (xy 308.372256 -400.42846) (xy 308.367176 -400.41068) (xy 308.361588 -400.403314)
			(xy 308.346732 -400.38257) (xy 308.323099 -400.337354) (xy 308.307 -400.288942) (xy 308.298848 -400.238578)
			(xy 308.298342 -400.213068) (xy 308.298342 -400.212814) (xy 308.298931 -400.186188) (xy 308.307807 -400.13368)
			(xy 308.325297 -400.083381) (xy 308.350914 -400.036694) (xy 308.383942 -399.994921) (xy 308.423462 -399.959227)
			(xy 308.46837 -399.930607) (xy 308.517415 -399.90986) (xy 308.543198 -399.903188) (xy 308.554179 -399.89996)
			(xy 308.572019 -399.885677) (xy 308.581926 -399.865084) (xy 308.582568 -399.853658) (xy 308.582568 -399.165826)
			(xy 308.582137 -399.155757) (xy 308.574421 -399.137159) (xy 308.567582 -399.129758) (xy 308.384448 -398.946624)
			(xy 308.376979 -398.939915) (xy 308.35841 -398.932335) (xy 308.34838 -398.931892) (xy 307.937408 -398.931892)
			(xy 307.927386 -398.931474) (xy 307.908868 -398.923805) (xy 307.894695 -398.909632) (xy 307.887026 -398.891114)
			(xy 307.886608 -398.881092) (xy 307.886608 -398.666716) (xy 307.877464 -398.666716) (xy 307.867456 -398.666242)
			(xy 307.848966 -398.658573) (xy 307.834815 -398.644417) (xy 307.827154 -398.625924) (xy 307.826664 -398.615916)
			(xy 307.826664 -398.411446) (xy 307.827444 -398.385723) (xy 307.839779 -398.335777) (xy 307.851048 -398.31264)
			(xy 307.85689 -398.30121) (xy 307.856636 -398.27581) (xy 307.803042 -398.178782) (xy 307.781452 -398.165066)
			(xy 307.768498 -398.16405) (xy 307.744599 -398.161953) (xy 307.697811 -398.151348) (xy 307.65317 -398.133778)
			(xy 307.611706 -398.109647) (xy 307.574377 -398.079513) (xy 307.542043 -398.044071) (xy 307.515452 -398.00414)
			(xy 307.495218 -397.960642) (xy 307.488082 -397.937736) (xy 307.486558 -397.931894) (xy 307.166264 -397.378174)
			(xy 307.1622 -397.373856) (xy 307.145997 -397.356147) (xy 307.118572 -397.316757) (xy 307.09743 -397.273667)
			(xy 307.083056 -397.227873) (xy 307.075782 -397.18043) (xy 307.075332 -397.156432) (xy 307.07551 -397.142384)
			(xy 307.078054 -397.114402) (xy 307.080412 -397.100552) (xy 307.0817 -397.091296) (xy 307.078303 -397.072932)
			(xy 307.073808 -397.064738) (xy 307.057044 -397.037814) (xy 307.051833 -397.030118) (xy 307.037114 -397.01879)
			(xy 307.028342 -397.015716) (xy 307.006715 -397.008919) (xy 306.965501 -396.990036) (xy 306.927381 -396.9655)
			(xy 306.893125 -396.935806) (xy 306.877974 -396.918942) (xy 306.875506 -396.916175) (xy 306.869897 -396.911325)
			(xy 306.866798 -396.90929) (xy 306.854774 -396.901203) (xy 306.834882 -396.880146) (xy 306.820873 -396.854792)
			(xy 306.813631 -396.826745) (xy 306.813204 -396.812262) (xy 306.813204 -396.800324) (xy 306.811426 -396.79372)
			(xy 306.806219 -396.773351) (xy 306.800619 -396.731683) (xy 306.80025 -396.710662) (xy 306.23637 -396.710662)
			(xy 306.23637 -396.71117) (xy 306.2362 -396.725795) (xy 306.233533 -396.754924) (xy 306.231036 -396.769336)
			(xy 306.229668 -396.77851) (xy 306.232943 -396.796753) (xy 306.237386 -396.804896) (xy 306.253896 -396.83182)
			(xy 306.259047 -396.839613) (xy 306.273786 -396.851067) (xy 306.282598 -396.854172) (xy 306.307517 -396.862322)
			(xy 306.354483 -396.885611) (xy 306.396964 -396.91633) (xy 306.433794 -396.953636) (xy 306.463965 -396.996506)
			(xy 306.48665 -397.043767) (xy 306.494434 -397.068802) (xy 306.495958 -397.074644) (xy 306.815744 -397.627602)
			(xy 306.819808 -397.63192) (xy 306.836001 -397.649637) (xy 306.863427 -397.689026) (xy 306.884571 -397.732113)
			(xy 306.898947 -397.777905) (xy 306.906224 -397.825346) (xy 306.906676 -397.849344) (xy 306.906207 -397.874807)
			(xy 306.898007 -397.92507) (xy 306.881843 -397.973364) (xy 306.858135 -398.018436) (xy 306.827497 -398.059116)
			(xy 306.790725 -398.09435) (xy 306.770024 -398.109186) (xy 306.761505 -398.115646) (xy 306.750303 -398.13383)
			(xy 306.747462 -398.154998) (xy 306.753473 -398.175492) (xy 306.767296 -398.191773) (xy 306.786544 -398.201027)
			(xy 306.797202 -398.201896) (xy 306.806854 -398.201388) (xy 306.815367 -398.20009) (xy 306.832533 -398.198694)
			(xy 306.841144 -398.198594) (xy 306.841398 -398.198848) (xy 307.14061 -398.198848) (xy 307.140864 -398.198594)
			(xy 307.161926 -398.198995) (xy 307.203285 -398.20695) (xy 307.242283 -398.222855) (xy 307.277409 -398.246094)
			(xy 307.307301 -398.275765) (xy 307.330799 -398.310717) (xy 307.346993 -398.349597) (xy 307.355254 -398.390896)
			(xy 307.355748 -398.411954) (xy 307.355748 -398.666716) (xy 307.346604 -398.666716) (xy 307.336581 -398.667123)
			(xy 307.318061 -398.674795) (xy 307.303888 -398.688971) (xy 307.296221 -398.707493) (xy 307.295804 -398.717516)
			(xy 307.295804 -398.881092) (xy 307.295374 -398.891112) (xy 307.287708 -398.909628) (xy 307.273538 -398.923801)
			(xy 307.255024 -398.931472) (xy 307.245004 -398.931892) (xy 306.737004 -398.931892) (xy 306.726982 -398.931477)
			(xy 306.708464 -398.923807) (xy 306.694291 -398.909633) (xy 306.686622 -398.891114) (xy 306.686204 -398.881092)
			(xy 306.686204 -398.666716) (xy 306.67706 -398.666716) (xy 306.667052 -398.666245) (xy 306.648562 -398.658575)
			(xy 306.634411 -398.644418) (xy 306.62675 -398.625924) (xy 306.62626 -398.615916) (xy 306.62626 -398.411954)
			(xy 306.6266 -398.394721) (xy 306.632172 -398.360708) (xy 306.643146 -398.328035) (xy 306.650898 -398.31264)
			(xy 306.65674 -398.30121) (xy 306.656486 -398.27581) (xy 306.602892 -398.178782) (xy 306.581302 -398.165066)
			(xy 306.568348 -398.16405) (xy 306.544453 -398.161913) (xy 306.497667 -398.151315) (xy 306.453026 -398.133751)
			(xy 306.411562 -398.109627) (xy 306.374231 -398.079498) (xy 306.341897 -398.044062) (xy 306.315304 -398.004135)
			(xy 306.295069 -397.96064) (xy 306.287932 -397.937736) (xy 306.286408 -397.931894) (xy 305.96586 -397.377412)
			(xy 305.961796 -397.373094) (xy 305.9457 -397.355418) (xy 305.918449 -397.316141) (xy 305.897436 -397.273203)
			(xy 305.883143 -397.227586) (xy 305.875895 -397.180334) (xy 305.875436 -397.156432) (xy 305.875614 -397.142384)
			(xy 305.878158 -397.114402) (xy 305.880516 -397.100552) (xy 305.881803 -397.091296) (xy 305.878407 -397.072932)
			(xy 305.873912 -397.064738) (xy 305.857148 -397.037814) (xy 305.851935 -397.030119) (xy 305.837217 -397.018791)
			(xy 305.828446 -397.015716) (xy 305.806819 -397.008918) (xy 305.765605 -396.990035) (xy 305.727485 -396.965499)
			(xy 305.693229 -396.935806) (xy 305.678078 -396.918942) (xy 305.675609 -396.916176) (xy 305.670001 -396.911325)
			(xy 305.666902 -396.90929) (xy 305.654879 -396.901202) (xy 305.634987 -396.880146) (xy 305.620977 -396.854792)
			(xy 305.613735 -396.826745) (xy 305.613308 -396.812262) (xy 305.613308 -396.800324) (xy 305.61153 -396.79372)
			(xy 305.606323 -396.773351) (xy 305.600723 -396.731683) (xy 305.600354 -396.710662) (xy 305.03622 -396.710662)
			(xy 305.03622 -396.71117) (xy 305.036049 -396.725795) (xy 305.033382 -396.754924) (xy 305.030886 -396.769336)
			(xy 305.029524 -396.77851) (xy 305.032796 -396.796752) (xy 305.037236 -396.804896) (xy 305.053746 -396.83182)
			(xy 305.058915 -396.839599) (xy 305.073641 -396.851061) (xy 305.082448 -396.854172) (xy 305.107338 -396.862212)
			(xy 305.154216 -396.885407) (xy 305.196627 -396.916016) (xy 305.233409 -396.953201) (xy 305.263554 -396.995943)
			(xy 305.286237 -397.043071) (xy 305.29403 -397.06804) (xy 305.295554 -397.073882) (xy 305.615848 -397.627602)
			(xy 305.619912 -397.63192) (xy 305.636106 -397.649637) (xy 305.663531 -397.689025) (xy 305.684675 -397.732113)
			(xy 305.699052 -397.777905) (xy 305.706328 -397.825346) (xy 305.70678 -397.849344) (xy 305.706309 -397.874807)
			(xy 305.69811 -397.92507) (xy 305.681946 -397.973364) (xy 305.658238 -398.018436) (xy 305.6276 -398.059116)
			(xy 305.590828 -398.094349) (xy 305.570128 -398.109186) (xy 305.561607 -398.115644) (xy 305.550404 -398.133829)
			(xy 305.547563 -398.154998) (xy 305.553573 -398.175493) (xy 305.567398 -398.191774) (xy 305.586648 -398.201028)
			(xy 305.597306 -398.201896) (xy 305.606958 -398.201388) (xy 305.615471 -398.200089) (xy 305.632637 -398.198694)
			(xy 305.641248 -398.198594) (xy 305.641502 -398.198848) (xy 305.940714 -398.198848) (xy 305.940968 -398.198594)
			(xy 305.96203 -398.198991) (xy 306.003389 -398.206947) (xy 306.042388 -398.222853) (xy 306.077514 -398.246092)
			(xy 306.107405 -398.275763) (xy 306.130903 -398.310716) (xy 306.147097 -398.349596) (xy 306.155358 -398.390895)
			(xy 306.155852 -398.411954) (xy 306.155852 -398.666716) (xy 306.146708 -398.666716) (xy 306.136685 -398.667126)
			(xy 306.118165 -398.674797) (xy 306.103992 -398.688972) (xy 306.096325 -398.707493) (xy 306.095908 -398.717516)
			(xy 306.095908 -398.881092) (xy 306.095406 -398.891098) (xy 306.08775 -398.909588) (xy 306.073602 -398.923741)
			(xy 306.055114 -398.931402) (xy 306.045108 -398.931892) (xy 305.537108 -398.931892) (xy 305.527086 -398.931474)
			(xy 305.508568 -398.923805) (xy 305.494395 -398.909632) (xy 305.486726 -398.891114) (xy 305.486308 -398.881092)
			(xy 305.486308 -398.666716) (xy 305.477164 -398.666716) (xy 305.467156 -398.666242) (xy 305.448666 -398.658573)
			(xy 305.434515 -398.644417) (xy 305.426854 -398.625924) (xy 305.426364 -398.615916) (xy 305.426364 -398.411954)
			(xy 305.426715 -398.394722) (xy 305.432284 -398.360709) (xy 305.443253 -398.328036) (xy 305.451002 -398.31264)
			(xy 305.456844 -398.30121) (xy 305.45659 -398.27581) (xy 305.402996 -398.178782) (xy 305.381406 -398.165066)
			(xy 305.368452 -398.16405) (xy 305.344558 -398.161909) (xy 305.297771 -398.151313) (xy 305.25313 -398.133749)
			(xy 305.211666 -398.109625) (xy 305.174336 -398.079497) (xy 305.142001 -398.044061) (xy 305.115409 -398.004134)
			(xy 305.095173 -397.96064) (xy 305.088036 -397.937736) (xy 305.086512 -397.931894) (xy 304.766218 -397.378174)
			(xy 304.762154 -397.373856) (xy 304.745995 -397.356122) (xy 304.718626 -397.31672) (xy 304.697536 -397.27363)
			(xy 304.683208 -397.227845) (xy 304.675974 -397.180419) (xy 304.67554 -397.156432) (xy 304.675722 -397.142384)
			(xy 304.678262 -397.114402) (xy 304.68062 -397.100552) (xy 304.681939 -397.091272) (xy 304.678413 -397.072876)
			(xy 304.673762 -397.064738) (xy 304.656998 -397.037814) (xy 304.651803 -397.030105) (xy 304.637072 -397.018785)
			(xy 304.628296 -397.015716) (xy 304.606676 -397.008898) (xy 304.56546 -396.990022) (xy 304.527339 -396.965492)
			(xy 304.493081 -396.935803) (xy 304.477928 -396.918942) (xy 304.475465 -396.91617) (xy 304.469853 -396.911323)
			(xy 304.466752 -396.90929) (xy 304.454691 -396.901229) (xy 304.434733 -396.880186) (xy 304.420659 -396.854829)
			(xy 304.413357 -396.826762) (xy 304.412904 -396.812262) (xy 304.412904 -396.800324) (xy 304.41138 -396.79372)
			(xy 304.406174 -396.773351) (xy 304.400573 -396.731683) (xy 304.400204 -396.710662) (xy 303.836324 -396.710662)
			(xy 303.836324 -396.71117) (xy 303.836153 -396.725795) (xy 303.833486 -396.754924) (xy 303.83099 -396.769336)
			(xy 303.829628 -396.77851) (xy 303.8329 -396.796752) (xy 303.83734 -396.804896) (xy 303.85385 -396.83182)
			(xy 303.859017 -396.8396) (xy 303.873745 -396.851061) (xy 303.882552 -396.854172) (xy 303.907442 -396.86221)
			(xy 303.954321 -396.885406) (xy 303.996731 -396.916015) (xy 304.033513 -396.9532) (xy 304.063658 -396.995943)
			(xy 304.086341 -397.043071) (xy 304.094134 -397.06804) (xy 304.095658 -397.073882) (xy 304.415952 -397.627602)
			(xy 304.420016 -397.63192) (xy 304.43621 -397.649636) (xy 304.463635 -397.689025) (xy 304.48478 -397.732113)
			(xy 304.499156 -397.777905) (xy 304.506432 -397.825346) (xy 304.506884 -397.849344) (xy 304.506412 -397.874807)
			(xy 304.498212 -397.92507) (xy 304.482048 -397.973363) (xy 304.458341 -398.018435) (xy 304.427703 -398.059116)
			(xy 304.390932 -398.094349) (xy 304.370232 -398.109186) (xy 304.361718 -398.115621) (xy 304.350519 -398.133764)
			(xy 304.347647 -398.154891) (xy 304.353596 -398.175366) (xy 304.367342 -398.191664) (xy 304.386521 -398.20098)
			(xy 304.397156 -398.201896) (xy 304.407062 -398.201388) (xy 304.415512 -398.200097) (xy 304.43255 -398.198701)
			(xy 304.441098 -398.198594) (xy 304.441352 -398.198848) (xy 304.740564 -398.198848) (xy 304.740818 -398.198594)
			(xy 304.761864 -398.199017) (xy 304.803183 -398.207009) (xy 304.842138 -398.222937) (xy 304.87722 -398.246184)
			(xy 304.907072 -398.27585) (xy 304.930537 -398.310787) (xy 304.946707 -398.349642) (xy 304.954956 -398.390911)
			(xy 304.955448 -398.411954) (xy 304.955448 -398.666716) (xy 304.946304 -398.666716) (xy 304.936281 -398.667123)
			(xy 304.917761 -398.674795) (xy 304.903588 -398.688971) (xy 304.895921 -398.707493) (xy 304.895504 -398.717516)
			(xy 304.895504 -398.881092) (xy 304.895074 -398.891112) (xy 304.887408 -398.909628) (xy 304.873238 -398.923801)
			(xy 304.854724 -398.931472) (xy 304.844704 -398.931892) (xy 304.337212 -398.931892) (xy 304.32719 -398.931471)
			(xy 304.308672 -398.923803) (xy 304.294499 -398.909631) (xy 304.28683 -398.891114) (xy 304.286412 -398.881092)
			(xy 304.286412 -398.717516) (xy 304.285968 -398.707497) (xy 304.278305 -398.688983) (xy 304.264141 -398.67481)
			(xy 304.245631 -398.667138) (xy 304.235612 -398.666716) (xy 304.226468 -398.666716) (xy 304.226468 -398.411446)
			(xy 304.227247 -398.385723) (xy 304.239583 -398.335777) (xy 304.250852 -398.31264) (xy 304.256694 -398.30121)
			(xy 304.25644 -398.27581) (xy 304.208942 -398.190212) (xy 304.202233 -398.179423) (xy 304.1809 -398.16569)
			(xy 304.168302 -398.16405) (xy 304.144427 -398.161882) (xy 304.097682 -398.151249) (xy 304.053086 -398.133664)
			(xy 304.011664 -398.109532) (xy 303.974373 -398.079409) (xy 303.94207 -398.043988) (xy 303.9155 -398.004086)
			(xy 303.895276 -397.960623) (xy 303.88814 -397.937736) (xy 303.886616 -397.931894) (xy 303.566322 -397.378174)
			(xy 303.562258 -397.373856) (xy 303.546099 -397.356121) (xy 303.518731 -397.31672) (xy 303.49764 -397.27363)
			(xy 303.483312 -397.227845) (xy 303.476078 -397.180419) (xy 303.475644 -397.156432) (xy 303.475826 -397.142384)
			(xy 303.478366 -397.114402) (xy 303.480724 -397.100552) (xy 303.482043 -397.091272) (xy 303.478517 -397.072876)
			(xy 303.473866 -397.064738) (xy 303.457102 -397.037814) (xy 303.451905 -397.030106) (xy 303.437176 -397.018785)
			(xy 303.4284 -397.015716) (xy 303.40678 -397.008896) (xy 303.365565 -396.990021) (xy 303.327443 -396.965491)
			(xy 303.293185 -396.935803) (xy 303.278032 -396.918942) (xy 303.275569 -396.91617) (xy 303.269957 -396.911323)
			(xy 303.266856 -396.90929) (xy 303.254795 -396.901228) (xy 303.234838 -396.880186) (xy 303.220763 -396.854829)
			(xy 303.213461 -396.826762) (xy 303.213008 -396.812262) (xy 303.213008 -396.800324) (xy 303.211484 -396.79372)
			(xy 303.206278 -396.773351) (xy 303.200677 -396.731683) (xy 303.200308 -396.710662) (xy 301.433898 -396.710662)
			(xy 301.427228 -396.753647) (xy 301.420022 -396.777972) (xy 301.420022 -396.778226) (xy 301.417736 -396.785846)
			(xy 301.417736 -396.876778) (xy 301.417193 -396.893439) (xy 301.408583 -396.92563) (xy 301.391944 -396.9545)
			(xy 301.368405 -396.978086) (xy 301.339569 -396.994784) (xy 301.307396 -397.003459) (xy 301.290736 -397.004032)
			(xy 301.16145 -397.004032) (xy 301.157386 -397.004794) (xy 301.144391 -397.006718) (xy 301.118198 -397.008749)
			(xy 301.105062 -397.008858) (xy 301.104554 -397.008858) (xy 301.091417 -397.008763) (xy 301.065224 -397.006728)
			(xy 301.05223 -397.004794) (xy 301.048166 -397.004032) (xy 300.909228 -397.004032) (xy 300.892537 -397.003441)
			(xy 300.860289 -396.994819) (xy 300.831365 -396.978154) (xy 300.807733 -396.954578) (xy 300.790998 -396.925695)
			(xy 300.782299 -396.893467) (xy 300.78172 -396.876778) (xy 300.78172 -396.749524) (xy 300.780704 -396.744444)
			(xy 300.777596 -396.728047) (xy 300.774285 -396.694838) (xy 300.7741 -396.67815) (xy 300.572142 -396.67815)
			(xy 300.57217 -396.679674) (xy 300.571661 -396.70756) (xy 300.563541 -396.762736) (xy 300.547473 -396.816143)
			(xy 300.523801 -396.86664) (xy 300.493028 -396.913153) (xy 300.455811 -396.95469) (xy 300.412943 -396.990365)
			(xy 300.365337 -397.019419) (xy 300.314008 -397.041231) (xy 300.260051 -397.055337) (xy 300.204614 -397.061437)
			(xy 300.14888 -397.0594) (xy 300.094037 -397.04927) (xy 300.041253 -397.031263) (xy 299.991653 -397.005762)
			(xy 299.946295 -396.973311) (xy 299.906146 -396.934602) (xy 299.87206 -396.890459) (xy 299.844764 -396.841824)
			(xy 299.824841 -396.789733) (xy 299.812715 -396.735296) (xy 299.808644 -396.679674) (xy 298.733718 -396.679674)
			(xy 298.733718 -399.008092) (xy 300.762416 -399.008092) (xy 300.762823 -398.984859) (xy 300.769318 -398.938848)
			(xy 300.782191 -398.8942) (xy 300.801191 -398.851795) (xy 300.825942 -398.812469) (xy 300.840648 -398.794478)
			(xy 300.84649 -398.78762) (xy 300.849538 -398.779238) (xy 300.852078 -398.76603) (xy 300.85284 -398.756886)
			(xy 300.85284 -398.695926) (xy 300.852717 -398.691378) (xy 300.851061 -398.682433) (xy 300.849538 -398.678146)
			(xy 300.84649 -398.669764) (xy 300.840648 -398.662906) (xy 300.825935 -398.64492) (xy 300.801188 -398.60559)
			(xy 300.782189 -398.563184) (xy 300.769311 -398.518537) (xy 300.762809 -398.472526) (xy 300.762416 -398.449292)
			(xy 300.762926 -398.423305) (xy 300.771056 -398.37197) (xy 300.787117 -398.32254) (xy 300.810713 -398.27623)
			(xy 300.841263 -398.234182) (xy 300.878014 -398.197431) (xy 300.920062 -398.166881) (xy 300.966372 -398.143285)
			(xy 301.015802 -398.127224) (xy 301.067137 -398.119094) (xy 301.119111 -398.119094) (xy 301.170446 -398.127224)
			(xy 301.219876 -398.143285) (xy 301.266186 -398.166881) (xy 301.308234 -398.197431) (xy 301.344985 -398.234182)
			(xy 301.375535 -398.27623) (xy 301.399131 -398.32254) (xy 301.415192 -398.37197) (xy 301.423322 -398.423305)
			(xy 301.423832 -398.449292) (xy 301.423463 -398.472527) (xy 301.416957 -398.518539) (xy 301.404074 -398.563186)
			(xy 301.385067 -398.605591) (xy 301.378567 -398.615916) (xy 303.026064 -398.615916) (xy 303.026064 -398.411954)
			(xy 303.026597 -398.39045) (xy 303.035195 -398.34831) (xy 303.052053 -398.308744) (xy 303.076489 -398.273352)
			(xy 303.107515 -398.243568) (xy 303.143875 -398.220597) (xy 303.184096 -398.205368) (xy 303.226552 -398.198498)
			(xy 303.24806 -398.198848) (xy 303.250092 -398.198848) (xy 303.533556 -398.198848) (xy 303.555053 -398.198501)
			(xy 303.59748 -398.205433) (xy 303.637668 -398.220697) (xy 303.673998 -398.243679) (xy 303.705008 -398.273452)
			(xy 303.729448 -398.308817) (xy 303.746335 -398.348351) (xy 303.754987 -398.39046) (xy 303.755552 -398.411954)
			(xy 303.755552 -398.666716) (xy 303.746408 -398.666716) (xy 303.736385 -398.667126) (xy 303.717865 -398.674797)
			(xy 303.703692 -398.688972) (xy 303.696025 -398.707493) (xy 303.695608 -398.717516) (xy 303.695608 -398.881092)
			(xy 303.695106 -398.891098) (xy 303.68745 -398.909588) (xy 303.673302 -398.923741) (xy 303.654814 -398.931402)
			(xy 303.644808 -398.931892) (xy 303.136808 -398.931892) (xy 303.126786 -398.931474) (xy 303.108268 -398.923805)
			(xy 303.094095 -398.909632) (xy 303.086426 -398.891114) (xy 303.086008 -398.881092) (xy 303.086008 -398.693386)
			(xy 303.069752 -398.66824) (xy 303.056036 -398.662144) (xy 303.047306 -398.657792) (xy 303.033793 -398.643743)
			(xy 303.026506 -398.625663) (xy 303.026064 -398.615916) (xy 301.378567 -398.615916) (xy 301.360309 -398.644916)
			(xy 301.3456 -398.662906) (xy 301.339758 -398.669764) (xy 301.33671 -398.678146) (xy 301.33417 -398.691354)
			(xy 301.333408 -398.700498) (xy 301.333408 -398.761458) (xy 301.333519 -398.766007) (xy 301.335187 -398.77495)
			(xy 301.33671 -398.779238) (xy 301.339758 -398.78762) (xy 301.3456 -398.794478) (xy 301.360313 -398.812464)
			(xy 301.385058 -398.851794) (xy 301.404057 -398.894201) (xy 301.416935 -398.938848) (xy 301.423438 -398.984858)
			(xy 301.423832 -399.008092) (xy 301.423832 -399.008346) (xy 301.4234 -399.032396) (xy 301.41641 -399.079986)
			(xy 301.402612 -399.126065) (xy 301.392844 -399.148046) (xy 301.38751 -399.159476) (xy 301.38878 -399.184622)
			(xy 301.445168 -399.278602) (xy 301.466758 -399.291556) (xy 301.479204 -399.292318) (xy 301.504203 -399.294126)
			(xy 301.553249 -399.304464) (xy 301.600173 -399.322083) (xy 301.643901 -399.346581) (xy 301.683433 -399.377396)
			(xy 301.717863 -399.413822) (xy 301.746403 -399.455026) (xy 301.7684 -399.500065) (xy 301.783349 -399.547907)
			(xy 301.790908 -399.597456) (xy 301.79137 -399.622518) (xy 301.79086 -399.648505) (xy 301.78273 -399.69984)
			(xy 301.766669 -399.74927) (xy 301.743073 -399.79558) (xy 301.712523 -399.837628) (xy 301.675772 -399.874379)
			(xy 301.633724 -399.904929) (xy 301.587414 -399.928525) (xy 301.537984 -399.944586) (xy 301.486649 -399.952716)
			(xy 301.434675 -399.952716) (xy 301.38334 -399.944586) (xy 301.33391 -399.928525) (xy 301.2876 -399.904929)
			(xy 301.245552 -399.874379) (xy 301.208801 -399.837628) (xy 301.178251 -399.79558) (xy 301.154655 -399.74927)
			(xy 301.138594 -399.69984) (xy 301.130464 -399.648505) (xy 301.129954 -399.622518) (xy 301.129954 -399.622264)
			(xy 301.130391 -399.598214) (xy 301.137379 -399.550625) (xy 301.151175 -399.504546) (xy 301.160942 -399.482564)
			(xy 301.166276 -399.471134) (xy 301.165006 -399.445988) (xy 301.108618 -399.352008) (xy 301.087028 -399.339054)
			(xy 301.074582 -399.338292) (xy 301.04959 -399.3364) (xy 301.000547 -399.326075) (xy 300.953625 -399.308467)
			(xy 300.909896 -399.283981) (xy 300.870363 -399.253176) (xy 300.835932 -399.216758) (xy 300.80739 -399.175562)
			(xy 300.785391 -399.13053) (xy 300.77044 -399.082695) (xy 300.762878 -399.033151) (xy 300.762416 -399.008092)
			(xy 298.733718 -399.008092) (xy 298.733718 -399.528284) (xy 298.73328 -399.538348) (xy 298.725546 -399.556932)
			(xy 298.718732 -399.564352) (xy 298.517564 -399.76552) (xy 298.510167 -399.77237) (xy 298.491568 -399.780104)
			(xy 298.481496 -399.780506) (xy 298.290996 -399.780506) (xy 298.284046 -399.78075) (xy 298.270658 -399.784492)
			(xy 298.26458 -399.787872) (xy 298.243244 -399.800826) (xy 298.239839 -399.80298) (xy 298.233712 -399.808214)
			(xy 298.231052 -399.81124) (xy 298.227496 -399.815558) (xy 298.224956 -399.820384) (xy 298.209965 -399.847484)
			(xy 298.173779 -399.897746) (xy 298.131147 -399.94267) (xy 298.082846 -399.981434) (xy 298.029759 -400.013331)
			(xy 297.972855 -400.037778) (xy 297.913175 -400.054328) (xy 297.851808 -400.06268) (xy 297.789876 -400.06268)
			(xy 297.728509 -400.054328) (xy 297.668829 -400.037778) (xy 297.611925 -400.013331) (xy 297.558838 -399.981434)
			(xy 297.510537 -399.94267) (xy 297.467905 -399.897746) (xy 297.431719 -399.847484) (xy 297.416728 -399.820384)
			(xy 297.414188 -399.815558) (xy 297.410632 -399.81124) (xy 297.407951 -399.808234) (xy 297.401827 -399.803004)
			(xy 297.39844 -399.800826) (xy 297.377104 -399.787872) (xy 297.37105 -399.784437) (xy 297.357646 -399.7807)
			(xy 297.350688 -399.780506) (xy 297.30065 -399.780506) (xy 297.290584 -399.780939) (xy 297.271993 -399.788666)
			(xy 297.264582 -399.795492) (xy 296.807128 -400.252946) (xy 302.122332 -400.252946) (xy 302.122332 -399.998184)
			(xy 302.131476 -399.998184) (xy 302.141498 -399.99776) (xy 302.160017 -399.990095) (xy 302.174191 -399.975924)
			(xy 302.181859 -399.957406) (xy 302.182276 -399.947384) (xy 302.182276 -399.783808) (xy 302.182794 -399.773804)
			(xy 302.190446 -399.755317) (xy 302.20459 -399.741164) (xy 302.223072 -399.7335) (xy 302.233076 -399.733008)
			(xy 302.741076 -399.733008) (xy 302.751097 -399.73344) (xy 302.769615 -399.741103) (xy 302.783788 -399.755272)
			(xy 302.791457 -399.773787) (xy 302.791876 -399.783808) (xy 302.791876 -399.971514) (xy 302.808132 -399.99666)
			(xy 302.821848 -400.002756) (xy 302.830575 -400.007114) (xy 302.84409 -400.02116) (xy 302.851378 -400.039238)
			(xy 302.85182 -400.048984) (xy 302.85182 -400.252946) (xy 302.851269 -400.275554) (xy 302.841744 -400.319756)
			(xy 302.823132 -400.360964) (xy 302.796265 -400.397333) (xy 302.779684 -400.412712) (xy 302.77943 -400.412966)
			(xy 302.772931 -400.419198) (xy 302.764481 -400.435085) (xy 302.76292 -400.443954) (xy 302.762158 -400.450304)
			(xy 302.76165 -400.456908) (xy 302.76165 -400.536664) (xy 302.765206 -400.549872) (xy 302.768762 -400.555714)
			(xy 302.782512 -400.580307) (xy 302.802093 -400.633133) (xy 302.812069 -400.688581) (xy 302.812704 -400.71675)
			(xy 302.812214 -400.741739) (xy 302.804395 -400.791102) (xy 302.788951 -400.838634) (xy 302.766261 -400.883166)
			(xy 302.736885 -400.923599) (xy 302.701545 -400.958939) (xy 302.661112 -400.988315) (xy 302.61658 -401.011005)
			(xy 302.569048 -401.026449) (xy 302.519685 -401.034268) (xy 302.469707 -401.034268) (xy 302.420344 -401.026449)
			(xy 302.372812 -401.011005) (xy 302.32828 -400.988315) (xy 302.287847 -400.958939) (xy 302.252507 -400.923599)
			(xy 302.223131 -400.883166) (xy 302.200441 -400.838634) (xy 302.184997 -400.791102) (xy 302.177178 -400.741739)
			(xy 302.176688 -400.71675) (xy 302.177369 -400.687549) (xy 302.188018 -400.630127) (xy 302.208967 -400.575613)
			(xy 302.223678 -400.55038) (xy 302.228145 -400.542382) (xy 302.231665 -400.524419) (xy 302.230536 -400.515328)
			(xy 302.219106 -400.44878) (xy 302.217651 -400.441741) (xy 302.211338 -400.428836) (xy 302.20666 -400.42338)
			(xy 302.20412 -400.420586) (xy 302.201072 -400.418046) (xy 302.186646 -400.405803) (xy 302.161977 -400.37712)
			(xy 302.142741 -400.344542) (xy 302.12954 -400.309087) (xy 302.122786 -400.271861) (xy 302.122332 -400.252946)
			(xy 296.807128 -400.252946) (xy 296.512488 -400.547586) (xy 296.505645 -400.554985) (xy 296.497929 -400.573584)
			(xy 296.497502 -400.583654) (xy 296.497502 -401.674838) (xy 303.434496 -401.674838) (xy 303.434496 -400.811238)
			(xy 303.434935 -400.785718) (xy 303.441724 -400.735133) (xy 303.455199 -400.685906) (xy 303.47512 -400.638915)
			(xy 303.50113 -400.595001) (xy 303.532765 -400.554949) (xy 303.550828 -400.536918) (xy 303.557432 -400.530568)
			(xy 303.565306 -400.513804) (xy 303.572164 -400.42846) (xy 303.567084 -400.41068) (xy 303.561496 -400.403314)
			(xy 303.546641 -400.382569) (xy 303.523008 -400.337354) (xy 303.506908 -400.288941) (xy 303.498756 -400.238578)
			(xy 303.49825 -400.213068) (xy 303.49825 -400.212814) (xy 303.49874 -400.187825) (xy 303.506559 -400.138462)
			(xy 303.522003 -400.09093) (xy 303.544693 -400.046398) (xy 303.574069 -400.005965) (xy 303.609409 -399.970625)
			(xy 303.649842 -399.941249) (xy 303.694374 -399.918559) (xy 303.741906 -399.903115) (xy 303.791269 -399.895296)
			(xy 303.841247 -399.895296) (xy 303.89061 -399.903115) (xy 303.938142 -399.918559) (xy 303.982674 -399.941249)
			(xy 304.023107 -399.970625) (xy 304.058447 -400.005965) (xy 304.087823 -400.046398) (xy 304.110513 -400.09093)
			(xy 304.125957 -400.138462) (xy 304.133776 -400.187825) (xy 304.134266 -400.212814) (xy 304.134266 -400.213068)
			(xy 304.13376 -400.238576) (xy 304.125585 -400.288935) (xy 304.109486 -400.337346) (xy 304.085876 -400.382571)
			(xy 304.07102 -400.403314) (xy 304.065432 -400.41068) (xy 304.060352 -400.42846) (xy 304.06721 -400.513804)
			(xy 304.075084 -400.530568) (xy 304.081688 -400.536918) (xy 304.099728 -400.554971) (xy 304.131357 -400.595024)
			(xy 304.157367 -400.638935) (xy 304.177293 -400.68592) (xy 304.190781 -400.735141) (xy 304.19759 -400.78572)
			(xy 304.19802 -400.811238) (xy 304.19802 -401.674838) (xy 304.634392 -401.674838) (xy 304.634392 -400.811238)
			(xy 304.634832 -400.785719) (xy 304.641621 -400.735133) (xy 304.655096 -400.685906) (xy 304.675016 -400.638915)
			(xy 304.701026 -400.595002) (xy 304.732661 -400.554949) (xy 304.750724 -400.536918) (xy 304.757582 -400.530568)
			(xy 304.765456 -400.513804) (xy 304.771552 -400.43735) (xy 304.771907 -400.428285) (xy 304.766961 -400.410843)
			(xy 304.7619 -400.403314) (xy 304.761646 -400.40306) (xy 304.746779 -400.382324) (xy 304.723156 -400.337102)
			(xy 304.707061 -400.288688) (xy 304.698908 -400.238324) (xy 304.6984 -400.212814) (xy 304.69889 -400.187825)
			(xy 304.706709 -400.138462) (xy 304.722153 -400.09093) (xy 304.744843 -400.046398) (xy 304.774219 -400.005965)
			(xy 304.809559 -399.970625) (xy 304.849992 -399.941249) (xy 304.894524 -399.918559) (xy 304.942056 -399.903115)
			(xy 304.991419 -399.895296) (xy 305.041397 -399.895296) (xy 305.09076 -399.903115) (xy 305.138292 -399.918559)
			(xy 305.182824 -399.941249) (xy 305.223257 -399.970625) (xy 305.258597 -400.005965) (xy 305.287973 -400.046398)
			(xy 305.310663 -400.09093) (xy 305.326107 -400.138462) (xy 305.333926 -400.187825) (xy 305.334416 -400.212814)
			(xy 305.333908 -400.238367) (xy 305.32572 -400.288813) (xy 305.309558 -400.337296) (xy 305.285839 -400.382565)
			(xy 305.270916 -400.403314) (xy 305.265328 -400.41068) (xy 305.260248 -400.42846) (xy 305.266344 -400.504914)
			(xy 305.267434 -400.513914) (xy 305.27511 -400.530322) (xy 305.28133 -400.536918) (xy 305.281584 -400.537172)
			(xy 305.299629 -400.555193) (xy 305.331245 -400.595206) (xy 305.357247 -400.639076) (xy 305.377172 -400.68602)
			(xy 305.390663 -400.7352) (xy 305.39748 -400.78574) (xy 305.397916 -400.811238) (xy 305.397916 -401.674838)
			(xy 305.834796 -401.674838) (xy 305.834796 -400.81073) (xy 305.835237 -400.785262) (xy 305.842039 -400.734783)
			(xy 305.8555 -400.685658) (xy 305.87538 -400.638762) (xy 305.901325 -400.594929) (xy 305.932873 -400.554939)
			(xy 305.950874 -400.536918) (xy 305.957478 -400.530568) (xy 305.965352 -400.513804) (xy 305.97221 -400.42846)
			(xy 305.96713 -400.41068) (xy 305.961542 -400.403314) (xy 305.946693 -400.382565) (xy 305.923057 -400.337352)
			(xy 305.906955 -400.28894) (xy 305.898802 -400.238577) (xy 305.898296 -400.213068) (xy 305.898296 -400.212814)
			(xy 305.898786 -400.187825) (xy 305.906605 -400.138462) (xy 305.922049 -400.09093) (xy 305.944739 -400.046398)
			(xy 305.974115 -400.005965) (xy 306.009455 -399.970625) (xy 306.049888 -399.941249) (xy 306.09442 -399.918559)
			(xy 306.141952 -399.903115) (xy 306.191315 -399.895296) (xy 306.241293 -399.895296) (xy 306.290656 -399.903115)
			(xy 306.338188 -399.918559) (xy 306.38272 -399.941249) (xy 306.423153 -399.970625) (xy 306.458493 -400.005965)
			(xy 306.487869 -400.046398) (xy 306.510559 -400.09093) (xy 306.526003 -400.138462) (xy 306.533822 -400.187825)
			(xy 306.534312 -400.212814) (xy 306.534312 -400.213068) (xy 306.533817 -400.238577) (xy 306.52564 -400.288936)
			(xy 306.509538 -400.337347) (xy 306.485924 -400.382572) (xy 306.471066 -400.403314) (xy 306.465478 -400.41068)
			(xy 306.460398 -400.42846) (xy 306.467256 -400.513804) (xy 306.47513 -400.530568) (xy 306.481734 -400.536918)
			(xy 306.49973 -400.554944) (xy 306.531272 -400.594936) (xy 306.557214 -400.638769) (xy 306.577094 -400.685664)
			(xy 306.59056 -400.734786) (xy 306.597371 -400.785263) (xy 306.597812 -400.81073) (xy 306.597812 -401.674838)
			(xy 306.597802 -401.675346) (xy 307.034692 -401.675346) (xy 307.034692 -400.81073) (xy 307.035134 -400.785262)
			(xy 307.041937 -400.734783) (xy 307.055397 -400.685658) (xy 307.075277 -400.638762) (xy 307.101221 -400.594929)
			(xy 307.132769 -400.554939) (xy 307.15077 -400.536918) (xy 307.157374 -400.530568) (xy 307.165248 -400.513804)
			(xy 307.172106 -400.42846) (xy 307.167026 -400.41068) (xy 307.161438 -400.403314) (xy 307.146588 -400.382565)
			(xy 307.122953 -400.337352) (xy 307.106851 -400.288941) (xy 307.098698 -400.238577) (xy 307.098192 -400.213068)
			(xy 307.098192 -400.212814) (xy 307.098682 -400.187825) (xy 307.106501 -400.138462) (xy 307.121945 -400.09093)
			(xy 307.144635 -400.046398) (xy 307.174011 -400.005965) (xy 307.209351 -399.970625) (xy 307.249784 -399.941249)
			(xy 307.294316 -399.918559) (xy 307.341848 -399.903115) (xy 307.391211 -399.895296) (xy 307.441189 -399.895296)
			(xy 307.490552 -399.903115) (xy 307.538084 -399.918559) (xy 307.582616 -399.941249) (xy 307.623049 -399.970625)
			(xy 307.658389 -400.005965) (xy 307.687765 -400.046398) (xy 307.710455 -400.09093) (xy 307.725899 -400.138462)
			(xy 307.733718 -400.187825) (xy 307.734208 -400.212814) (xy 307.734208 -400.213068) (xy 307.733713 -400.238577)
			(xy 307.725536 -400.288936) (xy 307.709435 -400.337348) (xy 307.68582 -400.382572) (xy 307.670962 -400.403314)
			(xy 307.665374 -400.41068) (xy 307.660294 -400.42846) (xy 307.667152 -400.513804) (xy 307.675026 -400.530568)
			(xy 307.68163 -400.536918) (xy 307.699625 -400.554944) (xy 307.731167 -400.594937) (xy 307.75711 -400.63877)
			(xy 307.77699 -400.685664) (xy 307.790456 -400.734786) (xy 307.797267 -400.785263) (xy 307.797708 -400.81073)
			(xy 307.797708 -401.675346) (xy 307.797127 -401.705083) (xy 307.787847 -401.76383) (xy 307.769566 -401.820427)
			(xy 307.742725 -401.873501) (xy 307.707976 -401.92177) (xy 307.687472 -401.943316) (xy 307.681146 -401.950275)
			(xy 307.673589 -401.967478) (xy 307.67274 -401.976844) (xy 307.67147 -402.008086) (xy 307.671462 -402.017336)
			(xy 307.677186 -402.03491) (xy 307.682646 -402.042376) (xy 307.700663 -402.065522) (xy 307.7294 -402.11665)
			(xy 307.749038 -402.171916) (xy 307.759007 -402.229713) (xy 307.759608 -402.259038) (xy 307.759128 -402.284737)
			(xy 307.751467 -402.335561) (xy 307.736318 -402.384675) (xy 307.714017 -402.430983) (xy 307.685064 -402.47345)
			(xy 307.650104 -402.511127) (xy 307.60992 -402.543173) (xy 307.565408 -402.568872) (xy 307.517563 -402.587649)
			(xy 307.467454 -402.599087) (xy 307.4162 -402.602928) (xy 307.364946 -402.599087) (xy 307.314837 -402.587649)
			(xy 307.266992 -402.568872) (xy 307.22248 -402.543173) (xy 307.182296 -402.511127) (xy 307.147336 -402.47345)
			(xy 307.118383 -402.430983) (xy 307.096082 -402.384675) (xy 307.080933 -402.335561) (xy 307.073272 -402.284737)
			(xy 307.072792 -402.259038) (xy 307.073377 -402.22971) (xy 307.083337 -402.171907) (xy 307.102972 -402.116636)
			(xy 307.131712 -402.065505) (xy 307.149754 -402.042376) (xy 307.155259 -402.034931) (xy 307.160995 -402.017344)
			(xy 307.16093 -402.008086) (xy 307.15966 -401.976844) (xy 307.158781 -401.967484) (xy 307.151236 -401.950285)
			(xy 307.144928 -401.943316) (xy 307.124423 -401.921771) (xy 307.089669 -401.873505) (xy 307.062828 -401.82043)
			(xy 307.044551 -401.763833) (xy 307.035281 -401.705084) (xy 307.034692 -401.675346) (xy 306.597802 -401.675346)
			(xy 306.597263 -401.703991) (xy 306.588392 -401.76162) (xy 306.570862 -401.817229) (xy 306.545082 -401.869527)
			(xy 306.511649 -401.917297) (xy 306.491894 -401.938744) (xy 306.485738 -401.945828) (xy 306.478579 -401.963162)
			(xy 306.477924 -401.972526) (xy 306.476146 -402.041106) (xy 306.47628 -402.050363) (xy 306.482419 -402.067817)
			(xy 306.488084 -402.075142) (xy 306.488592 -402.07565) (xy 306.504906 -402.095283) (xy 306.532379 -402.138305)
			(xy 306.553482 -402.184784) (xy 306.56779 -402.233783) (xy 306.575014 -402.284315) (xy 306.57546 -402.309838)
			(xy 306.574958 -402.336715) (xy 306.566946 -402.38987) (xy 306.551102 -402.441236) (xy 306.527778 -402.489668)
			(xy 306.497497 -402.534082) (xy 306.460935 -402.573487) (xy 306.418907 -402.607003) (xy 306.372354 -402.63388)
			(xy 306.322315 -402.653519) (xy 306.269908 -402.66548) (xy 306.216304 -402.669498) (xy 306.1627 -402.66548)
			(xy 306.110293 -402.653519) (xy 306.060254 -402.63388) (xy 306.013701 -402.607003) (xy 305.971673 -402.573487)
			(xy 305.935111 -402.534082) (xy 305.90483 -402.489668) (xy 305.881506 -402.441236) (xy 305.865662 -402.38987)
			(xy 305.85765 -402.336715) (xy 305.857148 -402.309838) (xy 305.857621 -402.284281) (xy 305.864857 -402.233682)
			(xy 305.879202 -402.184622) (xy 305.900366 -402.138095) (xy 305.92792 -402.095044) (xy 305.94427 -402.075396)
			(xy 305.944524 -402.075142) (xy 305.950194 -402.067825) (xy 305.9563 -402.050363) (xy 305.956462 -402.041106)
			(xy 305.95443 -401.962874) (xy 305.947318 -401.945856) (xy 305.940714 -401.938744) (xy 305.920981 -401.917278)
			(xy 305.887542 -401.869515) (xy 305.861757 -401.817222) (xy 305.844223 -401.761616) (xy 305.835351 -401.70399)
			(xy 305.834796 -401.674838) (xy 305.397916 -401.674838) (xy 305.397408 -401.702712) (xy 305.389301 -401.757868)
			(xy 305.373251 -401.811257) (xy 305.349599 -401.86174) (xy 305.318851 -401.908242) (xy 305.300634 -401.929346)
			(xy 305.294792 -401.93595) (xy 305.287934 -401.952714) (xy 305.285902 -402.027136) (xy 305.286019 -402.036041)
			(xy 305.291613 -402.052934) (xy 305.296824 -402.060156) (xy 305.297078 -402.06041) (xy 305.311849 -402.079584)
			(xy 305.336676 -402.121132) (xy 305.355712 -402.165631) (xy 305.368613 -402.212281) (xy 305.375147 -402.260238)
			(xy 305.375564 -402.284438) (xy 305.375062 -402.311334) (xy 305.367044 -402.364526) (xy 305.351188 -402.415929)
			(xy 305.327849 -402.464395) (xy 305.297546 -402.508841) (xy 305.260958 -402.548274) (xy 305.218901 -402.581813)
			(xy 305.172315 -402.608709) (xy 305.122241 -402.628362) (xy 305.069796 -402.640332) (xy 305.016154 -402.644352)
			(xy 304.962512 -402.640332) (xy 304.910067 -402.628362) (xy 304.859993 -402.608709) (xy 304.813407 -402.581813)
			(xy 304.77135 -402.548274) (xy 304.734762 -402.508841) (xy 304.704459 -402.464395) (xy 304.68112 -402.415929)
			(xy 304.665264 -402.364526) (xy 304.657246 -402.311334) (xy 304.656744 -402.284438) (xy 304.657158 -402.260235)
			(xy 304.663658 -402.212269) (xy 304.676546 -402.165611) (xy 304.695587 -402.121109) (xy 304.720436 -402.079569)
			(xy 304.73523 -402.06041) (xy 304.735484 -402.060156) (xy 304.74075 -402.052965) (xy 304.746339 -402.03605)
			(xy 304.746406 -402.027136) (xy 304.744374 -401.952714) (xy 304.737516 -401.93595) (xy 304.731674 -401.929346)
			(xy 304.71347 -401.908232) (xy 304.682725 -401.861729) (xy 304.659074 -401.811249) (xy 304.643019 -401.757864)
			(xy 304.634902 -401.702711) (xy 304.634392 -401.674838) (xy 304.19802 -401.674838) (xy 304.197511 -401.702712)
			(xy 304.189404 -401.757868) (xy 304.173354 -401.811257) (xy 304.149703 -401.86174) (xy 304.118954 -401.908242)
			(xy 304.100738 -401.929346) (xy 304.094896 -401.93595) (xy 304.088038 -401.952714) (xy 304.086006 -402.027136)
			(xy 304.086122 -402.036041) (xy 304.091716 -402.052934) (xy 304.096928 -402.060156) (xy 304.097182 -402.06041)
			(xy 304.111953 -402.079583) (xy 304.13678 -402.121131) (xy 304.155816 -402.165631) (xy 304.168717 -402.212281)
			(xy 304.175251 -402.260238) (xy 304.175668 -402.284438) (xy 304.175166 -402.311334) (xy 304.167148 -402.364526)
			(xy 304.151292 -402.415929) (xy 304.127953 -402.464395) (xy 304.09765 -402.508841) (xy 304.061062 -402.548274)
			(xy 304.019005 -402.581813) (xy 303.972419 -402.608709) (xy 303.922345 -402.628362) (xy 303.8699 -402.640332)
			(xy 303.816258 -402.644352) (xy 303.762616 -402.640332) (xy 303.710171 -402.628362) (xy 303.660097 -402.608709)
			(xy 303.613511 -402.581813) (xy 303.571454 -402.548274) (xy 303.534866 -402.508841) (xy 303.504563 -402.464395)
			(xy 303.481224 -402.415929) (xy 303.465368 -402.364526) (xy 303.45735 -402.311334) (xy 303.456848 -402.284438)
			(xy 303.457261 -402.260235) (xy 303.463761 -402.212269) (xy 303.476649 -402.165611) (xy 303.495691 -402.121109)
			(xy 303.52054 -402.079569) (xy 303.535334 -402.06041) (xy 303.535588 -402.060156) (xy 303.540855 -402.052965)
			(xy 303.546443 -402.03605) (xy 303.54651 -402.027136) (xy 303.544478 -401.952714) (xy 303.53762 -401.93595)
			(xy 303.531778 -401.929346) (xy 303.513575 -401.908231) (xy 303.48283 -401.861729) (xy 303.459178 -401.811249)
			(xy 303.443123 -401.757864) (xy 303.435006 -401.702711) (xy 303.434496 -401.674838) (xy 296.497502 -401.674838)
			(xy 296.497502 -404.142194) (xy 296.497976 -404.152065) (xy 296.505439 -404.170344) (xy 296.51198 -404.177754)
			(xy 296.512234 -404.178008) (xy 296.982388 -404.648162) (xy 296.982896 -404.64867) (xy 296.99028 -404.655244)
			(xy 297.008579 -404.662676) (xy 297.018456 -404.663148) (xy 299.721524 -404.663148) (xy 299.731591 -404.663577)
			(xy 299.750185 -404.671303) (xy 299.757592 -404.678134) (xy 299.82795 -404.748492) (xy 304.627278 -404.748492)
			(xy 304.631349 -404.69287) (xy 304.643475 -404.638433) (xy 304.663398 -404.586342) (xy 304.690694 -404.537707)
			(xy 304.72478 -404.493564) (xy 304.764929 -404.454855) (xy 304.810287 -404.422404) (xy 304.859887 -404.396903)
			(xy 304.912671 -404.378896) (xy 304.967514 -404.368766) (xy 305.023248 -404.366729) (xy 305.078685 -404.372829)
			(xy 305.132642 -404.386935) (xy 305.183971 -404.408747) (xy 305.231577 -404.437801) (xy 305.274445 -404.473476)
			(xy 305.311662 -404.515013) (xy 305.342435 -404.561526) (xy 305.366107 -404.612023) (xy 305.382175 -404.66543)
			(xy 305.390295 -404.720606) (xy 305.390804 -404.748492) (xy 305.390295 -404.776378) (xy 305.382175 -404.831554)
			(xy 305.366107 -404.884961) (xy 305.342435 -404.935458) (xy 305.311662 -404.981971) (xy 305.274445 -405.023508)
			(xy 305.231577 -405.059183) (xy 305.183971 -405.088237) (xy 305.132642 -405.110049) (xy 305.078685 -405.124155)
			(xy 305.023248 -405.130255) (xy 304.967514 -405.128218) (xy 304.912671 -405.118088) (xy 304.859887 -405.100081)
			(xy 304.810287 -405.07458) (xy 304.764929 -405.042129) (xy 304.72478 -405.00342) (xy 304.690694 -404.959277)
			(xy 304.663398 -404.910642) (xy 304.643475 -404.858551) (xy 304.631349 -404.804114) (xy 304.627278 -404.748492)
			(xy 299.82795 -404.748492) (xy 300.227492 -405.148034) (xy 300.234334 -405.155434) (xy 300.242057 -405.174032)
			(xy 300.242478 -405.184102) (xy 300.242478 -406.316942) (xy 300.242942 -406.326818) (xy 300.250389 -406.345112)
			(xy 300.256956 -406.352502) (xy 300.25721 -406.352756) (xy 300.42993 -406.525476) (xy 300.430438 -406.525984)
			(xy 300.43782 -406.532566) (xy 300.456118 -406.540017) (xy 300.465998 -406.540462)
		)
		(stroke
			(width 0)
			(type solid)
		)
		(fill yes)
		(layer "B.Cu")
		(net "P0V9_CPU0_RT0_2A")
	)
	(gr_poly
		(pts
			(xy 354.612194 -406.540462) (xy 354.622264 -406.540039) (xy 354.640866 -406.532322) (xy 354.648262 -406.525476)
			(xy 357.801672 -403.372066) (xy 357.808516 -403.364667) (xy 357.816243 -403.346069) (xy 357.816658 -403.335998)
			(xy 357.816658 -401.076922) (xy 357.817097 -401.066859) (xy 357.824838 -401.048281) (xy 357.831644 -401.040854)
			(xy 358.129586 -400.742912) (xy 358.136436 -400.735515) (xy 358.144177 -400.716917) (xy 358.144572 -400.706844)
			(xy 358.144572 -397.895572) (xy 358.144143 -397.885505) (xy 358.136418 -397.86691) (xy 358.129586 -397.859504)
			(xy 358.100376 -397.830294) (xy 358.092976 -397.823452) (xy 358.074378 -397.815727) (xy 358.064308 -397.815308)
			(xy 357.087932 -397.815308) (xy 357.077867 -397.814873) (xy 357.05928 -397.807142) (xy 357.051864 -397.800322)
			(xy 356.81793 -397.566388) (xy 356.809392 -397.558567) (xy 356.787572 -397.550886) (xy 356.77602 -397.551656)
			(xy 356.696518 -397.561308) (xy 356.685194 -397.563266) (xy 356.665805 -397.575539) (xy 356.65918 -397.58493)
			(xy 356.65918 -397.585184) (xy 356.644825 -397.607751) (xy 356.610007 -397.648347) (xy 356.569109 -397.68281)
			(xy 356.546404 -397.696944) (xy 356.53472 -397.703802) (xy 356.521766 -397.726916) (xy 356.521766 -397.828008)
			(xy 356.52216 -397.836661) (xy 356.528014 -397.852952) (xy 356.53895 -397.866371) (xy 356.54615 -397.871188)
			(xy 356.546404 -397.871442) (xy 356.567117 -397.884316) (xy 356.604862 -397.915197) (xy 356.637659 -397.951289)
			(xy 356.664796 -397.99181) (xy 356.685683 -398.035879) (xy 356.699867 -398.082538) (xy 356.70704 -398.130776)
			(xy 356.70744 -398.15516) (xy 356.70693 -398.181147) (xy 356.6988 -398.232482) (xy 356.682739 -398.281912)
			(xy 356.659143 -398.328222) (xy 356.628593 -398.37027) (xy 356.591842 -398.407021) (xy 356.549794 -398.437571)
			(xy 356.503484 -398.461167) (xy 356.454054 -398.477228) (xy 356.402719 -398.485358) (xy 356.350745 -398.485358)
			(xy 356.29941 -398.477228) (xy 356.24998 -398.461167) (xy 356.20367 -398.437571) (xy 356.161622 -398.407021)
			(xy 356.124871 -398.37027) (xy 356.094321 -398.328222) (xy 356.070725 -398.281912) (xy 356.054664 -398.232482)
			(xy 356.046534 -398.181147) (xy 356.046024 -398.15516) (xy 356.046457 -398.130749) (xy 356.053629 -398.082456)
			(xy 356.067826 -398.035743) (xy 356.088739 -397.991627) (xy 356.115914 -397.951066) (xy 356.148758 -397.914943)
			(xy 356.186558 -397.884044) (xy 356.207314 -397.871188) (xy 356.218998 -397.86433) (xy 356.231952 -397.841216)
			(xy 356.231952 -397.740124) (xy 356.231563 -397.731468) (xy 356.225718 -397.715167) (xy 356.214786 -397.701736)
			(xy 356.207568 -397.696944) (xy 356.207314 -397.69669) (xy 356.186603 -397.683815) (xy 356.148863 -397.652933)
			(xy 356.116072 -397.61684) (xy 356.088942 -397.576318) (xy 356.068062 -397.53225) (xy 356.053887 -397.48559)
			(xy 356.046723 -397.437355) (xy 356.046278 -397.412972) (xy 356.046835 -397.385351) (xy 356.056013 -397.330877)
			(xy 356.074108 -397.278683) (xy 356.10062 -397.230219) (xy 356.134811 -397.18683) (xy 356.175732 -397.14972)
			(xy 356.198678 -397.134334) (xy 356.210108 -397.127222) (xy 356.222554 -397.103346) (xy 356.218998 -396.9893)
			(xy 356.205282 -396.966694) (xy 356.193344 -396.96009) (xy 356.171652 -396.947456) (xy 356.132012 -396.916659)
			(xy 356.097481 -396.880226) (xy 356.06885 -396.838995) (xy 356.046778 -396.793911) (xy 356.03177 -396.746009)
			(xy 356.024173 -396.69639) (xy 356.023672 -396.671292) (xy 356.023672 -396.671038) (xy 356.024009 -396.648924)
			(xy 356.029873 -396.605088) (xy 356.035356 -396.583662) (xy 356.037315 -396.575653) (xy 356.03653 -396.559196)
			(xy 356.033832 -396.551404) (xy 356.02291 -396.523972) (xy 356.019522 -396.516369) (xy 356.008766 -396.503679)
			(xy 356.001828 -396.49908) (xy 355.976466 -396.483209) (xy 355.930266 -396.445195) (xy 355.890135 -396.400823)
			(xy 355.856939 -396.351049) (xy 355.831394 -396.296949) (xy 355.814052 -396.239689) (xy 355.805286 -396.180506)
			(xy 355.804724 -396.150592) (xy 355.805219 -396.121526) (xy 355.813493 -396.063986) (xy 355.829873 -396.008209)
			(xy 355.854024 -395.955331) (xy 355.885454 -395.906428) (xy 355.923525 -395.862496) (xy 355.96746 -395.82443)
			(xy 356.016366 -395.793004) (xy 356.069246 -395.768859) (xy 356.125025 -395.752485) (xy 356.182566 -395.744216)
			(xy 356.211632 -395.743684) (xy 356.390702 -395.743684) (xy 356.400722 -395.743264) (xy 356.419235 -395.735593)
			(xy 356.433403 -395.72142) (xy 356.441068 -395.702904) (xy 356.441502 -395.692884) (xy 356.441502 -395.453108)
			(xy 356.441084 -395.443085) (xy 356.433415 -395.424565) (xy 356.419243 -395.41039) (xy 356.400724 -395.402718)
			(xy 356.390702 -395.402308) (xy 356.37724 -395.402308) (xy 355.270562 -394.295376) (xy 355.263713 -394.287979)
			(xy 355.255977 -394.26938) (xy 355.255576 -394.259308) (xy 355.255576 -392.209274) (xy 355.256003 -392.199205)
			(xy 355.263722 -392.180605) (xy 355.270562 -392.173206) (xy 355.295454 -392.148314) (xy 355.302139 -392.140903)
			(xy 355.309739 -392.122469) (xy 355.309739 -392.102531) (xy 355.302139 -392.084097) (xy 355.295454 -392.076686)
			(xy 355.010466 -391.791698) (xy 355.003613 -391.784303) (xy 354.995868 -391.765704) (xy 354.99548 -391.75563)
			(xy 354.99548 -391.001504) (xy 354.995902 -390.991433) (xy 355.003613 -390.972826) (xy 355.010466 -390.965436)
			(xy 355.124004 -390.851898) (xy 355.13085 -390.844499) (xy 355.138583 -390.825901) (xy 355.13899 -390.81583)
			(xy 355.13899 -390.035796) (xy 355.138566 -390.025726) (xy 355.130849 -390.007124) (xy 355.124004 -389.999728)
			(xy 355.121718 -389.997696) (xy 355.11487 -389.990298) (xy 355.107135 -389.9717) (xy 355.106732 -389.961628)
			(xy 355.106732 -388.002272) (xy 355.106305 -387.992203) (xy 355.098587 -387.973603) (xy 355.091746 -387.966204)
			(xy 354.907596 -387.782054) (xy 354.9002 -387.775202) (xy 354.881601 -387.767461) (xy 354.871528 -387.767068)
			(xy 349.167958 -387.767068) (xy 349.157924 -387.767503) (xy 349.139343 -387.775071) (xy 349.13189 -387.7818)
			(xy 349.045276 -387.868414) (xy 349.038424 -387.87581) (xy 349.030682 -387.894409) (xy 349.03029 -387.904482)
			(xy 349.03029 -391.001758) (xy 349.029856 -391.011823) (xy 349.022126 -391.030411) (xy 349.015304 -391.037826)
			(xy 348.792213 -391.260917) (xy 349.213934 -391.260917) (xy 349.213934 -391.208943) (xy 349.222064 -391.157608)
			(xy 349.238125 -391.108178) (xy 349.261721 -391.061868) (xy 349.292271 -391.01982) (xy 349.329022 -390.983069)
			(xy 349.37107 -390.952519) (xy 349.41738 -390.928923) (xy 349.46681 -390.912862) (xy 349.518145 -390.904732)
			(xy 349.570119 -390.904732) (xy 349.621454 -390.912862) (xy 349.670884 -390.928923) (xy 349.717194 -390.952519)
			(xy 349.759242 -390.983069) (xy 349.795993 -391.01982) (xy 349.826543 -391.061868) (xy 349.850139 -391.108178)
			(xy 349.8662 -391.157608) (xy 349.87433 -391.208943) (xy 349.87484 -391.23493) (xy 349.87433 -391.260917)
			(xy 350.41383 -391.260917) (xy 350.41383 -391.208943) (xy 350.42196 -391.157608) (xy 350.438021 -391.108178)
			(xy 350.461617 -391.061868) (xy 350.492167 -391.01982) (xy 350.528918 -390.983069) (xy 350.570966 -390.952519)
			(xy 350.617276 -390.928923) (xy 350.666706 -390.912862) (xy 350.718041 -390.904732) (xy 350.770015 -390.904732)
			(xy 350.82135 -390.912862) (xy 350.87078 -390.928923) (xy 350.91709 -390.952519) (xy 350.959138 -390.983069)
			(xy 350.995889 -391.01982) (xy 351.026439 -391.061868) (xy 351.050035 -391.108178) (xy 351.066096 -391.157608)
			(xy 351.074226 -391.208943) (xy 351.074736 -391.23493) (xy 351.074226 -391.260917) (xy 351.613726 -391.260917)
			(xy 351.613726 -391.208943) (xy 351.621856 -391.157608) (xy 351.637917 -391.108178) (xy 351.661513 -391.061868)
			(xy 351.692063 -391.01982) (xy 351.728814 -390.983069) (xy 351.770862 -390.952519) (xy 351.817172 -390.928923)
			(xy 351.866602 -390.912862) (xy 351.917937 -390.904732) (xy 351.969911 -390.904732) (xy 352.021246 -390.912862)
			(xy 352.070676 -390.928923) (xy 352.116986 -390.952519) (xy 352.159034 -390.983069) (xy 352.195785 -391.01982)
			(xy 352.226335 -391.061868) (xy 352.249931 -391.108178) (xy 352.265992 -391.157608) (xy 352.274122 -391.208943)
			(xy 352.274632 -391.23493) (xy 352.274122 -391.260917) (xy 352.813876 -391.260917) (xy 352.813876 -391.208943)
			(xy 352.822006 -391.157608) (xy 352.838067 -391.108178) (xy 352.861663 -391.061868) (xy 352.892213 -391.01982)
			(xy 352.928964 -390.983069) (xy 352.971012 -390.952519) (xy 353.017322 -390.928923) (xy 353.066752 -390.912862)
			(xy 353.118087 -390.904732) (xy 353.170061 -390.904732) (xy 353.221396 -390.912862) (xy 353.270826 -390.928923)
			(xy 353.317136 -390.952519) (xy 353.359184 -390.983069) (xy 353.395935 -391.01982) (xy 353.426485 -391.061868)
			(xy 353.450081 -391.108178) (xy 353.466142 -391.157608) (xy 353.474272 -391.208943) (xy 353.474782 -391.23493)
			(xy 353.474272 -391.260917) (xy 354.013772 -391.260917) (xy 354.013772 -391.208943) (xy 354.021902 -391.157608)
			(xy 354.037963 -391.108178) (xy 354.061559 -391.061868) (xy 354.092109 -391.01982) (xy 354.12886 -390.983069)
			(xy 354.170908 -390.952519) (xy 354.217218 -390.928923) (xy 354.266648 -390.912862) (xy 354.317983 -390.904732)
			(xy 354.369957 -390.904732) (xy 354.421292 -390.912862) (xy 354.470722 -390.928923) (xy 354.517032 -390.952519)
			(xy 354.55908 -390.983069) (xy 354.595831 -391.01982) (xy 354.626381 -391.061868) (xy 354.649977 -391.108178)
			(xy 354.666038 -391.157608) (xy 354.674168 -391.208943) (xy 354.674678 -391.23493) (xy 354.674168 -391.260917)
			(xy 354.666038 -391.312252) (xy 354.649977 -391.361682) (xy 354.626381 -391.407992) (xy 354.595831 -391.45004)
			(xy 354.55908 -391.486791) (xy 354.517032 -391.517341) (xy 354.470722 -391.540937) (xy 354.421292 -391.556998)
			(xy 354.369957 -391.565128) (xy 354.317983 -391.565128) (xy 354.266648 -391.556998) (xy 354.217218 -391.540937)
			(xy 354.170908 -391.517341) (xy 354.12886 -391.486791) (xy 354.092109 -391.45004) (xy 354.061559 -391.407992)
			(xy 354.037963 -391.361682) (xy 354.021902 -391.312252) (xy 354.013772 -391.260917) (xy 353.474272 -391.260917)
			(xy 353.466142 -391.312252) (xy 353.450081 -391.361682) (xy 353.426485 -391.407992) (xy 353.395935 -391.45004)
			(xy 353.359184 -391.486791) (xy 353.317136 -391.517341) (xy 353.270826 -391.540937) (xy 353.221396 -391.556998)
			(xy 353.170061 -391.565128) (xy 353.118087 -391.565128) (xy 353.066752 -391.556998) (xy 353.017322 -391.540937)
			(xy 352.971012 -391.517341) (xy 352.928964 -391.486791) (xy 352.892213 -391.45004) (xy 352.861663 -391.407992)
			(xy 352.838067 -391.361682) (xy 352.822006 -391.312252) (xy 352.813876 -391.260917) (xy 352.274122 -391.260917)
			(xy 352.265992 -391.312252) (xy 352.249931 -391.361682) (xy 352.226335 -391.407992) (xy 352.195785 -391.45004)
			(xy 352.159034 -391.486791) (xy 352.116986 -391.517341) (xy 352.070676 -391.540937) (xy 352.021246 -391.556998)
			(xy 351.969911 -391.565128) (xy 351.917937 -391.565128) (xy 351.866602 -391.556998) (xy 351.817172 -391.540937)
			(xy 351.770862 -391.517341) (xy 351.728814 -391.486791) (xy 351.692063 -391.45004) (xy 351.661513 -391.407992)
			(xy 351.637917 -391.361682) (xy 351.621856 -391.312252) (xy 351.613726 -391.260917) (xy 351.074226 -391.260917)
			(xy 351.066096 -391.312252) (xy 351.050035 -391.361682) (xy 351.026439 -391.407992) (xy 350.995889 -391.45004)
			(xy 350.959138 -391.486791) (xy 350.91709 -391.517341) (xy 350.87078 -391.540937) (xy 350.82135 -391.556998)
			(xy 350.770015 -391.565128) (xy 350.718041 -391.565128) (xy 350.666706 -391.556998) (xy 350.617276 -391.540937)
			(xy 350.570966 -391.517341) (xy 350.528918 -391.486791) (xy 350.492167 -391.45004) (xy 350.461617 -391.407992)
			(xy 350.438021 -391.361682) (xy 350.42196 -391.312252) (xy 350.41383 -391.260917) (xy 349.87433 -391.260917)
			(xy 349.8662 -391.312252) (xy 349.850139 -391.361682) (xy 349.826543 -391.407992) (xy 349.795993 -391.45004)
			(xy 349.759242 -391.486791) (xy 349.717194 -391.517341) (xy 349.670884 -391.540937) (xy 349.621454 -391.556998)
			(xy 349.570119 -391.565128) (xy 349.518145 -391.565128) (xy 349.46681 -391.556998) (xy 349.41738 -391.540937)
			(xy 349.37107 -391.517341) (xy 349.329022 -391.486791) (xy 349.292271 -391.45004) (xy 349.261721 -391.407992)
			(xy 349.238125 -391.361682) (xy 349.222064 -391.312252) (xy 349.213934 -391.260917) (xy 348.792213 -391.260917)
			(xy 348.471236 -391.581894) (xy 348.463834 -391.588731) (xy 348.445236 -391.596443) (xy 348.435168 -391.59688)
			(xy 342.185752 -391.59688) (xy 342.175686 -391.596448) (xy 342.157096 -391.588719) (xy 342.149684 -391.581894)
			(xy 342.13927 -391.57148) (xy 342.13927 -391.56894) (xy 341.999316 -391.428986) (xy 341.99247 -391.421587)
			(xy 341.984738 -391.402989) (xy 341.98433 -391.392918) (xy 341.98433 -387.861302) (xy 341.983908 -387.851231)
			(xy 341.976198 -387.832623) (xy 341.969344 -387.825234) (xy 341.92591 -387.7818) (xy 341.918486 -387.775021)
			(xy 341.899889 -387.767424) (xy 341.889842 -387.767068) (xy 334.762348 -387.767068) (xy 334.752281 -387.7675)
			(xy 334.733688 -387.775224) (xy 334.72628 -387.782054) (xy 334.437736 -388.070344) (xy 334.430893 -388.077743)
			(xy 334.423169 -388.096342) (xy 334.42275 -388.106412) (xy 334.42275 -390.875266) (xy 334.423227 -390.88499)
			(xy 334.43053 -390.903021) (xy 334.436974 -390.910318) (xy 334.457802 -390.932162) (xy 334.464359 -390.938502)
			(xy 334.480767 -390.946434) (xy 334.489806 -390.947656) (xy 334.515783 -390.950622) (xy 334.566404 -390.963694)
			(xy 334.614339 -390.984565) (xy 334.658394 -391.012716) (xy 334.678274 -391.029698) (xy 334.684878 -391.03554)
			(xy 334.70088 -391.042144) (xy 334.774032 -391.045192) (xy 334.782665 -391.045205) (xy 334.799162 -391.040154)
			(xy 334.80629 -391.035286) (xy 334.826999 -391.02053) (xy 334.872125 -390.997096) (xy 334.920403 -390.981136)
			(xy 334.970604 -390.973055) (xy 334.996028 -390.972548) (xy 335.021019 -390.973041) (xy 335.070386 -390.980863)
			(xy 335.117921 -390.996312) (xy 335.162454 -391.019007) (xy 335.202889 -391.048388) (xy 335.238231 -391.083732)
			(xy 335.267608 -391.12417) (xy 335.290299 -391.168705) (xy 335.305743 -391.216242) (xy 335.312661 -391.259919)
			(xy 336.026488 -391.259919) (xy 336.026488 -391.209941) (xy 336.034307 -391.160578) (xy 336.049751 -391.113046)
			(xy 336.072441 -391.068514) (xy 336.101817 -391.028081) (xy 336.137157 -390.992741) (xy 336.17759 -390.963365)
			(xy 336.222122 -390.940675) (xy 336.269654 -390.925231) (xy 336.319017 -390.917412) (xy 336.368995 -390.917412)
			(xy 336.418358 -390.925231) (xy 336.46589 -390.940675) (xy 336.510422 -390.963365) (xy 336.550855 -390.992741)
			(xy 336.586195 -391.028081) (xy 336.615571 -391.068514) (xy 336.638261 -391.113046) (xy 336.653705 -391.160578)
			(xy 336.661524 -391.209941) (xy 336.662014 -391.23493) (xy 336.661524 -391.259919) (xy 336.661366 -391.260917)
			(xy 337.213958 -391.260917) (xy 337.213958 -391.208943) (xy 337.222088 -391.157608) (xy 337.238149 -391.108178)
			(xy 337.261745 -391.061868) (xy 337.292295 -391.01982) (xy 337.329046 -390.983069) (xy 337.371094 -390.952519)
			(xy 337.417404 -390.928923) (xy 337.466834 -390.912862) (xy 337.518169 -390.904732) (xy 337.570143 -390.904732)
			(xy 337.621478 -390.912862) (xy 337.670908 -390.928923) (xy 337.717218 -390.952519) (xy 337.759266 -390.983069)
			(xy 337.796017 -391.01982) (xy 337.826567 -391.061868) (xy 337.850163 -391.108178) (xy 337.866224 -391.157608)
			(xy 337.874354 -391.208943) (xy 337.874864 -391.23493) (xy 337.874354 -391.260917) (xy 338.413854 -391.260917)
			(xy 338.413854 -391.208943) (xy 338.421984 -391.157608) (xy 338.438045 -391.108178) (xy 338.461641 -391.061868)
			(xy 338.492191 -391.01982) (xy 338.528942 -390.983069) (xy 338.57099 -390.952519) (xy 338.6173 -390.928923)
			(xy 338.66673 -390.912862) (xy 338.718065 -390.904732) (xy 338.770039 -390.904732) (xy 338.821374 -390.912862)
			(xy 338.870804 -390.928923) (xy 338.917114 -390.952519) (xy 338.959162 -390.983069) (xy 338.995913 -391.01982)
			(xy 339.026463 -391.061868) (xy 339.050059 -391.108178) (xy 339.06612 -391.157608) (xy 339.07425 -391.208943)
			(xy 339.07476 -391.23493) (xy 339.07425 -391.260917) (xy 339.61375 -391.260917) (xy 339.61375 -391.208943)
			(xy 339.62188 -391.157608) (xy 339.637941 -391.108178) (xy 339.661537 -391.061868) (xy 339.692087 -391.01982)
			(xy 339.728838 -390.983069) (xy 339.770886 -390.952519) (xy 339.817196 -390.928923) (xy 339.866626 -390.912862)
			(xy 339.917961 -390.904732) (xy 339.969935 -390.904732) (xy 340.02127 -390.912862) (xy 340.0707 -390.928923)
			(xy 340.11701 -390.952519) (xy 340.159058 -390.983069) (xy 340.195809 -391.01982) (xy 340.226359 -391.061868)
			(xy 340.249955 -391.108178) (xy 340.266016 -391.157608) (xy 340.274146 -391.208943) (xy 340.274656 -391.23493)
			(xy 340.274146 -391.260917) (xy 340.8139 -391.260917) (xy 340.8139 -391.208943) (xy 340.82203 -391.157608)
			(xy 340.838091 -391.108178) (xy 340.861687 -391.061868) (xy 340.892237 -391.01982) (xy 340.928988 -390.983069)
			(xy 340.971036 -390.952519) (xy 341.017346 -390.928923) (xy 341.066776 -390.912862) (xy 341.118111 -390.904732)
			(xy 341.170085 -390.904732) (xy 341.22142 -390.912862) (xy 341.27085 -390.928923) (xy 341.31716 -390.952519)
			(xy 341.359208 -390.983069) (xy 341.395959 -391.01982) (xy 341.426509 -391.061868) (xy 341.450105 -391.108178)
			(xy 341.466166 -391.157608) (xy 341.474296 -391.208943) (xy 341.474806 -391.23493) (xy 341.474296 -391.260917)
			(xy 341.466166 -391.312252) (xy 341.450105 -391.361682) (xy 341.426509 -391.407992) (xy 341.395959 -391.45004)
			(xy 341.359208 -391.486791) (xy 341.31716 -391.517341) (xy 341.27085 -391.540937) (xy 341.22142 -391.556998)
			(xy 341.170085 -391.565128) (xy 341.118111 -391.565128) (xy 341.066776 -391.556998) (xy 341.017346 -391.540937)
			(xy 340.971036 -391.517341) (xy 340.928988 -391.486791) (xy 340.892237 -391.45004) (xy 340.861687 -391.407992)
			(xy 340.838091 -391.361682) (xy 340.82203 -391.312252) (xy 340.8139 -391.260917) (xy 340.274146 -391.260917)
			(xy 340.266016 -391.312252) (xy 340.249955 -391.361682) (xy 340.226359 -391.407992) (xy 340.195809 -391.45004)
			(xy 340.159058 -391.486791) (xy 340.11701 -391.517341) (xy 340.0707 -391.540937) (xy 340.02127 -391.556998)
			(xy 339.969935 -391.565128) (xy 339.917961 -391.565128) (xy 339.866626 -391.556998) (xy 339.817196 -391.540937)
			(xy 339.770886 -391.517341) (xy 339.728838 -391.486791) (xy 339.692087 -391.45004) (xy 339.661537 -391.407992)
			(xy 339.637941 -391.361682) (xy 339.62188 -391.312252) (xy 339.61375 -391.260917) (xy 339.07425 -391.260917)
			(xy 339.06612 -391.312252) (xy 339.050059 -391.361682) (xy 339.026463 -391.407992) (xy 338.995913 -391.45004)
			(xy 338.959162 -391.486791) (xy 338.917114 -391.517341) (xy 338.870804 -391.540937) (xy 338.821374 -391.556998)
			(xy 338.770039 -391.565128) (xy 338.718065 -391.565128) (xy 338.66673 -391.556998) (xy 338.6173 -391.540937)
			(xy 338.57099 -391.517341) (xy 338.528942 -391.486791) (xy 338.492191 -391.45004) (xy 338.461641 -391.407992)
			(xy 338.438045 -391.361682) (xy 338.421984 -391.312252) (xy 338.413854 -391.260917) (xy 337.874354 -391.260917)
			(xy 337.866224 -391.312252) (xy 337.850163 -391.361682) (xy 337.826567 -391.407992) (xy 337.796017 -391.45004)
			(xy 337.759266 -391.486791) (xy 337.717218 -391.517341) (xy 337.670908 -391.540937) (xy 337.621478 -391.556998)
			(xy 337.570143 -391.565128) (xy 337.518169 -391.565128) (xy 337.466834 -391.556998) (xy 337.417404 -391.540937)
			(xy 337.371094 -391.517341) (xy 337.329046 -391.486791) (xy 337.292295 -391.45004) (xy 337.261745 -391.407992)
			(xy 337.238149 -391.361682) (xy 337.222088 -391.312252) (xy 337.213958 -391.260917) (xy 336.661366 -391.260917)
			(xy 336.653705 -391.309282) (xy 336.638261 -391.356814) (xy 336.615571 -391.401346) (xy 336.586195 -391.441779)
			(xy 336.550855 -391.477119) (xy 336.510422 -391.506495) (xy 336.46589 -391.529185) (xy 336.418358 -391.544629)
			(xy 336.368995 -391.552448) (xy 336.319017 -391.552448) (xy 336.269654 -391.544629) (xy 336.222122 -391.529185)
			(xy 336.17759 -391.506495) (xy 336.137157 -391.477119) (xy 336.101817 -391.441779) (xy 336.072441 -391.401346)
			(xy 336.049751 -391.356814) (xy 336.034307 -391.309282) (xy 336.026488 -391.259919) (xy 335.312661 -391.259919)
			(xy 335.313562 -391.265609) (xy 335.313562 -391.315591) (xy 335.305743 -391.364958) (xy 335.290299 -391.412495)
			(xy 335.267608 -391.45703) (xy 335.238231 -391.497468) (xy 335.202889 -391.532812) (xy 335.162454 -391.562193)
			(xy 335.117921 -391.584888) (xy 335.070386 -391.600337) (xy 335.021019 -391.608159) (xy 334.996028 -391.608564)
			(xy 334.995774 -391.608564) (xy 334.968366 -391.607958) (xy 334.914369 -391.598512) (xy 334.862783 -391.579971)
			(xy 334.815128 -391.552882) (xy 334.79359 -391.53592) (xy 334.786732 -391.530332) (xy 334.770222 -391.524236)
			(xy 334.697324 -391.523728) (xy 334.688743 -391.524019) (xy 334.672517 -391.529599) (xy 334.665574 -391.53465)
			(xy 334.66532 -391.534904) (xy 334.646308 -391.549591) (xy 334.604868 -391.573893) (xy 334.560346 -391.591941)
			(xy 334.513681 -391.603353) (xy 334.489806 -391.606024) (xy 334.480777 -391.607271) (xy 334.464385 -391.615214)
			(xy 334.457802 -391.621518) (xy 334.436974 -391.643362) (xy 334.430528 -391.65066) (xy 334.423217 -391.668688)
			(xy 334.42275 -391.678414) (xy 334.42275 -391.766298) (xy 334.422326 -391.776367) (xy 334.414606 -391.794967)
			(xy 334.407764 -391.802366) (xy 334.12049 -392.08964) (xy 334.113646 -392.097006) (xy 334.105897 -392.115542)
			(xy 334.105892 -392.135632) (xy 334.113631 -392.154172) (xy 334.12049 -392.161522) (xy 334.146398 -392.18743)
			(xy 334.163166 -392.204871) (xy 334.191601 -392.244013) (xy 334.213563 -392.287121) (xy 334.228511 -392.333134)
			(xy 334.236078 -392.380918) (xy 334.236568 -392.405108) (xy 334.236568 -392.61796) (xy 334.239616 -392.626342)
			(xy 334.24883 -392.653557) (xy 334.258786 -392.710139) (xy 334.259428 -392.738864) (xy 334.259428 -392.739372)
			(xy 334.258916 -392.765753) (xy 334.250544 -392.817845) (xy 334.234007 -392.867948) (xy 334.209726 -392.914789)
			(xy 334.178316 -392.957182) (xy 334.140574 -392.99405) (xy 334.097457 -393.024458) (xy 334.09694 -393.024711)
			(xy 335.672412 -393.024711) (xy 335.672412 -392.974733) (xy 335.680231 -392.92537) (xy 335.695675 -392.877838)
			(xy 335.718365 -392.833306) (xy 335.747741 -392.792873) (xy 335.783081 -392.757533) (xy 335.823514 -392.728157)
			(xy 335.868046 -392.705467) (xy 335.915578 -392.690023) (xy 335.964941 -392.682204) (xy 336.014919 -392.682204)
			(xy 336.064282 -392.690023) (xy 336.111814 -392.705467) (xy 336.156346 -392.728157) (xy 336.196779 -392.757533)
			(xy 336.232119 -392.792873) (xy 336.261495 -392.833306) (xy 336.284185 -392.877838) (xy 336.299629 -392.92537)
			(xy 336.307448 -392.974733) (xy 336.307938 -392.999722) (xy 336.307448 -393.024711) (xy 336.30729 -393.025709)
			(xy 336.859628 -393.025709) (xy 336.859628 -392.973735) (xy 336.867758 -392.9224) (xy 336.883819 -392.87297)
			(xy 336.907415 -392.82666) (xy 336.937965 -392.784612) (xy 336.974716 -392.747861) (xy 337.016764 -392.717311)
			(xy 337.063074 -392.693715) (xy 337.112504 -392.677654) (xy 337.163839 -392.669524) (xy 337.215813 -392.669524)
			(xy 337.267148 -392.677654) (xy 337.316578 -392.693715) (xy 337.362888 -392.717311) (xy 337.404936 -392.747861)
			(xy 337.441687 -392.784612) (xy 337.472237 -392.82666) (xy 337.495833 -392.87297) (xy 337.511894 -392.9224)
			(xy 337.520024 -392.973735) (xy 337.520534 -392.999722) (xy 337.520024 -393.025709) (xy 338.059778 -393.025709)
			(xy 338.059778 -392.973735) (xy 338.067908 -392.9224) (xy 338.083969 -392.87297) (xy 338.107565 -392.82666)
			(xy 338.138115 -392.784612) (xy 338.174866 -392.747861) (xy 338.216914 -392.717311) (xy 338.263224 -392.693715)
			(xy 338.312654 -392.677654) (xy 338.363989 -392.669524) (xy 338.415963 -392.669524) (xy 338.467298 -392.677654)
			(xy 338.516728 -392.693715) (xy 338.563038 -392.717311) (xy 338.605086 -392.747861) (xy 338.641837 -392.784612)
			(xy 338.672387 -392.82666) (xy 338.695983 -392.87297) (xy 338.712044 -392.9224) (xy 338.720174 -392.973735)
			(xy 338.720684 -392.999722) (xy 338.720174 -393.025709) (xy 339.259674 -393.025709) (xy 339.259674 -392.973735)
			(xy 339.267804 -392.9224) (xy 339.283865 -392.87297) (xy 339.307461 -392.82666) (xy 339.338011 -392.784612)
			(xy 339.374762 -392.747861) (xy 339.41681 -392.717311) (xy 339.46312 -392.693715) (xy 339.51255 -392.677654)
			(xy 339.563885 -392.669524) (xy 339.615859 -392.669524) (xy 339.667194 -392.677654) (xy 339.716624 -392.693715)
			(xy 339.762934 -392.717311) (xy 339.804982 -392.747861) (xy 339.841733 -392.784612) (xy 339.872283 -392.82666)
			(xy 339.895879 -392.87297) (xy 339.91194 -392.9224) (xy 339.92007 -392.973735) (xy 339.92058 -392.999722)
			(xy 339.92007 -393.025709) (xy 340.459824 -393.025709) (xy 340.459824 -392.973735) (xy 340.467954 -392.9224)
			(xy 340.484015 -392.87297) (xy 340.507611 -392.82666) (xy 340.538161 -392.784612) (xy 340.574912 -392.747861)
			(xy 340.61696 -392.717311) (xy 340.66327 -392.693715) (xy 340.7127 -392.677654) (xy 340.764035 -392.669524)
			(xy 340.816009 -392.669524) (xy 340.867344 -392.677654) (xy 340.916774 -392.693715) (xy 340.963084 -392.717311)
			(xy 341.005132 -392.747861) (xy 341.041883 -392.784612) (xy 341.072433 -392.82666) (xy 341.096029 -392.87297)
			(xy 341.11209 -392.9224) (xy 341.12022 -392.973735) (xy 341.12073 -392.999722) (xy 341.12022 -393.025709)
			(xy 341.65972 -393.025709) (xy 341.65972 -392.973735) (xy 341.66785 -392.9224) (xy 341.683911 -392.87297)
			(xy 341.707507 -392.82666) (xy 341.738057 -392.784612) (xy 341.774808 -392.747861) (xy 341.816856 -392.717311)
			(xy 341.863166 -392.693715) (xy 341.912596 -392.677654) (xy 341.963931 -392.669524) (xy 342.015905 -392.669524)
			(xy 342.06724 -392.677654) (xy 342.11667 -392.693715) (xy 342.16298 -392.717311) (xy 342.205028 -392.747861)
			(xy 342.241779 -392.784612) (xy 342.272329 -392.82666) (xy 342.295925 -392.87297) (xy 342.311986 -392.9224)
			(xy 342.320116 -392.973735) (xy 342.320626 -392.999722) (xy 342.320116 -393.025709) (xy 342.859616 -393.025709)
			(xy 342.859616 -392.973735) (xy 342.867746 -392.9224) (xy 342.883807 -392.87297) (xy 342.907403 -392.82666)
			(xy 342.937953 -392.784612) (xy 342.974704 -392.747861) (xy 343.016752 -392.717311) (xy 343.063062 -392.693715)
			(xy 343.112492 -392.677654) (xy 343.163827 -392.669524) (xy 343.215801 -392.669524) (xy 343.267136 -392.677654)
			(xy 343.316566 -392.693715) (xy 343.362876 -392.717311) (xy 343.404924 -392.747861) (xy 343.441675 -392.784612)
			(xy 343.472225 -392.82666) (xy 343.495821 -392.87297) (xy 343.511882 -392.9224) (xy 343.520012 -392.973735)
			(xy 343.520522 -392.999722) (xy 343.520012 -393.025709) (xy 344.059766 -393.025709) (xy 344.059766 -392.973735)
			(xy 344.067896 -392.9224) (xy 344.083957 -392.87297) (xy 344.107553 -392.82666) (xy 344.138103 -392.784612)
			(xy 344.174854 -392.747861) (xy 344.216902 -392.717311) (xy 344.263212 -392.693715) (xy 344.312642 -392.677654)
			(xy 344.363977 -392.669524) (xy 344.415951 -392.669524) (xy 344.467286 -392.677654) (xy 344.516716 -392.693715)
			(xy 344.563026 -392.717311) (xy 344.605074 -392.747861) (xy 344.641825 -392.784612) (xy 344.672375 -392.82666)
			(xy 344.695971 -392.87297) (xy 344.712032 -392.9224) (xy 344.720162 -392.973735) (xy 344.720672 -392.999722)
			(xy 344.720162 -393.025709) (xy 345.259662 -393.025709) (xy 345.259662 -392.973735) (xy 345.267792 -392.9224)
			(xy 345.283853 -392.87297) (xy 345.307449 -392.82666) (xy 345.337999 -392.784612) (xy 345.37475 -392.747861)
			(xy 345.416798 -392.717311) (xy 345.463108 -392.693715) (xy 345.512538 -392.677654) (xy 345.563873 -392.669524)
			(xy 345.615847 -392.669524) (xy 345.667182 -392.677654) (xy 345.716612 -392.693715) (xy 345.762922 -392.717311)
			(xy 345.80497 -392.747861) (xy 345.841721 -392.784612) (xy 345.872271 -392.82666) (xy 345.895867 -392.87297)
			(xy 345.911928 -392.9224) (xy 345.920058 -392.973735) (xy 345.920568 -392.999722) (xy 345.920058 -393.025709)
			(xy 346.459812 -393.025709) (xy 346.459812 -392.973735) (xy 346.467942 -392.9224) (xy 346.484003 -392.87297)
			(xy 346.507599 -392.82666) (xy 346.538149 -392.784612) (xy 346.5749 -392.747861) (xy 346.616948 -392.717311)
			(xy 346.663258 -392.693715) (xy 346.712688 -392.677654) (xy 346.764023 -392.669524) (xy 346.815997 -392.669524)
			(xy 346.867332 -392.677654) (xy 346.916762 -392.693715) (xy 346.963072 -392.717311) (xy 347.00512 -392.747861)
			(xy 347.041871 -392.784612) (xy 347.072421 -392.82666) (xy 347.096017 -392.87297) (xy 347.112078 -392.9224)
			(xy 347.120208 -392.973735) (xy 347.120718 -392.999722) (xy 347.120208 -393.025709) (xy 347.659708 -393.025709)
			(xy 347.659708 -392.973735) (xy 347.667838 -392.9224) (xy 347.683899 -392.87297) (xy 347.707495 -392.82666)
			(xy 347.738045 -392.784612) (xy 347.774796 -392.747861) (xy 347.816844 -392.717311) (xy 347.863154 -392.693715)
			(xy 347.912584 -392.677654) (xy 347.963919 -392.669524) (xy 348.015893 -392.669524) (xy 348.067228 -392.677654)
			(xy 348.116658 -392.693715) (xy 348.162968 -392.717311) (xy 348.205016 -392.747861) (xy 348.241767 -392.784612)
			(xy 348.272317 -392.82666) (xy 348.295913 -392.87297) (xy 348.311974 -392.9224) (xy 348.320104 -392.973735)
			(xy 348.320614 -392.999722) (xy 348.320104 -393.025709) (xy 348.859604 -393.025709) (xy 348.859604 -392.973735)
			(xy 348.867734 -392.9224) (xy 348.883795 -392.87297) (xy 348.907391 -392.82666) (xy 348.937941 -392.784612)
			(xy 348.974692 -392.747861) (xy 349.01674 -392.717311) (xy 349.06305 -392.693715) (xy 349.11248 -392.677654)
			(xy 349.163815 -392.669524) (xy 349.215789 -392.669524) (xy 349.267124 -392.677654) (xy 349.316554 -392.693715)
			(xy 349.362864 -392.717311) (xy 349.404912 -392.747861) (xy 349.441663 -392.784612) (xy 349.472213 -392.82666)
			(xy 349.495809 -392.87297) (xy 349.51187 -392.9224) (xy 349.52 -392.973735) (xy 349.52051 -392.999722)
			(xy 349.52 -393.025709) (xy 350.059754 -393.025709) (xy 350.059754 -392.973735) (xy 350.067884 -392.9224)
			(xy 350.083945 -392.87297) (xy 350.107541 -392.82666) (xy 350.138091 -392.784612) (xy 350.174842 -392.747861)
			(xy 350.21689 -392.717311) (xy 350.2632 -392.693715) (xy 350.31263 -392.677654) (xy 350.363965 -392.669524)
			(xy 350.415939 -392.669524) (xy 350.467274 -392.677654) (xy 350.516704 -392.693715) (xy 350.563014 -392.717311)
			(xy 350.605062 -392.747861) (xy 350.641813 -392.784612) (xy 350.672363 -392.82666) (xy 350.695959 -392.87297)
			(xy 350.71202 -392.9224) (xy 350.72015 -392.973735) (xy 350.72066 -392.999722) (xy 350.72015 -393.025709)
			(xy 351.25965 -393.025709) (xy 351.25965 -392.973735) (xy 351.26778 -392.9224) (xy 351.283841 -392.87297)
			(xy 351.307437 -392.82666) (xy 351.337987 -392.784612) (xy 351.374738 -392.747861) (xy 351.416786 -392.717311)
			(xy 351.463096 -392.693715) (xy 351.512526 -392.677654) (xy 351.563861 -392.669524) (xy 351.615835 -392.669524)
			(xy 351.66717 -392.677654) (xy 351.7166 -392.693715) (xy 351.76291 -392.717311) (xy 351.804958 -392.747861)
			(xy 351.841709 -392.784612) (xy 351.872259 -392.82666) (xy 351.895855 -392.87297) (xy 351.911916 -392.9224)
			(xy 351.920046 -392.973735) (xy 351.920556 -392.999722) (xy 351.920046 -393.025709) (xy 352.4598 -393.025709)
			(xy 352.4598 -392.973735) (xy 352.46793 -392.9224) (xy 352.483991 -392.87297) (xy 352.507587 -392.82666)
			(xy 352.538137 -392.784612) (xy 352.574888 -392.747861) (xy 352.616936 -392.717311) (xy 352.663246 -392.693715)
			(xy 352.712676 -392.677654) (xy 352.764011 -392.669524) (xy 352.815985 -392.669524) (xy 352.86732 -392.677654)
			(xy 352.91675 -392.693715) (xy 352.96306 -392.717311) (xy 353.005108 -392.747861) (xy 353.041859 -392.784612)
			(xy 353.072409 -392.82666) (xy 353.096005 -392.87297) (xy 353.112066 -392.9224) (xy 353.120196 -392.973735)
			(xy 353.120706 -392.999722) (xy 353.120196 -393.025709) (xy 353.659696 -393.025709) (xy 353.659696 -392.973735)
			(xy 353.667826 -392.9224) (xy 353.683887 -392.87297) (xy 353.707483 -392.82666) (xy 353.738033 -392.784612)
			(xy 353.774784 -392.747861) (xy 353.816832 -392.717311) (xy 353.863142 -392.693715) (xy 353.912572 -392.677654)
			(xy 353.963907 -392.669524) (xy 354.015881 -392.669524) (xy 354.067216 -392.677654) (xy 354.116646 -392.693715)
			(xy 354.162956 -392.717311) (xy 354.205004 -392.747861) (xy 354.241755 -392.784612) (xy 354.272305 -392.82666)
			(xy 354.295901 -392.87297) (xy 354.311962 -392.9224) (xy 354.320092 -392.973735) (xy 354.320602 -392.999722)
			(xy 354.320092 -393.025709) (xy 354.311962 -393.077044) (xy 354.295901 -393.126474) (xy 354.272305 -393.172784)
			(xy 354.241755 -393.214832) (xy 354.205004 -393.251583) (xy 354.162956 -393.282133) (xy 354.116646 -393.305729)
			(xy 354.067216 -393.32179) (xy 354.015881 -393.32992) (xy 353.963907 -393.32992) (xy 353.912572 -393.32179)
			(xy 353.863142 -393.305729) (xy 353.816832 -393.282133) (xy 353.774784 -393.251583) (xy 353.738033 -393.214832)
			(xy 353.707483 -393.172784) (xy 353.683887 -393.126474) (xy 353.667826 -393.077044) (xy 353.659696 -393.025709)
			(xy 353.120196 -393.025709) (xy 353.112066 -393.077044) (xy 353.096005 -393.126474) (xy 353.072409 -393.172784)
			(xy 353.041859 -393.214832) (xy 353.005108 -393.251583) (xy 352.96306 -393.282133) (xy 352.91675 -393.305729)
			(xy 352.86732 -393.32179) (xy 352.815985 -393.32992) (xy 352.764011 -393.32992) (xy 352.712676 -393.32179)
			(xy 352.663246 -393.305729) (xy 352.616936 -393.282133) (xy 352.574888 -393.251583) (xy 352.538137 -393.214832)
			(xy 352.507587 -393.172784) (xy 352.483991 -393.126474) (xy 352.46793 -393.077044) (xy 352.4598 -393.025709)
			(xy 351.920046 -393.025709) (xy 351.911916 -393.077044) (xy 351.895855 -393.126474) (xy 351.872259 -393.172784)
			(xy 351.841709 -393.214832) (xy 351.804958 -393.251583) (xy 351.76291 -393.282133) (xy 351.7166 -393.305729)
			(xy 351.66717 -393.32179) (xy 351.615835 -393.32992) (xy 351.563861 -393.32992) (xy 351.512526 -393.32179)
			(xy 351.463096 -393.305729) (xy 351.416786 -393.282133) (xy 351.374738 -393.251583) (xy 351.337987 -393.214832)
			(xy 351.307437 -393.172784) (xy 351.283841 -393.126474) (xy 351.26778 -393.077044) (xy 351.25965 -393.025709)
			(xy 350.72015 -393.025709) (xy 350.71202 -393.077044) (xy 350.695959 -393.126474) (xy 350.672363 -393.172784)
			(xy 350.641813 -393.214832) (xy 350.605062 -393.251583) (xy 350.563014 -393.282133) (xy 350.516704 -393.305729)
			(xy 350.467274 -393.32179) (xy 350.415939 -393.32992) (xy 350.363965 -393.32992) (xy 350.31263 -393.32179)
			(xy 350.2632 -393.305729) (xy 350.21689 -393.282133) (xy 350.174842 -393.251583) (xy 350.138091 -393.214832)
			(xy 350.107541 -393.172784) (xy 350.083945 -393.126474) (xy 350.067884 -393.077044) (xy 350.059754 -393.025709)
			(xy 349.52 -393.025709) (xy 349.51187 -393.077044) (xy 349.495809 -393.126474) (xy 349.472213 -393.172784)
			(xy 349.441663 -393.214832) (xy 349.404912 -393.251583) (xy 349.362864 -393.282133) (xy 349.316554 -393.305729)
			(xy 349.267124 -393.32179) (xy 349.215789 -393.32992) (xy 349.163815 -393.32992) (xy 349.11248 -393.32179)
			(xy 349.06305 -393.305729) (xy 349.01674 -393.282133) (xy 348.974692 -393.251583) (xy 348.937941 -393.214832)
			(xy 348.907391 -393.172784) (xy 348.883795 -393.126474) (xy 348.867734 -393.077044) (xy 348.859604 -393.025709)
			(xy 348.320104 -393.025709) (xy 348.311974 -393.077044) (xy 348.295913 -393.126474) (xy 348.272317 -393.172784)
			(xy 348.241767 -393.214832) (xy 348.205016 -393.251583) (xy 348.162968 -393.282133) (xy 348.116658 -393.305729)
			(xy 348.067228 -393.32179) (xy 348.015893 -393.32992) (xy 347.963919 -393.32992) (xy 347.912584 -393.32179)
			(xy 347.863154 -393.305729) (xy 347.816844 -393.282133) (xy 347.774796 -393.251583) (xy 347.738045 -393.214832)
			(xy 347.707495 -393.172784) (xy 347.683899 -393.126474) (xy 347.667838 -393.077044) (xy 347.659708 -393.025709)
			(xy 347.120208 -393.025709) (xy 347.112078 -393.077044) (xy 347.096017 -393.126474) (xy 347.072421 -393.172784)
			(xy 347.041871 -393.214832) (xy 347.00512 -393.251583) (xy 346.963072 -393.282133) (xy 346.916762 -393.305729)
			(xy 346.867332 -393.32179) (xy 346.815997 -393.32992) (xy 346.764023 -393.32992) (xy 346.712688 -393.32179)
			(xy 346.663258 -393.305729) (xy 346.616948 -393.282133) (xy 346.5749 -393.251583) (xy 346.538149 -393.214832)
			(xy 346.507599 -393.172784) (xy 346.484003 -393.126474) (xy 346.467942 -393.077044) (xy 346.459812 -393.025709)
			(xy 345.920058 -393.025709) (xy 345.911928 -393.077044) (xy 345.895867 -393.126474) (xy 345.872271 -393.172784)
			(xy 345.841721 -393.214832) (xy 345.80497 -393.251583) (xy 345.762922 -393.282133) (xy 345.716612 -393.305729)
			(xy 345.667182 -393.32179) (xy 345.615847 -393.32992) (xy 345.563873 -393.32992) (xy 345.512538 -393.32179)
			(xy 345.463108 -393.305729) (xy 345.416798 -393.282133) (xy 345.37475 -393.251583) (xy 345.337999 -393.214832)
			(xy 345.307449 -393.172784) (xy 345.283853 -393.126474) (xy 345.267792 -393.077044) (xy 345.259662 -393.025709)
			(xy 344.720162 -393.025709) (xy 344.712032 -393.077044) (xy 344.695971 -393.126474) (xy 344.672375 -393.172784)
			(xy 344.641825 -393.214832) (xy 344.605074 -393.251583) (xy 344.563026 -393.282133) (xy 344.516716 -393.305729)
			(xy 344.467286 -393.32179) (xy 344.415951 -393.32992) (xy 344.363977 -393.32992) (xy 344.312642 -393.32179)
			(xy 344.263212 -393.305729) (xy 344.216902 -393.282133) (xy 344.174854 -393.251583) (xy 344.138103 -393.214832)
			(xy 344.107553 -393.172784) (xy 344.083957 -393.126474) (xy 344.067896 -393.077044) (xy 344.059766 -393.025709)
			(xy 343.520012 -393.025709) (xy 343.511882 -393.077044) (xy 343.495821 -393.126474) (xy 343.472225 -393.172784)
			(xy 343.441675 -393.214832) (xy 343.404924 -393.251583) (xy 343.362876 -393.282133) (xy 343.316566 -393.305729)
			(xy 343.267136 -393.32179) (xy 343.215801 -393.32992) (xy 343.163827 -393.32992) (xy 343.112492 -393.32179)
			(xy 343.063062 -393.305729) (xy 343.016752 -393.282133) (xy 342.974704 -393.251583) (xy 342.937953 -393.214832)
			(xy 342.907403 -393.172784) (xy 342.883807 -393.126474) (xy 342.867746 -393.077044) (xy 342.859616 -393.025709)
			(xy 342.320116 -393.025709) (xy 342.311986 -393.077044) (xy 342.295925 -393.126474) (xy 342.272329 -393.172784)
			(xy 342.241779 -393.214832) (xy 342.205028 -393.251583) (xy 342.16298 -393.282133) (xy 342.11667 -393.305729)
			(xy 342.06724 -393.32179) (xy 342.015905 -393.32992) (xy 341.963931 -393.32992) (xy 341.912596 -393.32179)
			(xy 341.863166 -393.305729) (xy 341.816856 -393.282133) (xy 341.774808 -393.251583) (xy 341.738057 -393.214832)
			(xy 341.707507 -393.172784) (xy 341.683911 -393.126474) (xy 341.66785 -393.077044) (xy 341.65972 -393.025709)
			(xy 341.12022 -393.025709) (xy 341.11209 -393.077044) (xy 341.096029 -393.126474) (xy 341.072433 -393.172784)
			(xy 341.041883 -393.214832) (xy 341.005132 -393.251583) (xy 340.963084 -393.282133) (xy 340.916774 -393.305729)
			(xy 340.867344 -393.32179) (xy 340.816009 -393.32992) (xy 340.764035 -393.32992) (xy 340.7127 -393.32179)
			(xy 340.66327 -393.305729) (xy 340.61696 -393.282133) (xy 340.574912 -393.251583) (xy 340.538161 -393.214832)
			(xy 340.507611 -393.172784) (xy 340.484015 -393.126474) (xy 340.467954 -393.077044) (xy 340.459824 -393.025709)
			(xy 339.92007 -393.025709) (xy 339.91194 -393.077044) (xy 339.895879 -393.126474) (xy 339.872283 -393.172784)
			(xy 339.841733 -393.214832) (xy 339.804982 -393.251583) (xy 339.762934 -393.282133) (xy 339.716624 -393.305729)
			(xy 339.667194 -393.32179) (xy 339.615859 -393.32992) (xy 339.563885 -393.32992) (xy 339.51255 -393.32179)
			(xy 339.46312 -393.305729) (xy 339.41681 -393.282133) (xy 339.374762 -393.251583) (xy 339.338011 -393.214832)
			(xy 339.307461 -393.172784) (xy 339.283865 -393.126474) (xy 339.267804 -393.077044) (xy 339.259674 -393.025709)
			(xy 338.720174 -393.025709) (xy 338.712044 -393.077044) (xy 338.695983 -393.126474) (xy 338.672387 -393.172784)
			(xy 338.641837 -393.214832) (xy 338.605086 -393.251583) (xy 338.563038 -393.282133) (xy 338.516728 -393.305729)
			(xy 338.467298 -393.32179) (xy 338.415963 -393.32992) (xy 338.363989 -393.32992) (xy 338.312654 -393.32179)
			(xy 338.263224 -393.305729) (xy 338.216914 -393.282133) (xy 338.174866 -393.251583) (xy 338.138115 -393.214832)
			(xy 338.107565 -393.172784) (xy 338.083969 -393.126474) (xy 338.067908 -393.077044) (xy 338.059778 -393.025709)
			(xy 337.520024 -393.025709) (xy 337.511894 -393.077044) (xy 337.495833 -393.126474) (xy 337.472237 -393.172784)
			(xy 337.441687 -393.214832) (xy 337.404936 -393.251583) (xy 337.362888 -393.282133) (xy 337.316578 -393.305729)
			(xy 337.267148 -393.32179) (xy 337.215813 -393.32992) (xy 337.163839 -393.32992) (xy 337.112504 -393.32179)
			(xy 337.063074 -393.305729) (xy 337.016764 -393.282133) (xy 336.974716 -393.251583) (xy 336.937965 -393.214832)
			(xy 336.907415 -393.172784) (xy 336.883819 -393.126474) (xy 336.867758 -393.077044) (xy 336.859628 -393.025709)
			(xy 336.30729 -393.025709) (xy 336.299629 -393.074074) (xy 336.284185 -393.121606) (xy 336.261495 -393.166138)
			(xy 336.232119 -393.206571) (xy 336.196779 -393.241911) (xy 336.156346 -393.271287) (xy 336.111814 -393.293977)
			(xy 336.064282 -393.309421) (xy 336.014919 -393.31724) (xy 335.964941 -393.31724) (xy 335.915578 -393.309421)
			(xy 335.868046 -393.293977) (xy 335.823514 -393.271287) (xy 335.783081 -393.241911) (xy 335.747741 -393.206571)
			(xy 335.718365 -393.166138) (xy 335.695675 -393.121606) (xy 335.680231 -393.074074) (xy 335.672412 -393.024711)
			(xy 334.09694 -393.024711) (xy 334.050059 -393.047635) (xy 334.024986 -393.055856) (xy 334.015842 -393.05865)
			(xy 334.00111 -393.07008) (xy 333.956152 -393.145772) (xy 333.953104 -393.164314) (xy 333.955136 -393.173712)
			(xy 333.959756 -393.196997) (xy 333.964723 -393.24421) (xy 333.965042 -393.267946) (xy 333.964562 -393.298032)
			(xy 333.956667 -393.357683) (xy 333.941019 -393.415784) (xy 333.917889 -393.471333) (xy 333.887676 -393.523369)
			(xy 333.850901 -393.570995) (xy 333.829914 -393.592558) (xy 333.823075 -393.599959) (xy 333.815359 -393.618557)
			(xy 333.814928 -393.628626) (xy 333.814928 -393.863322) (xy 333.81823 -393.871704) (xy 333.827449 -393.898918)
			(xy 333.837414 -393.9555) (xy 333.838042 -393.984226) (xy 333.838042 -393.984734) (xy 333.837545 -394.010516)
			(xy 333.829535 -394.061454) (xy 333.813715 -394.110531) (xy 333.790468 -394.156557) (xy 333.775812 -394.177774)
			(xy 333.771407 -394.184405) (xy 333.766495 -394.199538) (xy 333.76616 -394.207492) (xy 333.76616 -394.25753)
			(xy 335.361534 -394.25753) (xy 335.362094 -394.22995) (xy 335.371294 -394.175561) (xy 335.379822 -394.149326)
			(xy 335.382616 -394.141452) (xy 335.382616 -393.99718) (xy 335.383117 -393.980483) (xy 335.391755 -393.948226)
			(xy 335.408437 -393.919298) (xy 335.432031 -393.895666) (xy 335.460931 -393.878936) (xy 335.493174 -393.870245)
			(xy 335.50987 -393.869672) (xy 335.89087 -393.869672) (xy 335.900776 -393.87018) (xy 335.912552 -393.870527)
			(xy 335.9344 -393.861791) (xy 335.942686 -393.853416) (xy 336.004408 -393.784836) (xy 336.010758 -393.761976)
			(xy 336.009996 -393.758166) (xy 336.009996 -393.757404) (xy 336.00687 -393.741331) (xy 336.003561 -393.708753)
			(xy 336.003392 -393.69238) (xy 336.003899 -393.667592) (xy 336.011657 -393.618626) (xy 336.026978 -393.571477)
			(xy 336.049486 -393.527304) (xy 336.078625 -393.487195) (xy 336.11368 -393.452138) (xy 336.153787 -393.422996)
			(xy 336.197958 -393.400486) (xy 336.245107 -393.385162) (xy 336.294072 -393.377401) (xy 336.31886 -393.376912)
			(xy 336.342472 -393.377378) (xy 336.389168 -393.384419) (xy 336.434295 -393.398337) (xy 336.476846 -393.41882)
			(xy 336.515871 -393.445412) (xy 336.550502 -393.477519) (xy 336.579964 -393.514425) (xy 336.592164 -393.534646)
			(xy 336.601387 -393.551158) (xy 336.616289 -393.585921) (xy 336.621882 -393.603988) (xy 336.62239 -393.60602)
			(xy 336.623406 -393.610084) (xy 336.671325 -393.692888) (xy 337.203288 -393.692888) (xy 337.203288 -393.69238)
			(xy 337.203799 -393.667592) (xy 337.211557 -393.618627) (xy 337.226878 -393.571478) (xy 337.249385 -393.527305)
			(xy 337.278524 -393.487197) (xy 337.313578 -393.45214) (xy 337.353685 -393.422997) (xy 337.397855 -393.400487)
			(xy 337.445003 -393.385162) (xy 337.493968 -393.377401) (xy 337.518756 -393.376912) (xy 337.54415 -393.377434)
			(xy 337.594283 -393.385559) (xy 337.64247 -393.401605) (xy 337.687465 -393.42516) (xy 337.728108 -393.455614)
			(xy 337.763351 -393.492183) (xy 337.792285 -393.533924) (xy 337.814162 -393.579758) (xy 337.821778 -393.603988)
			(xy 337.823302 -393.60983) (xy 337.871052 -393.69238) (xy 338.403184 -393.69238) (xy 338.403698 -393.667605)
			(xy 338.411448 -393.618664) (xy 338.426753 -393.571537) (xy 338.449238 -393.527382) (xy 338.478349 -393.487285)
			(xy 338.51337 -393.452232) (xy 338.553441 -393.423085) (xy 338.597576 -393.400561) (xy 338.64469 -393.385214)
			(xy 338.693623 -393.37742) (xy 338.718398 -393.376912) (xy 338.718906 -393.376912) (xy 338.744301 -393.37739)
			(xy 338.794437 -393.385522) (xy 338.842624 -393.401576) (xy 338.887619 -393.425137) (xy 338.928262 -393.455598)
			(xy 338.963505 -393.492173) (xy 338.992437 -393.533918) (xy 339.014313 -393.579756) (xy 339.021928 -393.603988)
			(xy 339.023452 -393.60983) (xy 339.344 -394.164312) (xy 339.348064 -394.16863) (xy 339.364166 -394.186267)
			(xy 339.391389 -394.225504) (xy 339.412388 -394.268395) (xy 339.426684 -394.313961) (xy 339.43395 -394.361161)
			(xy 339.434424 -394.385038) (xy 339.434424 -394.385546) (xy 339.433662 -394.405866) (xy 339.4329 -394.415772)
			(xy 339.43925 -394.434822) (xy 339.499956 -394.504164) (xy 339.517736 -394.513054) (xy 339.527896 -394.513816)
			(xy 339.552874 -394.515997) (xy 339.601733 -394.527254) (xy 339.648219 -394.546037) (xy 339.691184 -394.571881)
			(xy 339.729561 -394.604147) (xy 339.746336 -394.622782) (xy 339.748801 -394.625552) (xy 339.754411 -394.6304)
			(xy 339.757512 -394.632434) (xy 339.769576 -394.640491) (xy 339.789536 -394.661533) (xy 339.803611 -394.686892)
			(xy 339.810909 -394.714962) (xy 339.81136 -394.729462) (xy 339.81136 -394.7414) (xy 339.812884 -394.748004)
			(xy 339.818077 -394.768376) (xy 339.823686 -394.810042) (xy 339.82406 -394.831062) (xy 339.823677 -394.852082)
			(xy 339.818077 -394.893748) (xy 339.812884 -394.91412) (xy 339.81136 -394.920724) (xy 339.81136 -395.034262)
			(xy 339.810834 -395.049256) (xy 339.803092 -395.078226) (xy 339.788124 -395.10421) (xy 339.766947 -395.125441)
			(xy 339.741002 -395.140477) (xy 339.712052 -395.148294) (xy 339.69706 -395.148816) (xy 339.514942 -395.148816)
			(xy 339.514434 -395.14907) (xy 339.49767 -395.14907) (xy 339.497162 -395.148816) (xy 339.315552 -395.148816)
			(xy 339.300521 -395.148362) (xy 339.271484 -395.140582) (xy 339.245443 -395.125564) (xy 339.224167 -395.104328)
			(xy 339.2091 -395.078314) (xy 339.201266 -395.049292) (xy 339.200744 -395.034262) (xy 339.200744 -394.920724)
			(xy 339.19922 -394.91412) (xy 339.194013 -394.893751) (xy 339.188413 -394.852083) (xy 339.188044 -394.831062)
			(xy 339.188806 -394.808456) (xy 339.189568 -394.79855) (xy 339.183218 -394.779246) (xy 339.12302 -394.709904)
			(xy 339.104986 -394.70076) (xy 339.09508 -394.699998) (xy 339.071206 -394.697762) (xy 339.024479 -394.687007)
			(xy 338.979918 -394.669305) (xy 338.938549 -394.645062) (xy 338.901325 -394.614839) (xy 338.869104 -394.57933)
			(xy 338.842628 -394.539354) (xy 338.822507 -394.495831) (xy 338.815426 -394.472922) (xy 338.813902 -394.46708)
			(xy 338.494116 -393.914122) (xy 338.490052 -393.909804) (xy 338.473816 -393.892124) (xy 338.446398 -393.852725)
			(xy 338.425262 -393.809628) (xy 338.410896 -393.763828) (xy 338.40363 -393.71638) (xy 338.403184 -393.69238)
			(xy 337.871052 -393.69238) (xy 338.143596 -394.16355) (xy 338.14766 -394.167868) (xy 338.163869 -394.185538)
			(xy 338.191265 -394.224889) (xy 338.212394 -394.267931) (xy 338.22677 -394.313673) (xy 338.234062 -394.361064)
			(xy 338.234528 -394.385038) (xy 338.234528 -394.385546) (xy 338.233766 -394.405866) (xy 338.233004 -394.415772)
			(xy 338.239354 -394.434822) (xy 338.30006 -394.504164) (xy 338.31784 -394.513054) (xy 338.328 -394.513816)
			(xy 338.352979 -394.515994) (xy 338.401837 -394.527252) (xy 338.448324 -394.546036) (xy 338.491288 -394.571881)
			(xy 338.529665 -394.604146) (xy 338.54644 -394.622782) (xy 338.548904 -394.625553) (xy 338.554515 -394.6304)
			(xy 338.557616 -394.632434) (xy 338.569681 -394.64049) (xy 338.58964 -394.661533) (xy 338.603715 -394.686892)
			(xy 338.611013 -394.714961) (xy 338.611464 -394.729462) (xy 338.611464 -394.7414) (xy 338.612988 -394.748004)
			(xy 338.618179 -394.768377) (xy 338.62379 -394.810042) (xy 338.624164 -394.831062) (xy 338.623784 -394.852082)
			(xy 338.618183 -394.893749) (xy 338.612988 -394.91412) (xy 338.611464 -394.920724) (xy 338.611464 -395.034262)
			(xy 338.610934 -395.049255) (xy 338.603192 -395.078225) (xy 338.588225 -395.104208) (xy 338.567049 -395.12544)
			(xy 338.541105 -395.140476) (xy 338.512156 -395.148294) (xy 338.497164 -395.148816) (xy 338.315046 -395.148816)
			(xy 338.314538 -395.14907) (xy 338.297774 -395.14907) (xy 338.297266 -395.148816) (xy 338.115656 -395.148816)
			(xy 338.100626 -395.148359) (xy 338.071588 -395.14058) (xy 338.045547 -395.125563) (xy 338.024271 -395.104326)
			(xy 338.009204 -395.078314) (xy 338.00137 -395.049291) (xy 338.000848 -395.034262) (xy 338.000848 -394.920724)
			(xy 337.999324 -394.91412) (xy 337.994117 -394.893751) (xy 337.988517 -394.852083) (xy 337.988148 -394.831062)
			(xy 337.98891 -394.808456) (xy 337.989672 -394.79855) (xy 337.983322 -394.779246) (xy 337.923124 -394.709904)
			(xy 337.90509 -394.70076) (xy 337.895184 -394.699998) (xy 337.871356 -394.697816) (xy 337.824725 -394.687086)
			(xy 337.78025 -394.669437) (xy 337.738949 -394.645275) (xy 337.70177 -394.615154) (xy 337.669566 -394.579765)
			(xy 337.643074 -394.539919) (xy 337.622903 -394.496529) (xy 337.615784 -394.473684) (xy 337.61426 -394.467842)
			(xy 337.293966 -393.914122) (xy 337.289902 -393.909804) (xy 337.273758 -393.892124) (xy 337.246436 -393.852811)
			(xy 337.225364 -393.809822) (xy 337.211027 -393.764144) (xy 337.203753 -393.716825) (xy 337.203288 -393.692888)
			(xy 336.671325 -393.692888) (xy 336.9437 -394.16355) (xy 336.947764 -394.167868) (xy 336.963973 -394.185537)
			(xy 336.99137 -394.224888) (xy 337.012499 -394.26793) (xy 337.026874 -394.313673) (xy 337.034166 -394.361064)
			(xy 337.034632 -394.385038) (xy 337.034632 -394.385546) (xy 337.03387 -394.405866) (xy 337.033108 -394.415772)
			(xy 337.039458 -394.434822) (xy 337.100164 -394.504164) (xy 337.117944 -394.513054) (xy 337.128104 -394.513816)
			(xy 337.153054 -394.516031) (xy 337.201854 -394.527312) (xy 337.248284 -394.5461) (xy 337.291196 -394.571931)
			(xy 337.329531 -394.604167) (xy 337.34629 -394.622782) (xy 337.348748 -394.625559) (xy 337.354363 -394.630402)
			(xy 337.357466 -394.632434) (xy 337.369493 -394.640517) (xy 337.389387 -394.661574) (xy 337.403397 -394.686929)
			(xy 337.410635 -394.714978) (xy 337.41106 -394.729462) (xy 337.41106 -394.7414) (xy 337.412838 -394.748004)
			(xy 337.41803 -394.768376) (xy 337.42364 -394.810042) (xy 337.424014 -394.831062) (xy 337.423632 -394.852082)
			(xy 337.418032 -394.893748) (xy 337.412838 -394.91412) (xy 337.41106 -394.920724) (xy 337.41106 -395.034262)
			(xy 337.410575 -395.049282) (xy 337.402808 -395.078302) (xy 337.387794 -395.104321) (xy 337.366556 -395.125567)
			(xy 337.340542 -395.140591) (xy 337.311526 -395.148369) (xy 337.296506 -395.148816) (xy 337.114896 -395.148816)
			(xy 337.114388 -395.14907) (xy 337.097624 -395.14907) (xy 337.097116 -395.148816) (xy 336.915506 -395.148816)
			(xy 336.900481 -395.148402) (xy 336.871454 -395.140624) (xy 336.84543 -395.125597) (xy 336.824184 -395.104345)
			(xy 336.809164 -395.078317) (xy 336.801394 -395.049288) (xy 336.800952 -395.034262) (xy 336.800952 -394.920724)
			(xy 336.799174 -394.91412) (xy 336.793968 -394.893751) (xy 336.788367 -394.852083) (xy 336.787998 -394.831062)
			(xy 336.78876 -394.808456) (xy 336.789522 -394.798296) (xy 336.783426 -394.7795) (xy 336.729832 -394.717524)
			(xy 336.722893 -394.710274) (xy 336.70499 -394.701254) (xy 336.695034 -394.699998) (xy 336.671225 -394.697777)
			(xy 336.624633 -394.687022) (xy 336.580198 -394.669359) (xy 336.538936 -394.645193) (xy 336.501794 -394.615077)
			(xy 336.469622 -394.579702) (xy 336.443155 -394.539877) (xy 336.423002 -394.496514) (xy 336.415888 -394.473684)
			(xy 336.414364 -394.467842) (xy 336.096864 -393.919202) (xy 336.090006 -393.909804) (xy 336.081624 -393.90066)
			(xy 336.041238 -393.924028) (xy 336.032576 -393.929617) (xy 336.020241 -393.946107) (xy 336.015376 -393.966117)
			(xy 336.0166 -393.976352) (xy 336.018124 -393.996926) (xy 336.018124 -393.997434) (xy 336.018124 -394.201904)
			(xy 336.018886 -394.205714) (xy 336.020789 -394.21852) (xy 336.022827 -394.24433) (xy 336.02295 -394.257276)
			(xy 336.02295 -394.25753) (xy 336.022779 -394.273119) (xy 336.019853 -394.30416) (xy 336.017108 -394.319506)
			(xy 336.0166 -394.321538) (xy 336.013044 -394.338048) (xy 336.012536 -394.339572) (xy 336.008043 -394.35621)
			(xy 335.996085 -394.388535) (xy 335.98866 -394.404088) (xy 335.98866 -394.404342) (xy 335.98466 -394.413623)
			(xy 335.983466 -394.43378) (xy 335.986374 -394.443458) (xy 336.014314 -394.522198) (xy 336.028284 -394.537184)
			(xy 336.037682 -394.541502) (xy 336.058258 -394.551346) (xy 336.096646 -394.57598) (xy 336.131139 -394.605824)
			(xy 336.146394 -394.622782) (xy 336.148852 -394.625559) (xy 336.154467 -394.630403) (xy 336.15757 -394.632434)
			(xy 336.169598 -394.640516) (xy 336.189491 -394.661573) (xy 336.203501 -394.686929) (xy 336.210739 -394.714978)
			(xy 336.211164 -394.729462) (xy 336.211164 -394.7414) (xy 336.212942 -394.748004) (xy 336.218134 -394.768376)
			(xy 336.223744 -394.810042) (xy 336.224118 -394.831062) (xy 336.223736 -394.852082) (xy 336.218136 -394.893748)
			(xy 336.212942 -394.91412) (xy 336.211164 -394.920724) (xy 336.211164 -395.034262) (xy 336.210675 -395.049282)
			(xy 336.202908 -395.078301) (xy 336.187895 -395.10432) (xy 336.166658 -395.125566) (xy 336.140645 -395.14059)
			(xy 336.11163 -395.148369) (xy 336.09661 -395.148816) (xy 335.915 -395.148816) (xy 335.914492 -395.14907)
			(xy 335.897728 -395.14907) (xy 335.89722 -395.148816) (xy 335.71561 -395.148816) (xy 335.700585 -395.148399)
			(xy 335.671558 -395.140622) (xy 335.645534 -395.125595) (xy 335.624288 -395.104343) (xy 335.609268 -395.078316)
			(xy 335.601498 -395.049287) (xy 335.601056 -395.034262) (xy 335.601056 -394.920724) (xy 335.599278 -394.91412)
			(xy 335.594072 -394.893751) (xy 335.588471 -394.852083) (xy 335.588102 -394.831062) (xy 335.588468 -394.810041)
			(xy 335.594079 -394.768375) (xy 335.599278 -394.748004) (xy 335.601056 -394.7414) (xy 335.601056 -394.729462)
			(xy 335.601251 -394.718867) (xy 335.605084 -394.698029) (xy 335.608676 -394.68806) (xy 335.612232 -394.678916)
			(xy 335.611978 -394.659612) (xy 335.577942 -394.576554) (xy 335.564988 -394.562838) (xy 335.555844 -394.558774)
			(xy 335.531372 -394.547168) (xy 335.486333 -394.517087) (xy 335.446797 -394.480069) (xy 335.413823 -394.437103)
			(xy 335.388292 -394.389337) (xy 335.370886 -394.338049) (xy 335.362071 -394.284611) (xy 335.361534 -394.25753)
			(xy 333.76616 -394.25753) (xy 333.76616 -394.551408) (xy 333.766871 -394.564135) (xy 333.779015 -394.586509)
			(xy 333.789274 -394.59408) (xy 333.811995 -394.609472) (xy 333.852463 -394.646539) (xy 333.886258 -394.689777)
			(xy 333.912453 -394.738) (xy 333.930328 -394.789885) (xy 333.939395 -394.844009) (xy 333.939896 -394.871448)
			(xy 333.939896 -394.871956) (xy 333.939327 -394.899093) (xy 333.930418 -394.952633) (xy 333.91288 -395.003997)
			(xy 333.900526 -395.028166) (xy 333.896462 -395.035532) (xy 333.893668 -395.051788) (xy 333.906114 -395.129004)
			(xy 333.913988 -395.14399) (xy 333.91983 -395.149578) (xy 333.93186 -395.161882) (xy 333.949483 -395.191424)
			(xy 333.958639 -395.224581) (xy 333.9592 -395.24178) (xy 333.9592 -395.377162) (xy 333.959708 -395.380972)
			(xy 333.961379 -395.393094) (xy 333.963156 -395.417503) (xy 333.963264 -395.42974) (xy 333.963175 -395.441977)
			(xy 333.961398 -395.466387) (xy 333.959708 -395.478508) (xy 333.9592 -395.482318) (xy 333.9592 -395.62278)
			(xy 333.958706 -395.639503) (xy 333.950054 -395.671809) (xy 333.933333 -395.700775) (xy 333.909685 -395.724426)
			(xy 333.880721 -395.741149) (xy 333.848415 -395.749804) (xy 333.831692 -395.750288) (xy 333.714598 -395.750288)
			(xy 333.708756 -395.751558) (xy 333.68369 -395.756993) (xy 333.632556 -395.760961) (xy 333.581422 -395.756993)
			(xy 333.556356 -395.751558) (xy 333.550514 -395.750288) (xy 333.526892 -395.750288) (xy 333.509585 -395.749706)
			(xy 333.476243 -395.740407) (xy 333.446623 -395.722494) (xy 333.422904 -395.697284) (xy 333.41437 -395.682216)
			(xy 333.412377 -395.678577) (xy 333.407399 -395.67194) (xy 333.404464 -395.669008) (xy 333.385424 -395.650172)
			(xy 333.353089 -395.60748) (xy 333.328061 -395.560132) (xy 333.310995 -395.509369) (xy 333.302337 -395.456518)
			(xy 333.301848 -395.42974) (xy 333.301979 -395.417821) (xy 333.303759 -395.394048) (xy 333.305404 -395.382242)
			(xy 333.305404 -395.381988) (xy 333.306414 -395.371112) (xy 333.300218 -395.350189) (xy 333.293466 -395.341602)
			(xy 333.243174 -395.283436) (xy 333.235623 -395.275517) (xy 333.215748 -395.266417) (xy 333.20482 -395.26591)
			(xy 331.889608 -395.26591) (xy 331.879537 -395.266332) (xy 331.860932 -395.274045) (xy 331.85354 -395.280896)
			(xy 331.276452 -395.857984) (xy 331.269613 -395.865384) (xy 331.261901 -395.883983) (xy 331.261466 -395.894052)
			(xy 331.261466 -396.679674) (xy 332.336392 -396.679674) (xy 332.340463 -396.624052) (xy 332.352589 -396.569615)
			(xy 332.372512 -396.517524) (xy 332.399808 -396.468889) (xy 332.433894 -396.424746) (xy 332.474043 -396.386037)
			(xy 332.519401 -396.353586) (xy 332.569001 -396.328085) (xy 332.621785 -396.310078) (xy 332.676628 -396.299948)
			(xy 332.732362 -396.297911) (xy 332.787799 -396.304011) (xy 332.841756 -396.318117) (xy 332.893085 -396.339929)
			(xy 332.940691 -396.368983) (xy 332.983559 -396.404658) (xy 333.020776 -396.446195) (xy 333.051549 -396.492708)
			(xy 333.075221 -396.543205) (xy 333.091289 -396.596612) (xy 333.099409 -396.651788) (xy 333.09989 -396.67815)
			(xy 333.301848 -396.67815) (xy 333.302024 -396.661462) (xy 333.305335 -396.628251) (xy 333.308452 -396.611856)
			(xy 333.309468 -396.606776) (xy 333.309468 -396.571978) (xy 333.310057 -396.554049) (xy 333.320016 -396.519602)
			(xy 333.339146 -396.489273) (xy 333.365942 -396.465446) (xy 333.381858 -396.45717) (xy 333.385865 -396.455153)
			(xy 333.393144 -396.449909) (xy 333.396336 -396.446756) (xy 333.415117 -396.428295) (xy 333.457452 -396.396979)
			(xy 333.504219 -396.372774) (xy 333.554232 -396.356291) (xy 333.606226 -396.347949) (xy 333.632556 -396.347442)
			(xy 333.660377 -396.348047) (xy 333.715233 -396.35736) (xy 333.767755 -396.375729) (xy 333.816458 -396.402635)
			(xy 333.859966 -396.43732) (xy 333.878936 -396.457678) (xy 333.888588 -396.46606) (xy 333.900587 -396.474607)
			(xy 333.920669 -396.496149) (xy 333.935297 -396.521709) (xy 333.943697 -396.549936) (xy 333.944976 -396.564612)
			(xy 333.947262 -396.577058) (xy 333.954707 -396.601666) (xy 333.96274 -396.652445) (xy 333.963264 -396.67815)
			(xy 333.962809 -396.703582) (xy 333.961712 -396.710662) (xy 335.728056 -396.710662) (xy 335.728424 -396.689641)
			(xy 335.734034 -396.647975) (xy 335.739232 -396.627604) (xy 335.740756 -396.621) (xy 335.740756 -396.507462)
			(xy 335.7412 -396.492464) (xy 335.748961 -396.463488) (xy 335.763947 -396.437503) (xy 335.785139 -396.416273)
			(xy 335.811097 -396.401241) (xy 335.840059 -396.393427) (xy 335.855056 -396.392908) (xy 336.037174 -396.392908)
			(xy 336.037682 -396.392654) (xy 336.054446 -396.392654) (xy 336.054954 -396.392908) (xy 336.236564 -396.392908)
			(xy 336.251593 -396.393412) (xy 336.280631 -396.401174) (xy 336.306674 -396.416179) (xy 336.327954 -396.437407)
			(xy 336.343021 -396.463415) (xy 336.350852 -396.492434) (xy 336.351372 -396.507462) (xy 336.351372 -396.621)
			(xy 336.352896 -396.627604) (xy 336.358087 -396.647977) (xy 336.363698 -396.689642) (xy 336.364072 -396.710662)
			(xy 336.927952 -396.710662) (xy 336.92832 -396.689641) (xy 336.93393 -396.647975) (xy 336.939128 -396.627604)
			(xy 336.940652 -396.621) (xy 336.940652 -396.507462) (xy 336.9411 -396.492464) (xy 336.948861 -396.463489)
			(xy 336.963846 -396.437504) (xy 336.985037 -396.416274) (xy 337.010994 -396.401242) (xy 337.039955 -396.393427)
			(xy 337.054952 -396.392908) (xy 337.23707 -396.392908) (xy 337.237578 -396.392654) (xy 337.254342 -396.392654)
			(xy 337.25485 -396.392908) (xy 337.43646 -396.392908) (xy 337.451489 -396.393415) (xy 337.480526 -396.401176)
			(xy 337.50657 -396.416181) (xy 337.527849 -396.437408) (xy 337.542917 -396.463416) (xy 337.550748 -396.492435)
			(xy 337.551268 -396.507462) (xy 337.551268 -396.621) (xy 337.552792 -396.627604) (xy 337.557983 -396.647977)
			(xy 337.563594 -396.689642) (xy 337.563968 -396.710662) (xy 338.128102 -396.710662) (xy 338.128468 -396.689641)
			(xy 338.134079 -396.647975) (xy 338.139278 -396.627604) (xy 338.141056 -396.621) (xy 338.141056 -396.507462)
			(xy 338.141503 -396.492443) (xy 338.149286 -396.46343) (xy 338.164312 -396.437419) (xy 338.185557 -396.416182)
			(xy 338.211574 -396.401167) (xy 338.24059 -396.393396) (xy 338.25561 -396.392908) (xy 338.43722 -396.392908)
			(xy 338.437728 -396.392654) (xy 338.454492 -396.392654) (xy 338.455 -396.392908) (xy 338.63661 -396.392908)
			(xy 338.651624 -396.393427) (xy 338.680629 -396.401199) (xy 338.706635 -396.416212) (xy 338.727871 -396.437442)
			(xy 338.74289 -396.463445) (xy 338.75067 -396.492448) (xy 338.751164 -396.507462) (xy 338.751164 -396.621)
			(xy 338.752942 -396.627604) (xy 338.758134 -396.647976) (xy 338.763744 -396.689642) (xy 338.764118 -396.710662)
			(xy 339.327998 -396.710662) (xy 339.328365 -396.689641) (xy 339.333975 -396.647975) (xy 339.339174 -396.627604)
			(xy 339.340952 -396.621) (xy 339.340952 -396.507462) (xy 339.341403 -396.492443) (xy 339.349185 -396.46343)
			(xy 339.364211 -396.43742) (xy 339.385455 -396.416184) (xy 339.411471 -396.401169) (xy 339.440487 -396.393397)
			(xy 339.455506 -396.392908) (xy 339.637116 -396.392908) (xy 339.637624 -396.392654) (xy 339.654388 -396.392654)
			(xy 339.654896 -396.392908) (xy 339.836506 -396.392908) (xy 339.85152 -396.39343) (xy 339.880525 -396.401202)
			(xy 339.906531 -396.416214) (xy 339.927767 -396.437444) (xy 339.942786 -396.463445) (xy 339.950566 -396.492448)
			(xy 339.95106 -396.507462) (xy 339.95106 -396.621) (xy 339.952838 -396.627604) (xy 339.95803 -396.647976)
			(xy 339.96364 -396.689642) (xy 339.964014 -396.710662) (xy 339.964014 -396.71117) (xy 339.963843 -396.725795)
			(xy 339.961177 -396.754924) (xy 339.95868 -396.769336) (xy 339.957319 -396.77851) (xy 339.960591 -396.796752)
			(xy 339.96503 -396.804896) (xy 339.98154 -396.83182) (xy 339.986711 -396.839597) (xy 340.001436 -396.85106)
			(xy 340.010242 -396.854172) (xy 340.035131 -396.862215) (xy 340.082009 -396.88541) (xy 340.12442 -396.916018)
			(xy 340.161202 -396.953202) (xy 340.191348 -396.995944) (xy 340.214031 -397.043071) (xy 340.221824 -397.06804)
			(xy 340.223348 -397.073882) (xy 340.317836 -397.237204) (xy 340.349586 -397.250412) (xy 340.36635 -397.24584)
			(xy 340.376936 -397.242385) (xy 340.393971 -397.22809) (xy 340.403373 -397.207937) (xy 340.403942 -397.196818)
			(xy 340.403942 -396.0495) (xy 340.41715 -396.0495) (xy 340.41715 -395.877542) (xy 340.417584 -395.867473)
			(xy 340.425297 -395.848875) (xy 340.432136 -395.841474) (xy 340.496398 -395.777212) (xy 340.503121 -395.769841)
			(xy 340.510755 -395.751425) (xy 340.510817 -395.73149) (xy 340.503298 -395.713027) (xy 340.496652 -395.705584)
			(xy 340.495382 -395.704314) (xy 340.494366 -395.703298) (xy 340.486783 -395.696474) (xy 340.472421 -395.681984)
			(xy 340.465664 -395.674342) (xy 340.463196 -395.671574) (xy 340.457588 -395.666725) (xy 340.454488 -395.66469)
			(xy 340.442434 -395.656618) (xy 340.422474 -395.63558) (xy 340.408397 -395.610226) (xy 340.401094 -395.582161)
			(xy 340.40064 -395.567662) (xy 340.40064 -395.555724) (xy 340.399116 -395.54912) (xy 340.393909 -395.528751)
			(xy 340.388309 -395.487083) (xy 340.38794 -395.466062) (xy 340.388308 -395.445041) (xy 340.393918 -395.403375)
			(xy 340.399116 -395.383004) (xy 340.40064 -395.3764) (xy 340.40064 -395.262862) (xy 340.401298 -395.244743)
			(xy 340.412553 -395.210297) (xy 340.422738 -395.195298) (xy 340.427243 -395.188633) (xy 340.432284 -395.173364)
			(xy 340.432644 -395.165326) (xy 340.432644 -395.131798) (xy 340.43234 -395.12375) (xy 340.427293 -395.108467)
			(xy 340.422738 -395.101826) (xy 340.41265 -395.086777) (xy 340.401396 -395.052363) (xy 340.40064 -395.034262)
			(xy 340.40064 -394.920724) (xy 340.399116 -394.91412) (xy 340.393909 -394.893751) (xy 340.388309 -394.852083)
			(xy 340.38794 -394.831062) (xy 340.388702 -394.808456) (xy 340.389464 -394.798296) (xy 340.383368 -394.7795)
			(xy 340.329774 -394.717524) (xy 340.322856 -394.710251) (xy 340.304937 -394.701244) (xy 340.294976 -394.699998)
			(xy 340.271162 -394.697824) (xy 340.224569 -394.68706) (xy 340.180133 -394.669389) (xy 340.138872 -394.645216)
			(xy 340.101731 -394.615094) (xy 340.06956 -394.579713) (xy 340.043095 -394.539883) (xy 340.022943 -394.496516)
			(xy 340.01583 -394.473684) (xy 340.014306 -394.467842) (xy 339.694012 -393.914122) (xy 339.689948 -393.909804)
			(xy 339.673711 -393.892125) (xy 339.646294 -393.852725) (xy 339.625158 -393.809628) (xy 339.610792 -393.763828)
			(xy 339.603526 -393.71638) (xy 339.60308 -393.69238) (xy 339.603499 -393.6676) (xy 339.611251 -393.61865)
			(xy 339.626562 -393.571515) (xy 339.649055 -393.527353) (xy 339.678177 -393.487252) (xy 339.713211 -393.452198)
			(xy 339.753295 -393.423053) (xy 339.797443 -393.400534) (xy 339.844569 -393.385195) (xy 339.893514 -393.377413)
			(xy 339.918294 -393.376912) (xy 339.918802 -393.376912) (xy 339.944197 -393.377394) (xy 339.994333 -393.385525)
			(xy 340.04252 -393.401578) (xy 340.087515 -393.425139) (xy 340.128158 -393.455599) (xy 340.1634 -393.492173)
			(xy 340.192333 -393.533918) (xy 340.214209 -393.579756) (xy 340.221824 -393.603988) (xy 340.223348 -393.60983)
			(xy 340.543642 -394.16355) (xy 340.547706 -394.167868) (xy 340.563854 -394.185578) (xy 340.5912 -394.224935)
			(xy 340.612282 -394.267973) (xy 340.626616 -394.313704) (xy 340.63387 -394.361076) (xy 340.63432 -394.385038)
			(xy 340.63432 -394.385546) (xy 340.633812 -394.405866) (xy 340.63305 -394.415772) (xy 340.6394 -394.434822)
			(xy 340.700106 -394.504164) (xy 340.717886 -394.513054) (xy 340.728046 -394.513816) (xy 340.752999 -394.516006)
			(xy 340.801799 -394.527293) (xy 340.848229 -394.546087) (xy 340.89114 -394.571924) (xy 340.929474 -394.604164)
			(xy 340.946232 -394.622782) (xy 340.948697 -394.625552) (xy 340.954308 -394.6304) (xy 340.957408 -394.632434)
			(xy 340.969472 -394.640492) (xy 340.989431 -394.661534) (xy 341.003506 -394.686892) (xy 341.010805 -394.714962)
			(xy 341.011256 -394.729462) (xy 341.011256 -394.7414) (xy 341.01278 -394.748004) (xy 341.017973 -394.768376)
			(xy 341.023582 -394.810042) (xy 341.023956 -394.831062) (xy 341.023573 -394.852082) (xy 341.017973 -394.893748)
			(xy 341.01278 -394.91412) (xy 341.011256 -394.920724) (xy 341.011256 -394.981176) (xy 341.011806 -394.991177)
			(xy 341.01945 -395.00966) (xy 341.033583 -395.023812) (xy 341.052056 -395.03148) (xy 341.062056 -395.031976)
			(xy 341.065866 -395.031976) (xy 341.06993 -395.031214) (xy 341.081598 -395.029455) (xy 341.105121 -395.027551)
			(xy 341.11692 -395.027404) (xy 341.550244 -395.027404) (xy 341.560254 -395.026948) (xy 341.578746 -395.019275)
			(xy 341.592897 -395.005112) (xy 341.600556 -394.986614) (xy 341.601044 -394.976604) (xy 341.601044 -394.920724)
			(xy 341.599266 -394.91412) (xy 341.59406 -394.893751) (xy 341.588459 -394.852083) (xy 341.58809 -394.831062)
			(xy 341.588852 -394.808456) (xy 341.589614 -394.79855) (xy 341.583264 -394.779246) (xy 341.523066 -394.709904)
			(xy 341.505032 -394.70076) (xy 341.495126 -394.699998) (xy 341.471301 -394.697782) (xy 341.424672 -394.687058)
			(xy 341.380197 -394.669415) (xy 341.338896 -394.645258) (xy 341.301717 -394.615142) (xy 341.269511 -394.579757)
			(xy 341.243019 -394.539914) (xy 341.222846 -394.496528) (xy 341.215726 -394.473684) (xy 341.214202 -394.467842)
			(xy 340.893908 -393.914122) (xy 340.889844 -393.909804) (xy 340.873607 -393.892125) (xy 340.846189 -393.852726)
			(xy 340.825054 -393.809629) (xy 340.810688 -393.763828) (xy 340.803422 -393.71638) (xy 340.802976 -393.69238)
			(xy 340.803399 -393.6676) (xy 340.811151 -393.618651) (xy 340.826462 -393.571516) (xy 340.848954 -393.527355)
			(xy 340.878076 -393.487254) (xy 340.913109 -393.452199) (xy 340.953192 -393.423054) (xy 340.99734 -393.400535)
			(xy 341.044466 -393.385195) (xy 341.093411 -393.377414) (xy 341.11819 -393.376912) (xy 341.118698 -393.376912)
			(xy 341.144093 -393.377397) (xy 341.194228 -393.385528) (xy 341.242415 -393.401581) (xy 341.287411 -393.425141)
			(xy 341.328054 -393.455601) (xy 341.363296 -393.492174) (xy 341.392229 -393.533918) (xy 341.414105 -393.579756)
			(xy 341.42172 -393.603988) (xy 341.423244 -393.60983) (xy 341.743538 -394.16355) (xy 341.747602 -394.167868)
			(xy 341.763749 -394.185579) (xy 341.791096 -394.224935) (xy 341.812178 -394.267973) (xy 341.826511 -394.313704)
			(xy 341.833766 -394.361076) (xy 341.834216 -394.385038) (xy 341.834216 -394.385546) (xy 341.833708 -394.405866)
			(xy 341.832946 -394.415772) (xy 341.839296 -394.434822) (xy 341.900002 -394.504164) (xy 341.917782 -394.513054)
			(xy 341.927942 -394.513816) (xy 341.952917 -394.516029) (xy 342.001774 -394.527278) (xy 342.048261 -394.546054)
			(xy 342.091227 -394.571891) (xy 342.129606 -394.60415) (xy 342.146382 -394.622782) (xy 342.148841 -394.625558)
			(xy 342.154456 -394.630402) (xy 342.157558 -394.632434) (xy 342.169583 -394.640519) (xy 342.189478 -394.661575)
			(xy 342.203488 -394.686929) (xy 342.210727 -394.714978) (xy 342.211152 -394.729462) (xy 342.211152 -394.7414)
			(xy 342.21293 -394.748004) (xy 342.218122 -394.768376) (xy 342.223732 -394.810042) (xy 342.224106 -394.831062)
			(xy 342.223724 -394.852082) (xy 342.218124 -394.893748) (xy 342.21293 -394.91412) (xy 342.211152 -394.920724)
			(xy 342.211152 -394.976604) (xy 342.211684 -394.986606) (xy 342.219336 -395.005089) (xy 342.233474 -395.01924)
			(xy 342.25195 -395.026908) (xy 342.261952 -395.027404) (xy 342.338914 -395.027404) (xy 342.368373 -395.02814)
			(xy 342.426185 -395.039517) (xy 342.453722 -395.05001) (xy 342.46312 -395.05382) (xy 342.764618 -395.05382)
			(xy 342.770994 -395.053611) (xy 342.783337 -395.050402) (xy 342.789002 -395.04747) (xy 342.80094 -395.041374)
			(xy 342.80094 -394.920724) (xy 342.799162 -394.91412) (xy 342.793956 -394.893751) (xy 342.788355 -394.852083)
			(xy 342.787986 -394.831062) (xy 342.788748 -394.808456) (xy 342.78951 -394.798296) (xy 342.783414 -394.7795)
			(xy 342.72982 -394.717524) (xy 342.722886 -394.71027) (xy 342.704979 -394.701252) (xy 342.695022 -394.699998)
			(xy 342.671212 -394.697787) (xy 342.62462 -394.68703) (xy 342.580184 -394.669365) (xy 342.538923 -394.645197)
			(xy 342.501781 -394.615081) (xy 342.469609 -394.579704) (xy 342.443143 -394.539878) (xy 342.422989 -394.496515)
			(xy 342.415876 -394.473684) (xy 342.414352 -394.467842) (xy 342.094058 -393.914122) (xy 342.089994 -393.909804)
			(xy 342.073849 -393.892125) (xy 342.046527 -393.852812) (xy 342.025456 -393.809823) (xy 342.011119 -393.764145)
			(xy 342.003845 -393.716825) (xy 342.00338 -393.692888) (xy 342.00338 -393.69238) (xy 342.003775 -393.667585)
			(xy 342.011536 -393.618607) (xy 342.026863 -393.571447) (xy 342.04938 -393.527264) (xy 342.078532 -393.487149)
			(xy 342.113601 -393.452088) (xy 342.153723 -393.422945) (xy 342.19791 -393.400437) (xy 342.245074 -393.38512)
			(xy 342.294053 -393.377369) (xy 342.318848 -393.376912) (xy 342.344245 -393.377353) (xy 342.394382 -393.385492)
			(xy 342.44257 -393.401552) (xy 342.487565 -393.425119) (xy 342.528208 -393.455584) (xy 342.563449 -393.492164)
			(xy 342.592381 -393.533912) (xy 342.614255 -393.579754) (xy 342.62187 -393.603988) (xy 342.623394 -393.60983)
			(xy 342.943688 -394.16355) (xy 342.947752 -394.167868) (xy 342.963959 -394.185539) (xy 342.991356 -394.224889)
			(xy 343.012486 -394.267931) (xy 343.026862 -394.313674) (xy 343.034154 -394.361064) (xy 343.03462 -394.385038)
			(xy 343.03462 -394.385546) (xy 343.033858 -394.405866) (xy 343.033096 -394.415772) (xy 343.039446 -394.434822)
			(xy 343.100152 -394.504164) (xy 343.117932 -394.513054) (xy 343.128092 -394.513816) (xy 343.153041 -394.516038)
			(xy 343.201841 -394.527318) (xy 343.248271 -394.546104) (xy 343.291183 -394.571933) (xy 343.329519 -394.604167)
			(xy 343.346278 -394.622782) (xy 343.348738 -394.625557) (xy 343.354352 -394.630402) (xy 343.357454 -394.632434)
			(xy 343.369478 -394.640521) (xy 343.389373 -394.661576) (xy 343.403384 -394.68693) (xy 343.410623 -394.714978)
			(xy 343.411048 -394.729462) (xy 343.411048 -394.7414) (xy 343.412826 -394.748004) (xy 343.418017 -394.768377)
			(xy 343.423628 -394.810042) (xy 343.424002 -394.831062) (xy 343.423621 -394.852082) (xy 343.41802 -394.893748)
			(xy 343.412826 -394.91412) (xy 343.411048 -394.920724) (xy 343.411048 -394.958824) (xy 343.411401 -394.968853)
			(xy 343.419088 -394.987379) (xy 343.433281 -395.001552) (xy 343.451819 -395.009213) (xy 343.461848 -395.009624)
			(xy 343.950036 -395.009624) (xy 343.960043 -395.009142) (xy 343.978531 -395.001475) (xy 343.992682 -394.987321)
			(xy 344.000344 -394.968831) (xy 344.000836 -394.958824) (xy 344.000836 -394.920724) (xy 343.999312 -394.91412)
			(xy 343.994107 -394.893751) (xy 343.988505 -394.852083) (xy 343.988136 -394.831062) (xy 343.988898 -394.808456)
			(xy 343.98966 -394.79855) (xy 343.98331 -394.779246) (xy 343.923112 -394.709904) (xy 343.905078 -394.70076)
			(xy 343.895172 -394.699998) (xy 343.871351 -394.697745) (xy 343.824723 -394.687027) (xy 343.780248 -394.669391)
			(xy 343.738947 -394.64524) (xy 343.701767 -394.615129) (xy 343.66956 -394.579748) (xy 343.643066 -394.539909)
			(xy 343.622893 -394.496526) (xy 343.615772 -394.473684) (xy 343.614248 -394.467842) (xy 343.293954 -393.914122)
			(xy 343.28989 -393.909804) (xy 343.273744 -393.892126) (xy 343.246422 -393.852812) (xy 343.225351 -393.809823)
			(xy 343.211015 -393.764145) (xy 343.203741 -393.716825) (xy 343.203276 -393.692888) (xy 343.203276 -393.69238)
			(xy 343.203675 -393.667586) (xy 343.211436 -393.618608) (xy 343.226763 -393.571448) (xy 343.24928 -393.527266)
			(xy 343.278431 -393.48715) (xy 343.313499 -393.452089) (xy 343.35362 -393.422946) (xy 343.397807 -393.400439)
			(xy 343.44497 -393.385121) (xy 343.49395 -393.37737) (xy 343.518744 -393.376912) (xy 343.544141 -393.377357)
			(xy 343.594278 -393.385495) (xy 343.642465 -393.401554) (xy 343.687461 -393.42512) (xy 343.728104 -393.455586)
			(xy 343.763345 -393.492164) (xy 343.792276 -393.533913) (xy 343.814151 -393.579754) (xy 343.821766 -393.603988)
			(xy 343.82329 -393.60983) (xy 344.143584 -394.16355) (xy 344.147648 -394.167868) (xy 344.163855 -394.18554)
			(xy 344.191252 -394.22489) (xy 344.212382 -394.267931) (xy 344.226758 -394.313674) (xy 344.23405 -394.361064)
			(xy 344.234516 -394.385038) (xy 344.234516 -394.385546) (xy 344.233754 -394.405866) (xy 344.232992 -394.415772)
			(xy 344.239342 -394.434822) (xy 344.300048 -394.504164) (xy 344.317828 -394.513054) (xy 344.327988 -394.513816)
			(xy 344.352966 -394.516002) (xy 344.401824 -394.527257) (xy 344.448311 -394.54604) (xy 344.491275 -394.571883)
			(xy 344.529653 -394.604147) (xy 344.546428 -394.622782) (xy 344.548894 -394.625552) (xy 344.554504 -394.6304)
			(xy 344.557604 -394.632434) (xy 344.569667 -394.640494) (xy 344.589627 -394.661535) (xy 344.603702 -394.686893)
			(xy 344.611001 -394.714962) (xy 344.611452 -394.729462) (xy 344.611452 -394.7414) (xy 344.612976 -394.748004)
			(xy 344.618168 -394.768376) (xy 344.623778 -394.810042) (xy 344.624152 -394.831062) (xy 344.623769 -394.852082)
			(xy 344.618169 -394.893748) (xy 344.612976 -394.91412) (xy 344.611452 -394.920724) (xy 344.611452 -394.958824)
			(xy 344.611967 -394.968827) (xy 344.619626 -394.98731) (xy 344.633769 -395.001461) (xy 344.652249 -395.009128)
			(xy 344.662252 -395.009624) (xy 345.149932 -395.009624) (xy 345.159939 -395.009139) (xy 345.178427 -395.001473)
			(xy 345.192578 -394.98732) (xy 345.20024 -394.968831) (xy 345.200732 -394.958824) (xy 345.200732 -394.920724)
			(xy 345.199208 -394.91412) (xy 345.194003 -394.893751) (xy 345.188401 -394.852083) (xy 345.188032 -394.831062)
			(xy 345.188794 -394.808456) (xy 345.189556 -394.79855) (xy 345.183206 -394.779246) (xy 345.123008 -394.709904)
			(xy 345.104974 -394.70076) (xy 345.095068 -394.699998) (xy 345.071193 -394.697772) (xy 345.024466 -394.687015)
			(xy 344.979904 -394.669311) (xy 344.938536 -394.645067) (xy 344.901312 -394.614842) (xy 344.869092 -394.579332)
			(xy 344.842616 -394.539355) (xy 344.822495 -394.495832) (xy 344.815414 -394.472922) (xy 344.81389 -394.46708)
			(xy 344.494104 -393.914122) (xy 344.49004 -393.909804) (xy 344.473802 -393.892126) (xy 344.446385 -393.852726)
			(xy 344.425249 -393.809629) (xy 344.410884 -393.763828) (xy 344.403618 -393.71638) (xy 344.403172 -393.69238)
			(xy 344.403599 -393.667601) (xy 344.411351 -393.618652) (xy 344.426661 -393.571517) (xy 344.449154 -393.527356)
			(xy 344.478274 -393.487255) (xy 344.513307 -393.452201) (xy 344.55339 -393.423055) (xy 344.597537 -393.400536)
			(xy 344.644663 -393.385196) (xy 344.693607 -393.377414) (xy 344.718386 -393.376912) (xy 344.718894 -393.376912)
			(xy 344.744289 -393.377401) (xy 344.794424 -393.385531) (xy 344.842611 -393.401583) (xy 344.887606 -393.425143)
			(xy 344.928249 -393.455602) (xy 344.963492 -393.492175) (xy 344.992424 -393.533919) (xy 345.014301 -393.579756)
			(xy 345.021916 -393.603988) (xy 345.02344 -393.60983) (xy 345.343988 -394.164312) (xy 345.348052 -394.16863)
			(xy 345.364151 -394.186269) (xy 345.391375 -394.225505) (xy 345.412375 -394.268396) (xy 345.426671 -394.313961)
			(xy 345.433938 -394.361161) (xy 345.434412 -394.385038) (xy 345.434412 -394.385546) (xy 345.43365 -394.405866)
			(xy 345.432888 -394.415772) (xy 345.439238 -394.434822) (xy 345.499944 -394.504164) (xy 345.517724 -394.513054)
			(xy 345.527884 -394.513816) (xy 345.552861 -394.516004) (xy 345.60172 -394.527259) (xy 345.648207 -394.546041)
			(xy 345.691171 -394.571884) (xy 345.729549 -394.604147) (xy 345.746324 -394.622782) (xy 345.74879 -394.625551)
			(xy 345.7544 -394.6304) (xy 345.7575 -394.632434) (xy 345.769562 -394.640495) (xy 345.789523 -394.661535)
			(xy 345.803598 -394.686893) (xy 345.810897 -394.714962) (xy 345.811348 -394.729462) (xy 345.811348 -394.7414)
			(xy 345.812872 -394.748004) (xy 345.818064 -394.768376) (xy 345.823674 -394.810042) (xy 345.824048 -394.831062)
			(xy 345.823665 -394.852082) (xy 345.818065 -394.893748) (xy 345.812872 -394.91412) (xy 345.811348 -394.920724)
			(xy 345.811348 -394.958824) (xy 345.811701 -394.968853) (xy 345.819388 -394.987379) (xy 345.833581 -395.001552)
			(xy 345.852119 -395.009213) (xy 345.862148 -395.009624) (xy 346.36329 -395.009624) (xy 346.372648 -395.009706)
			(xy 346.39133 -395.010847) (xy 346.400628 -395.01191) (xy 346.400628 -394.920724) (xy 346.399104 -394.91412)
			(xy 346.393899 -394.893751) (xy 346.388297 -394.852083) (xy 346.387928 -394.831062) (xy 346.38869 -394.808456)
			(xy 346.389452 -394.798296) (xy 346.383356 -394.7795) (xy 346.329762 -394.717524) (xy 346.322813 -394.710286)
			(xy 346.304917 -394.701259) (xy 346.294964 -394.699998) (xy 346.271158 -394.697753) (xy 346.224567 -394.687001)
			(xy 346.180131 -394.669342) (xy 346.13887 -394.64518) (xy 346.101727 -394.615068) (xy 346.069554 -394.579696)
			(xy 346.043087 -394.539873) (xy 346.022932 -394.496513) (xy 346.015818 -394.473684) (xy 346.014294 -394.467842)
			(xy 345.694 -393.914122) (xy 345.689936 -393.909804) (xy 345.673697 -393.892127) (xy 345.64628 -393.852726)
			(xy 345.625145 -393.809629) (xy 345.61078 -393.763828) (xy 345.603514 -393.71638) (xy 345.603068 -393.69238)
			(xy 345.603499 -393.667601) (xy 345.611251 -393.618652) (xy 345.626561 -393.571518) (xy 345.649053 -393.527357)
			(xy 345.678173 -393.487256) (xy 345.713206 -393.452202) (xy 345.753288 -393.423057) (xy 345.797435 -393.400537)
			(xy 345.844559 -393.385197) (xy 345.893503 -393.377414) (xy 345.918282 -393.376912) (xy 345.91879 -393.376912)
			(xy 345.944185 -393.377404) (xy 345.99432 -393.385534) (xy 346.042507 -393.401585) (xy 346.087502 -393.425144)
			(xy 346.128145 -393.455603) (xy 346.163388 -393.492176) (xy 346.19232 -393.533919) (xy 346.214197 -393.579756)
			(xy 346.221812 -393.603988) (xy 346.223336 -393.60983) (xy 346.54363 -394.16355) (xy 346.547694 -394.167868)
			(xy 346.56384 -394.18558) (xy 346.591187 -394.224936) (xy 346.61227 -394.267974) (xy 346.626603 -394.313704)
			(xy 346.633858 -394.361076) (xy 346.634308 -394.385038) (xy 346.634308 -394.385546) (xy 346.6338 -394.405866)
			(xy 346.633038 -394.415772) (xy 346.639388 -394.434822) (xy 346.700094 -394.504164) (xy 346.717874 -394.513054)
			(xy 346.728034 -394.513816) (xy 346.752986 -394.516013) (xy 346.801786 -394.527299) (xy 346.848216 -394.546091)
			(xy 346.891128 -394.571926) (xy 346.929462 -394.604165) (xy 346.94622 -394.622782) (xy 346.948687 -394.625551)
			(xy 346.954296 -394.6304) (xy 346.957396 -394.632434) (xy 346.969457 -394.640496) (xy 346.989418 -394.661536)
			(xy 347.003494 -394.686893) (xy 347.010793 -394.714962) (xy 347.011244 -394.729462) (xy 347.011244 -394.7414)
			(xy 347.012768 -394.748004) (xy 347.01796 -394.768376) (xy 347.02357 -394.810042) (xy 347.023944 -394.831062)
			(xy 347.023561 -394.852082) (xy 347.017962 -394.893748) (xy 347.012768 -394.91412) (xy 347.011244 -394.920724)
			(xy 347.011244 -395.00302) (xy 347.011604 -395.013048) (xy 347.019289 -395.031574) (xy 347.03348 -395.045747)
			(xy 347.052015 -395.053408) (xy 347.062044 -395.05382) (xy 347.401388 -395.05382) (xy 347.413834 -395.050518)
			(xy 347.419422 -395.04747) (xy 347.446427 -395.033332) (xy 347.504521 -395.014902) (xy 347.534738 -395.010894)
			(xy 347.543576 -395.009572) (xy 347.559576 -395.001633) (xy 347.56598 -394.9954) (xy 347.587062 -394.973302)
			(xy 347.593428 -394.965972) (xy 347.600604 -394.947949) (xy 347.601032 -394.93825) (xy 347.601032 -394.920724)
			(xy 347.599254 -394.91412) (xy 347.594048 -394.893751) (xy 347.588447 -394.852083) (xy 347.588078 -394.831062)
			(xy 347.58884 -394.808456) (xy 347.589602 -394.79855) (xy 347.583252 -394.779246) (xy 347.523054 -394.709904)
			(xy 347.50502 -394.70076) (xy 347.495114 -394.699998) (xy 347.471288 -394.697792) (xy 347.424659 -394.687065)
			(xy 347.380184 -394.669421) (xy 347.338883 -394.645263) (xy 347.301704 -394.615145) (xy 347.269498 -394.579759)
			(xy 347.243006 -394.539915) (xy 347.222834 -394.496528) (xy 347.215714 -394.473684) (xy 347.21419 -394.467842)
			(xy 346.893896 -393.914122) (xy 346.889832 -393.909804) (xy 346.873593 -393.892127) (xy 346.846176 -393.852727)
			(xy 346.825041 -393.809629) (xy 346.810675 -393.763828) (xy 346.80341 -393.71638) (xy 346.802964 -393.69238)
			(xy 346.803399 -393.667601) (xy 346.811151 -393.618653) (xy 346.826461 -393.571519) (xy 346.848952 -393.527358)
			(xy 346.878072 -393.487258) (xy 346.913104 -393.452203) (xy 346.953186 -393.423058) (xy 346.997332 -393.400538)
			(xy 347.044456 -393.385198) (xy 347.093399 -393.377415) (xy 347.118178 -393.376912) (xy 347.118686 -393.376912)
			(xy 347.144081 -393.377408) (xy 347.194216 -393.385537) (xy 347.242402 -393.401588) (xy 347.287398 -393.425146)
			(xy 347.328041 -393.455605) (xy 347.363283 -393.492177) (xy 347.392216 -393.53392) (xy 347.414093 -393.579757)
			(xy 347.421708 -393.603988) (xy 347.423232 -393.60983) (xy 347.471276 -393.692888) (xy 348.003368 -393.692888)
			(xy 348.003368 -393.69238) (xy 348.003775 -393.667586) (xy 348.011535 -393.618609) (xy 348.026862 -393.571449)
			(xy 348.049378 -393.527268) (xy 348.078529 -393.487153) (xy 348.113596 -393.452092) (xy 348.153716 -393.422949)
			(xy 348.197901 -393.400441) (xy 348.245064 -393.385122) (xy 348.294042 -393.37737) (xy 348.318836 -393.376912)
			(xy 348.344232 -393.377364) (xy 348.394369 -393.385501) (xy 348.442557 -393.401559) (xy 348.487552 -393.425124)
			(xy 348.528195 -393.455588) (xy 348.563437 -393.492166) (xy 348.592368 -393.533914) (xy 348.614243 -393.579755)
			(xy 348.621858 -393.603988) (xy 348.623382 -393.60983) (xy 348.671426 -393.692888) (xy 349.203264 -393.692888)
			(xy 349.203264 -393.69238) (xy 349.203675 -393.667586) (xy 349.211435 -393.61861) (xy 349.226762 -393.57145)
			(xy 349.249278 -393.527269) (xy 349.278427 -393.487154) (xy 349.313494 -393.452094) (xy 349.353614 -393.42295)
			(xy 349.397798 -393.400442) (xy 349.44496 -393.385123) (xy 349.493938 -393.377371) (xy 349.518732 -393.376912)
			(xy 349.544128 -393.377367) (xy 349.594265 -393.385503) (xy 349.642452 -393.401561) (xy 349.687448 -393.425126)
			(xy 349.728091 -393.45559) (xy 349.763332 -393.492167) (xy 349.792264 -393.533914) (xy 349.814139 -393.579755)
			(xy 349.821754 -393.603988) (xy 349.823278 -393.60983) (xy 349.871028 -393.69238) (xy 350.40316 -393.69238)
			(xy 350.403599 -393.667601) (xy 350.41135 -393.618653) (xy 350.42666 -393.57152) (xy 350.449152 -393.527359)
			(xy 350.478271 -393.487259) (xy 350.513302 -393.452205) (xy 350.553383 -393.423059) (xy 350.597529 -393.400539)
			(xy 350.644653 -393.385199) (xy 350.693595 -393.377415) (xy 350.718374 -393.376912) (xy 350.718882 -393.376912)
			(xy 350.744277 -393.377411) (xy 350.794411 -393.38554) (xy 350.842598 -393.40159) (xy 350.887593 -393.425148)
			(xy 350.928236 -393.455606) (xy 350.963479 -393.492178) (xy 350.992412 -393.53392) (xy 351.014289 -393.579757)
			(xy 351.021904 -393.603988) (xy 351.023428 -393.60983) (xy 351.07115 -393.69238) (xy 351.603056 -393.69238)
			(xy 351.603499 -393.667601) (xy 351.61125 -393.618654) (xy 351.62656 -393.571521) (xy 351.649051 -393.527361)
			(xy 351.67817 -393.48726) (xy 351.7132 -393.452206) (xy 351.753281 -393.423061) (xy 351.797426 -393.40054)
			(xy 351.844549 -393.385199) (xy 351.893492 -393.377415) (xy 351.91827 -393.376912) (xy 351.918778 -393.376912)
			(xy 351.944173 -393.377415) (xy 351.994307 -393.385543) (xy 352.042494 -393.401592) (xy 352.087489 -393.42515)
			(xy 352.128132 -393.455607) (xy 352.163375 -393.492179) (xy 352.192308 -393.533921) (xy 352.214185 -393.579757)
			(xy 352.2218 -393.603988) (xy 352.223324 -393.60983) (xy 352.271368 -393.692888) (xy 352.80346 -393.692888)
			(xy 352.80346 -393.69238) (xy 352.803875 -393.667586) (xy 352.811635 -393.61861) (xy 352.826962 -393.571451)
			(xy 352.849477 -393.52727) (xy 352.878626 -393.487156) (xy 352.913692 -393.452095) (xy 352.953811 -393.422952)
			(xy 352.997996 -393.400443) (xy 353.045157 -393.385124) (xy 353.094134 -393.377371) (xy 353.118928 -393.376912)
			(xy 353.144324 -393.377371) (xy 353.194461 -393.385506) (xy 353.242648 -393.401563) (xy 353.287643 -393.425127)
			(xy 353.328286 -393.455591) (xy 353.363528 -393.492168) (xy 353.39246 -393.533915) (xy 353.414335 -393.579755)
			(xy 353.42195 -393.603988) (xy 353.423474 -393.60983) (xy 353.47149 -393.692888) (xy 354.003356 -393.692888)
			(xy 354.003356 -393.69238) (xy 354.003775 -393.667587) (xy 354.011535 -393.618611) (xy 354.026861 -393.571452)
			(xy 354.049376 -393.527272) (xy 354.078525 -393.487157) (xy 354.113591 -393.452097) (xy 354.153709 -393.422953)
			(xy 354.197893 -393.400444) (xy 354.245054 -393.385125) (xy 354.294031 -393.377371) (xy 354.318824 -393.376912)
			(xy 354.34422 -393.377374) (xy 354.394356 -393.385509) (xy 354.442544 -393.401566) (xy 354.487539 -393.425129)
			(xy 354.528182 -393.455592) (xy 354.563424 -393.492169) (xy 354.592356 -393.533915) (xy 354.614231 -393.579755)
			(xy 354.621846 -393.603988) (xy 354.62337 -393.60983) (xy 354.943664 -394.16355) (xy 354.947728 -394.167868)
			(xy 354.963931 -394.185543) (xy 354.99133 -394.224892) (xy 355.012461 -394.267932) (xy 355.026838 -394.313674)
			(xy 355.03413 -394.361064) (xy 355.034596 -394.385038) (xy 355.034596 -394.385546) (xy 355.033834 -394.405612)
			(xy 355.033668 -394.41566) (xy 355.040195 -394.434647) (xy 355.046534 -394.442442) (xy 355.101144 -394.504164)
			(xy 355.119178 -394.513054) (xy 355.129338 -394.513562) (xy 355.154718 -394.51551) (xy 355.204425 -394.526466)
			(xy 355.251754 -394.545195) (xy 355.295497 -394.571222) (xy 355.334538 -394.603881) (xy 355.351588 -394.622782)
			(xy 355.354046 -394.625558) (xy 355.359662 -394.630402) (xy 355.362764 -394.632434) (xy 355.37484 -394.640475)
			(xy 355.394795 -394.661525) (xy 355.408865 -394.686888) (xy 355.416162 -394.71496) (xy 355.416612 -394.729462)
			(xy 355.416612 -394.7414) (xy 355.418136 -394.748004) (xy 355.423328 -394.768376) (xy 355.428938 -394.810042)
			(xy 355.429312 -394.831062) (xy 355.42893 -394.852082) (xy 355.42333 -394.893748) (xy 355.418136 -394.91412)
			(xy 355.416612 -394.920724) (xy 355.416612 -395.034262) (xy 355.416133 -395.04926) (xy 355.408387 -395.078237)
			(xy 355.393411 -395.104226) (xy 355.372225 -395.125458) (xy 355.346269 -395.140491) (xy 355.317308 -395.1483)
			(xy 355.302312 -395.148816) (xy 355.120194 -395.148816) (xy 355.119686 -395.14907) (xy 355.102922 -395.14907)
			(xy 355.102414 -395.148816) (xy 354.920804 -395.148816) (xy 354.905776 -395.148317) (xy 354.87674 -395.140549)
			(xy 354.850699 -395.125542) (xy 354.829421 -395.104313) (xy 354.814353 -395.078307) (xy 354.806518 -395.049289)
			(xy 354.805996 -395.034262) (xy 354.805996 -394.920724) (xy 354.804472 -394.91412) (xy 354.799266 -394.893751)
			(xy 354.793665 -394.852083) (xy 354.793296 -394.831062) (xy 354.794058 -394.80871) (xy 354.79482 -394.79855)
			(xy 354.78847 -394.7795) (xy 354.727256 -394.70965) (xy 354.709222 -394.70076) (xy 354.699062 -394.700252)
			(xy 354.674977 -394.698277) (xy 354.627772 -394.687949) (xy 354.582694 -394.670543) (xy 354.540798 -394.646465)
			(xy 354.503065 -394.616279) (xy 354.470376 -394.580692) (xy 354.443497 -394.540536) (xy 354.423057 -394.49675)
			(xy 354.415852 -394.473684) (xy 354.414328 -394.467842) (xy 354.094034 -393.914122) (xy 354.08997 -393.909804)
			(xy 354.073821 -393.892129) (xy 354.0465 -393.852814) (xy 354.02543 -393.809824) (xy 354.011094 -393.764145)
			(xy 354.003821 -393.716825) (xy 354.003356 -393.692888) (xy 353.47149 -393.692888) (xy 353.744022 -394.164312)
			(xy 353.748086 -394.16863) (xy 353.764139 -394.186297) (xy 353.791308 -394.225543) (xy 353.812256 -394.268434)
			(xy 353.826507 -394.313989) (xy 353.833734 -394.361172) (xy 353.834192 -394.385038) (xy 353.834192 -394.385546)
			(xy 353.833684 -394.405866) (xy 353.832922 -394.415772) (xy 353.839272 -394.434822) (xy 353.899978 -394.504164)
			(xy 353.917758 -394.513054) (xy 353.927918 -394.513816) (xy 353.952898 -394.515983) (xy 354.001756 -394.527244)
			(xy 354.048243 -394.54603) (xy 354.091207 -394.571878) (xy 354.129583 -394.604145) (xy 354.146358 -394.622782)
			(xy 354.14882 -394.625555) (xy 354.154433 -394.630401) (xy 354.157534 -394.632434) (xy 354.169575 -394.640496)
			(xy 354.189464 -394.661562) (xy 354.203468 -394.686924) (xy 354.210704 -394.714977) (xy 354.211128 -394.729462)
			(xy 354.211128 -394.7414) (xy 354.212906 -394.748004) (xy 354.218097 -394.768377) (xy 354.223708 -394.810042)
			(xy 354.224082 -394.831062) (xy 354.223701 -394.852082) (xy 354.2181 -394.893749) (xy 354.212906 -394.91412)
			(xy 354.211128 -394.920724) (xy 354.211128 -395.034262) (xy 354.210674 -395.049285) (xy 354.202905 -395.078309)
			(xy 354.187886 -395.104332) (xy 354.166641 -395.125578) (xy 354.14062 -395.1406) (xy 354.111597 -395.148373)
			(xy 354.096574 -395.148816) (xy 353.914964 -395.148816) (xy 353.914456 -395.14907) (xy 353.897692 -395.14907)
			(xy 353.897184 -395.148816) (xy 353.715574 -395.148816) (xy 353.700547 -395.14843) (xy 353.671519 -395.140644)
			(xy 353.645496 -395.125611) (xy 353.62425 -395.104353) (xy 353.609231 -395.078321) (xy 353.601462 -395.049289)
			(xy 353.60102 -395.034262) (xy 353.60102 -394.920724) (xy 353.599242 -394.91412) (xy 353.594035 -394.893751)
			(xy 353.588435 -394.852083) (xy 353.588066 -394.831062) (xy 353.588828 -394.808456) (xy 353.58959 -394.79855)
			(xy 353.58324 -394.779246) (xy 353.523042 -394.709904) (xy 353.505008 -394.70076) (xy 353.495102 -394.699998)
			(xy 353.47123 -394.697744) (xy 353.424503 -394.686993) (xy 353.379942 -394.669293) (xy 353.338573 -394.645054)
			(xy 353.301349 -394.614832) (xy 353.269128 -394.579325) (xy 353.242651 -394.539351) (xy 353.222529 -394.49583)
			(xy 353.215448 -394.472922) (xy 353.213924 -394.46708) (xy 352.894138 -393.914122) (xy 352.890074 -393.909804)
			(xy 352.873925 -393.892128) (xy 352.846605 -393.852814) (xy 352.825534 -393.809824) (xy 352.811198 -393.764145)
			(xy 352.803925 -393.716825) (xy 352.80346 -393.692888) (xy 352.271368 -393.692888) (xy 352.543618 -394.16355)
			(xy 352.547682 -394.167868) (xy 352.563843 -394.185567) (xy 352.591184 -394.224928) (xy 352.612263 -394.267969)
			(xy 352.626593 -394.313702) (xy 352.633846 -394.361075) (xy 352.634296 -394.385038) (xy 352.634296 -394.385546)
			(xy 352.633788 -394.405866) (xy 352.633026 -394.415772) (xy 352.639376 -394.434822) (xy 352.700082 -394.504164)
			(xy 352.717862 -394.513054) (xy 352.728022 -394.513816) (xy 352.753002 -394.515981) (xy 352.801861 -394.527242)
			(xy 352.848348 -394.546029) (xy 352.891311 -394.571877) (xy 352.929687 -394.604145) (xy 352.946462 -394.622782)
			(xy 352.948923 -394.625556) (xy 352.954536 -394.630401) (xy 352.957638 -394.632434) (xy 352.96968 -394.640495)
			(xy 352.989568 -394.661562) (xy 353.003572 -394.686923) (xy 353.010808 -394.714977) (xy 353.011232 -394.729462)
			(xy 353.011232 -394.7414) (xy 353.01301 -394.748004) (xy 353.018201 -394.768377) (xy 353.023812 -394.810042)
			(xy 353.024186 -394.831062) (xy 353.023805 -394.852082) (xy 353.018204 -394.893749) (xy 353.01301 -394.91412)
			(xy 353.011232 -394.920724) (xy 353.011232 -395.034262) (xy 353.010775 -395.049285) (xy 353.003005 -395.078308)
			(xy 352.987987 -395.10433) (xy 352.966743 -395.125577) (xy 352.940723 -395.140599) (xy 352.911701 -395.148372)
			(xy 352.896678 -395.148816) (xy 352.715068 -395.148816) (xy 352.71456 -395.14907) (xy 352.697796 -395.14907)
			(xy 352.697288 -395.148816) (xy 352.515678 -395.148816) (xy 352.500651 -395.148427) (xy 352.471623 -395.140642)
			(xy 352.4456 -395.125609) (xy 352.424354 -395.104352) (xy 352.409335 -395.078321) (xy 352.401566 -395.049289)
			(xy 352.401124 -395.034262) (xy 352.401124 -394.920724) (xy 352.399346 -394.91412) (xy 352.394139 -394.893751)
			(xy 352.388539 -394.852083) (xy 352.38817 -394.831062) (xy 352.388932 -394.808456) (xy 352.389694 -394.79855)
			(xy 352.383344 -394.779246) (xy 352.323146 -394.709904) (xy 352.305112 -394.70076) (xy 352.295206 -394.699998)
			(xy 352.27138 -394.697798) (xy 352.22475 -394.687071) (xy 352.180275 -394.669425) (xy 352.138974 -394.645266)
			(xy 352.101795 -394.615148) (xy 352.06959 -394.57976) (xy 352.043098 -394.539916) (xy 352.022926 -394.496528)
			(xy 352.015806 -394.473684) (xy 352.014282 -394.467842) (xy 351.693988 -393.914122) (xy 351.689924 -393.909804)
			(xy 351.6737 -393.892113) (xy 351.646278 -393.852718) (xy 351.625138 -393.809624) (xy 351.610769 -393.763826)
			(xy 351.603503 -393.71638) (xy 351.603056 -393.69238) (xy 351.07115 -393.69238) (xy 351.343976 -394.164312)
			(xy 351.34804 -394.16863) (xy 351.364137 -394.186271) (xy 351.391362 -394.225506) (xy 351.412362 -394.268396)
			(xy 351.426659 -394.313962) (xy 351.433926 -394.361161) (xy 351.4344 -394.385038) (xy 351.4344 -394.385546)
			(xy 351.433638 -394.405866) (xy 351.432876 -394.415772) (xy 351.439226 -394.434822) (xy 351.499932 -394.504164)
			(xy 351.517712 -394.513054) (xy 351.527872 -394.513816) (xy 351.552849 -394.516011) (xy 351.601707 -394.527265)
			(xy 351.648194 -394.546044) (xy 351.691158 -394.571886) (xy 351.729536 -394.604148) (xy 351.746312 -394.622782)
			(xy 351.74878 -394.62555) (xy 351.754388 -394.630399) (xy 351.757488 -394.632434) (xy 351.769569 -394.640468)
			(xy 351.789522 -394.661521) (xy 351.803591 -394.686886) (xy 351.810886 -394.71496) (xy 351.811336 -394.729462)
			(xy 351.811336 -394.7414) (xy 351.81286 -394.748004) (xy 351.818052 -394.768376) (xy 351.823662 -394.810042)
			(xy 351.824036 -394.831062) (xy 351.823653 -394.852082) (xy 351.818054 -394.893748) (xy 351.81286 -394.91412)
			(xy 351.811336 -394.920724) (xy 351.811336 -395.034262) (xy 351.810833 -395.049258) (xy 351.803089 -395.078231)
			(xy 351.788117 -395.104218) (xy 351.766936 -395.12545) (xy 351.740986 -395.140484) (xy 351.71203 -395.148297)
			(xy 351.697036 -395.148816) (xy 351.514918 -395.148816) (xy 351.51441 -395.14907) (xy 351.497646 -395.14907)
			(xy 351.497138 -395.148816) (xy 351.315528 -395.148816) (xy 351.300501 -395.148295) (xy 351.271466 -395.140534)
			(xy 351.245425 -395.125531) (xy 351.224147 -395.104306) (xy 351.209078 -395.078303) (xy 351.201243 -395.049288)
			(xy 351.20072 -395.034262) (xy 351.20072 -394.920724) (xy 351.199196 -394.91412) (xy 351.19399 -394.893751)
			(xy 351.188389 -394.852083) (xy 351.18802 -394.831062) (xy 351.188782 -394.808456) (xy 351.189544 -394.79855)
			(xy 351.183194 -394.779246) (xy 351.122996 -394.709904) (xy 351.104962 -394.70076) (xy 351.095056 -394.699998)
			(xy 351.07118 -394.697782) (xy 351.024452 -394.687023) (xy 350.979891 -394.669317) (xy 350.938522 -394.645072)
			(xy 350.901299 -394.614846) (xy 350.869079 -394.579334) (xy 350.842603 -394.539356) (xy 350.822483 -394.495832)
			(xy 350.815402 -394.472922) (xy 350.813878 -394.46708) (xy 350.494092 -393.914122) (xy 350.490028 -393.909804)
			(xy 350.473805 -393.892113) (xy 350.446382 -393.852718) (xy 350.425242 -393.809624) (xy 350.410873 -393.763826)
			(xy 350.403607 -393.71638) (xy 350.40316 -393.69238) (xy 349.871028 -393.69238) (xy 350.143572 -394.16355)
			(xy 350.147636 -394.167868) (xy 350.163841 -394.185542) (xy 350.191239 -394.224891) (xy 350.212369 -394.267932)
			(xy 350.226746 -394.313674) (xy 350.234038 -394.361064) (xy 350.234504 -394.385038) (xy 350.234504 -394.385546)
			(xy 350.233742 -394.405866) (xy 350.23298 -394.415772) (xy 350.23933 -394.434822) (xy 350.300036 -394.504164)
			(xy 350.317816 -394.513054) (xy 350.327976 -394.513816) (xy 350.352953 -394.516009) (xy 350.401811 -394.527263)
			(xy 350.448298 -394.546043) (xy 350.491263 -394.571885) (xy 350.52964 -394.604148) (xy 350.546416 -394.622782)
			(xy 350.548883 -394.62555) (xy 350.554492 -394.630399) (xy 350.557592 -394.632434) (xy 350.569674 -394.640467)
			(xy 350.589626 -394.66152) (xy 350.603695 -394.686886) (xy 350.61099 -394.71496) (xy 350.61144 -394.729462)
			(xy 350.61144 -394.7414) (xy 350.612964 -394.748004) (xy 350.618156 -394.768376) (xy 350.623766 -394.810042)
			(xy 350.62414 -394.831062) (xy 350.623757 -394.852082) (xy 350.618158 -394.893748) (xy 350.612964 -394.91412)
			(xy 350.61144 -394.920724) (xy 350.61144 -395.034262) (xy 350.610933 -395.049257) (xy 350.60319 -395.07823)
			(xy 350.588218 -395.104216) (xy 350.567038 -395.125448) (xy 350.541088 -395.140483) (xy 350.512134 -395.148297)
			(xy 350.49714 -395.148816) (xy 350.315022 -395.148816) (xy 350.314514 -395.14907) (xy 350.29775 -395.14907)
			(xy 350.297242 -395.148816) (xy 350.115632 -395.148816) (xy 350.100605 -395.148292) (xy 350.071571 -395.140531)
			(xy 350.045529 -395.125529) (xy 350.024251 -395.104305) (xy 350.009182 -395.078302) (xy 350.001347 -395.049288)
			(xy 350.000824 -395.034262) (xy 350.000824 -394.920724) (xy 349.9993 -394.91412) (xy 349.994094 -394.893751)
			(xy 349.988493 -394.852083) (xy 349.988124 -394.831062) (xy 349.988886 -394.808456) (xy 349.989648 -394.79855)
			(xy 349.983298 -394.779246) (xy 349.9231 -394.709904) (xy 349.905066 -394.70076) (xy 349.89516 -394.699998)
			(xy 349.871338 -394.697755) (xy 349.82471 -394.687035) (xy 349.780235 -394.669397) (xy 349.738934 -394.645245)
			(xy 349.701754 -394.615132) (xy 349.669548 -394.57975) (xy 349.643054 -394.53991) (xy 349.622881 -394.496526)
			(xy 349.61576 -394.473684) (xy 349.614236 -394.467842) (xy 349.293942 -393.914122) (xy 349.289878 -393.909804)
			(xy 349.27373 -393.892128) (xy 349.246409 -393.852813) (xy 349.225339 -393.809824) (xy 349.211002 -393.764145)
			(xy 349.203729 -393.716825) (xy 349.203264 -393.692888) (xy 348.671426 -393.692888) (xy 348.943676 -394.16355)
			(xy 348.94774 -394.167868) (xy 348.963945 -394.185541) (xy 348.991343 -394.224891) (xy 349.012473 -394.267932)
			(xy 349.02685 -394.313674) (xy 349.034142 -394.361064) (xy 349.034608 -394.385038) (xy 349.034608 -394.385546)
			(xy 349.033846 -394.405866) (xy 349.033084 -394.415772) (xy 349.039434 -394.434822) (xy 349.10014 -394.504164)
			(xy 349.11792 -394.513054) (xy 349.12808 -394.513816) (xy 349.153028 -394.516046) (xy 349.201828 -394.527323)
			(xy 349.248258 -394.546108) (xy 349.291171 -394.571935) (xy 349.329506 -394.604168) (xy 349.346266 -394.622782)
			(xy 349.348727 -394.625556) (xy 349.35434 -394.630402) (xy 349.357442 -394.632434) (xy 349.369485 -394.640494)
			(xy 349.389373 -394.661561) (xy 349.403377 -394.686923) (xy 349.410612 -394.714976) (xy 349.411036 -394.729462)
			(xy 349.411036 -394.7414) (xy 349.412814 -394.748004) (xy 349.418005 -394.768377) (xy 349.423616 -394.810042)
			(xy 349.42399 -394.831062) (xy 349.423609 -394.852082) (xy 349.418008 -394.893748) (xy 349.412814 -394.91412)
			(xy 349.411036 -394.920724) (xy 349.411036 -395.034262) (xy 349.410393 -395.052383) (xy 349.399128 -395.086828)
			(xy 349.388938 -395.101826) (xy 349.384452 -395.108489) (xy 349.379529 -395.123769) (xy 349.379286 -395.131798)
			(xy 349.379286 -395.165326) (xy 349.379599 -395.173344) (xy 349.384507 -395.188609) (xy 349.388938 -395.195298)
			(xy 349.399033 -395.210343) (xy 349.410283 -395.24476) (xy 349.411036 -395.262862) (xy 349.411036 -395.3764)
			(xy 349.412814 -395.383004) (xy 349.418005 -395.403377) (xy 349.423616 -395.445042) (xy 349.42399 -395.466062)
			(xy 349.423609 -395.487082) (xy 349.418008 -395.528748) (xy 349.412814 -395.54912) (xy 349.411036 -395.555724)
			(xy 349.411036 -395.567662) (xy 349.410545 -395.583032) (xy 349.402416 -395.612678) (xy 349.386729 -395.639114)
			(xy 349.364603 -395.660453) (xy 349.351346 -395.668246) (xy 349.347536 -395.672818) (xy 349.340228 -395.682286)
			(xy 349.334542 -395.705487) (xy 349.336614 -395.717268) (xy 349.343726 -395.749018) (xy 349.347031 -395.760519)
			(xy 349.362252 -395.778938) (xy 349.372936 -395.784324) (xy 349.394359 -395.79407) (xy 349.434312 -395.818943)
			(xy 349.470163 -395.849433) (xy 349.485966 -395.866874) (xy 349.488428 -395.869647) (xy 349.494041 -395.874493)
			(xy 349.497142 -395.876526) (xy 349.509286 -395.884608) (xy 349.529376 -395.905746) (xy 349.543523 -395.931247)
			(xy 349.550822 -395.959481) (xy 349.551244 -395.974062) (xy 349.551244 -395.986508) (xy 349.553022 -395.992858)
			(xy 349.558155 -396.013172) (xy 349.56363 -396.054712) (xy 349.563944 -396.075662) (xy 349.56361 -396.096611)
			(xy 349.558134 -396.138148) (xy 349.553022 -396.158466) (xy 349.551244 -396.164816) (xy 349.551244 -396.621508)
			(xy 349.553022 -396.627858) (xy 349.558155 -396.648172) (xy 349.56363 -396.689712) (xy 349.563944 -396.710662)
			(xy 350.128078 -396.710662) (xy 350.128445 -396.689641) (xy 350.134055 -396.647975) (xy 350.139254 -396.627604)
			(xy 350.141032 -396.621) (xy 350.141032 -396.507462) (xy 350.141502 -396.492445) (xy 350.149284 -396.463435)
			(xy 350.164306 -396.437427) (xy 350.185546 -396.416191) (xy 350.211557 -396.401174) (xy 350.240569 -396.393399)
			(xy 350.255586 -396.392908) (xy 350.437196 -396.392908) (xy 350.437704 -396.392654) (xy 350.454468 -396.392654)
			(xy 350.454976 -396.392908) (xy 350.636586 -396.392908) (xy 350.651599 -396.393448) (xy 350.680603 -396.401215)
			(xy 350.706609 -396.416223) (xy 350.727845 -396.437449) (xy 350.742865 -396.463449) (xy 350.750645 -396.492449)
			(xy 350.75114 -396.507462) (xy 350.75114 -396.621) (xy 350.752918 -396.627604) (xy 350.758109 -396.647977)
			(xy 350.76372 -396.689642) (xy 350.764094 -396.710662) (xy 351.327974 -396.710662) (xy 351.328341 -396.689641)
			(xy 351.333951 -396.647975) (xy 351.33915 -396.627604) (xy 351.340928 -396.621) (xy 351.340928 -396.507462)
			(xy 351.341402 -396.492445) (xy 351.349183 -396.463436) (xy 351.364205 -396.437428) (xy 351.385444 -396.416192)
			(xy 351.411455 -396.401175) (xy 351.440465 -396.3934) (xy 351.455482 -396.392908) (xy 351.637092 -396.392908)
			(xy 351.6376 -396.392654) (xy 351.654364 -396.392654) (xy 351.654872 -396.392908) (xy 351.836482 -396.392908)
			(xy 351.851495 -396.393452) (xy 351.880499 -396.401217) (xy 351.906505 -396.416224) (xy 351.927741 -396.437451)
			(xy 351.942761 -396.463449) (xy 351.950541 -396.492449) (xy 351.951036 -396.507462) (xy 351.951036 -396.621)
			(xy 351.952814 -396.627604) (xy 351.958005 -396.647977) (xy 351.963616 -396.689642) (xy 351.96399 -396.710662)
			(xy 352.528124 -396.710662) (xy 352.52849 -396.689641) (xy 352.534101 -396.647975) (xy 352.5393 -396.627604)
			(xy 352.540824 -396.621) (xy 352.540824 -396.507462) (xy 352.541299 -396.492466) (xy 352.549058 -396.463496)
			(xy 352.564039 -396.437514) (xy 352.585224 -396.416284) (xy 352.611175 -396.40125) (xy 352.640129 -396.393431)
			(xy 352.655124 -396.392908) (xy 352.837242 -396.392908) (xy 352.83775 -396.392654) (xy 352.854514 -396.392654)
			(xy 352.855022 -396.392908) (xy 353.036632 -396.392908) (xy 353.051664 -396.393352) (xy 353.080704 -396.40113)
			(xy 353.106748 -396.416149) (xy 353.128025 -396.437388) (xy 353.143091 -396.463405) (xy 353.150921 -396.492431)
			(xy 353.15144 -396.507462) (xy 353.15144 -396.621) (xy 353.152964 -396.627604) (xy 353.158156 -396.647976)
			(xy 353.163766 -396.689642) (xy 353.16414 -396.710662) (xy 353.72802 -396.710662) (xy 353.728386 -396.689641)
			(xy 353.733997 -396.647975) (xy 353.739196 -396.627604) (xy 353.74072 -396.621) (xy 353.74072 -396.507462)
			(xy 353.741199 -396.492467) (xy 353.748958 -396.463497) (xy 353.763938 -396.437515) (xy 353.785122 -396.416286)
			(xy 353.811072 -396.401251) (xy 353.840026 -396.393431) (xy 353.85502 -396.392908) (xy 354.037138 -396.392908)
			(xy 354.037646 -396.392654) (xy 354.05441 -396.392654) (xy 354.054918 -396.392908) (xy 354.236528 -396.392908)
			(xy 354.25156 -396.393356) (xy 354.2806 -396.401133) (xy 354.306644 -396.416151) (xy 354.327921 -396.437389)
			(xy 354.342987 -396.463405) (xy 354.350817 -396.492431) (xy 354.351336 -396.507462) (xy 354.351336 -396.621)
			(xy 354.35286 -396.627604) (xy 354.358052 -396.647976) (xy 354.363662 -396.689642) (xy 354.364036 -396.710662)
			(xy 354.364036 -396.71117) (xy 354.363867 -396.725795) (xy 354.361199 -396.754924) (xy 354.358702 -396.769336)
			(xy 354.357339 -396.77851) (xy 354.360611 -396.796752) (xy 354.365052 -396.804896) (xy 354.381562 -396.83182)
			(xy 354.386725 -396.839603) (xy 354.401456 -396.851063) (xy 354.410264 -396.854172) (xy 354.435137 -396.86226)
			(xy 354.482017 -396.885443) (xy 354.524431 -396.916041) (xy 354.561216 -396.953217) (xy 354.591365 -396.995952)
			(xy 354.614051 -397.043074) (xy 354.621846 -397.06804) (xy 354.62337 -397.073882) (xy 354.943664 -397.627602)
			(xy 354.947728 -397.63192) (xy 354.963924 -397.649634) (xy 354.991349 -397.689024) (xy 355.012492 -397.732112)
			(xy 355.026868 -397.777905) (xy 355.034144 -397.825346) (xy 355.034596 -397.849344) (xy 355.034124 -397.874121)
			(xy 355.02637 -397.923064) (xy 355.01106 -397.970193) (xy 354.988571 -398.01435) (xy 354.959455 -398.054447)
			(xy 354.924429 -398.0895) (xy 354.884353 -398.118646) (xy 354.840214 -398.141169) (xy 354.793096 -398.156514)
			(xy 354.744158 -398.164305) (xy 354.719382 -398.164812) (xy 354.718874 -398.164812) (xy 354.693479 -398.164334)
			(xy 354.643344 -398.1562) (xy 354.595158 -398.140145) (xy 354.550164 -398.116583) (xy 354.509521 -398.086122)
			(xy 354.474279 -398.049548) (xy 354.445346 -398.007805) (xy 354.423468 -397.961967) (xy 354.415852 -397.937736)
			(xy 354.414328 -397.931894) (xy 354.094034 -397.378174) (xy 354.08997 -397.373856) (xy 354.073813 -397.35612)
			(xy 354.046444 -397.316719) (xy 354.025353 -397.273629) (xy 354.011025 -397.227845) (xy 354.00379 -397.180419)
			(xy 354.003356 -397.156432) (xy 354.003537 -397.142384) (xy 354.006078 -397.114402) (xy 354.008436 -397.100552)
			(xy 354.009753 -397.091272) (xy 354.006228 -397.072876) (xy 354.001578 -397.064738) (xy 353.984814 -397.037814)
			(xy 353.979613 -397.03011) (xy 353.964887 -397.018787) (xy 353.956112 -397.015716) (xy 353.934481 -397.008931)
			(xy 353.893267 -396.990044) (xy 353.855149 -396.965504) (xy 353.820894 -396.935807) (xy 353.805744 -396.918942)
			(xy 353.803279 -396.916172) (xy 353.797668 -396.911324) (xy 353.794568 -396.90929) (xy 353.78251 -396.901224)
			(xy 353.762552 -396.880184) (xy 353.748476 -396.854828) (xy 353.741174 -396.826761) (xy 353.74072 -396.812262)
			(xy 353.74072 -396.800324) (xy 353.739196 -396.79372) (xy 353.73399 -396.773351) (xy 353.728389 -396.731683)
			(xy 353.72802 -396.710662) (xy 353.16414 -396.710662) (xy 353.16414 -396.71117) (xy 353.16397 -396.725795)
			(xy 353.161303 -396.754924) (xy 353.158806 -396.769336) (xy 353.157442 -396.77851) (xy 353.160715 -396.796752)
			(xy 353.165156 -396.804896) (xy 353.181666 -396.83182) (xy 353.186828 -396.839604) (xy 353.201559 -396.851063)
			(xy 353.210368 -396.854172) (xy 353.2353 -396.862283) (xy 353.282265 -396.885582) (xy 353.324743 -396.916309)
			(xy 353.361571 -396.953623) (xy 353.391739 -396.996499) (xy 353.414422 -397.043765) (xy 353.422204 -397.068802)
			(xy 353.423728 -397.074644) (xy 353.743514 -397.627602) (xy 353.747578 -397.63192) (xy 353.763747 -397.649578)
			(xy 353.791063 -397.688899) (xy 353.812128 -397.731893) (xy 353.82646 -397.777575) (xy 353.833729 -397.824898)
			(xy 353.834192 -397.848836) (xy 353.834192 -397.849344) (xy 353.833674 -397.874792) (xy 353.825504 -397.925027)
			(xy 353.809383 -397.973301) (xy 353.785728 -398.018365) (xy 353.755152 -398.059052) (xy 353.718446 -398.094308)
			(xy 353.697794 -398.109186) (xy 353.68929 -398.11566) (xy 353.678099 -398.13384) (xy 353.675262 -398.155)
			(xy 353.681269 -398.175486) (xy 353.695082 -398.191763) (xy 353.714319 -398.201022) (xy 353.724972 -398.201896)
			(xy 353.734624 -398.201388) (xy 353.743138 -398.200093) (xy 353.760303 -398.198695) (xy 353.768914 -398.198594)
			(xy 353.769168 -398.198848) (xy 354.06838 -398.198848) (xy 354.068634 -398.198594) (xy 354.08968 -398.199002)
			(xy 354.131 -398.206998) (xy 354.169955 -398.222928) (xy 354.205037 -398.246178) (xy 354.234888 -398.275846)
			(xy 354.258353 -398.310784) (xy 354.274523 -398.349641) (xy 354.282772 -398.390911) (xy 354.283264 -398.411954)
			(xy 354.283264 -398.615916) (xy 354.908104 -398.615916) (xy 354.908104 -398.411954) (xy 354.908673 -398.390896)
			(xy 354.916916 -398.349594) (xy 354.933094 -398.310708) (xy 354.956579 -398.275747) (xy 354.986459 -398.246067)
			(xy 355.021577 -398.222818) (xy 355.060571 -398.206902) (xy 355.101927 -398.198936) (xy 355.122988 -398.198594)
			(xy 355.123242 -398.198848) (xy 355.422454 -398.198848) (xy 355.422708 -398.198594) (xy 355.443771 -398.198955)
			(xy 355.485132 -398.206918) (xy 355.524131 -398.222831) (xy 355.559256 -398.246075) (xy 355.589147 -398.275751)
			(xy 355.612644 -398.310709) (xy 355.628837 -398.349592) (xy 355.637098 -398.390894) (xy 355.637592 -398.411954)
			(xy 355.637592 -398.666716) (xy 355.628448 -398.666716) (xy 355.618428 -398.667159) (xy 355.599909 -398.674816)
			(xy 355.585734 -398.688982) (xy 355.578065 -398.707496) (xy 355.577648 -398.717516) (xy 355.577648 -398.881092)
			(xy 355.577107 -398.891093) (xy 355.569459 -398.909576) (xy 355.555323 -398.923727) (xy 355.536849 -398.931396)
			(xy 355.526848 -398.931892) (xy 355.018848 -398.931892) (xy 355.008829 -398.931441) (xy 354.990311 -398.923785)
			(xy 354.976137 -398.909622) (xy 354.968467 -398.891111) (xy 354.968048 -398.881092) (xy 354.968048 -398.666716)
			(xy 354.958904 -398.666716) (xy 354.948899 -398.666209) (xy 354.93041 -398.658554) (xy 354.916257 -398.644407)
			(xy 354.908595 -398.625921) (xy 354.908104 -398.615916) (xy 354.283264 -398.615916) (xy 354.283264 -398.666716)
			(xy 354.27412 -398.666716) (xy 354.264098 -398.667137) (xy 354.245579 -398.674803) (xy 354.231405 -398.688975)
			(xy 354.223737 -398.707494) (xy 354.22332 -398.717516) (xy 354.22332 -398.881092) (xy 354.222806 -398.891097)
			(xy 354.215153 -398.909584) (xy 354.201008 -398.923737) (xy 354.182524 -398.9314) (xy 354.17252 -398.931892)
			(xy 353.665028 -398.931892) (xy 353.655008 -398.931457) (xy 353.63649 -398.923795) (xy 353.622316 -398.909627)
			(xy 353.614647 -398.891112) (xy 353.614228 -398.881092) (xy 353.614228 -398.717516) (xy 353.6137 -398.707513)
			(xy 353.606051 -398.689027) (xy 353.59191 -398.674874) (xy 353.573431 -398.667209) (xy 353.563428 -398.666716)
			(xy 353.554284 -398.666716) (xy 353.554284 -398.411446) (xy 353.555072 -398.385724) (xy 353.567403 -398.335778)
			(xy 353.578668 -398.31264) (xy 353.58451 -398.30121) (xy 353.584256 -398.27581) (xy 353.530662 -398.178782)
			(xy 353.509072 -398.165066) (xy 353.496118 -398.16405) (xy 353.472221 -398.161937) (xy 353.425434 -398.151335)
			(xy 353.380793 -398.133767) (xy 353.339328 -398.109639) (xy 353.301999 -398.079507) (xy 353.269665 -398.044067)
			(xy 353.243073 -398.004138) (xy 353.222838 -397.960641) (xy 353.215702 -397.937736) (xy 353.214178 -397.931894)
			(xy 352.89363 -397.377412) (xy 352.889566 -397.373094) (xy 352.873469 -397.355431) (xy 352.84628 -397.316133)
			(xy 352.825327 -397.273185) (xy 352.811091 -397.227568) (xy 352.803895 -397.180326) (xy 352.80346 -397.156432)
			(xy 352.803641 -397.142384) (xy 352.806182 -397.114402) (xy 352.80854 -397.100552) (xy 352.809871 -397.091273)
			(xy 352.806339 -397.072874) (xy 352.801682 -397.064738) (xy 352.784918 -397.037814) (xy 352.779715 -397.030111)
			(xy 352.76499 -397.018787) (xy 352.756216 -397.015716) (xy 352.734585 -397.008929) (xy 352.693372 -396.990043)
			(xy 352.655253 -396.965504) (xy 352.620999 -396.935807) (xy 352.605848 -396.918942) (xy 352.603383 -396.916172)
			(xy 352.597772 -396.911324) (xy 352.594672 -396.90929) (xy 352.582615 -396.901223) (xy 352.562656 -396.880183)
			(xy 352.54858 -396.854827) (xy 352.541278 -396.826761) (xy 352.540824 -396.812262) (xy 352.540824 -396.800324)
			(xy 352.5393 -396.79372) (xy 352.534094 -396.773351) (xy 352.528493 -396.731683) (xy 352.528124 -396.710662)
			(xy 351.96399 -396.710662) (xy 351.96399 -396.71117) (xy 351.96382 -396.725795) (xy 351.961153 -396.754924)
			(xy 351.958656 -396.769336) (xy 351.957285 -396.77851) (xy 351.960561 -396.796753) (xy 351.965006 -396.804896)
			(xy 351.981516 -396.83182) (xy 351.986696 -396.83959) (xy 352.001415 -396.851057) (xy 352.010218 -396.854172)
			(xy 352.035102 -396.862229) (xy 352.081981 -396.88542) (xy 352.124392 -396.916026) (xy 352.161175 -396.953207)
			(xy 352.191322 -396.995946) (xy 352.214006 -397.043072) (xy 352.2218 -397.06804) (xy 352.223324 -397.073882)
			(xy 352.543618 -397.627602) (xy 352.547682 -397.63192) (xy 352.563851 -397.649577) (xy 352.591167 -397.688898)
			(xy 352.612232 -397.731893) (xy 352.626564 -397.777575) (xy 352.633833 -397.824898) (xy 352.634296 -397.848836)
			(xy 352.634296 -397.849344) (xy 352.633776 -397.874791) (xy 352.625607 -397.925027) (xy 352.609486 -397.973301)
			(xy 352.585831 -398.018365) (xy 352.555255 -398.059052) (xy 352.51855 -398.094308) (xy 352.497898 -398.109186)
			(xy 352.489392 -398.115658) (xy 352.478199 -398.133839) (xy 352.475362 -398.155) (xy 352.481369 -398.175487)
			(xy 352.495184 -398.191765) (xy 352.514422 -398.201023) (xy 352.525076 -398.201896) (xy 352.534728 -398.201388)
			(xy 352.543242 -398.200093) (xy 352.560407 -398.198695) (xy 352.569018 -398.198594) (xy 352.569272 -398.198848)
			(xy 352.868484 -398.198848) (xy 352.868738 -398.198594) (xy 352.889784 -398.198999) (xy 352.931105 -398.206995)
			(xy 352.97006 -398.222926) (xy 353.005142 -398.246176) (xy 353.034993 -398.275844) (xy 353.058457 -398.310783)
			(xy 353.074627 -398.34964) (xy 353.082876 -398.390911) (xy 353.083368 -398.411954) (xy 353.083368 -398.666716)
			(xy 353.074224 -398.666716) (xy 353.064202 -398.66714) (xy 353.045683 -398.674805) (xy 353.031509 -398.688976)
			(xy 353.023841 -398.707494) (xy 353.023424 -398.717516) (xy 353.023424 -398.881092) (xy 353.022906 -398.891096)
			(xy 353.015254 -398.909583) (xy 353.00111 -398.923736) (xy 352.982628 -398.9314) (xy 352.972624 -398.931892)
			(xy 352.465132 -398.931892) (xy 352.455112 -398.931454) (xy 352.436594 -398.923793) (xy 352.42242 -398.909626)
			(xy 352.414751 -398.891112) (xy 352.414332 -398.881092) (xy 352.414332 -398.717516) (xy 352.4138 -398.707513)
			(xy 352.406151 -398.689028) (xy 352.392012 -398.674876) (xy 352.373534 -398.66721) (xy 352.363532 -398.666716)
			(xy 352.354388 -398.666716) (xy 352.354388 -398.411446) (xy 352.355175 -398.385724) (xy 352.367507 -398.335778)
			(xy 352.378772 -398.31264) (xy 352.384614 -398.30121) (xy 352.38436 -398.27581) (xy 352.330766 -398.178782)
			(xy 352.309176 -398.165066) (xy 352.296222 -398.16405) (xy 352.272325 -398.161934) (xy 352.225538 -398.151332)
			(xy 352.180897 -398.133765) (xy 352.139433 -398.109637) (xy 352.102103 -398.079506) (xy 352.069769 -398.044067)
			(xy 352.043177 -398.004138) (xy 352.022942 -397.960641) (xy 352.015806 -397.937736) (xy 352.014282 -397.931894)
			(xy 351.693988 -397.378174) (xy 351.689924 -397.373856) (xy 351.673725 -397.356144) (xy 351.646299 -397.316755)
			(xy 351.625155 -397.273666) (xy 351.61078 -397.227873) (xy 351.603506 -397.18043) (xy 351.603056 -397.156432)
			(xy 351.603234 -397.142384) (xy 351.605778 -397.114402) (xy 351.608136 -397.100552) (xy 351.609421 -397.091296)
			(xy 351.606026 -397.072933) (xy 351.601532 -397.064738) (xy 351.584768 -397.037814) (xy 351.579548 -397.030125)
			(xy 351.564835 -397.018794) (xy 351.556066 -397.015716) (xy 351.534442 -397.00891) (xy 351.493227 -396.99003)
			(xy 351.455107 -396.965496) (xy 351.42085 -396.935804) (xy 351.405698 -396.918942) (xy 351.403239 -396.916166)
			(xy 351.397624 -396.911322) (xy 351.394522 -396.90929) (xy 351.382503 -396.901196) (xy 351.362609 -396.880142)
			(xy 351.348598 -396.854791) (xy 351.341355 -396.826745) (xy 351.340928 -396.812262) (xy 351.340928 -396.800324)
			(xy 351.33915 -396.79372) (xy 351.333943 -396.773351) (xy 351.328343 -396.731683) (xy 351.327974 -396.710662)
			(xy 350.764094 -396.710662) (xy 350.764094 -396.71117) (xy 350.763924 -396.725795) (xy 350.761257 -396.754924)
			(xy 350.75876 -396.769336) (xy 350.757402 -396.77851) (xy 350.760672 -396.796751) (xy 350.76511 -396.804896)
			(xy 350.78162 -396.83182) (xy 350.786798 -396.839592) (xy 350.801518 -396.851057) (xy 350.810322 -396.854172)
			(xy 350.835245 -396.862308) (xy 350.882211 -396.885601) (xy 350.924691 -396.916323) (xy 350.96152 -396.953631)
			(xy 350.991691 -396.996504) (xy 351.014375 -397.043767) (xy 351.022158 -397.068802) (xy 351.023682 -397.074644)
			(xy 351.343468 -397.627602) (xy 351.347532 -397.63192) (xy 351.363729 -397.649634) (xy 351.391153 -397.689024)
			(xy 351.412297 -397.732112) (xy 351.426672 -397.777905) (xy 351.433948 -397.825346) (xy 351.4344 -397.849344)
			(xy 351.433921 -397.874807) (xy 351.425722 -397.925069) (xy 351.409559 -397.973362) (xy 351.385852 -398.018433)
			(xy 351.355217 -398.059114) (xy 351.318447 -398.094349) (xy 351.297748 -398.109186) (xy 351.289217 -398.115635)
			(xy 351.278007 -398.133822) (xy 351.275163 -398.154996) (xy 351.281176 -398.175497) (xy 351.295007 -398.19178)
			(xy 351.314264 -398.201031) (xy 351.324926 -398.201896) (xy 351.334578 -398.201388) (xy 351.343092 -398.200099)
			(xy 351.360257 -398.198697) (xy 351.368868 -398.198594) (xy 351.369122 -398.198848) (xy 351.668334 -398.198848)
			(xy 351.668588 -398.198594) (xy 351.689651 -398.198973) (xy 351.731011 -398.206933) (xy 351.770009 -398.222842)
			(xy 351.805135 -398.246084) (xy 351.835026 -398.275757) (xy 351.858524 -398.310712) (xy 351.874717 -398.349594)
			(xy 351.882978 -398.390895) (xy 351.883472 -398.411954) (xy 351.883472 -398.666716) (xy 351.874328 -398.666716)
			(xy 351.864307 -398.667143) (xy 351.845787 -398.674807) (xy 351.831613 -398.688977) (xy 351.823945 -398.707495)
			(xy 351.823528 -398.717516) (xy 351.823528 -398.881092) (xy 351.823006 -398.891096) (xy 351.815354 -398.909582)
			(xy 351.801212 -398.923734) (xy 351.782731 -398.931399) (xy 351.772728 -398.931892) (xy 351.264728 -398.931892)
			(xy 351.254708 -398.931457) (xy 351.23619 -398.923795) (xy 351.222016 -398.909627) (xy 351.214347 -398.891112)
			(xy 351.213928 -398.881092) (xy 351.213928 -398.666716) (xy 351.204784 -398.666716) (xy 351.194777 -398.666226)
			(xy 351.176288 -398.658564) (xy 351.162136 -398.644412) (xy 351.154474 -398.625923) (xy 351.153984 -398.615916)
			(xy 351.153984 -398.411954) (xy 351.154333 -398.394721) (xy 351.159902 -398.360709) (xy 351.170873 -398.328036)
			(xy 351.178622 -398.31264) (xy 351.184464 -398.30121) (xy 351.18421 -398.27581) (xy 351.130616 -398.178782)
			(xy 351.109026 -398.165066) (xy 351.096072 -398.16405) (xy 351.072171 -398.161974) (xy 351.025383 -398.151366)
			(xy 350.980741 -398.133791) (xy 350.939277 -398.109657) (xy 350.901948 -398.07952) (xy 350.869616 -398.044076)
			(xy 350.843025 -398.004143) (xy 350.822792 -397.960642) (xy 350.815656 -397.937736) (xy 350.814132 -397.931894)
			(xy 350.493584 -397.377412) (xy 350.48952 -397.373094) (xy 350.473428 -397.355414) (xy 350.446176 -397.316139)
			(xy 350.425162 -397.273202) (xy 350.410867 -397.227585) (xy 350.403619 -397.180334) (xy 350.40316 -397.156432)
			(xy 350.403338 -397.142384) (xy 350.405882 -397.114402) (xy 350.40824 -397.100552) (xy 350.409524 -397.091296)
			(xy 350.406129 -397.072933) (xy 350.401636 -397.064738) (xy 350.384872 -397.037814) (xy 350.379686 -397.030098)
			(xy 350.364949 -397.018781) (xy 350.35617 -397.015716) (xy 350.334546 -397.008908) (xy 350.293332 -396.990029)
			(xy 350.255211 -396.965495) (xy 350.220954 -396.935804) (xy 350.205802 -396.918942) (xy 350.203342 -396.916167)
			(xy 350.197728 -396.911322) (xy 350.194626 -396.90929) (xy 350.182608 -396.901195) (xy 350.162714 -396.880141)
			(xy 350.148702 -396.85479) (xy 350.14146 -396.826745) (xy 350.141032 -396.812262) (xy 350.141032 -396.800324)
			(xy 350.139254 -396.79372) (xy 350.134048 -396.773351) (xy 350.128447 -396.731683) (xy 350.128078 -396.710662)
			(xy 349.563944 -396.710662) (xy 349.563804 -396.725415) (xy 349.561128 -396.754799) (xy 349.55861 -396.769336)
			(xy 349.557245 -396.77851) (xy 349.560519 -396.796752) (xy 349.56496 -396.804896) (xy 349.58147 -396.83182)
			(xy 349.58663 -396.839606) (xy 349.601363 -396.851064) (xy 349.610172 -396.854172) (xy 349.635047 -396.862255)
			(xy 349.681927 -396.885439) (xy 349.72434 -396.916039) (xy 349.761125 -396.953216) (xy 349.791273 -396.995951)
			(xy 349.813959 -397.043074) (xy 349.821754 -397.06804) (xy 349.823278 -397.073882) (xy 350.143572 -397.627602)
			(xy 350.147636 -397.63192) (xy 350.163834 -397.649633) (xy 350.191258 -397.689023) (xy 350.212401 -397.732112)
			(xy 350.226776 -397.777904) (xy 350.234052 -397.825346) (xy 350.234504 -397.849344) (xy 350.234023 -397.874807)
			(xy 350.225824 -397.925068) (xy 350.209662 -397.973361) (xy 350.185955 -398.018433) (xy 350.15532 -398.059114)
			(xy 350.118551 -398.094349) (xy 350.097852 -398.109186) (xy 350.089319 -398.115633) (xy 350.078108 -398.133821)
			(xy 350.075263 -398.154996) (xy 350.081277 -398.175498) (xy 350.095109 -398.191781) (xy 350.114368 -398.201032)
			(xy 350.12503 -398.201896) (xy 350.134682 -398.201388) (xy 350.143196 -398.200098) (xy 350.160361 -398.198697)
			(xy 350.168972 -398.198594) (xy 350.169226 -398.198848) (xy 350.468438 -398.198848) (xy 350.468692 -398.198594)
			(xy 350.489755 -398.19897) (xy 350.531115 -398.20693) (xy 350.570114 -398.22284) (xy 350.605239 -398.246082)
			(xy 350.63513 -398.275756) (xy 350.658628 -398.310712) (xy 350.674821 -398.349594) (xy 350.683082 -398.390895)
			(xy 350.683576 -398.411954) (xy 350.683576 -398.666716) (xy 350.674432 -398.666716) (xy 350.664411 -398.667146)
			(xy 350.645892 -398.674809) (xy 350.631718 -398.688978) (xy 350.624049 -398.707495) (xy 350.623632 -398.717516)
			(xy 350.623632 -398.881092) (xy 350.623106 -398.891095) (xy 350.615455 -398.909581) (xy 350.601314 -398.923733)
			(xy 350.582835 -398.931398) (xy 350.572832 -398.931892) (xy 350.064832 -398.931892) (xy 350.054812 -398.931454)
			(xy 350.036294 -398.923793) (xy 350.02212 -398.909626) (xy 350.014451 -398.891112) (xy 350.014032 -398.881092)
			(xy 350.014032 -398.666716) (xy 350.004888 -398.666716) (xy 349.994882 -398.666222) (xy 349.976393 -398.658561)
			(xy 349.962241 -398.644411) (xy 349.954579 -398.625922) (xy 349.954088 -398.615916) (xy 349.954088 -398.411954)
			(xy 349.954436 -398.394721) (xy 349.960006 -398.360709) (xy 349.970977 -398.328036) (xy 349.978726 -398.31264)
			(xy 349.984568 -398.30121) (xy 349.984314 -398.27581) (xy 349.93072 -398.178782) (xy 349.90913 -398.165066)
			(xy 349.896176 -398.16405) (xy 349.872275 -398.161971) (xy 349.825487 -398.151363) (xy 349.780846 -398.133789)
			(xy 349.739382 -398.109656) (xy 349.702053 -398.079519) (xy 349.66972 -398.044075) (xy 349.64313 -398.004143)
			(xy 349.622896 -397.960642) (xy 349.61576 -397.937736) (xy 349.614236 -397.931894) (xy 349.293942 -397.378174)
			(xy 349.289878 -397.373856) (xy 349.273723 -397.356118) (xy 349.246353 -397.316718) (xy 349.225261 -397.273629)
			(xy 349.210933 -397.227845) (xy 349.203698 -397.180419) (xy 349.203264 -397.156432) (xy 349.203445 -397.142384)
			(xy 349.205986 -397.114402) (xy 349.208344 -397.100552) (xy 349.209675 -397.091273) (xy 349.206143 -397.072874)
			(xy 349.201486 -397.064738) (xy 349.184722 -397.037814) (xy 349.179518 -397.030112) (xy 349.164794 -397.018788)
			(xy 349.15602 -397.015716) (xy 349.134451 -397.008945) (xy 349.093324 -396.990177) (xy 349.055269 -396.965776)
			(xy 349.021051 -396.936234) (xy 349.005906 -396.91945) (xy 349.003445 -396.916676) (xy 348.997832 -396.91183)
			(xy 348.99473 -396.909798) (xy 348.982591 -396.901709) (xy 348.962502 -396.880572) (xy 348.948355 -396.855074)
			(xy 348.941053 -396.826842) (xy 348.940628 -396.812262) (xy 348.940628 -396.799816) (xy 348.93885 -396.793466)
			(xy 348.933721 -396.773151) (xy 348.928244 -396.731612) (xy 348.927928 -396.710662) (xy 348.928265 -396.689714)
			(xy 348.933738 -396.648176) (xy 348.93885 -396.627858) (xy 348.940628 -396.621508) (xy 348.940628 -396.164816)
			(xy 348.93885 -396.158466) (xy 348.933721 -396.138151) (xy 348.928244 -396.096612) (xy 348.927928 -396.075662)
			(xy 348.928265 -396.054714) (xy 348.933738 -396.013176) (xy 348.93885 -395.992858) (xy 348.940628 -395.986508)
			(xy 348.940628 -395.974062) (xy 348.941121 -395.958599) (xy 348.949347 -395.928786) (xy 348.965175 -395.902216)
			(xy 348.987474 -395.880786) (xy 349.000826 -395.87297) (xy 349.004382 -395.868906) (xy 349.011735 -395.859383)
			(xy 349.017433 -395.836044) (xy 349.015304 -395.824202) (xy 349.008192 -395.792706) (xy 349.004913 -395.781196)
			(xy 348.989672 -395.762783) (xy 348.978982 -395.7574) (xy 348.957496 -395.747584) (xy 348.917432 -395.722564)
			(xy 348.881514 -395.691887) (xy 348.865698 -395.674342) (xy 348.863239 -395.671566) (xy 348.857624 -395.666722)
			(xy 348.854522 -395.66469) (xy 348.842503 -395.656596) (xy 348.822609 -395.635542) (xy 348.808598 -395.610191)
			(xy 348.801355 -395.582145) (xy 348.800928 -395.567662) (xy 348.800928 -395.555724) (xy 348.79915 -395.54912)
			(xy 348.793943 -395.528751) (xy 348.788343 -395.487083) (xy 348.787974 -395.466062) (xy 348.788341 -395.445041)
			(xy 348.793951 -395.403375) (xy 348.79915 -395.383004) (xy 348.800928 -395.3764) (xy 348.800928 -395.262862)
			(xy 348.801588 -395.244743) (xy 348.812842 -395.210297) (xy 348.823026 -395.195298) (xy 348.827499 -395.188627)
			(xy 348.832431 -395.173353) (xy 348.832678 -395.165326) (xy 348.832678 -395.131798) (xy 348.832361 -395.12378)
			(xy 348.827457 -395.108515) (xy 348.823026 -395.101826) (xy 348.812947 -395.086772) (xy 348.801686 -395.052362)
			(xy 348.800928 -395.034262) (xy 348.800928 -394.920724) (xy 348.79915 -394.91412) (xy 348.793943 -394.893751)
			(xy 348.788343 -394.852083) (xy 348.787974 -394.831062) (xy 348.788736 -394.808456) (xy 348.789498 -394.798296)
			(xy 348.783402 -394.7795) (xy 348.729808 -394.717524) (xy 348.722878 -394.710265) (xy 348.704968 -394.70125)
			(xy 348.69501 -394.699998) (xy 348.671199 -394.697797) (xy 348.624606 -394.687038) (xy 348.580171 -394.669371)
			(xy 348.53891 -394.645202) (xy 348.501768 -394.615084) (xy 348.469596 -394.579706) (xy 348.44313 -394.539879)
			(xy 348.422977 -394.496515) (xy 348.415864 -394.473684) (xy 348.41434 -394.467842) (xy 348.094046 -393.914122)
			(xy 348.089982 -393.909804) (xy 348.073835 -393.892127) (xy 348.046513 -393.852813) (xy 348.025443 -393.809823)
			(xy 348.011107 -393.764145) (xy 348.003833 -393.716825) (xy 348.003368 -393.692888) (xy 347.471276 -393.692888)
			(xy 347.743526 -394.16355) (xy 347.74759 -394.167868) (xy 347.763752 -394.185566) (xy 347.791093 -394.224927)
			(xy 347.812171 -394.267969) (xy 347.826501 -394.313702) (xy 347.833754 -394.361075) (xy 347.834204 -394.385038)
			(xy 347.834204 -394.385546) (xy 347.833696 -394.405866) (xy 347.832934 -394.415772) (xy 347.839284 -394.434822)
			(xy 347.89999 -394.504164) (xy 347.91777 -394.513054) (xy 347.92793 -394.513816) (xy 347.952904 -394.516037)
			(xy 348.001761 -394.527284) (xy 348.048248 -394.546057) (xy 348.091214 -394.571893) (xy 348.129593 -394.60415)
			(xy 348.14637 -394.622782) (xy 348.14883 -394.625557) (xy 348.154444 -394.630402) (xy 348.157546 -394.632434)
			(xy 348.16959 -394.640493) (xy 348.189477 -394.66156) (xy 348.203481 -394.686923) (xy 348.210716 -394.714976)
			(xy 348.21114 -394.729462) (xy 348.21114 -394.7414) (xy 348.212918 -394.748004) (xy 348.218109 -394.768377)
			(xy 348.22372 -394.810042) (xy 348.224094 -394.831062) (xy 348.223713 -394.852082) (xy 348.218112 -394.893748)
			(xy 348.212918 -394.91412) (xy 348.21114 -394.920724) (xy 348.21114 -394.979398) (xy 348.240858 -395.009116)
			(xy 348.249748 -395.009116) (xy 348.259815 -395.009565) (xy 348.278413 -395.017269) (xy 348.285816 -395.024102)
			(xy 348.514162 -395.252194) (xy 348.520987 -395.259607) (xy 348.528716 -395.278196) (xy 348.529148 -395.288262)
			(xy 348.529148 -396.89913) (xy 348.529564 -396.909074) (xy 348.537011 -396.927508) (xy 348.543626 -396.934944)
			(xy 348.561496 -396.953848) (xy 348.591452 -396.996374) (xy 348.614043 -397.043228) (xy 348.621858 -397.06804)
			(xy 348.623382 -397.073882) (xy 348.943676 -397.627602) (xy 348.94774 -397.63192) (xy 348.963938 -397.649633)
			(xy 348.991362 -397.689023) (xy 349.012505 -397.732111) (xy 349.02688 -397.777904) (xy 349.034156 -397.825346)
			(xy 349.034608 -397.849344) (xy 349.0341 -397.874073) (xy 349.026363 -397.922922) (xy 349.0111 -397.969966)
			(xy 348.988685 -398.014053) (xy 348.959668 -398.054104) (xy 348.924758 -398.089138) (xy 348.905068 -398.104106)
			(xy 348.895759 -398.111674) (xy 348.884886 -398.133021) (xy 348.88424 -398.145) (xy 348.88424 -398.149826)
			(xy 348.884599 -398.159854) (xy 348.892285 -398.178379) (xy 348.906477 -398.192552) (xy 348.925012 -398.200214)
			(xy 348.93504 -398.200626) (xy 348.938342 -398.200626) (xy 348.94139 -398.200372) (xy 348.968822 -398.198594)
			(xy 348.969076 -398.198848) (xy 349.268288 -398.198848) (xy 349.268542 -398.198594) (xy 349.289588 -398.198995)
			(xy 349.330909 -398.206992) (xy 349.369864 -398.222924) (xy 349.404946 -398.246174) (xy 349.434797 -398.275843)
			(xy 349.458261 -398.310783) (xy 349.474431 -398.34964) (xy 349.48268 -398.390911) (xy 349.483172 -398.411954)
			(xy 349.483172 -398.666716) (xy 349.474028 -398.666716) (xy 349.464007 -398.667143) (xy 349.445487 -398.674807)
			(xy 349.431313 -398.688977) (xy 349.423645 -398.707495) (xy 349.423228 -398.717516) (xy 349.423228 -398.881092)
			(xy 349.422706 -398.891096) (xy 349.415054 -398.909582) (xy 349.400912 -398.923734) (xy 349.382431 -398.931399)
			(xy 349.372428 -398.931892) (xy 348.919038 -398.931892) (xy 348.90902 -398.932351) (xy 348.890506 -398.940006)
			(xy 348.876332 -398.954167) (xy 348.86866 -398.972675) (xy 348.868238 -398.982692) (xy 348.868238 -399.227119)
			(xy 355.897944 -399.227119) (xy 355.897944 -399.175145) (xy 355.906074 -399.12381) (xy 355.922135 -399.07438)
			(xy 355.945731 -399.02807) (xy 355.976281 -398.986022) (xy 356.013032 -398.949271) (xy 356.05508 -398.918721)
			(xy 356.10139 -398.895125) (xy 356.15082 -398.879064) (xy 356.202155 -398.870934) (xy 356.254129 -398.870934)
			(xy 356.305464 -398.879064) (xy 356.354894 -398.895125) (xy 356.401204 -398.918721) (xy 356.443252 -398.949271)
			(xy 356.480003 -398.986022) (xy 356.510553 -399.02807) (xy 356.534149 -399.07438) (xy 356.55021 -399.12381)
			(xy 356.55834 -399.175145) (xy 356.55885 -399.201132) (xy 356.55834 -399.227119) (xy 356.55021 -399.278454)
			(xy 356.534149 -399.327884) (xy 356.510553 -399.374194) (xy 356.480003 -399.416242) (xy 356.443252 -399.452993)
			(xy 356.401204 -399.483543) (xy 356.354894 -399.507139) (xy 356.305464 -399.5232) (xy 356.254129 -399.53133)
			(xy 356.202155 -399.53133) (xy 356.15082 -399.5232) (xy 356.10139 -399.507139) (xy 356.05508 -399.483543)
			(xy 356.013032 -399.452993) (xy 355.976281 -399.416242) (xy 355.945731 -399.374194) (xy 355.922135 -399.327884)
			(xy 355.906074 -399.278454) (xy 355.897944 -399.227119) (xy 348.868238 -399.227119) (xy 348.868238 -401.674838)
			(xy 349.162624 -401.674838) (xy 349.162624 -400.81073) (xy 349.163057 -400.785262) (xy 349.16986 -400.734782)
			(xy 349.183321 -400.685656) (xy 349.203203 -400.63876) (xy 349.22915 -400.594927) (xy 349.2607 -400.554939)
			(xy 349.278702 -400.536918) (xy 349.285306 -400.530568) (xy 349.29318 -400.513804) (xy 349.300038 -400.42846)
			(xy 349.294958 -400.41068) (xy 349.28937 -400.403314) (xy 349.274524 -400.382563) (xy 349.250887 -400.33735)
			(xy 349.234784 -400.28894) (xy 349.22663 -400.238577) (xy 349.226124 -400.213068) (xy 349.226124 -400.212814)
			(xy 349.226614 -400.187825) (xy 349.234433 -400.138462) (xy 349.249877 -400.09093) (xy 349.272567 -400.046398)
			(xy 349.301943 -400.005965) (xy 349.337283 -399.970625) (xy 349.377716 -399.941249) (xy 349.422248 -399.918559)
			(xy 349.46978 -399.903115) (xy 349.519143 -399.895296) (xy 349.569121 -399.895296) (xy 349.618484 -399.903115)
			(xy 349.666016 -399.918559) (xy 349.710548 -399.941249) (xy 349.750981 -399.970625) (xy 349.786321 -400.005965)
			(xy 349.815697 -400.046398) (xy 349.838387 -400.09093) (xy 349.853831 -400.138462) (xy 349.86165 -400.187825)
			(xy 349.86214 -400.212814) (xy 349.86214 -400.213068) (xy 349.861639 -400.238577) (xy 349.853463 -400.288935)
			(xy 349.837363 -400.337347) (xy 349.813751 -400.382572) (xy 349.798894 -400.403314) (xy 349.793306 -400.41068)
			(xy 349.788226 -400.42846) (xy 349.795084 -400.513804) (xy 349.802958 -400.530568) (xy 349.809562 -400.536918)
			(xy 349.827563 -400.554939) (xy 349.859104 -400.594933) (xy 349.885044 -400.638767) (xy 349.904923 -400.685662)
			(xy 349.918388 -400.734785) (xy 349.925199 -400.785263) (xy 349.92564 -400.81073) (xy 349.92564 -401.674838)
			(xy 349.92563 -401.675346) (xy 350.36252 -401.675346) (xy 350.36252 -400.81073) (xy 350.362954 -400.785262)
			(xy 350.369757 -400.734782) (xy 350.383218 -400.685656) (xy 350.403099 -400.63876) (xy 350.429046 -400.594928)
			(xy 350.460596 -400.554939) (xy 350.478598 -400.536918) (xy 350.485202 -400.530568) (xy 350.493076 -400.513804)
			(xy 350.499934 -400.42846) (xy 350.494854 -400.41068) (xy 350.489266 -400.403314) (xy 350.47442 -400.382563)
			(xy 350.450782 -400.337351) (xy 350.43468 -400.28894) (xy 350.426526 -400.238577) (xy 350.42602 -400.213068)
			(xy 350.42602 -400.212814) (xy 350.42651 -400.187825) (xy 350.434329 -400.138462) (xy 350.449773 -400.09093)
			(xy 350.472463 -400.046398) (xy 350.501839 -400.005965) (xy 350.537179 -399.970625) (xy 350.577612 -399.941249)
			(xy 350.622144 -399.918559) (xy 350.669676 -399.903115) (xy 350.719039 -399.895296) (xy 350.769017 -399.895296)
			(xy 350.81838 -399.903115) (xy 350.865912 -399.918559) (xy 350.910444 -399.941249) (xy 350.950877 -399.970625)
			(xy 350.986217 -400.005965) (xy 351.015593 -400.046398) (xy 351.038283 -400.09093) (xy 351.053727 -400.138462)
			(xy 351.061546 -400.187825) (xy 351.062036 -400.212814) (xy 351.062036 -400.213068) (xy 351.061536 -400.238577)
			(xy 351.05336 -400.288936) (xy 351.037259 -400.337347) (xy 351.013647 -400.382572) (xy 350.99879 -400.403314)
			(xy 350.993202 -400.41068) (xy 350.988122 -400.42846) (xy 350.99498 -400.513804) (xy 351.002854 -400.530568)
			(xy 351.009458 -400.536918) (xy 351.027458 -400.554939) (xy 351.058999 -400.594933) (xy 351.08494 -400.638767)
			(xy 351.104819 -400.685663) (xy 351.118284 -400.734785) (xy 351.125095 -400.785263) (xy 351.125536 -400.81073)
			(xy 351.125536 -401.674838) (xy 351.562416 -401.674838) (xy 351.562416 -400.81073) (xy 351.562851 -400.785262)
			(xy 351.569654 -400.734782) (xy 351.583115 -400.685657) (xy 351.602996 -400.63876) (xy 351.628942 -400.594928)
			(xy 351.660492 -400.554939) (xy 351.678494 -400.536918) (xy 351.685098 -400.530568) (xy 351.692972 -400.513804)
			(xy 351.69983 -400.42846) (xy 351.69475 -400.41068) (xy 351.689162 -400.403314) (xy 351.674315 -400.382563)
			(xy 351.650678 -400.337351) (xy 351.634575 -400.28894) (xy 351.626422 -400.238577) (xy 351.625916 -400.213068)
			(xy 351.625916 -400.212814) (xy 351.626406 -400.187825) (xy 351.634225 -400.138462) (xy 351.649669 -400.09093)
			(xy 351.672359 -400.046398) (xy 351.701735 -400.005965) (xy 351.737075 -399.970625) (xy 351.777508 -399.941249)
			(xy 351.82204 -399.918559) (xy 351.869572 -399.903115) (xy 351.918935 -399.895296) (xy 351.968913 -399.895296)
			(xy 352.018276 -399.903115) (xy 352.065808 -399.918559) (xy 352.11034 -399.941249) (xy 352.150773 -399.970625)
			(xy 352.186113 -400.005965) (xy 352.215489 -400.046398) (xy 352.238179 -400.09093) (xy 352.253623 -400.138462)
			(xy 352.261442 -400.187825) (xy 352.261932 -400.212814) (xy 352.261932 -400.213068) (xy 352.261433 -400.238577)
			(xy 352.253256 -400.288936) (xy 352.237156 -400.337347) (xy 352.213543 -400.382572) (xy 352.198686 -400.403314)
			(xy 352.193098 -400.41068) (xy 352.188018 -400.42846) (xy 352.194876 -400.513804) (xy 352.20275 -400.530568)
			(xy 352.209354 -400.536918) (xy 352.227353 -400.55494) (xy 352.258894 -400.594934) (xy 352.284835 -400.638768)
			(xy 352.304715 -400.685663) (xy 352.31818 -400.734786) (xy 352.324991 -400.785263) (xy 352.325432 -400.81073)
			(xy 352.325432 -401.674838) (xy 352.762312 -401.674838) (xy 352.762312 -400.811238) (xy 352.762746 -400.785718)
			(xy 352.769535 -400.735133) (xy 352.783011 -400.685905) (xy 352.802933 -400.638914) (xy 352.828944 -400.595)
			(xy 352.86058 -400.554949) (xy 352.878644 -400.536918) (xy 352.885248 -400.530568) (xy 352.893122 -400.513804)
			(xy 352.89998 -400.42846) (xy 352.8949 -400.41068) (xy 352.889312 -400.403314) (xy 352.874459 -400.382568)
			(xy 352.850825 -400.337353) (xy 352.834724 -400.288941) (xy 352.826572 -400.238578) (xy 352.826066 -400.213068)
			(xy 352.826066 -400.212814) (xy 352.826556 -400.187825) (xy 352.834375 -400.138462) (xy 352.849819 -400.09093)
			(xy 352.872509 -400.046398) (xy 352.901885 -400.005965) (xy 352.937225 -399.970625) (xy 352.977658 -399.941249)
			(xy 353.02219 -399.918559) (xy 353.069722 -399.903115) (xy 353.119085 -399.895296) (xy 353.169063 -399.895296)
			(xy 353.218426 -399.903115) (xy 353.265958 -399.918559) (xy 353.31049 -399.941249) (xy 353.350923 -399.970625)
			(xy 353.386263 -400.005965) (xy 353.415639 -400.046398) (xy 353.438329 -400.09093) (xy 353.453773 -400.138462)
			(xy 353.461592 -400.187825) (xy 353.462082 -400.212814) (xy 353.462082 -400.213068) (xy 353.461573 -400.238576)
			(xy 353.453398 -400.288934) (xy 353.4373 -400.337345) (xy 353.413691 -400.382571) (xy 353.398836 -400.403314)
			(xy 353.393248 -400.41068) (xy 353.388168 -400.42846) (xy 353.395026 -400.513804) (xy 353.4029 -400.530568)
			(xy 353.409504 -400.536918) (xy 353.427529 -400.554986) (xy 353.459162 -400.595034) (xy 353.485176 -400.638941)
			(xy 353.505106 -400.685923) (xy 353.518596 -400.735143) (xy 353.525406 -400.785721) (xy 353.525836 -400.811238)
			(xy 353.525836 -401.674838) (xy 353.962208 -401.674838) (xy 353.962208 -400.811238) (xy 353.962643 -400.785718)
			(xy 353.969432 -400.735133) (xy 353.982908 -400.685905) (xy 354.002829 -400.638914) (xy 354.02884 -400.595001)
			(xy 354.060476 -400.554949) (xy 354.07854 -400.536918) (xy 354.085144 -400.530568) (xy 354.093018 -400.513804)
			(xy 354.099876 -400.42846) (xy 354.094796 -400.41068) (xy 354.089208 -400.403314) (xy 354.074355 -400.382568)
			(xy 354.050721 -400.337353) (xy 354.03462 -400.288941) (xy 354.026468 -400.238578) (xy 354.025962 -400.213068)
			(xy 354.025962 -400.212814) (xy 354.026452 -400.187825) (xy 354.034271 -400.138462) (xy 354.049715 -400.09093)
			(xy 354.072405 -400.046398) (xy 354.101781 -400.005965) (xy 354.137121 -399.970625) (xy 354.177554 -399.941249)
			(xy 354.222086 -399.918559) (xy 354.269618 -399.903115) (xy 354.318981 -399.895296) (xy 354.368959 -399.895296)
			(xy 354.418322 -399.903115) (xy 354.465854 -399.918559) (xy 354.510386 -399.941249) (xy 354.550819 -399.970625)
			(xy 354.586159 -400.005965) (xy 354.615535 -400.046398) (xy 354.638225 -400.09093) (xy 354.653669 -400.138462)
			(xy 354.661488 -400.187825) (xy 354.661978 -400.212814) (xy 354.661978 -400.213068) (xy 354.66147 -400.238576)
			(xy 354.653295 -400.288934) (xy 354.637197 -400.337345) (xy 354.613587 -400.382571) (xy 354.598732 -400.403314)
			(xy 354.593144 -400.41068) (xy 354.588064 -400.42846) (xy 354.594922 -400.513804) (xy 354.602796 -400.530568)
			(xy 354.6094 -400.536918) (xy 354.627442 -400.554968) (xy 354.659071 -400.595022) (xy 354.68508 -400.638934)
			(xy 354.705006 -400.685919) (xy 354.718493 -400.73514) (xy 354.725302 -400.78572) (xy 354.725732 -400.811238)
			(xy 354.725732 -401.167838) (xy 355.963633 -401.167838) (xy 355.971456 -401.108408) (xy 355.986969 -401.050507)
			(xy 356.009908 -400.995126) (xy 356.039879 -400.943214) (xy 356.07637 -400.895657) (xy 356.118756 -400.853271)
			(xy 356.166312 -400.81678) (xy 356.218225 -400.786809) (xy 356.273605 -400.76387) (xy 356.331506 -400.748356)
			(xy 356.390936 -400.740533) (xy 356.45088 -400.740534) (xy 356.51031 -400.748359) (xy 356.56821 -400.763875)
			(xy 356.62359 -400.786816) (xy 356.675501 -400.816789) (xy 356.723056 -400.853282) (xy 356.765441 -400.895669)
			(xy 356.80193 -400.943227) (xy 356.831899 -400.995141) (xy 356.854836 -401.050522) (xy 356.870348 -401.108424)
			(xy 356.878169 -401.167854) (xy 356.878636 -401.197826) (xy 356.878575 -401.211319) (xy 356.87705 -401.238261)
			(xy 356.875588 -401.251674) (xy 356.874352 -401.266464) (xy 356.879484 -401.295683) (xy 356.8928 -401.322193)
			(xy 356.913175 -401.343754) (xy 356.93889 -401.358548) (xy 356.967772 -401.365323) (xy 356.997382 -401.363509)
			(xy 357.011478 -401.358862) (xy 357.043214 -401.347985) (xy 357.109256 -401.336226) (xy 357.142796 -401.335494)
			(xy 357.170049 -401.335953) (xy 357.224001 -401.34371) (xy 357.276299 -401.359065) (xy 357.32588 -401.381708)
			(xy 357.371734 -401.411176) (xy 357.412928 -401.44687) (xy 357.448622 -401.488063) (xy 357.47809 -401.533916)
			(xy 357.500733 -401.583497) (xy 357.51609 -401.635795) (xy 357.523847 -401.689747) (xy 357.523847 -401.744253)
			(xy 357.51609 -401.798205) (xy 357.500733 -401.850503) (xy 357.47809 -401.900084) (xy 357.448622 -401.945937)
			(xy 357.412928 -401.98713) (xy 357.371734 -402.022824) (xy 357.32588 -402.052292) (xy 357.276299 -402.074935)
			(xy 357.224001 -402.09029) (xy 357.170049 -402.098047) (xy 357.142796 -402.09851) (xy 357.115556 -402.098027)
			(xy 357.061631 -402.090276) (xy 357.009357 -402.074934) (xy 356.959796 -402.052311) (xy 356.913958 -402.022868)
			(xy 356.872775 -401.987204) (xy 356.837083 -401.946044) (xy 356.80761 -401.900225) (xy 356.784955 -401.85068)
			(xy 356.769577 -401.798416) (xy 356.761791 -401.744495) (xy 356.761288 -401.717256) (xy 356.761288 -401.716748)
			(xy 356.761542 -401.706588) (xy 356.761542 -401.705826) (xy 356.761345 -401.691014) (xy 356.753511 -401.662464)
			(xy 356.737822 -401.637356) (xy 356.715596 -401.617798) (xy 356.688697 -401.60543) (xy 356.659381 -401.601291)
			(xy 356.630109 -401.605727) (xy 356.616508 -401.611592) (xy 356.585787 -401.625458) (xy 356.521296 -401.645042)
			(xy 356.454628 -401.654937) (xy 356.420928 -401.655534) (xy 356.390956 -401.655069) (xy 356.331526 -401.647248)
			(xy 356.273624 -401.631737) (xy 356.218243 -401.6088) (xy 356.166329 -401.578831) (xy 356.118771 -401.542342)
			(xy 356.076383 -401.499958) (xy 356.03989 -401.452403) (xy 356.009917 -401.400492) (xy 355.986976 -401.345112)
			(xy 355.971459 -401.287212) (xy 355.963634 -401.227782) (xy 355.963633 -401.167838) (xy 354.725732 -401.167838)
			(xy 354.725732 -401.476718) (xy 354.726106 -401.485827) (xy 354.732454 -401.502903) (xy 354.744349 -401.516701)
			(xy 354.752148 -401.521422) (xy 354.842572 -401.570952) (xy 354.870004 -401.569936) (xy 354.881688 -401.56257)
			(xy 354.882196 -401.56257) (xy 354.904526 -401.548855) (xy 354.952221 -401.527148) (xy 355.002506 -401.5124)
			(xy 355.05437 -401.504906) (xy 355.08057 -401.504404) (xy 355.108174 -401.504868) (xy 355.162766 -401.513092)
			(xy 355.215522 -401.529362) (xy 355.265264 -401.553313) (xy 355.31088 -401.58441) (xy 355.351352 -401.621959)
			(xy 355.385775 -401.665121) (xy 355.41338 -401.712932) (xy 355.433551 -401.764323) (xy 355.445837 -401.818147)
			(xy 355.449963 -401.8732) (xy 355.445837 -401.928253) (xy 355.433551 -401.982077) (xy 355.41338 -402.033468)
			(xy 355.385775 -402.081279) (xy 355.351352 -402.124441) (xy 355.31088 -402.16199) (xy 355.265264 -402.193087)
			(xy 355.215522 -402.217038) (xy 355.162766 -402.233308) (xy 355.108174 -402.241532) (xy 355.08057 -402.24202)
			(xy 355.052599 -402.241456) (xy 354.997301 -402.23299) (xy 354.943916 -402.21627) (xy 354.893667 -402.191682)
			(xy 354.847707 -402.159788) (xy 354.80709 -402.12132) (xy 354.772746 -402.07716) (xy 354.745465 -402.028321)
			(xy 354.725871 -401.975922) (xy 354.719636 -401.94865) (xy 354.716867 -401.938443) (xy 354.704531 -401.9213)
			(xy 354.68635 -401.910552) (xy 354.665383 -401.908009) (xy 354.65512 -401.91055) (xy 354.648263 -401.912944)
			(xy 354.636143 -401.920936) (xy 354.631244 -401.926298) (xy 354.62845 -401.929346) (xy 354.622608 -401.93595)
			(xy 354.61575 -401.952714) (xy 354.613718 -402.027136) (xy 354.613832 -402.036041) (xy 354.619428 -402.052934)
			(xy 354.62464 -402.060156) (xy 354.624894 -402.06041) (xy 354.639667 -402.079582) (xy 354.664493 -402.121131)
			(xy 354.683528 -402.165631) (xy 354.696429 -402.212281) (xy 354.702963 -402.260238) (xy 354.70338 -402.284438)
			(xy 354.702878 -402.311334) (xy 354.69486 -402.364526) (xy 354.679004 -402.415929) (xy 354.655665 -402.464395)
			(xy 354.625362 -402.508841) (xy 354.588774 -402.548274) (xy 354.546717 -402.581813) (xy 354.500131 -402.608709)
			(xy 354.450057 -402.628362) (xy 354.397612 -402.640332) (xy 354.34397 -402.644352) (xy 354.290328 -402.640332)
			(xy 354.237883 -402.628362) (xy 354.187809 -402.608709) (xy 354.141223 -402.581813) (xy 354.099166 -402.548274)
			(xy 354.062578 -402.508841) (xy 354.032275 -402.464395) (xy 354.008936 -402.415929) (xy 353.99308 -402.364526)
			(xy 353.985062 -402.311334) (xy 353.98456 -402.284438) (xy 353.984971 -402.260235) (xy 353.991471 -402.212269)
			(xy 354.004359 -402.165611) (xy 354.023401 -402.121108) (xy 354.048252 -402.079569) (xy 354.063046 -402.06041)
			(xy 354.0633 -402.060156) (xy 354.068568 -402.052966) (xy 354.074155 -402.03605) (xy 354.074222 -402.027136)
			(xy 354.07219 -401.952714) (xy 354.065332 -401.93595) (xy 354.05949 -401.929346) (xy 354.041289 -401.908229)
			(xy 354.010543 -401.861728) (xy 353.986891 -401.811248) (xy 353.970835 -401.757864) (xy 353.962718 -401.702711)
			(xy 353.962208 -401.674838) (xy 353.525836 -401.674838) (xy 353.52528 -401.704002) (xy 353.516359 -401.761644)
			(xy 353.498775 -401.817259) (xy 353.472937 -401.869552) (xy 353.439447 -401.917309) (xy 353.419664 -401.938744)
			(xy 353.413503 -401.945825) (xy 353.406348 -401.963162) (xy 353.405694 -401.972526) (xy 353.403916 -402.041106)
			(xy 353.404056 -402.050363) (xy 353.410192 -402.067816) (xy 353.415854 -402.075142) (xy 353.416362 -402.07565)
			(xy 353.432721 -402.095259) (xy 353.460251 -402.13827) (xy 353.481407 -402.184748) (xy 353.495761 -402.233757)
			(xy 353.503023 -402.284305) (xy 353.503484 -402.309838) (xy 353.502982 -402.336734) (xy 353.494964 -402.389926)
			(xy 353.479108 -402.441329) (xy 353.455769 -402.489795) (xy 353.425466 -402.534241) (xy 353.388878 -402.573674)
			(xy 353.346821 -402.607213) (xy 353.300235 -402.634109) (xy 353.250161 -402.653762) (xy 353.197716 -402.665732)
			(xy 353.144074 -402.669752) (xy 353.090432 -402.665732) (xy 353.037987 -402.653762) (xy 352.987913 -402.634109)
			(xy 352.941327 -402.607213) (xy 352.89927 -402.573674) (xy 352.862682 -402.534241) (xy 352.832379 -402.489795)
			(xy 352.80904 -402.441329) (xy 352.793184 -402.389926) (xy 352.785166 -402.336734) (xy 352.784664 -402.309838)
			(xy 352.785137 -402.28427) (xy 352.792414 -402.233655) (xy 352.80681 -402.184587) (xy 352.828034 -402.138064)
			(xy 352.855655 -402.095029) (xy 352.87204 -402.075396) (xy 352.872294 -402.075142) (xy 352.877961 -402.067823)
			(xy 352.884069 -402.050362) (xy 352.884232 -402.041106) (xy 352.8822 -401.962874) (xy 352.875088 -401.945856)
			(xy 352.868484 -401.938744) (xy 352.848695 -401.917314) (xy 352.815205 -401.869558) (xy 352.789371 -401.817263)
			(xy 352.771793 -401.761646) (xy 352.762883 -401.704002) (xy 352.762312 -401.674838) (xy 352.325432 -401.674838)
			(xy 352.324877 -401.703991) (xy 352.316007 -401.761619) (xy 352.298478 -401.817228) (xy 352.272699 -401.869526)
			(xy 352.239268 -401.917297) (xy 352.219514 -401.938744) (xy 352.213347 -401.94582) (xy 352.206196 -401.963161)
			(xy 352.205544 -401.972526) (xy 352.203766 -402.041106) (xy 352.203917 -402.050362) (xy 352.210047 -402.067814)
			(xy 352.215704 -402.075142) (xy 352.216212 -402.07565) (xy 352.232529 -402.09528) (xy 352.260001 -402.138303)
			(xy 352.281103 -402.184783) (xy 352.29541 -402.233783) (xy 352.302634 -402.284315) (xy 352.30308 -402.309838)
			(xy 352.302578 -402.336715) (xy 352.294566 -402.38987) (xy 352.278722 -402.441236) (xy 352.255398 -402.489668)
			(xy 352.225117 -402.534082) (xy 352.188555 -402.573487) (xy 352.146527 -402.607003) (xy 352.099974 -402.63388)
			(xy 352.049935 -402.653519) (xy 351.997528 -402.66548) (xy 351.943924 -402.669498) (xy 351.89032 -402.66548)
			(xy 351.837913 -402.653519) (xy 351.787874 -402.63388) (xy 351.741321 -402.607003) (xy 351.699293 -402.573487)
			(xy 351.662731 -402.534082) (xy 351.63245 -402.489668) (xy 351.609126 -402.441236) (xy 351.593282 -402.38987)
			(xy 351.58527 -402.336715) (xy 351.584768 -402.309838) (xy 351.585236 -402.284281) (xy 351.592473 -402.233681)
			(xy 351.606819 -402.184621) (xy 351.627984 -402.138094) (xy 351.655539 -402.095043) (xy 351.67189 -402.075396)
			(xy 351.672144 -402.075142) (xy 351.677805 -402.067819) (xy 351.683918 -402.050362) (xy 351.684082 -402.041106)
			(xy 351.68205 -401.962874) (xy 351.674938 -401.945856) (xy 351.668334 -401.938744) (xy 351.648604 -401.917275)
			(xy 351.615164 -401.869513) (xy 351.589378 -401.817221) (xy 351.571844 -401.761615) (xy 351.562971 -401.70399)
			(xy 351.562416 -401.674838) (xy 351.125536 -401.674838) (xy 351.125536 -401.675346) (xy 351.125038 -401.703743)
			(xy 351.116627 -401.75991) (xy 351.099968 -401.814205) (xy 351.075432 -401.865424) (xy 351.043561 -401.912432)
			(xy 351.024698 -401.933664) (xy 351.018836 -401.940599) (xy 351.01193 -401.957377) (xy 351.011236 -401.96643)
			(xy 351.01022 -401.997418) (xy 351.01027 -402.00657) (xy 351.016141 -402.023891) (xy 351.02165 -402.0312)
			(xy 351.036992 -402.050549) (xy 351.062766 -402.092669) (xy 351.082545 -402.137914) (xy 351.095958 -402.185438)
			(xy 351.102753 -402.234348) (xy 351.103184 -402.259038) (xy 351.102682 -402.285915) (xy 351.09467 -402.33907)
			(xy 351.078826 -402.390436) (xy 351.055502 -402.438868) (xy 351.025221 -402.483282) (xy 350.988659 -402.522687)
			(xy 350.946631 -402.556203) (xy 350.900078 -402.58308) (xy 350.850039 -402.602719) (xy 350.797632 -402.61468)
			(xy 350.744028 -402.618698) (xy 350.690424 -402.61468) (xy 350.638017 -402.602719) (xy 350.587978 -402.58308)
			(xy 350.541425 -402.556203) (xy 350.499397 -402.522687) (xy 350.462835 -402.483282) (xy 350.432554 -402.438868)
			(xy 350.40923 -402.390436) (xy 350.393386 -402.33907) (xy 350.385374 -402.285915) (xy 350.384872 -402.259038)
			(xy 350.385277 -402.234345) (xy 350.392033 -402.185422) (xy 350.405436 -402.137889) (xy 350.425234 -402.092644)
			(xy 350.45105 -402.050542) (xy 350.466406 -402.0312) (xy 350.471894 -402.023884) (xy 350.477734 -402.006564)
			(xy 350.477836 -401.997418) (xy 350.47682 -401.96643) (xy 350.476184 -401.957365) (xy 350.469264 -401.940573)
			(xy 350.463358 -401.933664) (xy 350.444538 -401.912402) (xy 350.412719 -401.865375) (xy 350.388204 -401.814159)
			(xy 350.371533 -401.759882) (xy 350.363071 -401.703735) (xy 350.36252 -401.675346) (xy 349.92563 -401.675346)
			(xy 349.925083 -401.703991) (xy 349.916213 -401.761619) (xy 349.898685 -401.817228) (xy 349.872906 -401.869526)
			(xy 349.839476 -401.917297) (xy 349.819722 -401.938744) (xy 349.813556 -401.945821) (xy 349.806404 -401.963161)
			(xy 349.805752 -401.972526) (xy 349.803974 -402.041106) (xy 349.804124 -402.050362) (xy 349.810254 -402.067815)
			(xy 349.815912 -402.075142) (xy 349.81642 -402.07565) (xy 349.832739 -402.095279) (xy 349.86021 -402.138303)
			(xy 349.881312 -402.184783) (xy 349.895619 -402.233783) (xy 349.902842 -402.284315) (xy 349.903288 -402.309838)
			(xy 349.902786 -402.336715) (xy 349.894774 -402.38987) (xy 349.87893 -402.441236) (xy 349.855606 -402.489668)
			(xy 349.825325 -402.534082) (xy 349.788763 -402.573487) (xy 349.746735 -402.607003) (xy 349.700182 -402.63388)
			(xy 349.650143 -402.653519) (xy 349.597736 -402.66548) (xy 349.544132 -402.669498) (xy 349.490528 -402.66548)
			(xy 349.438121 -402.653519) (xy 349.388082 -402.63388) (xy 349.341529 -402.607003) (xy 349.299501 -402.573487)
			(xy 349.262939 -402.534082) (xy 349.232658 -402.489668) (xy 349.209334 -402.441236) (xy 349.19349 -402.38987)
			(xy 349.185478 -402.336715) (xy 349.184976 -402.309838) (xy 349.185442 -402.284281) (xy 349.192679 -402.233681)
			(xy 349.207025 -402.184621) (xy 349.228191 -402.138094) (xy 349.255747 -402.095043) (xy 349.272098 -402.075396)
			(xy 349.272352 -402.075142) (xy 349.278014 -402.06782) (xy 349.284126 -402.050362) (xy 349.28429 -402.041106)
			(xy 349.282258 -401.962874) (xy 349.275146 -401.945856) (xy 349.268542 -401.938744) (xy 349.248814 -401.917273)
			(xy 349.215373 -401.869512) (xy 349.189586 -401.81722) (xy 349.172052 -401.761615) (xy 349.163179 -401.70399)
			(xy 349.162624 -401.674838) (xy 348.868238 -401.674838) (xy 348.868238 -402.810218) (xy 348.867839 -402.820291)
			(xy 348.860102 -402.838889) (xy 348.853252 -402.846286) (xy 348.567502 -403.132036) (xy 348.5601 -403.138873)
			(xy 348.541502 -403.146593) (xy 348.531434 -403.147022) (xy 341.714582 -403.147022) (xy 341.704509 -403.146626)
			(xy 341.68591 -403.138887) (xy 341.678514 -403.132036) (xy 341.227664 -402.681186) (xy 341.219172 -402.673439)
			(xy 341.197476 -402.66591) (xy 341.186008 -402.666708) (xy 341.1855 -402.666708) (xy 341.175188 -402.667864)
			(xy 341.154474 -402.669137) (xy 341.144098 -402.669248) (xy 341.118427 -402.668754) (xy 341.067607 -402.661448)
			(xy 341.018345 -402.646984) (xy 340.971642 -402.625656) (xy 340.928449 -402.5979) (xy 340.889646 -402.56428)
			(xy 340.856021 -402.52548) (xy 340.828261 -402.48229) (xy 340.806929 -402.435589) (xy 340.79246 -402.386328)
			(xy 340.785148 -402.335509) (xy 340.784688 -402.309838) (xy 340.785156 -402.28427) (xy 340.792433 -402.233654)
			(xy 340.80683 -402.184586) (xy 340.828056 -402.138063) (xy 340.855678 -402.095029) (xy 340.872064 -402.075396)
			(xy 340.872318 -402.075142) (xy 340.877987 -402.067825) (xy 340.884094 -402.050363) (xy 340.884256 -402.041106)
			(xy 340.882224 -401.962874) (xy 340.875112 -401.945856) (xy 340.868508 -401.938744) (xy 340.848723 -401.91731)
			(xy 340.815232 -401.869556) (xy 340.789396 -401.817262) (xy 340.771818 -401.761645) (xy 340.762907 -401.704002)
			(xy 340.762336 -401.674838) (xy 340.762336 -400.811238) (xy 340.762762 -400.785718) (xy 340.769552 -400.735132)
			(xy 340.783029 -400.685903) (xy 340.802952 -400.638913) (xy 340.828965 -400.594999) (xy 340.860603 -400.554948)
			(xy 340.878668 -400.536918) (xy 340.885272 -400.530568) (xy 340.893146 -400.513804) (xy 340.900004 -400.42846)
			(xy 340.894924 -400.41068) (xy 340.889336 -400.403314) (xy 340.874486 -400.382566) (xy 340.85085 -400.337352)
			(xy 340.834749 -400.288941) (xy 340.826596 -400.238577) (xy 340.82609 -400.213068) (xy 340.82609 -400.212814)
			(xy 340.826526 -400.189125) (xy 340.833541 -400.142269) (xy 340.847432 -400.096974) (xy 340.867891 -400.054241)
			(xy 340.894466 -400.015018) (xy 340.926567 -399.980174) (xy 340.963485 -399.950479) (xy 341.0044 -399.926593)
			(xy 341.026242 -399.917412) (xy 341.04072 -399.91157) (xy 341.058246 -399.885916) (xy 341.058246 -399.197576)
			(xy 341.057847 -399.187503) (xy 341.05011 -399.168905) (xy 341.04326 -399.161508) (xy 340.828376 -398.946878)
			(xy 340.820981 -398.940032) (xy 340.802378 -398.932316) (xy 340.792308 -398.931892) (xy 340.465156 -398.931892)
			(xy 340.455145 -398.931448) (xy 340.43665 -398.923772) (xy 340.422499 -398.909606) (xy 340.414842 -398.891104)
			(xy 340.414356 -398.881092) (xy 340.414356 -398.666716) (xy 340.405212 -398.666716) (xy 340.395207 -398.666203)
			(xy 340.376719 -398.65855) (xy 340.362566 -398.644405) (xy 340.354903 -398.625921) (xy 340.354412 -398.615916)
			(xy 340.354412 -398.411446) (xy 340.354996 -398.389372) (xy 340.364108 -398.346174) (xy 340.381892 -398.305766)
			(xy 340.39429 -398.287494) (xy 340.399116 -398.281144) (xy 340.403942 -398.265904) (xy 340.403942 -398.236694)
			(xy 340.403583 -398.225996) (xy 340.395023 -398.206396) (xy 340.387432 -398.198848) (xy 340.364064 -398.177766)
			(xy 340.356509 -398.171628) (xy 340.338237 -398.164963) (xy 340.328504 -398.164812) (xy 340.318852 -398.164812)
			(xy 340.293456 -398.164354) (xy 340.243321 -398.156216) (xy 340.195134 -398.140157) (xy 340.15014 -398.116593)
			(xy 340.109497 -398.086129) (xy 340.074256 -398.049553) (xy 340.045323 -398.007807) (xy 340.023446 -397.961968)
			(xy 340.01583 -397.937736) (xy 340.014306 -397.931894) (xy 339.694012 -397.378174) (xy 339.689948 -397.373856)
			(xy 339.673736 -397.356155) (xy 339.646315 -397.316761) (xy 339.625175 -397.27367) (xy 339.610803 -397.227874)
			(xy 339.60353 -397.180431) (xy 339.60308 -397.156432) (xy 339.603259 -397.142384) (xy 339.605802 -397.114402)
			(xy 339.60816 -397.100552) (xy 339.609455 -397.091296) (xy 339.606055 -397.072931) (xy 339.601556 -397.064738)
			(xy 339.584792 -397.037814) (xy 339.579599 -397.030104) (xy 339.564867 -397.018784) (xy 339.55609 -397.015716)
			(xy 339.534469 -397.0089) (xy 339.493254 -396.990023) (xy 339.455132 -396.965493) (xy 339.420875 -396.935803)
			(xy 339.405722 -396.918942) (xy 339.40326 -396.916169) (xy 339.397647 -396.911323) (xy 339.394546 -396.90929)
			(xy 339.382533 -396.901189) (xy 339.362637 -396.880138) (xy 339.348623 -396.854789) (xy 339.34138 -396.826744)
			(xy 339.340952 -396.812262) (xy 339.340952 -396.800324) (xy 339.339174 -396.79372) (xy 339.333968 -396.773351)
			(xy 339.328367 -396.731683) (xy 339.327998 -396.710662) (xy 338.764118 -396.710662) (xy 338.764118 -396.71117)
			(xy 338.763947 -396.725795) (xy 338.76128 -396.754924) (xy 338.758784 -396.769336) (xy 338.757423 -396.77851)
			(xy 338.760694 -396.796752) (xy 338.765134 -396.804896) (xy 338.781644 -396.83182) (xy 338.786814 -396.839598)
			(xy 338.80154 -396.85106) (xy 338.810346 -396.854172) (xy 338.835274 -396.862295) (xy 338.882239 -396.885591)
			(xy 338.924718 -396.916316) (xy 338.961547 -396.953627) (xy 338.991716 -396.996502) (xy 339.014399 -397.043766)
			(xy 339.022182 -397.068802) (xy 339.023706 -397.074644) (xy 339.343492 -397.627602) (xy 339.347556 -397.63192)
			(xy 339.363757 -397.64963) (xy 339.39118 -397.689021) (xy 339.412322 -397.732111) (xy 339.426697 -397.777904)
			(xy 339.433972 -397.825346) (xy 339.434424 -397.849344) (xy 339.433935 -397.874806) (xy 339.425736 -397.925067)
			(xy 339.409575 -397.973359) (xy 339.38587 -398.018431) (xy 339.355237 -398.059112) (xy 339.31847 -398.094348)
			(xy 339.297772 -398.109186) (xy 339.289279 -398.11567) (xy 339.278095 -398.133848) (xy 339.275261 -398.155001)
			(xy 339.281265 -398.175482) (xy 339.295072 -398.191756) (xy 339.314301 -398.201018) (xy 339.32495 -398.201896)
			(xy 339.334602 -398.201388) (xy 339.343116 -398.200096) (xy 339.360281 -398.198696) (xy 339.368892 -398.198594)
			(xy 339.369146 -398.198848) (xy 339.668358 -398.198848) (xy 339.668612 -398.198594) (xy 339.689675 -398.198951)
			(xy 339.731036 -398.206915) (xy 339.770035 -398.222828) (xy 339.805161 -398.246073) (xy 339.835052 -398.27575)
			(xy 339.858549 -398.310708) (xy 339.874742 -398.349591) (xy 339.883003 -398.390894) (xy 339.883496 -398.411954)
			(xy 339.883496 -398.666716) (xy 339.874352 -398.666716) (xy 339.864339 -398.667149) (xy 339.845843 -398.674828)
			(xy 339.831692 -398.688997) (xy 339.824037 -398.707503) (xy 339.823552 -398.717516) (xy 339.823552 -398.881092)
			(xy 339.823173 -398.891119) (xy 339.815497 -398.909645) (xy 339.801311 -398.923819) (xy 339.782779 -398.931481)
			(xy 339.772752 -398.931892) (xy 339.264752 -398.931892) (xy 339.25474 -398.931451) (xy 339.236246 -398.923774)
			(xy 339.222094 -398.909607) (xy 339.214438 -398.891104) (xy 339.213952 -398.881092) (xy 339.213952 -398.666716)
			(xy 339.204808 -398.666716) (xy 339.194803 -398.666206) (xy 339.176314 -398.658552) (xy 339.162162 -398.644406)
			(xy 339.154499 -398.625921) (xy 339.154008 -398.615916) (xy 339.154008 -398.411954) (xy 339.154354 -398.394721)
			(xy 339.159924 -398.360708) (xy 339.170896 -398.328035) (xy 339.178646 -398.31264) (xy 339.184488 -398.30121)
			(xy 339.184234 -398.27581) (xy 339.13064 -398.178782) (xy 339.10905 -398.165066) (xy 339.096096 -398.16405)
			(xy 339.072197 -398.161955) (xy 339.025409 -398.15135) (xy 338.980768 -398.133779) (xy 338.939304 -398.109648)
			(xy 338.901975 -398.079513) (xy 338.869641 -398.044072) (xy 338.84305 -398.00414) (xy 338.822816 -397.960642)
			(xy 338.81568 -397.937736) (xy 338.814156 -397.931894) (xy 338.493608 -397.377412) (xy 338.489544 -397.373094)
			(xy 338.473439 -397.355426) (xy 338.446191 -397.316146) (xy 338.425181 -397.273206) (xy 338.410889 -397.227587)
			(xy 338.403642 -397.180334) (xy 338.403184 -397.156432) (xy 338.403363 -397.142384) (xy 338.405906 -397.114402)
			(xy 338.408264 -397.100552) (xy 338.409559 -397.091296) (xy 338.406159 -397.072931) (xy 338.40166 -397.064738)
			(xy 338.384896 -397.037814) (xy 338.379701 -397.030105) (xy 338.364971 -397.018784) (xy 338.356194 -397.015716)
			(xy 338.334573 -397.008899) (xy 338.293358 -396.990022) (xy 338.255237 -396.965492) (xy 338.220979 -396.935803)
			(xy 338.205826 -396.918942) (xy 338.203363 -396.91617) (xy 338.197751 -396.911323) (xy 338.19465 -396.90929)
			(xy 338.182616 -396.901218) (xy 338.162729 -396.880154) (xy 338.148722 -396.854796) (xy 338.141483 -396.826746)
			(xy 338.141056 -396.812262) (xy 338.141056 -396.800324) (xy 338.139278 -396.79372) (xy 338.134072 -396.773351)
			(xy 338.128471 -396.731683) (xy 338.128102 -396.710662) (xy 337.563968 -396.710662) (xy 337.563968 -396.71117)
			(xy 337.563798 -396.725795) (xy 337.561131 -396.754924) (xy 337.558634 -396.769336) (xy 337.557266 -396.77851)
			(xy 337.560541 -396.796753) (xy 337.564984 -396.804896) (xy 337.581494 -396.83182) (xy 337.586645 -396.839612)
			(xy 337.601384 -396.851067) (xy 337.610196 -396.854172) (xy 337.635076 -396.862242) (xy 337.681955 -396.885429)
			(xy 337.724367 -396.916032) (xy 337.761151 -396.953211) (xy 337.791299 -396.995948) (xy 337.813984 -397.043073)
			(xy 337.821778 -397.06804) (xy 337.823302 -397.073882) (xy 338.143596 -397.627602) (xy 338.14766 -397.63192)
			(xy 338.163862 -397.64963) (xy 338.191284 -397.689021) (xy 338.212426 -397.73211) (xy 338.226801 -397.777904)
			(xy 338.234076 -397.825346) (xy 338.234528 -397.849344) (xy 338.234037 -397.874806) (xy 338.225838 -397.925067)
			(xy 338.209677 -397.973359) (xy 338.185973 -398.018431) (xy 338.15534 -398.059112) (xy 338.118574 -398.094348)
			(xy 338.097876 -398.109186) (xy 338.089381 -398.115669) (xy 338.078196 -398.133847) (xy 338.075361 -398.155001)
			(xy 338.081366 -398.175483) (xy 338.095174 -398.191758) (xy 338.114404 -398.201019) (xy 338.125054 -398.201896)
			(xy 338.134706 -398.201388) (xy 338.14322 -398.200095) (xy 338.160385 -398.198696) (xy 338.168996 -398.198594)
			(xy 338.16925 -398.198848) (xy 338.468462 -398.198848) (xy 338.468716 -398.198594) (xy 338.489779 -398.198947)
			(xy 338.531141 -398.206912) (xy 338.57014 -398.222826) (xy 338.605265 -398.246072) (xy 338.635156 -398.275749)
			(xy 338.658653 -398.310707) (xy 338.674846 -398.349591) (xy 338.683107 -398.390894) (xy 338.6836 -398.411954)
			(xy 338.6836 -398.666716) (xy 338.674456 -398.666716) (xy 338.664444 -398.667153) (xy 338.645948 -398.67483)
			(xy 338.631796 -398.688998) (xy 338.624141 -398.707503) (xy 338.623656 -398.717516) (xy 338.623656 -398.881092)
			(xy 338.623273 -398.891118) (xy 338.615597 -398.909643) (xy 338.601413 -398.923818) (xy 338.582883 -398.93148)
			(xy 338.572856 -398.931892) (xy 338.064856 -398.931892) (xy 338.054845 -398.931448) (xy 338.03635 -398.923772)
			(xy 338.022199 -398.909606) (xy 338.014542 -398.891104) (xy 338.014056 -398.881092) (xy 338.014056 -398.666716)
			(xy 338.004912 -398.666716) (xy 337.994907 -398.666203) (xy 337.976419 -398.65855) (xy 337.962266 -398.644405)
			(xy 337.954603 -398.625921) (xy 337.954112 -398.615916) (xy 337.954112 -398.411954) (xy 337.954458 -398.394721)
			(xy 337.960028 -398.360708) (xy 337.971 -398.328035) (xy 337.97875 -398.31264) (xy 337.984592 -398.30121)
			(xy 337.984338 -398.27581) (xy 337.930744 -398.178782) (xy 337.909154 -398.165066) (xy 337.8962 -398.16405)
			(xy 337.872301 -398.161951) (xy 337.825514 -398.151347) (xy 337.780872 -398.133777) (xy 337.739408 -398.109646)
			(xy 337.702079 -398.079512) (xy 337.669745 -398.044071) (xy 337.643155 -398.00414) (xy 337.62292 -397.960642)
			(xy 337.615784 -397.937736) (xy 337.61426 -397.931894) (xy 337.293966 -397.378174) (xy 337.289902 -397.373856)
			(xy 337.273751 -397.356115) (xy 337.24638 -397.316716) (xy 337.225287 -397.273628) (xy 337.210957 -397.227844)
			(xy 337.203722 -397.180419) (xy 337.203288 -397.156432) (xy 337.203469 -397.142384) (xy 337.20601 -397.114402)
			(xy 337.208368 -397.100552) (xy 337.209695 -397.091273) (xy 337.206165 -397.072875) (xy 337.20151 -397.064738)
			(xy 337.184746 -397.037814) (xy 337.179534 -397.030118) (xy 337.164816 -397.018791) (xy 337.156044 -397.015716)
			(xy 337.134417 -397.008918) (xy 337.093203 -396.990036) (xy 337.055083 -396.9655) (xy 337.020827 -396.935806)
			(xy 337.005676 -396.918942) (xy 337.003207 -396.916175) (xy 336.997599 -396.911325) (xy 336.9945 -396.90929)
			(xy 336.982449 -396.901214) (xy 336.962488 -396.880178) (xy 336.948409 -396.854825) (xy 336.941106 -396.826761)
			(xy 336.940652 -396.812262) (xy 336.940652 -396.800324) (xy 336.939128 -396.79372) (xy 336.933921 -396.773351)
			(xy 336.928321 -396.731683) (xy 336.927952 -396.710662) (xy 336.364072 -396.710662) (xy 336.364072 -396.71117)
			(xy 336.363902 -396.725795) (xy 336.361235 -396.754924) (xy 336.358738 -396.769336) (xy 336.357369 -396.77851)
			(xy 336.360644 -396.796753) (xy 336.365088 -396.804896) (xy 336.381598 -396.83182) (xy 336.386748 -396.839613)
			(xy 336.401488 -396.851068) (xy 336.4103 -396.854172) (xy 336.43518 -396.862239) (xy 336.48206 -396.885428)
			(xy 336.524472 -396.916031) (xy 336.561256 -396.95321) (xy 336.591403 -396.995948) (xy 336.614088 -397.043073)
			(xy 336.621882 -397.06804) (xy 336.623406 -397.073882) (xy 336.9437 -397.627602) (xy 336.947764 -397.63192)
			(xy 336.963966 -397.649629) (xy 336.991388 -397.689021) (xy 337.01253 -397.73211) (xy 337.026905 -397.777904)
			(xy 337.03418 -397.825346) (xy 337.034632 -397.849344) (xy 337.034139 -397.874806) (xy 337.025941 -397.925066)
			(xy 337.00978 -397.973359) (xy 336.986076 -398.01843) (xy 336.955443 -398.059112) (xy 336.918677 -398.094347)
			(xy 336.89798 -398.109186) (xy 336.889492 -398.115645) (xy 336.87831 -398.133782) (xy 336.875445 -398.154895)
			(xy 336.881388 -398.175356) (xy 336.895119 -398.191648) (xy 336.914277 -398.200972) (xy 336.924904 -398.201896)
			(xy 336.93481 -398.201388) (xy 336.943261 -398.200103) (xy 336.960299 -398.198703) (xy 336.968846 -398.198594)
			(xy 336.9691 -398.198848) (xy 337.268312 -398.198848) (xy 337.268566 -398.198594) (xy 337.289613 -398.198973)
			(xy 337.330935 -398.206974) (xy 337.36989 -398.22291) (xy 337.404972 -398.246164) (xy 337.434822 -398.275836)
			(xy 337.458286 -398.310778) (xy 337.474456 -398.349637) (xy 337.482704 -398.39091) (xy 337.483196 -398.411954)
			(xy 337.483196 -398.666716) (xy 337.474052 -398.666716) (xy 337.464039 -398.667149) (xy 337.445543 -398.674828)
			(xy 337.431392 -398.688997) (xy 337.423737 -398.707503) (xy 337.423252 -398.717516) (xy 337.423252 -398.881092)
			(xy 337.422873 -398.891119) (xy 337.415197 -398.909645) (xy 337.401011 -398.923819) (xy 337.382479 -398.931481)
			(xy 337.372452 -398.931892) (xy 336.86496 -398.931892) (xy 336.854949 -398.931444) (xy 336.836455 -398.92377)
			(xy 336.822303 -398.909605) (xy 336.814646 -398.891104) (xy 336.81416 -398.881092) (xy 336.81416 -398.717516)
			(xy 336.813767 -398.707491) (xy 336.806094 -398.688966) (xy 336.791913 -398.674792) (xy 336.773385 -398.667129)
			(xy 336.76336 -398.666716) (xy 336.754216 -398.666716) (xy 336.754216 -398.411446) (xy 336.755 -398.385724)
			(xy 336.767333 -398.335777) (xy 336.7786 -398.31264) (xy 336.784442 -398.30121) (xy 336.784188 -398.27581)
			(xy 336.73669 -398.190212) (xy 336.729956 -398.179443) (xy 336.708642 -398.1657) (xy 336.69605 -398.16405)
			(xy 336.672179 -398.161843) (xy 336.625436 -398.151217) (xy 336.580839 -398.133639) (xy 336.539417 -398.109513)
			(xy 336.502125 -398.079395) (xy 336.469821 -398.043979) (xy 336.44325 -398.004081) (xy 336.423024 -397.960621)
			(xy 336.415888 -397.937736) (xy 336.414364 -397.931894) (xy 336.09407 -397.378174) (xy 336.090006 -397.373856)
			(xy 336.073839 -397.356129) (xy 336.046473 -397.316724) (xy 336.025385 -397.273633) (xy 336.011059 -397.227846)
			(xy 336.003826 -397.18042) (xy 336.003392 -397.156432) (xy 336.003573 -397.142384) (xy 336.006114 -397.114402)
			(xy 336.008472 -397.100552) (xy 336.009798 -397.091273) (xy 336.006269 -397.072875) (xy 336.001614 -397.064738)
			(xy 335.98485 -397.037814) (xy 335.979636 -397.030119) (xy 335.964919 -397.018791) (xy 335.956148 -397.015716)
			(xy 335.934521 -397.008917) (xy 335.893307 -396.990035) (xy 335.855187 -396.965499) (xy 335.820931 -396.935806)
			(xy 335.80578 -396.918942) (xy 335.803311 -396.916176) (xy 335.797703 -396.911325) (xy 335.794604 -396.90929)
			(xy 335.782554 -396.901213) (xy 335.762592 -396.880178) (xy 335.748514 -396.854825) (xy 335.74121 -396.826761)
			(xy 335.740756 -396.812262) (xy 335.740756 -396.800324) (xy 335.739232 -396.79372) (xy 335.734025 -396.773351)
			(xy 335.728425 -396.731683) (xy 335.728056 -396.710662) (xy 333.961712 -396.710662) (xy 333.95502 -396.753845)
			(xy 333.94777 -396.778226) (xy 333.945484 -396.785846) (xy 333.945484 -396.876778) (xy 333.944894 -396.893435)
			(xy 333.936288 -396.925619) (xy 333.919656 -396.954484) (xy 333.896128 -396.978069) (xy 333.867302 -396.99477)
			(xy 333.83514 -397.003453) (xy 333.818484 -397.004032) (xy 333.688182 -397.004032) (xy 333.684372 -397.004794)
			(xy 333.671567 -397.006699) (xy 333.645756 -397.008735) (xy 333.63281 -397.008858) (xy 333.632302 -397.008858)
			(xy 333.619357 -397.008721) (xy 333.593547 -397.006685) (xy 333.58074 -397.004794) (xy 333.57693 -397.004032)
			(xy 333.436976 -397.004032) (xy 333.420283 -397.003487) (xy 333.388033 -396.994852) (xy 333.35911 -396.978177)
			(xy 333.335479 -396.954593) (xy 333.318745 -396.925703) (xy 333.310047 -396.89347) (xy 333.309468 -396.876778)
			(xy 333.309468 -396.749524) (xy 333.308452 -396.744444) (xy 333.305344 -396.728047) (xy 333.302033 -396.694838)
			(xy 333.301848 -396.67815) (xy 333.09989 -396.67815) (xy 333.099918 -396.679674) (xy 333.099409 -396.70756)
			(xy 333.091289 -396.762736) (xy 333.075221 -396.816143) (xy 333.051549 -396.86664) (xy 333.020776 -396.913153)
			(xy 332.983559 -396.95469) (xy 332.940691 -396.990365) (xy 332.893085 -397.019419) (xy 332.841756 -397.041231)
			(xy 332.787799 -397.055337) (xy 332.732362 -397.061437) (xy 332.676628 -397.0594) (xy 332.621785 -397.04927)
			(xy 332.569001 -397.031263) (xy 332.519401 -397.005762) (xy 332.474043 -396.973311) (xy 332.433894 -396.934602)
			(xy 332.399808 -396.890459) (xy 332.372512 -396.841824) (xy 332.352589 -396.789733) (xy 332.340463 -396.735296)
			(xy 332.336392 -396.679674) (xy 331.261466 -396.679674) (xy 331.261466 -396.735554) (xy 331.261951 -396.7463)
			(xy 331.270773 -396.765898) (xy 331.278484 -396.7734) (xy 331.302797 -396.795747) (xy 331.346025 -396.845669)
			(xy 331.38243 -396.900765) (xy 331.411401 -396.960108) (xy 331.43245 -397.022701) (xy 331.445223 -397.087491)
			(xy 331.449505 -397.153389) (xy 331.445225 -397.219288) (xy 331.432455 -397.284078) (xy 331.411409 -397.346672)
			(xy 331.382441 -397.406016) (xy 331.346038 -397.461114) (xy 331.302812 -397.511038) (xy 331.278484 -397.533368)
			(xy 331.270859 -397.540932) (xy 331.262047 -397.560491) (xy 331.261466 -397.571214) (xy 331.261466 -399.008092)
			(xy 333.290164 -399.008092) (xy 333.290583 -398.984859) (xy 333.297077 -398.938849) (xy 333.309948 -398.894202)
			(xy 333.328945 -398.851797) (xy 333.353692 -398.81247) (xy 333.368396 -398.794478) (xy 333.374238 -398.78762)
			(xy 333.380588 -398.770602) (xy 333.380588 -398.686782) (xy 333.374238 -398.669764) (xy 333.368396 -398.662906)
			(xy 333.353675 -398.644926) (xy 333.328931 -398.605594) (xy 333.309934 -398.563186) (xy 333.297058 -398.518538)
			(xy 333.290557 -398.472526) (xy 333.290164 -398.449292) (xy 333.290674 -398.423305) (xy 333.298804 -398.37197)
			(xy 333.314865 -398.32254) (xy 333.338461 -398.27623) (xy 333.369011 -398.234182) (xy 333.405762 -398.197431)
			(xy 333.44781 -398.166881) (xy 333.49412 -398.143285) (xy 333.54355 -398.127224) (xy 333.594885 -398.119094)
			(xy 333.646859 -398.119094) (xy 333.698194 -398.127224) (xy 333.747624 -398.143285) (xy 333.793934 -398.166881)
			(xy 333.835982 -398.197431) (xy 333.872733 -398.234182) (xy 333.903283 -398.27623) (xy 333.926879 -398.32254)
			(xy 333.94294 -398.37197) (xy 333.95107 -398.423305) (xy 333.95158 -398.449292) (xy 333.951223 -398.472527)
			(xy 333.944717 -398.51854) (xy 333.931831 -398.563188) (xy 333.912821 -398.605593) (xy 333.906321 -398.615916)
			(xy 335.553812 -398.615916) (xy 335.553812 -398.411954) (xy 335.554373 -398.390895) (xy 335.562617 -398.349592)
			(xy 335.578795 -398.310706) (xy 335.602281 -398.275745) (xy 335.632163 -398.246064) (xy 335.667282 -398.222815)
			(xy 335.706277 -398.2069) (xy 335.747634 -398.198936) (xy 335.768696 -398.198594) (xy 335.76895 -398.198848)
			(xy 336.068162 -398.198848) (xy 336.068416 -398.198594) (xy 336.089479 -398.198947) (xy 336.130841 -398.206912)
			(xy 336.16984 -398.222826) (xy 336.204965 -398.246072) (xy 336.234856 -398.275749) (xy 336.258353 -398.310707)
			(xy 336.274546 -398.349591) (xy 336.282807 -398.390894) (xy 336.2833 -398.411954) (xy 336.2833 -398.666716)
			(xy 336.274156 -398.666716) (xy 336.264144 -398.667153) (xy 336.245648 -398.67483) (xy 336.231496 -398.688998)
			(xy 336.223841 -398.707503) (xy 336.223356 -398.717516) (xy 336.223356 -398.881092) (xy 336.222973 -398.891118)
			(xy 336.215297 -398.909643) (xy 336.201113 -398.923818) (xy 336.182583 -398.93148) (xy 336.172556 -398.931892)
			(xy 335.664556 -398.931892) (xy 335.654545 -398.931448) (xy 335.63605 -398.923772) (xy 335.621899 -398.909606)
			(xy 335.614242 -398.891104) (xy 335.613756 -398.881092) (xy 335.613756 -398.666716) (xy 335.604612 -398.666716)
			(xy 335.594607 -398.666203) (xy 335.576119 -398.65855) (xy 335.561966 -398.644405) (xy 335.554303 -398.625921)
			(xy 335.553812 -398.615916) (xy 333.906321 -398.615916) (xy 333.888059 -398.644917) (xy 333.873348 -398.662906)
			(xy 333.867506 -398.669764) (xy 333.861156 -398.686782) (xy 333.861156 -398.770602) (xy 333.867506 -398.78762)
			(xy 333.873348 -398.794478) (xy 333.888053 -398.81247) (xy 333.912801 -398.851798) (xy 333.931802 -398.894203)
			(xy 333.944682 -398.938849) (xy 333.951186 -398.984859) (xy 333.95158 -399.008092) (xy 333.95158 -399.008346)
			(xy 333.951153 -399.032396) (xy 333.944161 -399.079986) (xy 333.930362 -399.126065) (xy 333.920592 -399.148046)
			(xy 333.915258 -399.159476) (xy 333.916528 -399.184622) (xy 333.966312 -399.26768) (xy 333.973241 -399.27805)
			(xy 333.994553 -399.290957) (xy 334.006952 -399.292318) (xy 334.031948 -399.294171) (xy 334.080992 -399.304501)
			(xy 334.127916 -399.322114) (xy 334.171645 -399.346605) (xy 334.211177 -399.377415) (xy 334.245608 -399.413837)
			(xy 334.274149 -399.455037) (xy 334.296146 -399.500072) (xy 334.311096 -399.547911) (xy 334.318656 -399.597458)
			(xy 334.319118 -399.622518) (xy 334.318608 -399.648505) (xy 334.310478 -399.69984) (xy 334.294417 -399.74927)
			(xy 334.270821 -399.79558) (xy 334.240271 -399.837628) (xy 334.20352 -399.874379) (xy 334.161472 -399.904929)
			(xy 334.115162 -399.928525) (xy 334.065732 -399.944586) (xy 334.014397 -399.952716) (xy 333.962423 -399.952716)
			(xy 333.911088 -399.944586) (xy 333.861658 -399.928525) (xy 333.815348 -399.904929) (xy 333.7733 -399.874379)
			(xy 333.736549 -399.837628) (xy 333.705999 -399.79558) (xy 333.682403 -399.74927) (xy 333.666342 -399.69984)
			(xy 333.658212 -399.648505) (xy 333.657702 -399.622518) (xy 333.657702 -399.622264) (xy 333.658134 -399.598214)
			(xy 333.665124 -399.550624) (xy 333.678922 -399.504545) (xy 333.68869 -399.482564) (xy 333.694024 -399.471134)
			(xy 333.692754 -399.445988) (xy 333.64297 -399.36293) (xy 333.635998 -399.352595) (xy 333.614718 -399.33967)
			(xy 333.60233 -399.338292) (xy 333.577334 -399.336445) (xy 333.52829 -399.326112) (xy 333.481367 -399.308498)
			(xy 333.437639 -399.284005) (xy 333.398107 -399.253195) (xy 333.363676 -399.216773) (xy 333.335136 -399.175573)
			(xy 333.313138 -399.130537) (xy 333.298188 -399.082699) (xy 333.290626 -399.033152) (xy 333.290164 -399.008092)
			(xy 331.261466 -399.008092) (xy 331.261466 -399.528284) (xy 331.261027 -399.538347) (xy 331.253287 -399.556926)
			(xy 331.24648 -399.564352) (xy 331.045312 -399.76552) (xy 331.037918 -399.772377) (xy 331.019319 -399.780129)
			(xy 331.009244 -399.780506) (xy 330.700126 -399.780506) (xy 330.690062 -399.780943) (xy 330.671478 -399.788677)
			(xy 330.664058 -399.795492) (xy 330.605638 -399.854166) (xy 330.598238 -399.861006) (xy 330.579639 -399.868724)
			(xy 330.56957 -399.869152) (xy 329.740006 -399.869152) (xy 329.729978 -399.869599) (xy 329.711418 -399.877189)
			(xy 329.703938 -399.883884) (xy 329.68819 -399.899632) (xy 329.681339 -399.907028) (xy 329.673602 -399.925627)
			(xy 329.673204 -399.9357) (xy 329.673204 -400.633946) (xy 332.590648 -400.633946) (xy 332.591134 -400.606695)
			(xy 332.59889 -400.552747) (xy 332.614245 -400.500452) (xy 332.636887 -400.450875) (xy 332.666353 -400.405025)
			(xy 332.702044 -400.363834) (xy 332.743235 -400.328143) (xy 332.789085 -400.298677) (xy 332.838662 -400.276035)
			(xy 332.890957 -400.26068) (xy 332.944905 -400.252924) (xy 332.999407 -400.252924) (xy 332.99956 -400.252946)
			(xy 334.65008 -400.252946) (xy 334.65008 -399.998184) (xy 334.659224 -399.998184) (xy 334.669235 -399.997731)
			(xy 334.687731 -399.990061) (xy 334.701883 -399.975897) (xy 334.709539 -399.957396) (xy 334.710024 -399.947384)
			(xy 334.710024 -399.783808) (xy 334.710427 -399.773784) (xy 334.718098 -399.755263) (xy 334.732276 -399.741089)
			(xy 334.7508 -399.733423) (xy 334.760824 -399.733008) (xy 335.268824 -399.733008) (xy 335.278834 -399.733468)
			(xy 335.297328 -399.741137) (xy 335.311481 -399.755299) (xy 335.319138 -399.773797) (xy 335.319624 -399.783808)
			(xy 335.319624 -399.998184) (xy 335.328768 -399.998184) (xy 335.338785 -399.998645) (xy 335.357298 -400.006302)
			(xy 335.371471 -400.020461) (xy 335.379145 -400.038967) (xy 335.379568 -400.048984) (xy 335.379568 -400.252946)
			(xy 335.379001 -400.275553) (xy 335.369479 -400.319753) (xy 335.350871 -400.360961) (xy 335.32401 -400.397331)
			(xy 335.307432 -400.412712) (xy 335.300574 -400.418808) (xy 335.291938 -400.43481) (xy 335.281778 -400.50974)
			(xy 335.280911 -400.518623) (xy 335.284667 -400.536056) (xy 335.289144 -400.543776) (xy 335.289398 -400.543776)
			(xy 335.289398 -400.544284) (xy 335.301444 -400.563652) (xy 335.320513 -400.605082) (xy 335.333465 -400.648813)
			(xy 335.340034 -400.693946) (xy 335.340452 -400.71675) (xy 335.339962 -400.741739) (xy 335.332143 -400.791102)
			(xy 335.316699 -400.838634) (xy 335.294009 -400.883166) (xy 335.264633 -400.923599) (xy 335.229293 -400.958939)
			(xy 335.18886 -400.988315) (xy 335.144328 -401.011005) (xy 335.096796 -401.026449) (xy 335.047433 -401.034268)
			(xy 334.997455 -401.034268) (xy 334.948092 -401.026449) (xy 334.90056 -401.011005) (xy 334.856028 -400.988315)
			(xy 334.815595 -400.958939) (xy 334.780255 -400.923599) (xy 334.750879 -400.883166) (xy 334.728189 -400.838634)
			(xy 334.712745 -400.791102) (xy 334.704926 -400.741739) (xy 334.704436 -400.71675) (xy 334.70511 -400.687549)
			(xy 334.715761 -400.630126) (xy 334.736713 -400.575612) (xy 334.751426 -400.55038) (xy 334.755896 -400.542384)
			(xy 334.759413 -400.524419) (xy 334.758284 -400.515328) (xy 334.74533 -400.43989) (xy 334.73644 -400.424396)
			(xy 334.729328 -400.418554) (xy 334.72882 -400.418046) (xy 334.714384 -400.405815) (xy 334.689718 -400.377127)
			(xy 334.670485 -400.344546) (xy 334.657287 -400.309089) (xy 334.650533 -400.271862) (xy 334.65008 -400.252946)
			(xy 332.99956 -400.252946) (xy 333.053355 -400.26068) (xy 333.10565 -400.276035) (xy 333.155227 -400.298677)
			(xy 333.201077 -400.328143) (xy 333.242268 -400.363834) (xy 333.277959 -400.405025) (xy 333.307425 -400.450875)
			(xy 333.330067 -400.500452) (xy 333.345422 -400.552747) (xy 333.353178 -400.606695) (xy 333.353664 -400.633946)
			(xy 333.353156 -400.653504) (xy 333.353156 -400.653758) (xy 333.353152 -400.663694) (xy 333.35982 -400.682388)
			(xy 333.36611 -400.69008) (xy 333.420974 -400.75104) (xy 333.439262 -400.759676) (xy 333.449422 -400.760184)
			(xy 333.48097 -400.762389) (xy 333.543069 -400.774338) (xy 333.602934 -400.794718) (xy 333.659425 -400.823143)
			(xy 333.711467 -400.85907) (xy 333.75807 -400.901817) (xy 333.798348 -400.950571) (xy 333.831533 -401.004403)
			(xy 333.856995 -401.06229) (xy 333.874249 -401.123129) (xy 333.882967 -401.185765) (xy 333.883508 -401.217384)
			(xy 333.883018 -401.247352) (xy 333.875195 -401.306774) (xy 333.859682 -401.364667) (xy 333.836746 -401.42004)
			(xy 333.806779 -401.471946) (xy 333.770292 -401.519496) (xy 333.727912 -401.561876) (xy 333.680362 -401.598363)
			(xy 333.628456 -401.62833) (xy 333.573083 -401.651266) (xy 333.51519 -401.666779) (xy 333.455768 -401.674602)
			(xy 333.395832 -401.674602) (xy 333.33641 -401.666779) (xy 333.278517 -401.651266) (xy 333.223144 -401.62833)
			(xy 333.171238 -401.598363) (xy 333.123688 -401.561876) (xy 333.081308 -401.519496) (xy 333.044821 -401.471946)
			(xy 333.014854 -401.42004) (xy 332.991918 -401.364667) (xy 332.976405 -401.306774) (xy 332.968582 -401.247352)
			(xy 332.968092 -401.217384) (xy 332.968092 -401.21713) (xy 332.968378 -401.194564) (xy 332.972835 -401.149652)
			(xy 332.976982 -401.127468) (xy 332.978462 -401.117565) (xy 332.974522 -401.097951) (xy 332.969362 -401.089368)
			(xy 332.929738 -401.029932) (xy 332.923798 -401.021757) (xy 332.907041 -401.010492) (xy 332.897226 -401.008088)
			(xy 332.868782 -401.001828) (xy 332.814085 -400.98183) (xy 332.763061 -400.953754) (xy 332.716895 -400.918251)
			(xy 332.676659 -400.876147) (xy 332.643287 -400.828419) (xy 332.617553 -400.776174) (xy 332.600056 -400.720626)
			(xy 332.591201 -400.663065) (xy 332.590648 -400.633946) (xy 329.673204 -400.633946) (xy 329.673204 -401.043902)
			(xy 329.673628 -401.053972) (xy 329.681343 -401.072575) (xy 329.68819 -401.07997) (xy 329.826366 -401.217892)
			(xy 329.833217 -401.225289) (xy 329.84096 -401.243887) (xy 329.841352 -401.25396) (xy 329.841352 -401.674838)
			(xy 335.962244 -401.674838) (xy 335.962244 -400.811238) (xy 335.962668 -400.785718) (xy 335.969458 -400.735132)
			(xy 335.982935 -400.685903) (xy 336.002858 -400.638912) (xy 336.028872 -400.594999) (xy 336.060511 -400.554948)
			(xy 336.078576 -400.536918) (xy 336.08518 -400.530568) (xy 336.093054 -400.513804) (xy 336.099912 -400.42846)
			(xy 336.094832 -400.41068) (xy 336.089244 -400.403314) (xy 336.074395 -400.382565) (xy 336.050759 -400.337352)
			(xy 336.034657 -400.28894) (xy 336.026504 -400.238577) (xy 336.025998 -400.213068) (xy 336.025998 -400.212814)
			(xy 336.026488 -400.187825) (xy 336.034307 -400.138462) (xy 336.049751 -400.09093) (xy 336.072441 -400.046398)
			(xy 336.101817 -400.005965) (xy 336.137157 -399.970625) (xy 336.17759 -399.941249) (xy 336.222122 -399.918559)
			(xy 336.269654 -399.903115) (xy 336.319017 -399.895296) (xy 336.368995 -399.895296) (xy 336.418358 -399.903115)
			(xy 336.46589 -399.918559) (xy 336.510422 -399.941249) (xy 336.550855 -399.970625) (xy 336.586195 -400.005965)
			(xy 336.615571 -400.046398) (xy 336.638261 -400.09093) (xy 336.653705 -400.138462) (xy 336.661524 -400.187825)
			(xy 336.662014 -400.212814) (xy 336.662014 -400.213068) (xy 336.661518 -400.238577) (xy 336.653341 -400.288936)
			(xy 336.63724 -400.337347) (xy 336.613626 -400.382572) (xy 336.598768 -400.403314) (xy 336.59318 -400.41068)
			(xy 336.5881 -400.42846) (xy 336.594958 -400.513804) (xy 336.602832 -400.530568) (xy 336.609436 -400.536918)
			(xy 336.627467 -400.55498) (xy 336.659098 -400.59503) (xy 336.68511 -400.638939) (xy 336.705039 -400.685922)
			(xy 336.718528 -400.735142) (xy 336.725338 -400.785721) (xy 336.725768 -400.811238) (xy 336.725768 -401.674838)
			(xy 337.16214 -401.674838) (xy 337.16214 -400.811238) (xy 337.162565 -400.785718) (xy 337.169355 -400.735132)
			(xy 337.182832 -400.685903) (xy 337.202755 -400.638912) (xy 337.228768 -400.594999) (xy 337.260407 -400.554948)
			(xy 337.278472 -400.536918) (xy 337.28533 -400.530568) (xy 337.293204 -400.513804) (xy 337.2993 -400.43735)
			(xy 337.299647 -400.428285) (xy 337.294705 -400.410845) (xy 337.289648 -400.403314) (xy 337.289394 -400.40306)
			(xy 337.274533 -400.382319) (xy 337.250907 -400.3371) (xy 337.23481 -400.288687) (xy 337.226656 -400.238324)
			(xy 337.226148 -400.212814) (xy 337.226638 -400.187825) (xy 337.234457 -400.138462) (xy 337.249901 -400.09093)
			(xy 337.272591 -400.046398) (xy 337.301967 -400.005965) (xy 337.337307 -399.970625) (xy 337.37774 -399.941249)
			(xy 337.422272 -399.918559) (xy 337.469804 -399.903115) (xy 337.519167 -399.895296) (xy 337.569145 -399.895296)
			(xy 337.618508 -399.903115) (xy 337.66604 -399.918559) (xy 337.710572 -399.941249) (xy 337.751005 -399.970625)
			(xy 337.786345 -400.005965) (xy 337.815721 -400.046398) (xy 337.838411 -400.09093) (xy 337.853855 -400.138462)
			(xy 337.861674 -400.187825) (xy 337.862164 -400.212814) (xy 337.861647 -400.238367) (xy 337.85346 -400.288812)
			(xy 337.8373 -400.337295) (xy 337.813585 -400.382564) (xy 337.798664 -400.403314) (xy 337.793076 -400.41068)
			(xy 337.787996 -400.42846) (xy 337.794092 -400.504914) (xy 337.795195 -400.513912) (xy 337.802863 -400.53032)
			(xy 337.809078 -400.536918) (xy 337.809332 -400.537172) (xy 337.827385 -400.555184) (xy 337.858999 -400.595201)
			(xy 337.884999 -400.639073) (xy 337.904922 -400.686018) (xy 337.918411 -400.735199) (xy 337.925228 -400.785739)
			(xy 337.925664 -400.811238) (xy 337.925664 -401.674838) (xy 338.362544 -401.674838) (xy 338.362544 -400.81073)
			(xy 338.362971 -400.785262) (xy 338.369774 -400.734781) (xy 338.383237 -400.685655) (xy 338.403119 -400.638759)
			(xy 338.429067 -400.594926) (xy 338.460619 -400.554938) (xy 338.478622 -400.536918) (xy 338.485226 -400.530568)
			(xy 338.4931 -400.513804) (xy 338.499958 -400.42846) (xy 338.494878 -400.41068) (xy 338.48929 -400.403314)
			(xy 338.474434 -400.38257) (xy 338.450801 -400.337354) (xy 338.434702 -400.288941) (xy 338.42655 -400.238578)
			(xy 338.426044 -400.213068) (xy 338.426044 -400.212814) (xy 338.426534 -400.187825) (xy 338.434353 -400.138462)
			(xy 338.449797 -400.09093) (xy 338.472487 -400.046398) (xy 338.501863 -400.005965) (xy 338.537203 -399.970625)
			(xy 338.577636 -399.941249) (xy 338.622168 -399.918559) (xy 338.6697 -399.903115) (xy 338.719063 -399.895296)
			(xy 338.769041 -399.895296) (xy 338.818404 -399.903115) (xy 338.865936 -399.918559) (xy 338.910468 -399.941249)
			(xy 338.950901 -399.970625) (xy 338.986241 -400.005965) (xy 339.015617 -400.046398) (xy 339.038307 -400.09093)
			(xy 339.053751 -400.138462) (xy 339.06157 -400.187825) (xy 339.06206 -400.212814) (xy 339.06206 -400.213068)
			(xy 339.061555 -400.238576) (xy 339.05338 -400.288935) (xy 339.037281 -400.337346) (xy 339.01367 -400.382571)
			(xy 338.998814 -400.403314) (xy 338.993226 -400.41068) (xy 338.988146 -400.42846) (xy 338.995004 -400.513804)
			(xy 339.002878 -400.530568) (xy 339.009482 -400.536918) (xy 339.027486 -400.554935) (xy 339.059026 -400.59493)
			(xy 339.084966 -400.638766) (xy 339.104844 -400.685662) (xy 339.118309 -400.734785) (xy 339.125119 -400.785263)
			(xy 339.12556 -400.81073) (xy 339.12556 -401.674838) (xy 339.125551 -401.675346) (xy 339.56244 -401.675346)
			(xy 339.56244 -400.81073) (xy 339.562868 -400.785262) (xy 339.569671 -400.734781) (xy 339.583134 -400.685655)
			(xy 339.603016 -400.638759) (xy 339.628964 -400.594926) (xy 339.660515 -400.554938) (xy 339.678518 -400.536918)
			(xy 339.685122 -400.530568) (xy 339.692996 -400.513804) (xy 339.699854 -400.42846) (xy 339.694774 -400.41068)
			(xy 339.689186 -400.403314) (xy 339.67433 -400.38257) (xy 339.650697 -400.337354) (xy 339.634598 -400.288942)
			(xy 339.626446 -400.238578) (xy 339.62594 -400.213068) (xy 339.62594 -400.212814) (xy 339.62643 -400.187825)
			(xy 339.634249 -400.138462) (xy 339.649693 -400.09093) (xy 339.672383 -400.046398) (xy 339.701759 -400.005965)
			(xy 339.737099 -399.970625) (xy 339.777532 -399.941249) (xy 339.822064 -399.918559) (xy 339.869596 -399.903115)
			(xy 339.918959 -399.895296) (xy 339.968937 -399.895296) (xy 340.0183 -399.903115) (xy 340.065832 -399.918559)
			(xy 340.110364 -399.941249) (xy 340.150797 -399.970625) (xy 340.186137 -400.005965) (xy 340.215513 -400.046398)
			(xy 340.238203 -400.09093) (xy 340.253647 -400.138462) (xy 340.261466 -400.187825) (xy 340.261956 -400.212814)
			(xy 340.261956 -400.213068) (xy 340.261452 -400.238576) (xy 340.253276 -400.288935) (xy 340.237177 -400.337346)
			(xy 340.213566 -400.382571) (xy 340.19871 -400.403314) (xy 340.193122 -400.41068) (xy 340.188042 -400.42846)
			(xy 340.1949 -400.513804) (xy 340.202774 -400.530568) (xy 340.209378 -400.536918) (xy 340.227382 -400.554936)
			(xy 340.258922 -400.594931) (xy 340.284861 -400.638766) (xy 340.30474 -400.685662) (xy 340.318205 -400.734785)
			(xy 340.325015 -400.785263) (xy 340.325456 -400.81073) (xy 340.325456 -401.675346) (xy 340.324979 -401.703744)
			(xy 340.316566 -401.759912) (xy 340.299904 -401.814208) (xy 340.275362 -401.865427) (xy 340.243485 -401.912433)
			(xy 340.224618 -401.933664) (xy 340.218759 -401.940601) (xy 340.21185 -401.957378) (xy 340.211156 -401.96643)
			(xy 340.21014 -401.997418) (xy 340.210185 -402.00657) (xy 340.216059 -402.023892) (xy 340.22157 -402.0312)
			(xy 340.236915 -402.050547) (xy 340.262688 -402.092667) (xy 340.282466 -402.137914) (xy 340.295878 -402.185438)
			(xy 340.302673 -402.234348) (xy 340.303104 -402.259038) (xy 340.302602 -402.285915) (xy 340.29459 -402.33907)
			(xy 340.278746 -402.390436) (xy 340.255422 -402.438868) (xy 340.225141 -402.483282) (xy 340.188579 -402.522687)
			(xy 340.146551 -402.556203) (xy 340.099998 -402.58308) (xy 340.049959 -402.602719) (xy 339.997552 -402.61468)
			(xy 339.943948 -402.618698) (xy 339.890344 -402.61468) (xy 339.837937 -402.602719) (xy 339.787898 -402.58308)
			(xy 339.741345 -402.556203) (xy 339.699317 -402.522687) (xy 339.662755 -402.483282) (xy 339.632474 -402.438868)
			(xy 339.60915 -402.390436) (xy 339.593306 -402.33907) (xy 339.585294 -402.285915) (xy 339.584792 -402.259038)
			(xy 339.585193 -402.234344) (xy 339.591949 -402.185422) (xy 339.605353 -402.137888) (xy 339.625151 -402.092643)
			(xy 339.650969 -402.050542) (xy 339.666326 -402.0312) (xy 339.671805 -402.023879) (xy 339.677653 -402.006563)
			(xy 339.677756 -401.997418) (xy 339.67674 -401.96643) (xy 339.676099 -401.957366) (xy 339.669182 -401.940573)
			(xy 339.663278 -401.933664) (xy 339.644461 -401.912399) (xy 339.612641 -401.865373) (xy 339.588126 -401.814158)
			(xy 339.571453 -401.759881) (xy 339.562991 -401.703735) (xy 339.56244 -401.675346) (xy 339.125551 -401.675346)
			(xy 339.125025 -401.703992) (xy 339.116153 -401.761622) (xy 339.098621 -401.817232) (xy 339.072836 -401.86953)
			(xy 339.0394 -401.917299) (xy 339.019642 -401.938744) (xy 339.013479 -401.945823) (xy 339.006325 -401.963161)
			(xy 339.005672 -401.972526) (xy 339.003894 -402.041106) (xy 339.004039 -402.050362) (xy 339.010172 -402.067815)
			(xy 339.015832 -402.075142) (xy 339.01634 -402.07565) (xy 339.032662 -402.095277) (xy 339.060132 -402.138301)
			(xy 339.081233 -402.184782) (xy 339.095539 -402.233782) (xy 339.102762 -402.284315) (xy 339.103208 -402.309838)
			(xy 339.102706 -402.336715) (xy 339.094694 -402.38987) (xy 339.07885 -402.441236) (xy 339.055526 -402.489668)
			(xy 339.025245 -402.534082) (xy 338.988683 -402.573487) (xy 338.946655 -402.607003) (xy 338.900102 -402.63388)
			(xy 338.850063 -402.653519) (xy 338.797656 -402.66548) (xy 338.744052 -402.669498) (xy 338.690448 -402.66548)
			(xy 338.638041 -402.653519) (xy 338.588002 -402.63388) (xy 338.541449 -402.607003) (xy 338.499421 -402.573487)
			(xy 338.462859 -402.534082) (xy 338.432578 -402.489668) (xy 338.409254 -402.441236) (xy 338.39341 -402.38987)
			(xy 338.385398 -402.336715) (xy 338.384896 -402.309838) (xy 338.385357 -402.28428) (xy 338.392594 -402.23368)
			(xy 338.406942 -402.18462) (xy 338.428108 -402.138093) (xy 338.455666 -402.095043) (xy 338.472018 -402.075396)
			(xy 338.472272 -402.075142) (xy 338.477936 -402.067821) (xy 338.484047 -402.050362) (xy 338.48421 -402.041106)
			(xy 338.482178 -401.962874) (xy 338.475066 -401.945856) (xy 338.468462 -401.938744) (xy 338.44872 -401.917286)
			(xy 338.415285 -401.869519) (xy 338.389502 -401.817225) (xy 338.37197 -401.761617) (xy 338.363099 -401.703991)
			(xy 338.362544 -401.674838) (xy 337.925664 -401.674838) (xy 337.925169 -401.702713) (xy 337.917061 -401.75787)
			(xy 337.901008 -401.811259) (xy 337.877354 -401.861742) (xy 337.846601 -401.908243) (xy 337.828382 -401.929346)
			(xy 337.82254 -401.93595) (xy 337.815682 -401.952714) (xy 337.81365 -402.027136) (xy 337.813758 -402.036042)
			(xy 337.819357 -402.052935) (xy 337.824572 -402.060156) (xy 337.824826 -402.06041) (xy 337.83959 -402.079589)
			(xy 337.864419 -402.121135) (xy 337.883457 -402.165633) (xy 337.89636 -402.212282) (xy 337.902895 -402.260238)
			(xy 337.903312 -402.284438) (xy 337.90281 -402.311334) (xy 337.894792 -402.364526) (xy 337.878936 -402.415929)
			(xy 337.855597 -402.464395) (xy 337.825294 -402.508841) (xy 337.788706 -402.548274) (xy 337.746649 -402.581813)
			(xy 337.700063 -402.608709) (xy 337.649989 -402.628362) (xy 337.597544 -402.640332) (xy 337.543902 -402.644352)
			(xy 337.49026 -402.640332) (xy 337.437815 -402.628362) (xy 337.387741 -402.608709) (xy 337.341155 -402.581813)
			(xy 337.299098 -402.548274) (xy 337.26251 -402.508841) (xy 337.232207 -402.464395) (xy 337.208868 -402.415929)
			(xy 337.193012 -402.364526) (xy 337.184994 -402.311334) (xy 337.184492 -402.284438) (xy 337.184896 -402.260235)
			(xy 337.191397 -402.212268) (xy 337.204286 -402.165609) (xy 337.22333 -402.121107) (xy 337.248183 -402.079568)
			(xy 337.262978 -402.06041) (xy 337.263232 -402.060156) (xy 337.268504 -402.052968) (xy 337.274088 -402.03605)
			(xy 337.274154 -402.027136) (xy 337.272122 -401.952714) (xy 337.265264 -401.93595) (xy 337.259422 -401.929346)
			(xy 337.241226 -401.908225) (xy 337.210478 -401.861726) (xy 337.186824 -401.811247) (xy 337.170768 -401.757863)
			(xy 337.16265 -401.702711) (xy 337.16214 -401.674838) (xy 336.725768 -401.674838) (xy 336.725272 -401.702713)
			(xy 336.717164 -401.75787) (xy 336.701112 -401.811259) (xy 336.677457 -401.861742) (xy 336.646705 -401.908243)
			(xy 336.628486 -401.929346) (xy 336.622644 -401.93595) (xy 336.615786 -401.952714) (xy 336.613754 -402.027136)
			(xy 336.613861 -402.036042) (xy 336.61946 -402.052936) (xy 336.624676 -402.060156) (xy 336.62493 -402.06041)
			(xy 336.639694 -402.079589) (xy 336.664524 -402.121135) (xy 336.683561 -402.165633) (xy 336.696464 -402.212282)
			(xy 336.702999 -402.260238) (xy 336.703416 -402.284438) (xy 336.702914 -402.311334) (xy 336.694896 -402.364526)
			(xy 336.67904 -402.415929) (xy 336.655701 -402.464395) (xy 336.625398 -402.508841) (xy 336.58881 -402.548274)
			(xy 336.546753 -402.581813) (xy 336.500167 -402.608709) (xy 336.450093 -402.628362) (xy 336.397648 -402.640332)
			(xy 336.344006 -402.644352) (xy 336.290364 -402.640332) (xy 336.237919 -402.628362) (xy 336.187845 -402.608709)
			(xy 336.141259 -402.581813) (xy 336.099202 -402.548274) (xy 336.062614 -402.508841) (xy 336.032311 -402.464395)
			(xy 336.008972 -402.415929) (xy 335.993116 -402.364526) (xy 335.985098 -402.311334) (xy 335.984596 -402.284438)
			(xy 335.984999 -402.260235) (xy 335.9915 -402.212268) (xy 336.00439 -402.165609) (xy 336.023434 -402.121107)
			(xy 336.048287 -402.079568) (xy 336.063082 -402.06041) (xy 336.063336 -402.060156) (xy 336.068608 -402.052969)
			(xy 336.074192 -402.03605) (xy 336.074258 -402.027136) (xy 336.072226 -401.952714) (xy 336.065368 -401.93595)
			(xy 336.059526 -401.929346) (xy 336.041315 -401.908238) (xy 336.010573 -401.861733) (xy 335.986923 -401.811251)
			(xy 335.97087 -401.757865) (xy 335.962754 -401.702712) (xy 335.962244 -401.674838) (xy 329.841352 -401.674838)
			(xy 329.841352 -401.866608) (xy 329.84186 -401.867116) (xy 329.84186 -401.89531) (xy 329.842287 -401.905378)
			(xy 329.85001 -401.923974) (xy 329.856846 -401.931378) (xy 330.278486 -402.353272) (xy 330.285322 -402.360674)
			(xy 330.293033 -402.379272) (xy 330.293472 -402.38934) (xy 330.293472 -402.763986) (xy 334.657428 -402.763986)
			(xy 334.657428 -402.70405) (xy 334.665251 -402.644628) (xy 334.680764 -402.586735) (xy 334.7037 -402.531362)
			(xy 334.733667 -402.479456) (xy 334.770154 -402.431906) (xy 334.812534 -402.389526) (xy 334.860084 -402.353039)
			(xy 334.91199 -402.323072) (xy 334.967363 -402.300136) (xy 335.025256 -402.284623) (xy 335.084678 -402.2768)
			(xy 335.144614 -402.2768) (xy 335.204036 -402.284623) (xy 335.261929 -402.300136) (xy 335.317302 -402.323072)
			(xy 335.369208 -402.353039) (xy 335.416758 -402.389526) (xy 335.459138 -402.431906) (xy 335.495625 -402.479456)
			(xy 335.525592 -402.531362) (xy 335.548528 -402.586735) (xy 335.564041 -402.644628) (xy 335.571864 -402.70405)
			(xy 335.572354 -402.734018) (xy 335.571864 -402.763986) (xy 335.564041 -402.823408) (xy 335.548528 -402.881301)
			(xy 335.525592 -402.936674) (xy 335.495625 -402.98858) (xy 335.459138 -403.03613) (xy 335.416758 -403.07851)
			(xy 335.369208 -403.114997) (xy 335.317302 -403.144964) (xy 335.261929 -403.1679) (xy 335.204036 -403.183413)
			(xy 335.144614 -403.191236) (xy 335.084678 -403.191236) (xy 335.025256 -403.183413) (xy 334.967363 -403.1679)
			(xy 334.91199 -403.144964) (xy 334.860084 -403.114997) (xy 334.812534 -403.07851) (xy 334.770154 -403.03613)
			(xy 334.733667 -402.98858) (xy 334.7037 -402.936674) (xy 334.680764 -402.881301) (xy 334.665251 -402.823408)
			(xy 334.657428 -402.763986) (xy 330.293472 -402.763986) (xy 330.293472 -403.193504) (xy 330.293048 -403.203573)
			(xy 330.285329 -403.222174) (xy 330.278486 -403.229572) (xy 330.27493 -403.233128) (xy 330.268085 -403.240527)
			(xy 330.260356 -403.259125) (xy 330.259944 -403.269196) (xy 330.259944 -404.923201) (xy 354.337614 -404.923201)
			(xy 354.337614 -404.859279) (xy 354.345625 -404.795861) (xy 354.361522 -404.733947) (xy 354.385054 -404.674514)
			(xy 354.415848 -404.618499) (xy 354.453421 -404.566784) (xy 354.497178 -404.520187) (xy 354.546431 -404.479442)
			(xy 354.600402 -404.445191) (xy 354.658241 -404.417974) (xy 354.719034 -404.398221) (xy 354.781824 -404.386243)
			(xy 354.84562 -404.38223) (xy 354.909416 -404.386243) (xy 354.972206 -404.398221) (xy 355.032999 -404.417974)
			(xy 355.090838 -404.445191) (xy 355.144809 -404.479442) (xy 355.194062 -404.520187) (xy 355.237819 -404.566784)
			(xy 355.275392 -404.618499) (xy 355.306186 -404.674514) (xy 355.329718 -404.733947) (xy 355.345615 -404.795861)
			(xy 355.353626 -404.859279) (xy 355.354128 -404.89124) (xy 355.353626 -404.923201) (xy 355.345615 -404.986619)
			(xy 355.329718 -405.048533) (xy 355.306186 -405.107966) (xy 355.275392 -405.163981) (xy 355.237819 -405.215696)
			(xy 355.194062 -405.262293) (xy 355.144809 -405.303038) (xy 355.090838 -405.337289) (xy 355.032999 -405.364506)
			(xy 354.972206 -405.384259) (xy 354.909416 -405.396237) (xy 354.84562 -405.400251) (xy 354.781824 -405.396237)
			(xy 354.719034 -405.384259) (xy 354.658241 -405.364506) (xy 354.600402 -405.337289) (xy 354.546431 -405.303038)
			(xy 354.497178 -405.262293) (xy 354.453421 -405.215696) (xy 354.415848 -405.163981) (xy 354.385054 -405.107966)
			(xy 354.361522 -405.048533) (xy 354.345625 -404.986619) (xy 354.337614 -404.923201) (xy 330.259944 -404.923201)
			(xy 330.259944 -405.208994) (xy 330.260367 -405.219064) (xy 330.268085 -405.237666) (xy 330.27493 -405.245062)
			(xy 331.555344 -406.525476) (xy 331.562744 -406.532318) (xy 331.581342 -406.540041) (xy 331.591412 -406.540462)
		)
		(stroke
			(width 0)
			(type solid)
		)
		(fill yes)
		(layer "B.Cu")
		(net "P0V9_CPU0_RT1_2A")
	)
	(gr_poly
		(pts
			(xy 98.00209 -398.158462) (xy 98.01216 -398.15804) (xy 98.030764 -398.150324) (xy 98.038158 -398.143476)
			(xy 98.246692 -397.934942) (xy 98.248724 -397.896842) (xy 98.236786 -397.881602) (xy 98.221367 -397.861347)
			(xy 98.195465 -397.817525) (xy 98.175627 -397.770645) (xy 98.162205 -397.721541) (xy 98.155439 -397.671088)
			(xy 98.154998 -397.645636) (xy 98.155459 -397.618382) (xy 98.163212 -397.564427) (xy 98.178565 -397.512125)
			(xy 98.201205 -397.462541) (xy 98.230672 -397.416684) (xy 98.266366 -397.375487) (xy 98.30756 -397.33979)
			(xy 98.353415 -397.31032) (xy 98.402997 -397.287675) (xy 98.455298 -397.272318) (xy 98.509252 -397.264561)
			(xy 98.536506 -397.264128) (xy 98.561959 -397.264551) (xy 98.612411 -397.271326) (xy 98.661513 -397.284754)
			(xy 98.708392 -397.304597) (xy 98.752214 -397.330501) (xy 98.772472 -397.345916) (xy 98.787712 -397.357854)
			(xy 98.825812 -397.355822) (xy 98.942144 -397.23949) (xy 98.948954 -397.232168) (xy 98.956686 -397.213745)
			(xy 98.956748 -397.193765) (xy 98.95332 -397.184372) (xy 98.912426 -397.083534) (xy 98.88728 -397.066262)
			(xy 98.87204 -397.066008) (xy 98.839071 -397.064994) (xy 98.773798 -397.055492) (xy 98.710302 -397.03763)
			(xy 98.649649 -397.011707) (xy 98.592858 -396.978159) (xy 98.540881 -396.937548) (xy 98.494593 -396.890557)
			(xy 98.454769 -396.837974) (xy 98.42208 -396.780684) (xy 98.397074 -396.719647) (xy 98.38017 -396.655889)
			(xy 98.371653 -396.59048) (xy 98.371152 -396.5575) (xy 98.371616 -396.526768) (xy 98.379024 -396.465752)
			(xy 98.393732 -396.406074) (xy 98.415527 -396.348604) (xy 98.444089 -396.29418) (xy 98.479003 -396.243595)
			(xy 98.519759 -396.197588) (xy 98.565764 -396.156828) (xy 98.616346 -396.12191) (xy 98.670768 -396.093343)
			(xy 98.728236 -396.071544) (xy 98.787913 -396.056831) (xy 98.848928 -396.049418) (xy 98.87966 -396.048992)
			(xy 98.912636 -396.049519) (xy 98.978035 -396.058052) (xy 99.041782 -396.074967) (xy 99.102807 -396.09998)
			(xy 99.160088 -396.132672) (xy 99.212662 -396.172493) (xy 99.259647 -396.218776) (xy 99.300256 -396.270745)
			(xy 99.333806 -396.327526) (xy 99.359736 -396.388168) (xy 99.377609 -396.451653) (xy 99.387125 -396.516916)
			(xy 99.388168 -396.54988) (xy 99.388422 -396.56512) (xy 99.405694 -396.590266) (xy 99.506532 -396.63116)
			(xy 99.515946 -396.634442) (xy 99.535862 -396.634323) (xy 99.554247 -396.626663) (xy 99.56165 -396.619984)
			(xy 101.79939 -394.382244) (xy 101.806229 -394.374843) (xy 101.813945 -394.356245) (xy 101.814376 -394.346176)
			(xy 101.814376 -392.984228) (xy 101.816916 -392.981688) (xy 101.816916 -392.694922) (xy 101.817354 -392.684858)
			(xy 101.82509 -392.666276) (xy 101.831902 -392.658854) (xy 102.129844 -392.360912) (xy 102.136698 -392.353517)
			(xy 102.144446 -392.334918) (xy 102.14483 -392.324844) (xy 102.14483 -389.513572) (xy 102.144403 -389.503503)
			(xy 102.136684 -389.484903) (xy 102.129844 -389.477504) (xy 102.100634 -389.448294) (xy 102.093232 -389.441458)
			(xy 102.074634 -389.433749) (xy 102.064566 -389.433308) (xy 101.08819 -389.433308) (xy 101.07812 -389.432884)
			(xy 101.059518 -389.425167) (xy 101.052122 -389.418322) (xy 100.818188 -389.184388) (xy 100.809648 -389.176575)
			(xy 100.78783 -389.168912) (xy 100.776278 -389.169656) (xy 100.696776 -389.179308) (xy 100.68541 -389.181154)
			(xy 100.66596 -389.193442) (xy 100.659438 -389.20293) (xy 100.659438 -389.203184) (xy 100.645082 -389.22575)
			(xy 100.610261 -389.266342) (xy 100.569361 -389.3008) (xy 100.546662 -389.314944) (xy 100.534978 -389.321802)
			(xy 100.522024 -389.344916) (xy 100.522024 -389.446008) (xy 100.522418 -389.454662) (xy 100.528268 -389.470957)
			(xy 100.539199 -389.484383) (xy 100.546408 -389.489188) (xy 100.546662 -389.489442) (xy 100.567372 -389.502318)
			(xy 100.605111 -389.533202) (xy 100.637903 -389.569296) (xy 100.665034 -389.609817) (xy 100.685917 -389.653884)
			(xy 100.700098 -389.700542) (xy 100.70727 -389.748777) (xy 100.707698 -389.77316) (xy 100.707282 -389.796932)
			(xy 100.700464 -389.843986) (xy 100.686979 -389.889579) (xy 100.667103 -389.93277) (xy 100.641246 -389.972669)
			(xy 100.62591 -389.990838) (xy 100.620229 -389.99796) (xy 100.613851 -390.01501) (xy 100.613464 -390.024112)
			(xy 100.613464 -390.055608) (xy 100.613845 -390.06471) (xy 100.620232 -390.081757) (xy 100.62591 -390.088882)
			(xy 100.641256 -390.107043) (xy 100.667117 -390.14694) (xy 100.686989 -390.190133) (xy 100.700462 -390.23573)
			(xy 100.707257 -390.282787) (xy 100.707698 -390.30656) (xy 100.707146 -390.334166) (xy 100.697977 -390.388613)
			(xy 100.679889 -390.440778) (xy 100.653383 -390.489213) (xy 100.619196 -390.532569) (xy 100.578281 -390.569641)
			(xy 100.555298 -390.584944) (xy 100.547796 -390.590226) (xy 100.536857 -390.604939) (xy 100.533962 -390.613646)
			(xy 100.525326 -390.643618) (xy 100.523189 -390.652509) (xy 100.524632 -390.670724) (xy 100.52812 -390.679178)
			(xy 100.537902 -390.701199) (xy 100.55171 -390.747363) (xy 100.558685 -390.79504) (xy 100.559108 -390.819132)
			(xy 100.558598 -390.845119) (xy 100.550468 -390.896454) (xy 100.534407 -390.945884) (xy 100.510811 -390.992194)
			(xy 100.480261 -391.034242) (xy 100.44351 -391.070993) (xy 100.401462 -391.101543) (xy 100.355152 -391.125139)
			(xy 100.305722 -391.1412) (xy 100.254387 -391.14933) (xy 100.202413 -391.14933) (xy 100.151078 -391.1412)
			(xy 100.101648 -391.125139) (xy 100.055338 -391.101543) (xy 100.01329 -391.070993) (xy 99.976539 -391.034242)
			(xy 99.945989 -390.992194) (xy 99.922393 -390.945884) (xy 99.906332 -390.896454) (xy 99.898202 -390.845119)
			(xy 99.897692 -390.819132) (xy 99.898245 -390.791526) (xy 99.907414 -390.73708) (xy 99.925503 -390.684915)
			(xy 99.95201 -390.636481) (xy 99.986196 -390.593125) (xy 100.027111 -390.556052) (xy 100.050092 -390.540748)
			(xy 100.057595 -390.535466) (xy 100.068534 -390.520753) (xy 100.071428 -390.512046) (xy 100.080064 -390.482074)
			(xy 100.0822 -390.473184) (xy 100.080754 -390.454969) (xy 100.07727 -390.446514) (xy 100.067489 -390.424493)
			(xy 100.053682 -390.378329) (xy 100.046708 -390.330652) (xy 100.046282 -390.30656) (xy 100.046697 -390.282787)
			(xy 100.053511 -390.235732) (xy 100.066994 -390.190137) (xy 100.086867 -390.146943) (xy 100.112721 -390.107041)
			(xy 100.12807 -390.088882) (xy 100.133747 -390.081759) (xy 100.140121 -390.064708) (xy 100.140516 -390.055608)
			(xy 100.140516 -390.024112) (xy 100.140139 -390.015009) (xy 100.133754 -389.997959) (xy 100.12807 -389.990838)
			(xy 100.11272 -389.972679) (xy 100.08685 -389.932784) (xy 100.066971 -389.889591) (xy 100.053492 -389.843994)
			(xy 100.046692 -389.796934) (xy 100.046282 -389.77316) (xy 100.046715 -389.748749) (xy 100.053888 -389.700458)
			(xy 100.068087 -389.653748) (xy 100.089002 -389.609634) (xy 100.116179 -389.569077) (xy 100.149026 -389.532958)
			(xy 100.18683 -389.502065) (xy 100.207572 -389.489188) (xy 100.219256 -389.48233) (xy 100.23221 -389.459216)
			(xy 100.23221 -389.358124) (xy 100.23182 -389.349469) (xy 100.225972 -389.333172) (xy 100.215036 -389.319749)
			(xy 100.207826 -389.314944) (xy 100.207572 -389.31469) (xy 100.186863 -389.301814) (xy 100.149127 -389.27093)
			(xy 100.11634 -389.234835) (xy 100.089214 -389.194314) (xy 100.068337 -389.150245) (xy 100.054163 -389.103588)
			(xy 100.047001 -389.055354) (xy 100.046536 -389.030972) (xy 100.047093 -389.003352) (xy 100.056272 -388.94888)
			(xy 100.07437 -388.896688) (xy 100.100884 -388.848227) (xy 100.135078 -388.804842) (xy 100.176003 -388.767739)
			(xy 100.198936 -388.752334) (xy 100.210366 -388.745222) (xy 100.222812 -388.721346) (xy 100.219256 -388.6073)
			(xy 100.20554 -388.584694) (xy 100.193602 -388.57809) (xy 100.171912 -388.565455) (xy 100.132277 -388.534655)
			(xy 100.09775 -388.498221) (xy 100.069123 -388.456989) (xy 100.047054 -388.411906) (xy 100.032048 -388.364006)
			(xy 100.024451 -388.314389) (xy 100.02393 -388.289292) (xy 100.02393 -388.289038) (xy 100.024267 -388.266924)
			(xy 100.030131 -388.223088) (xy 100.035614 -388.201662) (xy 100.037571 -388.193653) (xy 100.036787 -388.177195)
			(xy 100.03409 -388.169404) (xy 100.023168 -388.141972) (xy 100.019777 -388.134372) (xy 100.009017 -388.121689)
			(xy 100.002086 -388.11708) (xy 99.976752 -388.101188) (xy 99.930609 -388.063146) (xy 99.89053 -388.018759)
			(xy 99.857381 -387.968985) (xy 99.831873 -387.914894) (xy 99.814556 -387.857653) (xy 99.805805 -387.798494)
			(xy 99.805236 -387.768592) (xy 99.805754 -387.739539) (xy 99.814022 -387.682026) (xy 99.830388 -387.626273)
			(xy 99.854519 -387.573416) (xy 99.885924 -387.524529) (xy 99.923965 -387.480608) (xy 99.967867 -387.442545)
			(xy 100.016738 -387.411116) (xy 100.069584 -387.386958) (xy 100.125328 -387.370565) (xy 100.182838 -387.362269)
			(xy 100.21189 -387.361684) (xy 100.35032 -387.361684) (xy 100.360324 -387.361192) (xy 100.378806 -387.353529)
			(xy 100.392949 -387.339376) (xy 100.400599 -387.320888) (xy 100.40112 -387.310884) (xy 100.40112 -387.071108)
			(xy 100.400634 -387.061098) (xy 100.392976 -387.0426) (xy 100.378824 -387.028439) (xy 100.36033 -387.020772)
			(xy 100.35032 -387.020308) (xy 99.765104 -387.020308) (xy 99.755033 -387.019886) (xy 99.736427 -387.012174)
			(xy 99.729036 -387.005322) (xy 99.455986 -386.732272) (xy 99.448657 -386.72545) (xy 99.430213 -386.717696)
			(xy 99.410206 -386.717613) (xy 99.391698 -386.725212) (xy 99.384358 -386.732018) (xy 99.38385 -386.732526)
			(xy 99.372851 -386.743031) (xy 99.346604 -386.758377) (xy 99.317263 -386.766347) (xy 99.302062 -386.766816)
			(xy 99.120452 -386.766816) (xy 99.119944 -386.76707) (xy 99.10318 -386.76707) (xy 99.102672 -386.766816)
			(xy 98.921062 -386.766816) (xy 98.90605 -386.766321) (xy 98.877052 -386.758541) (xy 98.851056 -386.74352)
			(xy 98.829833 -386.722283) (xy 98.81483 -386.696277) (xy 98.807069 -386.667274) (xy 98.806508 -386.652262)
			(xy 98.806508 -386.538724) (xy 98.80473 -386.53212) (xy 98.799536 -386.511748) (xy 98.793937 -386.470082)
			(xy 98.793554 -386.449062) (xy 98.794316 -386.42671) (xy 98.795078 -386.41655) (xy 98.788728 -386.3975)
			(xy 98.727514 -386.32765) (xy 98.70948 -386.31876) (xy 98.69932 -386.318252) (xy 98.675239 -386.316272)
			(xy 98.628044 -386.30592) (xy 98.582978 -386.2885) (xy 98.541091 -386.264417) (xy 98.503362 -386.234235)
			(xy 98.470671 -386.198658) (xy 98.443781 -386.158516) (xy 98.42332 -386.114745) (xy 98.41611 -386.091684)
			(xy 98.414586 -386.085842) (xy 98.094292 -385.532122) (xy 98.090228 -385.527804) (xy 98.074008 -385.510107)
			(xy 98.04657 -385.470719) (xy 98.025418 -385.427628) (xy 98.01104 -385.38183) (xy 98.003769 -385.334381)
			(xy 98.00336 -385.31038) (xy 98.003847 -385.285605) (xy 98.011598 -385.236665) (xy 98.026905 -385.189538)
			(xy 98.049393 -385.145385) (xy 98.078508 -385.105291) (xy 98.113534 -385.070242) (xy 98.153609 -385.041101)
			(xy 98.197748 -385.018584) (xy 98.244864 -385.003246) (xy 98.293799 -384.995463) (xy 98.318574 -384.994912)
			(xy 98.319082 -384.994912) (xy 98.344476 -384.995418) (xy 98.39461 -385.003547) (xy 98.442795 -385.019597)
			(xy 98.487789 -385.043154) (xy 98.528432 -385.073611) (xy 98.563673 -385.110182) (xy 98.592606 -385.151924)
			(xy 98.614482 -385.197759) (xy 98.622104 -385.221988) (xy 98.623628 -385.22783) (xy 98.943922 -385.78155)
			(xy 98.947986 -385.785868) (xy 98.964158 -385.803557) (xy 98.991509 -385.842915) (xy 99.012587 -385.885958)
			(xy 99.026908 -385.931696) (xy 99.034142 -385.979074) (xy 99.0346 -386.003038) (xy 99.0346 -386.003546)
			(xy 99.034092 -386.023612) (xy 99.033988 -386.033647) (xy 99.040532 -386.052597) (xy 99.046792 -386.060442)
			(xy 99.094544 -386.114544) (xy 99.101524 -386.121776) (xy 99.119596 -386.130537) (xy 99.129596 -386.131562)
			(xy 99.14382 -386.132578) (xy 99.154488 -386.133594) (xy 99.174808 -386.12699) (xy 99.238816 -386.069332)
			(xy 99.246487 -386.061819) (xy 99.25519 -386.042214) (xy 99.25558 -386.031486) (xy 99.25558 -383.817114)
			(xy 99.263454 -383.798572) (xy 99.268534 -383.793492) (xy 99.268534 -383.705608) (xy 99.268111 -383.695539)
			(xy 99.260391 -383.676938) (xy 99.253548 -383.66954) (xy 99.146868 -383.56286) (xy 99.139248 -383.544318)
			(xy 99.139248 -383.538222) (xy 99.01047 -383.409698) (xy 99.003616 -383.402303) (xy 98.995871 -383.383704)
			(xy 98.995484 -383.37363) (xy 98.995484 -382.619504) (xy 98.995906 -382.609433) (xy 99.003617 -382.590826)
			(xy 99.01047 -382.583436) (xy 99.124262 -382.469898) (xy 99.131112 -382.462501) (xy 99.138852 -382.443903)
			(xy 99.139248 -382.43383) (xy 99.139248 -379.624082) (xy 99.13882 -379.614014) (xy 99.131095 -379.59542)
			(xy 99.124262 -379.588014) (xy 98.910394 -379.374146) (xy 98.902997 -379.367295) (xy 98.884399 -379.359556)
			(xy 98.874326 -379.35916) (xy 93.19387 -379.35916) (xy 93.183804 -379.35959) (xy 93.165213 -379.367319)
			(xy 93.157802 -379.374146) (xy 93.045534 -379.486414) (xy 93.038686 -379.493812) (xy 93.030951 -379.51241)
			(xy 93.030548 -379.522482) (xy 93.030548 -382.619758) (xy 93.030113 -382.629822) (xy 93.022378 -382.648407)
			(xy 93.015562 -382.655826) (xy 92.792471 -382.878917) (xy 93.214192 -382.878917) (xy 93.214192 -382.826943)
			(xy 93.222322 -382.775608) (xy 93.238383 -382.726178) (xy 93.261979 -382.679868) (xy 93.292529 -382.63782)
			(xy 93.32928 -382.601069) (xy 93.371328 -382.570519) (xy 93.417638 -382.546923) (xy 93.467068 -382.530862)
			(xy 93.518403 -382.522732) (xy 93.570377 -382.522732) (xy 93.621712 -382.530862) (xy 93.671142 -382.546923)
			(xy 93.717452 -382.570519) (xy 93.7595 -382.601069) (xy 93.796251 -382.63782) (xy 93.826801 -382.679868)
			(xy 93.850397 -382.726178) (xy 93.866458 -382.775608) (xy 93.874588 -382.826943) (xy 93.875098 -382.85293)
			(xy 93.874588 -382.878917) (xy 94.414088 -382.878917) (xy 94.414088 -382.826943) (xy 94.422218 -382.775608)
			(xy 94.438279 -382.726178) (xy 94.461875 -382.679868) (xy 94.492425 -382.63782) (xy 94.529176 -382.601069)
			(xy 94.571224 -382.570519) (xy 94.617534 -382.546923) (xy 94.666964 -382.530862) (xy 94.718299 -382.522732)
			(xy 94.770273 -382.522732) (xy 94.821608 -382.530862) (xy 94.871038 -382.546923) (xy 94.917348 -382.570519)
			(xy 94.959396 -382.601069) (xy 94.996147 -382.63782) (xy 95.026697 -382.679868) (xy 95.050293 -382.726178)
			(xy 95.066354 -382.775608) (xy 95.074484 -382.826943) (xy 95.074994 -382.85293) (xy 95.074484 -382.878917)
			(xy 95.613984 -382.878917) (xy 95.613984 -382.826943) (xy 95.622114 -382.775608) (xy 95.638175 -382.726178)
			(xy 95.661771 -382.679868) (xy 95.692321 -382.63782) (xy 95.729072 -382.601069) (xy 95.77112 -382.570519)
			(xy 95.81743 -382.546923) (xy 95.86686 -382.530862) (xy 95.918195 -382.522732) (xy 95.970169 -382.522732)
			(xy 96.021504 -382.530862) (xy 96.070934 -382.546923) (xy 96.117244 -382.570519) (xy 96.159292 -382.601069)
			(xy 96.196043 -382.63782) (xy 96.226593 -382.679868) (xy 96.250189 -382.726178) (xy 96.26625 -382.775608)
			(xy 96.27438 -382.826943) (xy 96.27489 -382.85293) (xy 96.27438 -382.878917) (xy 96.814134 -382.878917)
			(xy 96.814134 -382.826943) (xy 96.822264 -382.775608) (xy 96.838325 -382.726178) (xy 96.861921 -382.679868)
			(xy 96.892471 -382.63782) (xy 96.929222 -382.601069) (xy 96.97127 -382.570519) (xy 97.01758 -382.546923)
			(xy 97.06701 -382.530862) (xy 97.118345 -382.522732) (xy 97.170319 -382.522732) (xy 97.221654 -382.530862)
			(xy 97.271084 -382.546923) (xy 97.317394 -382.570519) (xy 97.359442 -382.601069) (xy 97.396193 -382.63782)
			(xy 97.426743 -382.679868) (xy 97.450339 -382.726178) (xy 97.4664 -382.775608) (xy 97.47453 -382.826943)
			(xy 97.47504 -382.85293) (xy 97.47453 -382.878917) (xy 98.01403 -382.878917) (xy 98.01403 -382.826943)
			(xy 98.02216 -382.775608) (xy 98.038221 -382.726178) (xy 98.061817 -382.679868) (xy 98.092367 -382.63782)
			(xy 98.129118 -382.601069) (xy 98.171166 -382.570519) (xy 98.217476 -382.546923) (xy 98.266906 -382.530862)
			(xy 98.318241 -382.522732) (xy 98.370215 -382.522732) (xy 98.42155 -382.530862) (xy 98.47098 -382.546923)
			(xy 98.51729 -382.570519) (xy 98.559338 -382.601069) (xy 98.596089 -382.63782) (xy 98.626639 -382.679868)
			(xy 98.650235 -382.726178) (xy 98.666296 -382.775608) (xy 98.674426 -382.826943) (xy 98.674936 -382.85293)
			(xy 98.674426 -382.878917) (xy 98.666296 -382.930252) (xy 98.650235 -382.979682) (xy 98.626639 -383.025992)
			(xy 98.596089 -383.06804) (xy 98.559338 -383.104791) (xy 98.51729 -383.135341) (xy 98.47098 -383.158937)
			(xy 98.42155 -383.174998) (xy 98.370215 -383.183128) (xy 98.318241 -383.183128) (xy 98.266906 -383.174998)
			(xy 98.217476 -383.158937) (xy 98.171166 -383.135341) (xy 98.129118 -383.104791) (xy 98.092367 -383.06804)
			(xy 98.061817 -383.025992) (xy 98.038221 -382.979682) (xy 98.02216 -382.930252) (xy 98.01403 -382.878917)
			(xy 97.47453 -382.878917) (xy 97.4664 -382.930252) (xy 97.450339 -382.979682) (xy 97.426743 -383.025992)
			(xy 97.396193 -383.06804) (xy 97.359442 -383.104791) (xy 97.317394 -383.135341) (xy 97.271084 -383.158937)
			(xy 97.221654 -383.174998) (xy 97.170319 -383.183128) (xy 97.118345 -383.183128) (xy 97.06701 -383.174998)
			(xy 97.01758 -383.158937) (xy 96.97127 -383.135341) (xy 96.929222 -383.104791) (xy 96.892471 -383.06804)
			(xy 96.861921 -383.025992) (xy 96.838325 -382.979682) (xy 96.822264 -382.930252) (xy 96.814134 -382.878917)
			(xy 96.27438 -382.878917) (xy 96.26625 -382.930252) (xy 96.250189 -382.979682) (xy 96.226593 -383.025992)
			(xy 96.196043 -383.06804) (xy 96.159292 -383.104791) (xy 96.117244 -383.135341) (xy 96.070934 -383.158937)
			(xy 96.021504 -383.174998) (xy 95.970169 -383.183128) (xy 95.918195 -383.183128) (xy 95.86686 -383.174998)
			(xy 95.81743 -383.158937) (xy 95.77112 -383.135341) (xy 95.729072 -383.104791) (xy 95.692321 -383.06804)
			(xy 95.661771 -383.025992) (xy 95.638175 -382.979682) (xy 95.622114 -382.930252) (xy 95.613984 -382.878917)
			(xy 95.074484 -382.878917) (xy 95.066354 -382.930252) (xy 95.050293 -382.979682) (xy 95.026697 -383.025992)
			(xy 94.996147 -383.06804) (xy 94.959396 -383.104791) (xy 94.917348 -383.135341) (xy 94.871038 -383.158937)
			(xy 94.821608 -383.174998) (xy 94.770273 -383.183128) (xy 94.718299 -383.183128) (xy 94.666964 -383.174998)
			(xy 94.617534 -383.158937) (xy 94.571224 -383.135341) (xy 94.529176 -383.104791) (xy 94.492425 -383.06804)
			(xy 94.461875 -383.025992) (xy 94.438279 -382.979682) (xy 94.422218 -382.930252) (xy 94.414088 -382.878917)
			(xy 93.874588 -382.878917) (xy 93.866458 -382.930252) (xy 93.850397 -382.979682) (xy 93.826801 -383.025992)
			(xy 93.796251 -383.06804) (xy 93.7595 -383.104791) (xy 93.717452 -383.135341) (xy 93.671142 -383.158937)
			(xy 93.621712 -383.174998) (xy 93.570377 -383.183128) (xy 93.518403 -383.183128) (xy 93.467068 -383.174998)
			(xy 93.417638 -383.158937) (xy 93.371328 -383.135341) (xy 93.32928 -383.104791) (xy 93.292529 -383.06804)
			(xy 93.261979 -383.025992) (xy 93.238383 -382.979682) (xy 93.222322 -382.930252) (xy 93.214192 -382.878917)
			(xy 92.792471 -382.878917) (xy 92.471494 -383.199894) (xy 92.464095 -383.20674) (xy 92.445497 -383.214473)
			(xy 92.435426 -383.21488) (xy 86.18601 -383.21488) (xy 86.175939 -383.214458) (xy 86.157334 -383.206744)
			(xy 86.149942 -383.199894) (xy 86.139528 -383.18948) (xy 86.139528 -383.18694) (xy 85.999574 -383.046986)
			(xy 85.992722 -383.03959) (xy 85.984981 -383.020991) (xy 85.984588 -383.010918) (xy 85.984588 -379.479302)
			(xy 85.984165 -379.469232) (xy 85.97645 -379.450628) (xy 85.969602 -379.443234) (xy 85.864954 -379.338586)
			(xy 85.857557 -379.331737) (xy 85.838958 -379.324006) (xy 85.828886 -379.3236) (xy 85.331808 -379.3236)
			(xy 85.326982 -379.319028) (xy 78.763368 -379.319028) (xy 78.753301 -379.319458) (xy 78.734708 -379.327183)
			(xy 78.7273 -379.334014) (xy 78.437994 -379.623066) (xy 78.431158 -379.630468) (xy 78.423449 -379.649066)
			(xy 78.423008 -379.659134) (xy 78.423008 -382.493266) (xy 78.423483 -382.502991) (xy 78.430782 -382.521026)
			(xy 78.437232 -382.528318) (xy 78.45806 -382.550162) (xy 78.464615 -382.556507) (xy 78.481021 -382.564453)
			(xy 78.490064 -382.565656) (xy 78.516042 -382.568619) (xy 78.566666 -382.581685) (xy 78.614605 -382.602552)
			(xy 78.658666 -382.630699) (xy 78.678532 -382.647698) (xy 78.685136 -382.65354) (xy 78.701138 -382.660144)
			(xy 78.77429 -382.663192) (xy 78.78292 -382.663196) (xy 78.799405 -382.65813) (xy 78.806548 -382.653286)
			(xy 78.827257 -382.638527) (xy 78.872381 -382.615087) (xy 78.920659 -382.599121) (xy 78.970861 -382.591033)
			(xy 78.996286 -382.590548) (xy 79.021281 -382.591011) (xy 79.070657 -382.59883) (xy 79.118202 -382.614276)
			(xy 79.162744 -382.63697) (xy 79.203188 -382.666353) (xy 79.238538 -382.701701) (xy 79.267923 -382.742144)
			(xy 79.290618 -382.786685) (xy 79.306067 -382.834229) (xy 79.312986 -382.877919) (xy 80.026746 -382.877919)
			(xy 80.026746 -382.827941) (xy 80.034565 -382.778578) (xy 80.050009 -382.731046) (xy 80.072699 -382.686514)
			(xy 80.102075 -382.646081) (xy 80.137415 -382.610741) (xy 80.177848 -382.581365) (xy 80.22238 -382.558675)
			(xy 80.269912 -382.543231) (xy 80.319275 -382.535412) (xy 80.369253 -382.535412) (xy 80.418616 -382.543231)
			(xy 80.466148 -382.558675) (xy 80.51068 -382.581365) (xy 80.551113 -382.610741) (xy 80.586453 -382.646081)
			(xy 80.615829 -382.686514) (xy 80.638519 -382.731046) (xy 80.653963 -382.778578) (xy 80.661782 -382.827941)
			(xy 80.662272 -382.85293) (xy 80.661782 -382.877919) (xy 80.661624 -382.878917) (xy 81.214216 -382.878917)
			(xy 81.214216 -382.826943) (xy 81.222346 -382.775608) (xy 81.238407 -382.726178) (xy 81.262003 -382.679868)
			(xy 81.292553 -382.63782) (xy 81.329304 -382.601069) (xy 81.371352 -382.570519) (xy 81.417662 -382.546923)
			(xy 81.467092 -382.530862) (xy 81.518427 -382.522732) (xy 81.570401 -382.522732) (xy 81.621736 -382.530862)
			(xy 81.671166 -382.546923) (xy 81.717476 -382.570519) (xy 81.759524 -382.601069) (xy 81.796275 -382.63782)
			(xy 81.826825 -382.679868) (xy 81.850421 -382.726178) (xy 81.866482 -382.775608) (xy 81.874612 -382.826943)
			(xy 81.875122 -382.85293) (xy 81.874612 -382.878917) (xy 82.414112 -382.878917) (xy 82.414112 -382.826943)
			(xy 82.422242 -382.775608) (xy 82.438303 -382.726178) (xy 82.461899 -382.679868) (xy 82.492449 -382.63782)
			(xy 82.5292 -382.601069) (xy 82.571248 -382.570519) (xy 82.617558 -382.546923) (xy 82.666988 -382.530862)
			(xy 82.718323 -382.522732) (xy 82.770297 -382.522732) (xy 82.821632 -382.530862) (xy 82.871062 -382.546923)
			(xy 82.917372 -382.570519) (xy 82.95942 -382.601069) (xy 82.996171 -382.63782) (xy 83.026721 -382.679868)
			(xy 83.050317 -382.726178) (xy 83.066378 -382.775608) (xy 83.074508 -382.826943) (xy 83.075018 -382.85293)
			(xy 83.074508 -382.878917) (xy 83.614008 -382.878917) (xy 83.614008 -382.826943) (xy 83.622138 -382.775608)
			(xy 83.638199 -382.726178) (xy 83.661795 -382.679868) (xy 83.692345 -382.63782) (xy 83.729096 -382.601069)
			(xy 83.771144 -382.570519) (xy 83.817454 -382.546923) (xy 83.866884 -382.530862) (xy 83.918219 -382.522732)
			(xy 83.970193 -382.522732) (xy 84.021528 -382.530862) (xy 84.070958 -382.546923) (xy 84.117268 -382.570519)
			(xy 84.159316 -382.601069) (xy 84.196067 -382.63782) (xy 84.226617 -382.679868) (xy 84.250213 -382.726178)
			(xy 84.266274 -382.775608) (xy 84.274404 -382.826943) (xy 84.274914 -382.85293) (xy 84.274404 -382.878917)
			(xy 84.814158 -382.878917) (xy 84.814158 -382.826943) (xy 84.822288 -382.775608) (xy 84.838349 -382.726178)
			(xy 84.861945 -382.679868) (xy 84.892495 -382.63782) (xy 84.929246 -382.601069) (xy 84.971294 -382.570519)
			(xy 85.017604 -382.546923) (xy 85.067034 -382.530862) (xy 85.118369 -382.522732) (xy 85.170343 -382.522732)
			(xy 85.221678 -382.530862) (xy 85.271108 -382.546923) (xy 85.317418 -382.570519) (xy 85.359466 -382.601069)
			(xy 85.396217 -382.63782) (xy 85.426767 -382.679868) (xy 85.450363 -382.726178) (xy 85.466424 -382.775608)
			(xy 85.474554 -382.826943) (xy 85.475064 -382.85293) (xy 85.474554 -382.878917) (xy 85.466424 -382.930252)
			(xy 85.450363 -382.979682) (xy 85.426767 -383.025992) (xy 85.396217 -383.06804) (xy 85.359466 -383.104791)
			(xy 85.317418 -383.135341) (xy 85.271108 -383.158937) (xy 85.221678 -383.174998) (xy 85.170343 -383.183128)
			(xy 85.118369 -383.183128) (xy 85.067034 -383.174998) (xy 85.017604 -383.158937) (xy 84.971294 -383.135341)
			(xy 84.929246 -383.104791) (xy 84.892495 -383.06804) (xy 84.861945 -383.025992) (xy 84.838349 -382.979682)
			(xy 84.822288 -382.930252) (xy 84.814158 -382.878917) (xy 84.274404 -382.878917) (xy 84.266274 -382.930252)
			(xy 84.250213 -382.979682) (xy 84.226617 -383.025992) (xy 84.196067 -383.06804) (xy 84.159316 -383.104791)
			(xy 84.117268 -383.135341) (xy 84.070958 -383.158937) (xy 84.021528 -383.174998) (xy 83.970193 -383.183128)
			(xy 83.918219 -383.183128) (xy 83.866884 -383.174998) (xy 83.817454 -383.158937) (xy 83.771144 -383.135341)
			(xy 83.729096 -383.104791) (xy 83.692345 -383.06804) (xy 83.661795 -383.025992) (xy 83.638199 -382.979682)
			(xy 83.622138 -382.930252) (xy 83.614008 -382.878917) (xy 83.074508 -382.878917) (xy 83.066378 -382.930252)
			(xy 83.050317 -382.979682) (xy 83.026721 -383.025992) (xy 82.996171 -383.06804) (xy 82.95942 -383.104791)
			(xy 82.917372 -383.135341) (xy 82.871062 -383.158937) (xy 82.821632 -383.174998) (xy 82.770297 -383.183128)
			(xy 82.718323 -383.183128) (xy 82.666988 -383.174998) (xy 82.617558 -383.158937) (xy 82.571248 -383.135341)
			(xy 82.5292 -383.104791) (xy 82.492449 -383.06804) (xy 82.461899 -383.025992) (xy 82.438303 -382.979682)
			(xy 82.422242 -382.930252) (xy 82.414112 -382.878917) (xy 81.874612 -382.878917) (xy 81.866482 -382.930252)
			(xy 81.850421 -382.979682) (xy 81.826825 -383.025992) (xy 81.796275 -383.06804) (xy 81.759524 -383.104791)
			(xy 81.717476 -383.135341) (xy 81.671166 -383.158937) (xy 81.621736 -383.174998) (xy 81.570401 -383.183128)
			(xy 81.518427 -383.183128) (xy 81.467092 -383.174998) (xy 81.417662 -383.158937) (xy 81.371352 -383.135341)
			(xy 81.329304 -383.104791) (xy 81.292553 -383.06804) (xy 81.262003 -383.025992) (xy 81.238407 -382.979682)
			(xy 81.222346 -382.930252) (xy 81.214216 -382.878917) (xy 80.661624 -382.878917) (xy 80.653963 -382.927282)
			(xy 80.638519 -382.974814) (xy 80.615829 -383.019346) (xy 80.586453 -383.059779) (xy 80.551113 -383.095119)
			(xy 80.51068 -383.124495) (xy 80.466148 -383.147185) (xy 80.418616 -383.162629) (xy 80.369253 -383.170448)
			(xy 80.319275 -383.170448) (xy 80.269912 -383.162629) (xy 80.22238 -383.147185) (xy 80.177848 -383.124495)
			(xy 80.137415 -383.095119) (xy 80.102075 -383.059779) (xy 80.072699 -383.019346) (xy 80.050009 -382.974814)
			(xy 80.034565 -382.927282) (xy 80.026746 -382.877919) (xy 79.312986 -382.877919) (xy 79.313887 -382.883605)
			(xy 79.313887 -382.933595) (xy 79.306067 -382.982971) (xy 79.290618 -383.030515) (xy 79.267923 -383.075056)
			(xy 79.238538 -383.115499) (xy 79.203188 -383.150847) (xy 79.162744 -383.18023) (xy 79.118202 -383.202924)
			(xy 79.070657 -383.21837) (xy 79.021281 -383.226189) (xy 78.996286 -383.226564) (xy 78.996032 -383.226564)
			(xy 78.968623 -383.225963) (xy 78.914621 -383.216525) (xy 78.863029 -383.197992) (xy 78.815366 -383.170908)
			(xy 78.793848 -383.15392) (xy 78.78699 -383.148332) (xy 78.77048 -383.142236) (xy 78.697582 -383.141728)
			(xy 78.688998 -383.14201) (xy 78.67276 -383.147575) (xy 78.665832 -383.15265) (xy 78.665578 -383.152904)
			(xy 78.643445 -383.169915) (xy 78.594656 -383.197029) (xy 78.542003 -383.215557) (xy 78.486984 -383.224969)
			(xy 78.459076 -383.225548) (xy 78.458568 -383.225548) (xy 78.4479 -383.225294) (xy 78.437486 -383.22504)
			(xy 78.417928 -383.23266) (xy 78.070202 -383.580386) (xy 78.063366 -383.587751) (xy 78.055632 -383.60628)
			(xy 78.05564 -383.626358) (xy 78.063388 -383.644881) (xy 78.070202 -383.652268) (xy 78.146656 -383.728722)
			(xy 78.163383 -383.746124) (xy 78.191748 -383.785176) (xy 78.213656 -383.828183) (xy 78.228568 -383.874087)
			(xy 78.236118 -383.921759) (xy 78.236572 -383.945892) (xy 78.236572 -384.23596) (xy 78.239874 -384.244342)
			(xy 78.249089 -384.271557) (xy 78.259046 -384.328139) (xy 78.259686 -384.356864) (xy 78.259686 -384.357372)
			(xy 78.259174 -384.383754) (xy 78.250803 -384.435849) (xy 78.234268 -384.485954) (xy 78.209988 -384.532799)
			(xy 78.17858 -384.575197) (xy 78.14084 -384.61207) (xy 78.097725 -384.642485) (xy 78.097263 -384.642711)
			(xy 79.67267 -384.642711) (xy 79.67267 -384.592733) (xy 79.680489 -384.54337) (xy 79.695933 -384.495838)
			(xy 79.718623 -384.451306) (xy 79.747999 -384.410873) (xy 79.783339 -384.375533) (xy 79.823772 -384.346157)
			(xy 79.868304 -384.323467) (xy 79.915836 -384.308023) (xy 79.965199 -384.300204) (xy 80.015177 -384.300204)
			(xy 80.06454 -384.308023) (xy 80.112072 -384.323467) (xy 80.156604 -384.346157) (xy 80.197037 -384.375533)
			(xy 80.232377 -384.410873) (xy 80.261753 -384.451306) (xy 80.284443 -384.495838) (xy 80.299887 -384.54337)
			(xy 80.307706 -384.592733) (xy 80.308196 -384.617722) (xy 80.307706 -384.642711) (xy 80.307548 -384.643709)
			(xy 80.859886 -384.643709) (xy 80.859886 -384.591735) (xy 80.868016 -384.5404) (xy 80.884077 -384.49097)
			(xy 80.907673 -384.44466) (xy 80.938223 -384.402612) (xy 80.974974 -384.365861) (xy 81.017022 -384.335311)
			(xy 81.063332 -384.311715) (xy 81.112762 -384.295654) (xy 81.164097 -384.287524) (xy 81.216071 -384.287524)
			(xy 81.267406 -384.295654) (xy 81.316836 -384.311715) (xy 81.363146 -384.335311) (xy 81.405194 -384.365861)
			(xy 81.441945 -384.402612) (xy 81.472495 -384.44466) (xy 81.496091 -384.49097) (xy 81.512152 -384.5404)
			(xy 81.520282 -384.591735) (xy 81.520792 -384.617722) (xy 81.520282 -384.643709) (xy 82.060036 -384.643709)
			(xy 82.060036 -384.591735) (xy 82.068166 -384.5404) (xy 82.084227 -384.49097) (xy 82.107823 -384.44466)
			(xy 82.138373 -384.402612) (xy 82.175124 -384.365861) (xy 82.217172 -384.335311) (xy 82.263482 -384.311715)
			(xy 82.312912 -384.295654) (xy 82.364247 -384.287524) (xy 82.416221 -384.287524) (xy 82.467556 -384.295654)
			(xy 82.516986 -384.311715) (xy 82.563296 -384.335311) (xy 82.605344 -384.365861) (xy 82.642095 -384.402612)
			(xy 82.672645 -384.44466) (xy 82.696241 -384.49097) (xy 82.712302 -384.5404) (xy 82.720432 -384.591735)
			(xy 82.720942 -384.617722) (xy 82.720432 -384.643709) (xy 83.259932 -384.643709) (xy 83.259932 -384.591735)
			(xy 83.268062 -384.5404) (xy 83.284123 -384.49097) (xy 83.307719 -384.44466) (xy 83.338269 -384.402612)
			(xy 83.37502 -384.365861) (xy 83.417068 -384.335311) (xy 83.463378 -384.311715) (xy 83.512808 -384.295654)
			(xy 83.564143 -384.287524) (xy 83.616117 -384.287524) (xy 83.667452 -384.295654) (xy 83.716882 -384.311715)
			(xy 83.763192 -384.335311) (xy 83.80524 -384.365861) (xy 83.841991 -384.402612) (xy 83.872541 -384.44466)
			(xy 83.896137 -384.49097) (xy 83.912198 -384.5404) (xy 83.920328 -384.591735) (xy 83.920838 -384.617722)
			(xy 83.920328 -384.643709) (xy 84.460082 -384.643709) (xy 84.460082 -384.591735) (xy 84.468212 -384.5404)
			(xy 84.484273 -384.49097) (xy 84.507869 -384.44466) (xy 84.538419 -384.402612) (xy 84.57517 -384.365861)
			(xy 84.617218 -384.335311) (xy 84.663528 -384.311715) (xy 84.712958 -384.295654) (xy 84.764293 -384.287524)
			(xy 84.816267 -384.287524) (xy 84.867602 -384.295654) (xy 84.917032 -384.311715) (xy 84.963342 -384.335311)
			(xy 85.00539 -384.365861) (xy 85.042141 -384.402612) (xy 85.072691 -384.44466) (xy 85.096287 -384.49097)
			(xy 85.112348 -384.5404) (xy 85.120478 -384.591735) (xy 85.120988 -384.617722) (xy 85.120478 -384.643709)
			(xy 85.659978 -384.643709) (xy 85.659978 -384.591735) (xy 85.668108 -384.5404) (xy 85.684169 -384.49097)
			(xy 85.707765 -384.44466) (xy 85.738315 -384.402612) (xy 85.775066 -384.365861) (xy 85.817114 -384.335311)
			(xy 85.863424 -384.311715) (xy 85.912854 -384.295654) (xy 85.964189 -384.287524) (xy 86.016163 -384.287524)
			(xy 86.067498 -384.295654) (xy 86.116928 -384.311715) (xy 86.163238 -384.335311) (xy 86.205286 -384.365861)
			(xy 86.242037 -384.402612) (xy 86.272587 -384.44466) (xy 86.296183 -384.49097) (xy 86.312244 -384.5404)
			(xy 86.320374 -384.591735) (xy 86.320884 -384.617722) (xy 86.320374 -384.643709) (xy 86.859874 -384.643709)
			(xy 86.859874 -384.591735) (xy 86.868004 -384.5404) (xy 86.884065 -384.49097) (xy 86.907661 -384.44466)
			(xy 86.938211 -384.402612) (xy 86.974962 -384.365861) (xy 87.01701 -384.335311) (xy 87.06332 -384.311715)
			(xy 87.11275 -384.295654) (xy 87.164085 -384.287524) (xy 87.216059 -384.287524) (xy 87.267394 -384.295654)
			(xy 87.316824 -384.311715) (xy 87.363134 -384.335311) (xy 87.405182 -384.365861) (xy 87.441933 -384.402612)
			(xy 87.472483 -384.44466) (xy 87.496079 -384.49097) (xy 87.51214 -384.5404) (xy 87.52027 -384.591735)
			(xy 87.52078 -384.617722) (xy 87.52027 -384.643709) (xy 88.060024 -384.643709) (xy 88.060024 -384.591735)
			(xy 88.068154 -384.5404) (xy 88.084215 -384.49097) (xy 88.107811 -384.44466) (xy 88.138361 -384.402612)
			(xy 88.175112 -384.365861) (xy 88.21716 -384.335311) (xy 88.26347 -384.311715) (xy 88.3129 -384.295654)
			(xy 88.364235 -384.287524) (xy 88.416209 -384.287524) (xy 88.467544 -384.295654) (xy 88.516974 -384.311715)
			(xy 88.563284 -384.335311) (xy 88.605332 -384.365861) (xy 88.642083 -384.402612) (xy 88.672633 -384.44466)
			(xy 88.696229 -384.49097) (xy 88.71229 -384.5404) (xy 88.72042 -384.591735) (xy 88.72093 -384.617722)
			(xy 88.72042 -384.643709) (xy 89.25992 -384.643709) (xy 89.25992 -384.591735) (xy 89.26805 -384.5404)
			(xy 89.284111 -384.49097) (xy 89.307707 -384.44466) (xy 89.338257 -384.402612) (xy 89.375008 -384.365861)
			(xy 89.417056 -384.335311) (xy 89.463366 -384.311715) (xy 89.512796 -384.295654) (xy 89.564131 -384.287524)
			(xy 89.616105 -384.287524) (xy 89.66744 -384.295654) (xy 89.71687 -384.311715) (xy 89.76318 -384.335311)
			(xy 89.805228 -384.365861) (xy 89.841979 -384.402612) (xy 89.872529 -384.44466) (xy 89.896125 -384.49097)
			(xy 89.912186 -384.5404) (xy 89.920316 -384.591735) (xy 89.920826 -384.617722) (xy 89.920316 -384.643709)
			(xy 90.46007 -384.643709) (xy 90.46007 -384.591735) (xy 90.4682 -384.5404) (xy 90.484261 -384.49097)
			(xy 90.507857 -384.44466) (xy 90.538407 -384.402612) (xy 90.575158 -384.365861) (xy 90.617206 -384.335311)
			(xy 90.663516 -384.311715) (xy 90.712946 -384.295654) (xy 90.764281 -384.287524) (xy 90.816255 -384.287524)
			(xy 90.86759 -384.295654) (xy 90.91702 -384.311715) (xy 90.96333 -384.335311) (xy 91.005378 -384.365861)
			(xy 91.042129 -384.402612) (xy 91.072679 -384.44466) (xy 91.096275 -384.49097) (xy 91.112336 -384.5404)
			(xy 91.120466 -384.591735) (xy 91.120976 -384.617722) (xy 91.120466 -384.643709) (xy 91.659966 -384.643709)
			(xy 91.659966 -384.591735) (xy 91.668096 -384.5404) (xy 91.684157 -384.49097) (xy 91.707753 -384.44466)
			(xy 91.738303 -384.402612) (xy 91.775054 -384.365861) (xy 91.817102 -384.335311) (xy 91.863412 -384.311715)
			(xy 91.912842 -384.295654) (xy 91.964177 -384.287524) (xy 92.016151 -384.287524) (xy 92.067486 -384.295654)
			(xy 92.116916 -384.311715) (xy 92.163226 -384.335311) (xy 92.205274 -384.365861) (xy 92.242025 -384.402612)
			(xy 92.272575 -384.44466) (xy 92.296171 -384.49097) (xy 92.312232 -384.5404) (xy 92.320362 -384.591735)
			(xy 92.320872 -384.617722) (xy 92.320362 -384.643709) (xy 92.859862 -384.643709) (xy 92.859862 -384.591735)
			(xy 92.867992 -384.5404) (xy 92.884053 -384.49097) (xy 92.907649 -384.44466) (xy 92.938199 -384.402612)
			(xy 92.97495 -384.365861) (xy 93.016998 -384.335311) (xy 93.063308 -384.311715) (xy 93.112738 -384.295654)
			(xy 93.164073 -384.287524) (xy 93.216047 -384.287524) (xy 93.267382 -384.295654) (xy 93.316812 -384.311715)
			(xy 93.363122 -384.335311) (xy 93.40517 -384.365861) (xy 93.441921 -384.402612) (xy 93.472471 -384.44466)
			(xy 93.496067 -384.49097) (xy 93.512128 -384.5404) (xy 93.520258 -384.591735) (xy 93.520768 -384.617722)
			(xy 93.520258 -384.643709) (xy 94.060012 -384.643709) (xy 94.060012 -384.591735) (xy 94.068142 -384.5404)
			(xy 94.084203 -384.49097) (xy 94.107799 -384.44466) (xy 94.138349 -384.402612) (xy 94.1751 -384.365861)
			(xy 94.217148 -384.335311) (xy 94.263458 -384.311715) (xy 94.312888 -384.295654) (xy 94.364223 -384.287524)
			(xy 94.416197 -384.287524) (xy 94.467532 -384.295654) (xy 94.516962 -384.311715) (xy 94.563272 -384.335311)
			(xy 94.60532 -384.365861) (xy 94.642071 -384.402612) (xy 94.672621 -384.44466) (xy 94.696217 -384.49097)
			(xy 94.712278 -384.5404) (xy 94.720408 -384.591735) (xy 94.720918 -384.617722) (xy 94.720408 -384.643709)
			(xy 95.259908 -384.643709) (xy 95.259908 -384.591735) (xy 95.268038 -384.5404) (xy 95.284099 -384.49097)
			(xy 95.307695 -384.44466) (xy 95.338245 -384.402612) (xy 95.374996 -384.365861) (xy 95.417044 -384.335311)
			(xy 95.463354 -384.311715) (xy 95.512784 -384.295654) (xy 95.564119 -384.287524) (xy 95.616093 -384.287524)
			(xy 95.667428 -384.295654) (xy 95.716858 -384.311715) (xy 95.763168 -384.335311) (xy 95.805216 -384.365861)
			(xy 95.841967 -384.402612) (xy 95.872517 -384.44466) (xy 95.896113 -384.49097) (xy 95.912174 -384.5404)
			(xy 95.920304 -384.591735) (xy 95.920814 -384.617722) (xy 95.920304 -384.643709) (xy 96.460058 -384.643709)
			(xy 96.460058 -384.591735) (xy 96.468188 -384.5404) (xy 96.484249 -384.49097) (xy 96.507845 -384.44466)
			(xy 96.538395 -384.402612) (xy 96.575146 -384.365861) (xy 96.617194 -384.335311) (xy 96.663504 -384.311715)
			(xy 96.712934 -384.295654) (xy 96.764269 -384.287524) (xy 96.816243 -384.287524) (xy 96.867578 -384.295654)
			(xy 96.917008 -384.311715) (xy 96.963318 -384.335311) (xy 97.005366 -384.365861) (xy 97.042117 -384.402612)
			(xy 97.072667 -384.44466) (xy 97.096263 -384.49097) (xy 97.112324 -384.5404) (xy 97.120454 -384.591735)
			(xy 97.120964 -384.617722) (xy 97.120454 -384.643709) (xy 97.659954 -384.643709) (xy 97.659954 -384.591735)
			(xy 97.668084 -384.5404) (xy 97.684145 -384.49097) (xy 97.707741 -384.44466) (xy 97.738291 -384.402612)
			(xy 97.775042 -384.365861) (xy 97.81709 -384.335311) (xy 97.8634 -384.311715) (xy 97.91283 -384.295654)
			(xy 97.964165 -384.287524) (xy 98.016139 -384.287524) (xy 98.067474 -384.295654) (xy 98.116904 -384.311715)
			(xy 98.163214 -384.335311) (xy 98.205262 -384.365861) (xy 98.242013 -384.402612) (xy 98.272563 -384.44466)
			(xy 98.296159 -384.49097) (xy 98.31222 -384.5404) (xy 98.32035 -384.591735) (xy 98.32086 -384.617722)
			(xy 98.32035 -384.643709) (xy 98.31222 -384.695044) (xy 98.296159 -384.744474) (xy 98.272563 -384.790784)
			(xy 98.242013 -384.832832) (xy 98.205262 -384.869583) (xy 98.163214 -384.900133) (xy 98.116904 -384.923729)
			(xy 98.067474 -384.93979) (xy 98.016139 -384.94792) (xy 97.964165 -384.94792) (xy 97.91283 -384.93979)
			(xy 97.8634 -384.923729) (xy 97.81709 -384.900133) (xy 97.775042 -384.869583) (xy 97.738291 -384.832832)
			(xy 97.707741 -384.790784) (xy 97.684145 -384.744474) (xy 97.668084 -384.695044) (xy 97.659954 -384.643709)
			(xy 97.120454 -384.643709) (xy 97.112324 -384.695044) (xy 97.096263 -384.744474) (xy 97.072667 -384.790784)
			(xy 97.042117 -384.832832) (xy 97.005366 -384.869583) (xy 96.963318 -384.900133) (xy 96.917008 -384.923729)
			(xy 96.867578 -384.93979) (xy 96.816243 -384.94792) (xy 96.764269 -384.94792) (xy 96.712934 -384.93979)
			(xy 96.663504 -384.923729) (xy 96.617194 -384.900133) (xy 96.575146 -384.869583) (xy 96.538395 -384.832832)
			(xy 96.507845 -384.790784) (xy 96.484249 -384.744474) (xy 96.468188 -384.695044) (xy 96.460058 -384.643709)
			(xy 95.920304 -384.643709) (xy 95.912174 -384.695044) (xy 95.896113 -384.744474) (xy 95.872517 -384.790784)
			(xy 95.841967 -384.832832) (xy 95.805216 -384.869583) (xy 95.763168 -384.900133) (xy 95.716858 -384.923729)
			(xy 95.667428 -384.93979) (xy 95.616093 -384.94792) (xy 95.564119 -384.94792) (xy 95.512784 -384.93979)
			(xy 95.463354 -384.923729) (xy 95.417044 -384.900133) (xy 95.374996 -384.869583) (xy 95.338245 -384.832832)
			(xy 95.307695 -384.790784) (xy 95.284099 -384.744474) (xy 95.268038 -384.695044) (xy 95.259908 -384.643709)
			(xy 94.720408 -384.643709) (xy 94.712278 -384.695044) (xy 94.696217 -384.744474) (xy 94.672621 -384.790784)
			(xy 94.642071 -384.832832) (xy 94.60532 -384.869583) (xy 94.563272 -384.900133) (xy 94.516962 -384.923729)
			(xy 94.467532 -384.93979) (xy 94.416197 -384.94792) (xy 94.364223 -384.94792) (xy 94.312888 -384.93979)
			(xy 94.263458 -384.923729) (xy 94.217148 -384.900133) (xy 94.1751 -384.869583) (xy 94.138349 -384.832832)
			(xy 94.107799 -384.790784) (xy 94.084203 -384.744474) (xy 94.068142 -384.695044) (xy 94.060012 -384.643709)
			(xy 93.520258 -384.643709) (xy 93.512128 -384.695044) (xy 93.496067 -384.744474) (xy 93.472471 -384.790784)
			(xy 93.441921 -384.832832) (xy 93.40517 -384.869583) (xy 93.363122 -384.900133) (xy 93.316812 -384.923729)
			(xy 93.267382 -384.93979) (xy 93.216047 -384.94792) (xy 93.164073 -384.94792) (xy 93.112738 -384.93979)
			(xy 93.063308 -384.923729) (xy 93.016998 -384.900133) (xy 92.97495 -384.869583) (xy 92.938199 -384.832832)
			(xy 92.907649 -384.790784) (xy 92.884053 -384.744474) (xy 92.867992 -384.695044) (xy 92.859862 -384.643709)
			(xy 92.320362 -384.643709) (xy 92.312232 -384.695044) (xy 92.296171 -384.744474) (xy 92.272575 -384.790784)
			(xy 92.242025 -384.832832) (xy 92.205274 -384.869583) (xy 92.163226 -384.900133) (xy 92.116916 -384.923729)
			(xy 92.067486 -384.93979) (xy 92.016151 -384.94792) (xy 91.964177 -384.94792) (xy 91.912842 -384.93979)
			(xy 91.863412 -384.923729) (xy 91.817102 -384.900133) (xy 91.775054 -384.869583) (xy 91.738303 -384.832832)
			(xy 91.707753 -384.790784) (xy 91.684157 -384.744474) (xy 91.668096 -384.695044) (xy 91.659966 -384.643709)
			(xy 91.120466 -384.643709) (xy 91.112336 -384.695044) (xy 91.096275 -384.744474) (xy 91.072679 -384.790784)
			(xy 91.042129 -384.832832) (xy 91.005378 -384.869583) (xy 90.96333 -384.900133) (xy 90.91702 -384.923729)
			(xy 90.86759 -384.93979) (xy 90.816255 -384.94792) (xy 90.764281 -384.94792) (xy 90.712946 -384.93979)
			(xy 90.663516 -384.923729) (xy 90.617206 -384.900133) (xy 90.575158 -384.869583) (xy 90.538407 -384.832832)
			(xy 90.507857 -384.790784) (xy 90.484261 -384.744474) (xy 90.4682 -384.695044) (xy 90.46007 -384.643709)
			(xy 89.920316 -384.643709) (xy 89.912186 -384.695044) (xy 89.896125 -384.744474) (xy 89.872529 -384.790784)
			(xy 89.841979 -384.832832) (xy 89.805228 -384.869583) (xy 89.76318 -384.900133) (xy 89.71687 -384.923729)
			(xy 89.66744 -384.93979) (xy 89.616105 -384.94792) (xy 89.564131 -384.94792) (xy 89.512796 -384.93979)
			(xy 89.463366 -384.923729) (xy 89.417056 -384.900133) (xy 89.375008 -384.869583) (xy 89.338257 -384.832832)
			(xy 89.307707 -384.790784) (xy 89.284111 -384.744474) (xy 89.26805 -384.695044) (xy 89.25992 -384.643709)
			(xy 88.72042 -384.643709) (xy 88.71229 -384.695044) (xy 88.696229 -384.744474) (xy 88.672633 -384.790784)
			(xy 88.642083 -384.832832) (xy 88.605332 -384.869583) (xy 88.563284 -384.900133) (xy 88.516974 -384.923729)
			(xy 88.467544 -384.93979) (xy 88.416209 -384.94792) (xy 88.364235 -384.94792) (xy 88.3129 -384.93979)
			(xy 88.26347 -384.923729) (xy 88.21716 -384.900133) (xy 88.175112 -384.869583) (xy 88.138361 -384.832832)
			(xy 88.107811 -384.790784) (xy 88.084215 -384.744474) (xy 88.068154 -384.695044) (xy 88.060024 -384.643709)
			(xy 87.52027 -384.643709) (xy 87.51214 -384.695044) (xy 87.496079 -384.744474) (xy 87.472483 -384.790784)
			(xy 87.441933 -384.832832) (xy 87.405182 -384.869583) (xy 87.363134 -384.900133) (xy 87.316824 -384.923729)
			(xy 87.267394 -384.93979) (xy 87.216059 -384.94792) (xy 87.164085 -384.94792) (xy 87.11275 -384.93979)
			(xy 87.06332 -384.923729) (xy 87.01701 -384.900133) (xy 86.974962 -384.869583) (xy 86.938211 -384.832832)
			(xy 86.907661 -384.790784) (xy 86.884065 -384.744474) (xy 86.868004 -384.695044) (xy 86.859874 -384.643709)
			(xy 86.320374 -384.643709) (xy 86.312244 -384.695044) (xy 86.296183 -384.744474) (xy 86.272587 -384.790784)
			(xy 86.242037 -384.832832) (xy 86.205286 -384.869583) (xy 86.163238 -384.900133) (xy 86.116928 -384.923729)
			(xy 86.067498 -384.93979) (xy 86.016163 -384.94792) (xy 85.964189 -384.94792) (xy 85.912854 -384.93979)
			(xy 85.863424 -384.923729) (xy 85.817114 -384.900133) (xy 85.775066 -384.869583) (xy 85.738315 -384.832832)
			(xy 85.707765 -384.790784) (xy 85.684169 -384.744474) (xy 85.668108 -384.695044) (xy 85.659978 -384.643709)
			(xy 85.120478 -384.643709) (xy 85.112348 -384.695044) (xy 85.096287 -384.744474) (xy 85.072691 -384.790784)
			(xy 85.042141 -384.832832) (xy 85.00539 -384.869583) (xy 84.963342 -384.900133) (xy 84.917032 -384.923729)
			(xy 84.867602 -384.93979) (xy 84.816267 -384.94792) (xy 84.764293 -384.94792) (xy 84.712958 -384.93979)
			(xy 84.663528 -384.923729) (xy 84.617218 -384.900133) (xy 84.57517 -384.869583) (xy 84.538419 -384.832832)
			(xy 84.507869 -384.790784) (xy 84.484273 -384.744474) (xy 84.468212 -384.695044) (xy 84.460082 -384.643709)
			(xy 83.920328 -384.643709) (xy 83.912198 -384.695044) (xy 83.896137 -384.744474) (xy 83.872541 -384.790784)
			(xy 83.841991 -384.832832) (xy 83.80524 -384.869583) (xy 83.763192 -384.900133) (xy 83.716882 -384.923729)
			(xy 83.667452 -384.93979) (xy 83.616117 -384.94792) (xy 83.564143 -384.94792) (xy 83.512808 -384.93979)
			(xy 83.463378 -384.923729) (xy 83.417068 -384.900133) (xy 83.37502 -384.869583) (xy 83.338269 -384.832832)
			(xy 83.307719 -384.790784) (xy 83.284123 -384.744474) (xy 83.268062 -384.695044) (xy 83.259932 -384.643709)
			(xy 82.720432 -384.643709) (xy 82.712302 -384.695044) (xy 82.696241 -384.744474) (xy 82.672645 -384.790784)
			(xy 82.642095 -384.832832) (xy 82.605344 -384.869583) (xy 82.563296 -384.900133) (xy 82.516986 -384.923729)
			(xy 82.467556 -384.93979) (xy 82.416221 -384.94792) (xy 82.364247 -384.94792) (xy 82.312912 -384.93979)
			(xy 82.263482 -384.923729) (xy 82.217172 -384.900133) (xy 82.175124 -384.869583) (xy 82.138373 -384.832832)
			(xy 82.107823 -384.790784) (xy 82.084227 -384.744474) (xy 82.068166 -384.695044) (xy 82.060036 -384.643709)
			(xy 81.520282 -384.643709) (xy 81.512152 -384.695044) (xy 81.496091 -384.744474) (xy 81.472495 -384.790784)
			(xy 81.441945 -384.832832) (xy 81.405194 -384.869583) (xy 81.363146 -384.900133) (xy 81.316836 -384.923729)
			(xy 81.267406 -384.93979) (xy 81.216071 -384.94792) (xy 81.164097 -384.94792) (xy 81.112762 -384.93979)
			(xy 81.063332 -384.923729) (xy 81.017022 -384.900133) (xy 80.974974 -384.869583) (xy 80.938223 -384.832832)
			(xy 80.907673 -384.790784) (xy 80.884077 -384.744474) (xy 80.868016 -384.695044) (xy 80.859886 -384.643709)
			(xy 80.307548 -384.643709) (xy 80.299887 -384.692074) (xy 80.284443 -384.739606) (xy 80.261753 -384.784138)
			(xy 80.232377 -384.824571) (xy 80.197037 -384.859911) (xy 80.156604 -384.889287) (xy 80.112072 -384.911977)
			(xy 80.06454 -384.927421) (xy 80.015177 -384.93524) (xy 79.965199 -384.93524) (xy 79.915836 -384.927421)
			(xy 79.868304 -384.911977) (xy 79.823772 -384.889287) (xy 79.783339 -384.859911) (xy 79.747999 -384.824571)
			(xy 79.718623 -384.784138) (xy 79.695933 -384.739606) (xy 79.680489 -384.692074) (xy 79.67267 -384.642711)
			(xy 78.097263 -384.642711) (xy 78.050329 -384.66567) (xy 78.025244 -384.673856) (xy 78.0161 -384.67665)
			(xy 78.001368 -384.68808) (xy 77.95641 -384.763772) (xy 77.953362 -384.782314) (xy 77.955394 -384.791712)
			(xy 77.960014 -384.814997) (xy 77.96498 -384.86221) (xy 77.9653 -384.885946) (xy 77.964684 -384.92035)
			(xy 77.954391 -384.988382) (xy 77.934027 -385.054107) (xy 77.91958 -385.085336) (xy 77.917234 -385.090558)
			(xy 77.914664 -385.101712) (xy 77.9145 -385.107434) (xy 77.9145 -385.87553) (xy 79.361792 -385.87553)
			(xy 79.362354 -385.84795) (xy 79.371553 -385.793561) (xy 79.38008 -385.767326) (xy 79.38262 -385.759452)
			(xy 79.38262 -385.61518) (xy 79.383071 -385.598455) (xy 79.391734 -385.566147) (xy 79.408464 -385.537182)
			(xy 79.432121 -385.513535) (xy 79.461092 -385.496816) (xy 79.493403 -385.488165) (xy 79.510128 -385.487672)
			(xy 79.891128 -385.487672) (xy 79.901034 -385.48818) (xy 79.912809 -385.488501) (xy 79.934656 -385.479783)
			(xy 79.942944 -385.471416) (xy 80.004666 -385.402836) (xy 80.011016 -385.379976) (xy 80.010254 -385.376166)
			(xy 80.010254 -385.37515) (xy 80.005174 -385.342892) (xy 80.003396 -385.31038) (xy 80.003829 -385.286754)
			(xy 80.010891 -385.240032) (xy 80.02484 -385.194886) (xy 80.045363 -385.152323) (xy 80.072003 -385.113296)
			(xy 80.104163 -385.078677) (xy 80.141125 -385.049239) (xy 80.161384 -385.037076) (xy 80.18549 -385.023821)
			(xy 80.237185 -385.005014) (xy 80.291359 -384.995471) (xy 80.318864 -384.994912) (xy 80.319118 -384.994912)
			(xy 80.342732 -384.995331) (xy 80.38943 -385.002382) (xy 80.434558 -385.016307) (xy 80.477109 -385.036798)
			(xy 80.516134 -385.063397) (xy 80.550763 -385.09551) (xy 80.580223 -385.132422) (xy 80.592422 -385.152646)
			(xy 80.601643 -385.169159) (xy 80.616546 -385.203921) (xy 80.62214 -385.221988) (xy 80.622648 -385.22402)
			(xy 80.623664 -385.228084) (xy 80.671289 -385.31038) (xy 81.203292 -385.31038) (xy 81.203798 -385.285605)
			(xy 81.211548 -385.236663) (xy 81.226854 -385.189535) (xy 81.249339 -385.14538) (xy 81.278451 -385.105282)
			(xy 81.313474 -385.070229) (xy 81.353546 -385.041082) (xy 81.397682 -385.018559) (xy 81.444796 -385.003212)
			(xy 81.493731 -384.99542) (xy 81.518506 -384.994912) (xy 81.519014 -384.994912) (xy 81.54441 -384.995383)
			(xy 81.594546 -385.003516) (xy 81.642733 -385.019571) (xy 81.687728 -385.043134) (xy 81.728371 -385.073595)
			(xy 81.763613 -385.110171) (xy 81.792545 -385.151917) (xy 81.814421 -385.197756) (xy 81.822036 -385.221988)
			(xy 81.82356 -385.22783) (xy 81.87131 -385.31038) (xy 82.403696 -385.31038) (xy 82.404199 -385.285592)
			(xy 82.411957 -385.236626) (xy 82.427279 -385.189476) (xy 82.449786 -385.145303) (xy 82.478927 -385.105194)
			(xy 82.513982 -385.070137) (xy 82.554089 -385.040995) (xy 82.598261 -385.018485) (xy 82.64541 -385.003161)
			(xy 82.694376 -384.995401) (xy 82.719164 -384.994912) (xy 82.744613 -384.995373) (xy 82.794852 -385.003532)
			(xy 82.843132 -385.019645) (xy 82.888202 -385.043294) (xy 82.928894 -385.073868) (xy 82.964155 -385.110573)
			(xy 82.993071 -385.152459) (xy 83.014893 -385.198441) (xy 83.02244 -385.22275) (xy 83.023964 -385.228592)
			(xy 83.34375 -385.78155) (xy 83.347814 -385.785868) (xy 83.363963 -385.803577) (xy 83.391309 -385.842934)
			(xy 83.412391 -385.885973) (xy 83.426724 -385.931704) (xy 83.433978 -385.979076) (xy 83.434428 -386.003038)
			(xy 83.434428 -386.003546) (xy 83.43392 -386.023866) (xy 83.433158 -386.033772) (xy 83.439508 -386.052822)
			(xy 83.500214 -386.122164) (xy 83.517994 -386.131054) (xy 83.528154 -386.131816) (xy 83.55313 -386.134022)
			(xy 83.601987 -386.145273) (xy 83.648474 -386.16405) (xy 83.691439 -386.189889) (xy 83.729818 -386.222149)
			(xy 83.746594 -386.240782) (xy 83.749052 -386.243559) (xy 83.754667 -386.248403) (xy 83.75777 -386.250434)
			(xy 83.769798 -386.258516) (xy 83.789691 -386.279573) (xy 83.803701 -386.304929) (xy 83.810939 -386.332978)
			(xy 83.811364 -386.347462) (xy 83.811364 -386.3594) (xy 83.813142 -386.366004) (xy 83.818334 -386.386376)
			(xy 83.823944 -386.428042) (xy 83.824318 -386.449062) (xy 83.823936 -386.470082) (xy 83.818336 -386.511748)
			(xy 83.813142 -386.53212) (xy 83.811364 -386.538724) (xy 83.811364 -386.652262) (xy 83.810875 -386.667282)
			(xy 83.803108 -386.696301) (xy 83.788095 -386.72232) (xy 83.766858 -386.743566) (xy 83.740845 -386.75859)
			(xy 83.71183 -386.766369) (xy 83.69681 -386.766816) (xy 83.5152 -386.766816) (xy 83.514692 -386.76707)
			(xy 83.497928 -386.76707) (xy 83.49742 -386.766816) (xy 83.31581 -386.766816) (xy 83.300785 -386.766399)
			(xy 83.271758 -386.758622) (xy 83.245734 -386.743595) (xy 83.224488 -386.722343) (xy 83.209468 -386.696316)
			(xy 83.201698 -386.667287) (xy 83.201256 -386.652262) (xy 83.201256 -386.538724) (xy 83.199478 -386.53212)
			(xy 83.194272 -386.511751) (xy 83.188671 -386.470083) (xy 83.188302 -386.449062) (xy 83.189064 -386.426456)
			(xy 83.189826 -386.41655) (xy 83.183476 -386.397246) (xy 83.123278 -386.327904) (xy 83.105244 -386.31876)
			(xy 83.095338 -386.317998) (xy 83.071515 -386.315772) (xy 83.024886 -386.30505) (xy 82.980411 -386.287408)
			(xy 82.939109 -386.263253) (xy 82.90193 -386.233138) (xy 82.869724 -386.197754) (xy 82.843231 -386.157913)
			(xy 82.823058 -386.114527) (xy 82.815938 -386.091684) (xy 82.814414 -386.085842) (xy 82.493866 -385.53136)
			(xy 82.489802 -385.527042) (xy 82.473718 -385.509369) (xy 82.446529 -385.470072) (xy 82.425575 -385.427126)
			(xy 82.411335 -385.381512) (xy 82.404134 -385.334273) (xy 82.403696 -385.31038) (xy 81.87131 -385.31038)
			(xy 82.143854 -385.78155) (xy 82.147918 -385.785868) (xy 82.164068 -385.803576) (xy 82.191414 -385.842934)
			(xy 82.212495 -385.885972) (xy 82.226828 -385.931703) (xy 82.234082 -385.979076) (xy 82.234532 -386.003038)
			(xy 82.234532 -386.003546) (xy 82.234024 -386.023866) (xy 82.233262 -386.033772) (xy 82.239612 -386.052822)
			(xy 82.300318 -386.122164) (xy 82.318098 -386.131054) (xy 82.328258 -386.131816) (xy 82.353234 -386.13402)
			(xy 82.402091 -386.145271) (xy 82.448579 -386.164049) (xy 82.491543 -386.189888) (xy 82.529922 -386.222149)
			(xy 82.546698 -386.240782) (xy 82.549155 -386.24356) (xy 82.554771 -386.248403) (xy 82.557874 -386.250434)
			(xy 82.569903 -386.258515) (xy 82.589796 -386.279572) (xy 82.603805 -386.304928) (xy 82.611043 -386.332978)
			(xy 82.611468 -386.347462) (xy 82.611468 -386.3594) (xy 82.613246 -386.366004) (xy 82.618438 -386.386376)
			(xy 82.624048 -386.428042) (xy 82.624422 -386.449062) (xy 82.62404 -386.470082) (xy 82.61844 -386.511748)
			(xy 82.613246 -386.53212) (xy 82.611468 -386.538724) (xy 82.611468 -386.652262) (xy 82.610975 -386.667282)
			(xy 82.603209 -386.6963) (xy 82.588196 -386.722318) (xy 82.56696 -386.743564) (xy 82.540948 -386.758589)
			(xy 82.511934 -386.766368) (xy 82.496914 -386.766816) (xy 82.315304 -386.766816) (xy 82.314796 -386.76707)
			(xy 82.298032 -386.76707) (xy 82.297524 -386.766816) (xy 82.115914 -386.766816) (xy 82.100889 -386.766395)
			(xy 82.071862 -386.758619) (xy 82.045839 -386.743593) (xy 82.024592 -386.722342) (xy 82.009572 -386.696315)
			(xy 82.001802 -386.667287) (xy 82.00136 -386.652262) (xy 82.00136 -386.538724) (xy 81.999582 -386.53212)
			(xy 81.994376 -386.511751) (xy 81.988775 -386.470083) (xy 81.988406 -386.449062) (xy 81.989168 -386.426456)
			(xy 81.98993 -386.41655) (xy 81.98358 -386.397246) (xy 81.923382 -386.327904) (xy 81.905348 -386.31876)
			(xy 81.895442 -386.317998) (xy 81.871619 -386.315769) (xy 81.82499 -386.305047) (xy 81.780515 -386.287406)
			(xy 81.739214 -386.263252) (xy 81.702034 -386.233137) (xy 81.669828 -386.197754) (xy 81.643335 -386.157912)
			(xy 81.623162 -386.114527) (xy 81.616042 -386.091684) (xy 81.614518 -386.085842) (xy 81.294224 -385.532122)
			(xy 81.29016 -385.527804) (xy 81.273925 -385.510123) (xy 81.246507 -385.470724) (xy 81.225371 -385.427628)
			(xy 81.211004 -385.381828) (xy 81.203738 -385.33438) (xy 81.203292 -385.31038) (xy 80.671289 -385.31038)
			(xy 80.943958 -385.78155) (xy 80.948022 -385.785868) (xy 80.964173 -385.803576) (xy 80.991518 -385.842933)
			(xy 81.012599 -385.885972) (xy 81.026932 -385.931703) (xy 81.034186 -385.979076) (xy 81.034636 -386.003038)
			(xy 81.034636 -386.003546) (xy 81.034128 -386.023866) (xy 81.033366 -386.033772) (xy 81.039716 -386.052822)
			(xy 81.100422 -386.122164) (xy 81.118202 -386.131054) (xy 81.128362 -386.131816) (xy 81.153309 -386.134056)
			(xy 81.202108 -386.145331) (xy 81.248538 -386.164113) (xy 81.291452 -386.189938) (xy 81.329788 -386.222169)
			(xy 81.346548 -386.240782) (xy 81.349011 -386.243554) (xy 81.354623 -386.248401) (xy 81.357724 -386.250434)
			(xy 81.369791 -386.258488) (xy 81.389749 -386.279532) (xy 81.403823 -386.304891) (xy 81.411121 -386.332961)
			(xy 81.411572 -386.347462) (xy 81.411572 -386.3594) (xy 81.413096 -386.366004) (xy 81.418287 -386.386377)
			(xy 81.423898 -386.428042) (xy 81.424272 -386.449062) (xy 81.423892 -386.470082) (xy 81.418291 -386.511749)
			(xy 81.413096 -386.53212) (xy 81.411572 -386.538724) (xy 81.411572 -386.652262) (xy 81.411034 -386.667255)
			(xy 81.403293 -386.696223) (xy 81.388327 -386.722206) (xy 81.367153 -386.743437) (xy 81.341211 -386.758473)
			(xy 81.312263 -386.766293) (xy 81.297272 -386.766816) (xy 81.115154 -386.766816) (xy 81.114646 -386.76707)
			(xy 81.097882 -386.76707) (xy 81.097374 -386.766816) (xy 80.915764 -386.766816) (xy 80.900734 -386.766352)
			(xy 80.871697 -386.758575) (xy 80.845656 -386.743559) (xy 80.824379 -386.722324) (xy 80.809312 -386.696313)
			(xy 80.801478 -386.667291) (xy 80.800956 -386.652262) (xy 80.800956 -386.538724) (xy 80.799432 -386.53212)
			(xy 80.794225 -386.511751) (xy 80.788625 -386.470083) (xy 80.788256 -386.449062) (xy 80.789018 -386.426456)
			(xy 80.78978 -386.416296) (xy 80.783684 -386.3975) (xy 80.73009 -386.335524) (xy 80.723167 -386.328258)
			(xy 80.705252 -386.319247) (xy 80.695292 -386.317998) (xy 80.671479 -386.315811) (xy 80.624886 -386.305049)
			(xy 80.580451 -386.287381) (xy 80.53919 -386.263209) (xy 80.502048 -386.233089) (xy 80.469877 -386.19771)
			(xy 80.443412 -386.157881) (xy 80.423259 -386.114516) (xy 80.416146 -386.091684) (xy 80.414622 -386.085842)
			(xy 80.097122 -385.537202) (xy 80.090264 -385.527804) (xy 80.081882 -385.51866) (xy 80.02778 -385.549902)
			(xy 80.014318 -385.578604) (xy 80.016858 -385.594352) (xy 80.018636 -385.61518) (xy 80.018636 -385.819904)
			(xy 80.019144 -385.823714) (xy 80.021047 -385.83652) (xy 80.023085 -385.86233) (xy 80.023208 -385.875276)
			(xy 80.023208 -385.87553) (xy 80.023038 -385.891119) (xy 80.020112 -385.92216) (xy 80.017366 -385.937506)
			(xy 80.016858 -385.939538) (xy 80.013302 -385.956048) (xy 80.012794 -385.957572) (xy 80.008303 -385.974211)
			(xy 79.996343 -386.006535) (xy 79.988918 -386.022088) (xy 79.988918 -386.022342) (xy 79.984917 -386.031623)
			(xy 79.983723 -386.051781) (xy 79.986632 -386.061458) (xy 80.014572 -386.140198) (xy 80.028542 -386.155184)
			(xy 80.03794 -386.159502) (xy 80.058523 -386.169332) (xy 80.096909 -386.193972) (xy 80.131399 -386.223822)
			(xy 80.146652 -386.240782) (xy 80.149115 -386.243554) (xy 80.154727 -386.248401) (xy 80.157828 -386.250434)
			(xy 80.169896 -386.258486) (xy 80.189854 -386.279531) (xy 80.203927 -386.304891) (xy 80.211225 -386.332961)
			(xy 80.211676 -386.347462) (xy 80.211676 -386.3594) (xy 80.2132 -386.366004) (xy 80.218391 -386.386377)
			(xy 80.224002 -386.428042) (xy 80.224376 -386.449062) (xy 80.223995 -386.470082) (xy 80.218395 -386.511749)
			(xy 80.2132 -386.53212) (xy 80.211676 -386.538724) (xy 80.211676 -386.652262) (xy 80.211134 -386.667254)
			(xy 80.203393 -386.696222) (xy 80.188428 -386.722205) (xy 80.167255 -386.743436) (xy 80.141313 -386.758472)
			(xy 80.112367 -386.766293) (xy 80.097376 -386.766816) (xy 79.915258 -386.766816) (xy 79.91475 -386.76707)
			(xy 79.897986 -386.76707) (xy 79.897478 -386.766816) (xy 79.715868 -386.766816) (xy 79.700838 -386.766348)
			(xy 79.671801 -386.758572) (xy 79.64576 -386.743557) (xy 79.624483 -386.722323) (xy 79.609416 -386.696312)
			(xy 79.601582 -386.667291) (xy 79.60106 -386.652262) (xy 79.60106 -386.538724) (xy 79.599536 -386.53212)
			(xy 79.594329 -386.511751) (xy 79.588729 -386.470083) (xy 79.58836 -386.449062) (xy 79.588728 -386.428041)
			(xy 79.594338 -386.386375) (xy 79.599536 -386.366004) (xy 79.60106 -386.3594) (xy 79.60106 -386.347462)
			(xy 79.601353 -386.336861) (xy 79.605315 -386.316029) (xy 79.608934 -386.30606) (xy 79.61249 -386.296916)
			(xy 79.612236 -386.277612) (xy 79.5782 -386.194554) (xy 79.565246 -386.180838) (xy 79.556102 -386.176774)
			(xy 79.531643 -386.165141) (xy 79.486601 -386.135068) (xy 79.447063 -386.098055) (xy 79.414086 -386.055093)
			(xy 79.388552 -386.007331) (xy 79.371145 -385.956046) (xy 79.362329 -385.90261) (xy 79.361792 -385.87553)
			(xy 77.9145 -385.87553) (xy 77.9145 -386.361432) (xy 77.917802 -386.370322) (xy 77.928157 -386.399013)
			(xy 77.939402 -386.458955) (xy 77.940154 -386.489448) (xy 77.939477 -386.519948) (xy 77.928222 -386.579901)
			(xy 77.917802 -386.608574) (xy 77.9145 -386.617464) (xy 77.9145 -386.751068) (xy 77.921104 -386.76834)
			(xy 77.9272 -386.775198) (xy 77.937051 -386.787025) (xy 77.951352 -386.81427) (xy 77.958737 -386.844141)
			(xy 77.959204 -386.859526) (xy 77.959204 -386.995162) (xy 77.959966 -386.998972) (xy 77.961637 -387.011095)
			(xy 77.963414 -387.035503) (xy 77.963522 -387.04774) (xy 77.963433 -387.059977) (xy 77.961655 -387.084387)
			(xy 77.959966 -387.096508) (xy 77.959204 -387.100318) (xy 77.959204 -387.24078) (xy 77.958664 -387.257475)
			(xy 77.950036 -387.289732) (xy 77.933363 -387.318662) (xy 77.909777 -387.342298) (xy 77.880883 -387.359032)
			(xy 77.848644 -387.367728) (xy 77.83195 -387.368288) (xy 77.714856 -387.368288) (xy 77.709014 -387.369558)
			(xy 77.683948 -387.374993) (xy 77.632814 -387.378961) (xy 77.58168 -387.374993) (xy 77.556614 -387.369558)
			(xy 77.550772 -387.368288) (xy 77.52715 -387.368288) (xy 77.509846 -387.367701) (xy 77.476512 -387.358393)
			(xy 77.446902 -387.340476) (xy 77.423191 -387.315265) (xy 77.414628 -387.300216) (xy 77.412633 -387.296578)
			(xy 77.407653 -387.289944) (xy 77.404722 -387.287008) (xy 77.385684 -387.268171) (xy 77.353353 -387.225477)
			(xy 77.328328 -387.17813) (xy 77.311264 -387.127367) (xy 77.302608 -387.074517) (xy 77.302106 -387.04774)
			(xy 77.302237 -387.035821) (xy 77.304018 -387.012048) (xy 77.305662 -387.000242) (xy 77.305662 -386.999988)
			(xy 77.306672 -386.989113) (xy 77.300472 -386.968193) (xy 77.293724 -386.959602) (xy 77.243432 -386.901436)
			(xy 77.235879 -386.893524) (xy 77.216004 -386.88444) (xy 77.205078 -386.88391) (xy 75.889866 -386.88391)
			(xy 75.879799 -386.88434) (xy 75.861204 -386.892064) (xy 75.853798 -386.898896) (xy 75.27671 -387.475984)
			(xy 75.269876 -387.483387) (xy 75.26217 -387.501985) (xy 75.261724 -387.512052) (xy 75.261724 -388.297674)
			(xy 76.33665 -388.297674) (xy 76.340721 -388.242052) (xy 76.352847 -388.187615) (xy 76.37277 -388.135524)
			(xy 76.400066 -388.086889) (xy 76.434152 -388.042746) (xy 76.474301 -388.004037) (xy 76.519659 -387.971586)
			(xy 76.569259 -387.946085) (xy 76.622043 -387.928078) (xy 76.676886 -387.917948) (xy 76.73262 -387.915911)
			(xy 76.788057 -387.922011) (xy 76.842014 -387.936117) (xy 76.893343 -387.957929) (xy 76.940949 -387.986983)
			(xy 76.983817 -388.022658) (xy 77.021034 -388.064195) (xy 77.051807 -388.110708) (xy 77.075479 -388.161205)
			(xy 77.091547 -388.214612) (xy 77.099667 -388.269788) (xy 77.100148 -388.29615) (xy 77.302106 -388.29615)
			(xy 77.302283 -388.279462) (xy 77.305594 -388.246251) (xy 77.30871 -388.229856) (xy 77.30998 -388.224776)
			(xy 77.30998 -388.189978) (xy 77.310594 -388.172077) (xy 77.320522 -388.137678) (xy 77.339571 -388.107363)
			(xy 77.366255 -388.083492) (xy 77.382116 -388.07517) (xy 77.386048 -388.073121) (xy 77.393202 -388.067887)
			(xy 77.39634 -388.064756) (xy 77.415138 -388.046277) (xy 77.45752 -388.014937) (xy 77.504339 -387.990723)
			(xy 77.554409 -387.974248) (xy 77.606458 -387.96593) (xy 77.632814 -387.965442) (xy 77.660636 -387.966009)
			(xy 77.715495 -387.975331) (xy 77.768017 -387.993709) (xy 77.816719 -388.020624) (xy 77.860226 -388.055316)
			(xy 77.879194 -388.075678) (xy 77.888846 -388.08406) (xy 77.900857 -388.09259) (xy 77.920934 -388.11414)
			(xy 77.935558 -388.139705) (xy 77.943956 -388.167935) (xy 77.945234 -388.182612) (xy 77.94752 -388.195058)
			(xy 77.954963 -388.219667) (xy 77.962997 -388.270445) (xy 77.963522 -388.29615) (xy 77.963065 -388.321582)
			(xy 77.961968 -388.328662) (xy 79.728314 -388.328662) (xy 79.72868 -388.307641) (xy 79.734291 -388.265975)
			(xy 79.73949 -388.245604) (xy 79.741268 -388.239) (xy 79.741268 -388.125462) (xy 79.741703 -388.110442)
			(xy 79.749487 -388.081427) (xy 79.764515 -388.055415) (xy 79.785763 -388.034178) (xy 79.811782 -388.019164)
			(xy 79.840801 -388.011395) (xy 79.855822 -388.010908) (xy 80.037432 -388.010908) (xy 80.03794 -388.010654)
			(xy 80.054704 -388.010654) (xy 80.055212 -388.010908) (xy 80.236822 -388.010908) (xy 80.251837 -388.011416)
			(xy 80.280842 -388.019191) (xy 80.306848 -388.034207) (xy 80.328084 -388.055439) (xy 80.343102 -388.081443)
			(xy 80.350882 -388.110447) (xy 80.351376 -388.125462) (xy 80.351376 -388.239) (xy 80.353154 -388.245604)
			(xy 80.358346 -388.265976) (xy 80.363956 -388.307642) (xy 80.36433 -388.328662) (xy 80.92821 -388.328662)
			(xy 80.928576 -388.307641) (xy 80.934187 -388.265975) (xy 80.939386 -388.245604) (xy 80.941164 -388.239)
			(xy 80.941164 -388.125462) (xy 80.941603 -388.110442) (xy 80.949387 -388.081428) (xy 80.964414 -388.055416)
			(xy 80.985661 -388.03418) (xy 81.01168 -388.019165) (xy 81.040698 -388.011396) (xy 81.055718 -388.010908)
			(xy 81.237328 -388.010908) (xy 81.237836 -388.010654) (xy 81.2546 -388.010654) (xy 81.255108 -388.010908)
			(xy 81.436718 -388.010908) (xy 81.451732 -388.01142) (xy 81.480738 -388.019194) (xy 81.506744 -388.034208)
			(xy 81.527979 -388.05544) (xy 81.542998 -388.081444) (xy 81.550778 -388.110448) (xy 81.551272 -388.125462)
			(xy 81.551272 -388.239) (xy 81.55305 -388.245604) (xy 81.558242 -388.265976) (xy 81.563852 -388.307642)
			(xy 81.564226 -388.328662) (xy 82.12836 -388.328662) (xy 82.128728 -388.307641) (xy 82.134338 -388.265975)
			(xy 82.139536 -388.245604) (xy 82.14106 -388.239) (xy 82.14106 -388.125462) (xy 82.1415 -388.110463)
			(xy 82.149262 -388.081487) (xy 82.164248 -388.055502) (xy 82.185441 -388.034272) (xy 82.2114 -388.019239)
			(xy 82.240362 -388.011426) (xy 82.25536 -388.010908) (xy 82.437478 -388.010908) (xy 82.437986 -388.010654)
			(xy 82.45475 -388.010654) (xy 82.455258 -388.010908) (xy 82.636868 -388.010908) (xy 82.651897 -388.011408)
			(xy 82.680935 -388.019171) (xy 82.706979 -388.034177) (xy 82.728258 -388.055406) (xy 82.743325 -388.081415)
			(xy 82.751156 -388.110434) (xy 82.751676 -388.125462) (xy 82.751676 -388.239) (xy 82.7532 -388.245604)
			(xy 82.758391 -388.265977) (xy 82.764002 -388.307642) (xy 82.764376 -388.328662) (xy 83.328256 -388.328662)
			(xy 83.328624 -388.307641) (xy 83.334234 -388.265975) (xy 83.339432 -388.245604) (xy 83.340956 -388.239)
			(xy 83.340956 -388.125462) (xy 83.3414 -388.110464) (xy 83.349161 -388.081488) (xy 83.364147 -388.055503)
			(xy 83.385339 -388.034273) (xy 83.411297 -388.019241) (xy 83.440259 -388.011427) (xy 83.455256 -388.010908)
			(xy 83.637374 -388.010908) (xy 83.637882 -388.010654) (xy 83.654646 -388.010654) (xy 83.655154 -388.010908)
			(xy 83.836764 -388.010908) (xy 83.851793 -388.011412) (xy 83.880831 -388.019174) (xy 83.906874 -388.034179)
			(xy 83.928154 -388.055407) (xy 83.943221 -388.081415) (xy 83.951052 -388.110434) (xy 83.951572 -388.125462)
			(xy 83.951572 -388.239) (xy 83.953096 -388.245604) (xy 83.958287 -388.265977) (xy 83.963898 -388.307642)
			(xy 83.964272 -388.328662) (xy 83.964272 -388.32917) (xy 83.964102 -388.343795) (xy 83.961435 -388.372924)
			(xy 83.958938 -388.387336) (xy 83.957569 -388.39651) (xy 83.960844 -388.414753) (xy 83.965288 -388.422896)
			(xy 83.981798 -388.44982) (xy 83.986948 -388.457613) (xy 84.001688 -388.469068) (xy 84.0105 -388.472172)
			(xy 84.03538 -388.480239) (xy 84.08226 -388.503428) (xy 84.124672 -388.534031) (xy 84.161456 -388.57121)
			(xy 84.191603 -388.613948) (xy 84.214288 -388.661073) (xy 84.222082 -388.68604) (xy 84.223606 -388.691882)
			(xy 84.318094 -388.855204) (xy 84.349844 -388.868412) (xy 84.366608 -388.86384) (xy 84.377186 -388.860363)
			(xy 84.394225 -388.846081) (xy 84.40363 -388.825935) (xy 84.4042 -388.814818) (xy 84.4042 -387.6675)
			(xy 84.417408 -387.6675) (xy 84.417408 -387.495542) (xy 84.417853 -387.485475) (xy 84.42556 -387.466877)
			(xy 84.432394 -387.459474) (xy 84.496656 -387.395212) (xy 84.503373 -387.387838) (xy 84.510998 -387.369423)
			(xy 84.51106 -387.349492) (xy 84.50355 -387.33103) (xy 84.49691 -387.323584) (xy 84.49564 -387.322314)
			(xy 84.494624 -387.321298) (xy 84.487039 -387.314476) (xy 84.472678 -387.299985) (xy 84.465922 -387.292342)
			(xy 84.46346 -387.289569) (xy 84.457847 -387.284723) (xy 84.454746 -387.28269) (xy 84.442733 -387.274589)
			(xy 84.422837 -387.253538) (xy 84.408823 -387.228189) (xy 84.40158 -387.200144) (xy 84.401152 -387.185662)
			(xy 84.401152 -387.173724) (xy 84.399374 -387.16712) (xy 84.394168 -387.146751) (xy 84.388567 -387.105083)
			(xy 84.388198 -387.084062) (xy 84.388565 -387.063041) (xy 84.394175 -387.021375) (xy 84.399374 -387.001004)
			(xy 84.401152 -386.9944) (xy 84.401152 -386.880862) (xy 84.401808 -386.862743) (xy 84.413064 -386.828297)
			(xy 84.42325 -386.813298) (xy 84.427726 -386.806629) (xy 84.432656 -386.791353) (xy 84.432902 -386.783326)
			(xy 84.432902 -386.749798) (xy 84.432581 -386.741781) (xy 84.427679 -386.726515) (xy 84.42325 -386.719826)
			(xy 84.413164 -386.704776) (xy 84.401909 -386.670363) (xy 84.401152 -386.652262) (xy 84.401152 -386.538724)
			(xy 84.399374 -386.53212) (xy 84.394168 -386.511751) (xy 84.388567 -386.470083) (xy 84.388198 -386.449062)
			(xy 84.38896 -386.426456) (xy 84.389722 -386.416296) (xy 84.383626 -386.3975) (xy 84.330032 -386.335524)
			(xy 84.323093 -386.328274) (xy 84.30519 -386.319254) (xy 84.295234 -386.317998) (xy 84.271425 -386.315777)
			(xy 84.224833 -386.305022) (xy 84.180398 -386.287359) (xy 84.139136 -386.263193) (xy 84.101994 -386.233077)
			(xy 84.069822 -386.197702) (xy 84.043355 -386.157877) (xy 84.023202 -386.114514) (xy 84.016088 -386.091684)
			(xy 84.014564 -386.085842) (xy 83.69427 -385.532122) (xy 83.690206 -385.527804) (xy 83.674063 -385.510123)
			(xy 83.64674 -385.470811) (xy 83.625668 -385.427822) (xy 83.611331 -385.382144) (xy 83.604057 -385.334825)
			(xy 83.603592 -385.310888) (xy 83.603592 -385.31038) (xy 83.604099 -385.285592) (xy 83.611857 -385.236626)
			(xy 83.627178 -385.189477) (xy 83.649686 -385.145304) (xy 83.678825 -385.105195) (xy 83.71388 -385.070138)
			(xy 83.753987 -385.040996) (xy 83.798158 -385.018486) (xy 83.845307 -385.003162) (xy 83.894272 -384.995401)
			(xy 83.91906 -384.994912) (xy 83.944454 -384.995431) (xy 83.994588 -385.003556) (xy 84.042774 -385.019603)
			(xy 84.087769 -385.043158) (xy 84.128413 -385.073613) (xy 84.163656 -385.110183) (xy 84.192589 -385.151923)
			(xy 84.214466 -385.197758) (xy 84.222082 -385.221988) (xy 84.223606 -385.22783) (xy 84.5439 -385.78155)
			(xy 84.547964 -385.785868) (xy 84.564173 -385.803537) (xy 84.59157 -385.842888) (xy 84.612699 -385.88593)
			(xy 84.627074 -385.931673) (xy 84.634366 -385.979064) (xy 84.634832 -386.003038) (xy 84.634832 -386.003546)
			(xy 84.63407 -386.023866) (xy 84.633308 -386.033772) (xy 84.639658 -386.052822) (xy 84.700364 -386.122164)
			(xy 84.718144 -386.131054) (xy 84.728304 -386.131816) (xy 84.753254 -386.134031) (xy 84.802054 -386.145312)
			(xy 84.848484 -386.1641) (xy 84.891396 -386.189931) (xy 84.929731 -386.222167) (xy 84.94649 -386.240782)
			(xy 84.948948 -386.243559) (xy 84.954563 -386.248402) (xy 84.957666 -386.250434) (xy 84.969693 -386.258517)
			(xy 84.989587 -386.279574) (xy 85.003597 -386.304929) (xy 85.010835 -386.332978) (xy 85.01126 -386.347462)
			(xy 85.01126 -386.3594) (xy 85.013038 -386.366004) (xy 85.01823 -386.386376) (xy 85.02384 -386.428042)
			(xy 85.024214 -386.449062) (xy 85.023832 -386.470082) (xy 85.018232 -386.511748) (xy 85.013038 -386.53212)
			(xy 85.01126 -386.538724) (xy 85.01126 -386.599176) (xy 85.011807 -386.609177) (xy 85.019451 -386.627661)
			(xy 85.033585 -386.641813) (xy 85.052059 -386.649481) (xy 85.06206 -386.649976) (xy 85.066124 -386.649976)
			(xy 85.070188 -386.649214) (xy 85.081857 -386.647459) (xy 85.105379 -386.645553) (xy 85.117178 -386.645404)
			(xy 85.550248 -386.645404) (xy 85.560258 -386.644951) (xy 85.57875 -386.637277) (xy 85.592901 -386.623113)
			(xy 85.60056 -386.604615) (xy 85.601048 -386.594604) (xy 85.601048 -386.538724) (xy 85.599524 -386.53212)
			(xy 85.594317 -386.511751) (xy 85.588717 -386.470083) (xy 85.588348 -386.449062) (xy 85.58911 -386.426456)
			(xy 85.589872 -386.41655) (xy 85.583522 -386.397246) (xy 85.523324 -386.327904) (xy 85.50529 -386.31876)
			(xy 85.495384 -386.317998) (xy 85.471556 -386.315816) (xy 85.424925 -386.305086) (xy 85.38045 -386.287437)
			(xy 85.339149 -386.263275) (xy 85.30197 -386.233154) (xy 85.269766 -386.197765) (xy 85.243274 -386.157919)
			(xy 85.223103 -386.114529) (xy 85.215984 -386.091684) (xy 85.21446 -386.085842) (xy 84.894166 -385.532122)
			(xy 84.890102 -385.527804) (xy 84.873958 -385.510124) (xy 84.846636 -385.470811) (xy 84.825564 -385.427822)
			(xy 84.811227 -385.382144) (xy 84.803953 -385.334825) (xy 84.803488 -385.310888) (xy 84.803488 -385.31038)
			(xy 84.803999 -385.285592) (xy 84.811757 -385.236627) (xy 84.827078 -385.189478) (xy 84.849585 -385.145305)
			(xy 84.878724 -385.105197) (xy 84.913778 -385.07014) (xy 84.953885 -385.040997) (xy 84.998055 -385.018487)
			(xy 85.045203 -385.003162) (xy 85.094168 -384.995401) (xy 85.118956 -384.994912) (xy 85.14435 -384.995434)
			(xy 85.194483 -385.003559) (xy 85.24267 -385.019605) (xy 85.287665 -385.04316) (xy 85.328308 -385.073614)
			(xy 85.363551 -385.110183) (xy 85.392485 -385.151924) (xy 85.414362 -385.197758) (xy 85.421978 -385.221988)
			(xy 85.423502 -385.22783) (xy 85.743796 -385.78155) (xy 85.74786 -385.785868) (xy 85.764069 -385.803538)
			(xy 85.791465 -385.842889) (xy 85.812594 -385.885931) (xy 85.82697 -385.931673) (xy 85.834262 -385.979064)
			(xy 85.834728 -386.003038) (xy 85.834728 -386.003546) (xy 85.833966 -386.023866) (xy 85.833204 -386.033772)
			(xy 85.839554 -386.052822) (xy 85.90026 -386.122164) (xy 85.91804 -386.131054) (xy 85.9282 -386.131816)
			(xy 85.953179 -386.133994) (xy 86.002037 -386.145252) (xy 86.048524 -386.164036) (xy 86.091488 -386.189881)
			(xy 86.129865 -386.222146) (xy 86.14664 -386.240782) (xy 86.149104 -386.243553) (xy 86.154715 -386.2484)
			(xy 86.157816 -386.250434) (xy 86.169881 -386.25849) (xy 86.18984 -386.279533) (xy 86.203915 -386.304892)
			(xy 86.211213 -386.332961) (xy 86.211664 -386.347462) (xy 86.211664 -386.3594) (xy 86.213188 -386.366004)
			(xy 86.218379 -386.386377) (xy 86.22399 -386.428042) (xy 86.224364 -386.449062) (xy 86.223984 -386.470082)
			(xy 86.218383 -386.511749) (xy 86.213188 -386.53212) (xy 86.211664 -386.538724) (xy 86.211664 -386.594604)
			(xy 86.212184 -386.604607) (xy 86.219838 -386.623092) (xy 86.233981 -386.637244) (xy 86.252461 -386.64491)
			(xy 86.262464 -386.645404) (xy 86.339172 -386.645404) (xy 86.368632 -386.646124) (xy 86.426444 -386.657512)
			(xy 86.45398 -386.66801) (xy 86.463378 -386.67182) (xy 86.764876 -386.67182) (xy 86.77117 -386.671622)
			(xy 86.783376 -386.668545) (xy 86.789006 -386.665724) (xy 86.800944 -386.659628) (xy 86.800944 -386.538724)
			(xy 86.79942 -386.53212) (xy 86.794213 -386.511751) (xy 86.788613 -386.470083) (xy 86.788244 -386.449062)
			(xy 86.789006 -386.426456) (xy 86.789768 -386.416296) (xy 86.783672 -386.3975) (xy 86.730078 -386.335524)
			(xy 86.723159 -386.328253) (xy 86.705241 -386.319245) (xy 86.69528 -386.317998) (xy 86.671466 -386.315821)
			(xy 86.624873 -386.305057) (xy 86.580437 -386.287387) (xy 86.539177 -386.263214) (xy 86.502035 -386.233093)
			(xy 86.469864 -386.197712) (xy 86.443399 -386.157883) (xy 86.423247 -386.114516) (xy 86.416134 -386.091684)
			(xy 86.41461 -386.085842) (xy 86.094316 -385.532122) (xy 86.090252 -385.527804) (xy 86.074016 -385.510124)
			(xy 86.046598 -385.470725) (xy 86.025462 -385.427628) (xy 86.011096 -385.381828) (xy 86.00383 -385.33438)
			(xy 86.003384 -385.31038) (xy 86.003898 -385.285605) (xy 86.011648 -385.236664) (xy 86.026953 -385.189537)
			(xy 86.049438 -385.145382) (xy 86.078549 -385.105285) (xy 86.11357 -385.070232) (xy 86.153641 -385.041085)
			(xy 86.197776 -385.018561) (xy 86.24489 -385.003214) (xy 86.293823 -384.99542) (xy 86.318598 -384.994912)
			(xy 86.319106 -384.994912) (xy 86.344501 -384.99539) (xy 86.394637 -385.003522) (xy 86.442824 -385.019576)
			(xy 86.487819 -385.043137) (xy 86.528462 -385.073598) (xy 86.563705 -385.110173) (xy 86.592637 -385.151918)
			(xy 86.614513 -385.197756) (xy 86.622128 -385.221988) (xy 86.623652 -385.22783) (xy 86.943946 -385.78155)
			(xy 86.94801 -385.785868) (xy 86.964159 -385.803578) (xy 86.991505 -385.842934) (xy 87.012587 -385.885973)
			(xy 87.02692 -385.931704) (xy 87.034174 -385.979076) (xy 87.034624 -386.003038) (xy 87.034624 -386.003546)
			(xy 87.034116 -386.023866) (xy 87.033354 -386.033772) (xy 87.039704 -386.052822) (xy 87.10041 -386.122164)
			(xy 87.11819 -386.131054) (xy 87.12835 -386.131816) (xy 87.153303 -386.134003) (xy 87.202104 -386.145291)
			(xy 87.248533 -386.164086) (xy 87.291445 -386.189923) (xy 87.329778 -386.222164) (xy 87.346536 -386.240782)
			(xy 87.349001 -386.243552) (xy 87.354611 -386.2484) (xy 87.357712 -386.250434) (xy 87.369776 -386.258491)
			(xy 87.389736 -386.279533) (xy 87.403811 -386.304892) (xy 87.411109 -386.332962) (xy 87.41156 -386.347462)
			(xy 87.41156 -386.3594) (xy 87.413084 -386.366004) (xy 87.418277 -386.386376) (xy 87.423886 -386.428042)
			(xy 87.42426 -386.449062) (xy 87.423877 -386.470082) (xy 87.418277 -386.511748) (xy 87.413084 -386.53212)
			(xy 87.41156 -386.538724) (xy 87.41156 -386.576824) (xy 87.412067 -386.586828) (xy 87.419727 -386.605313)
			(xy 87.433874 -386.619464) (xy 87.452356 -386.62713) (xy 87.46236 -386.627624) (xy 87.950548 -386.627624)
			(xy 87.960556 -386.627152) (xy 87.979044 -386.619481) (xy 87.993194 -386.605324) (xy 88.000856 -386.586832)
			(xy 88.001348 -386.576824) (xy 88.001348 -386.538724) (xy 87.99957 -386.53212) (xy 87.994364 -386.511751)
			(xy 87.988763 -386.470083) (xy 87.988394 -386.449062) (xy 87.989156 -386.426456) (xy 87.989918 -386.41655)
			(xy 87.983568 -386.397246) (xy 87.92337 -386.327904) (xy 87.905336 -386.31876) (xy 87.89543 -386.317998)
			(xy 87.871606 -386.315779) (xy 87.824977 -386.305055) (xy 87.780502 -386.287413) (xy 87.739201 -386.263257)
			(xy 87.702021 -386.233141) (xy 87.669816 -386.197756) (xy 87.643323 -386.157913) (xy 87.62315 -386.114527)
			(xy 87.61603 -386.091684) (xy 87.614506 -386.085842) (xy 87.294212 -385.532122) (xy 87.290148 -385.527804)
			(xy 87.273911 -385.510125) (xy 87.246494 -385.470725) (xy 87.225358 -385.427628) (xy 87.210992 -385.381828)
			(xy 87.203726 -385.33438) (xy 87.20328 -385.31038) (xy 87.203699 -385.2856) (xy 87.211451 -385.23665)
			(xy 87.226762 -385.189515) (xy 87.249255 -385.145353) (xy 87.278377 -385.105252) (xy 87.313411 -385.070198)
			(xy 87.353495 -385.041053) (xy 87.397643 -385.018534) (xy 87.444769 -385.003195) (xy 87.493714 -384.995413)
			(xy 87.518494 -384.994912) (xy 87.519002 -384.994912) (xy 87.544397 -384.995394) (xy 87.594533 -385.003525)
			(xy 87.64272 -385.019578) (xy 87.687715 -385.043139) (xy 87.728358 -385.073599) (xy 87.7636 -385.110173)
			(xy 87.792533 -385.151918) (xy 87.814409 -385.197756) (xy 87.822024 -385.221988) (xy 87.823548 -385.22783)
			(xy 88.143842 -385.78155) (xy 88.147906 -385.785868) (xy 88.164054 -385.803578) (xy 88.1914 -385.842935)
			(xy 88.212482 -385.885973) (xy 88.226816 -385.931704) (xy 88.23407 -385.979076) (xy 88.23452 -386.003038)
			(xy 88.23452 -386.003546) (xy 88.234012 -386.023866) (xy 88.23325 -386.033772) (xy 88.2396 -386.052822)
			(xy 88.300306 -386.122164) (xy 88.318086 -386.131054) (xy 88.328246 -386.131816) (xy 88.353221 -386.134027)
			(xy 88.402078 -386.145276) (xy 88.448566 -386.164052) (xy 88.491531 -386.18989) (xy 88.52991 -386.222149)
			(xy 88.546686 -386.240782) (xy 88.549145 -386.243558) (xy 88.55476 -386.248402) (xy 88.557862 -386.250434)
			(xy 88.569888 -386.258518) (xy 88.589782 -386.279574) (xy 88.603792 -386.304929) (xy 88.611031 -386.332978)
			(xy 88.611456 -386.347462) (xy 88.611456 -386.3594) (xy 88.613234 -386.366004) (xy 88.618426 -386.386376)
			(xy 88.624036 -386.428042) (xy 88.62441 -386.449062) (xy 88.624028 -386.470082) (xy 88.618428 -386.511748)
			(xy 88.613234 -386.53212) (xy 88.611456 -386.538724) (xy 88.611456 -386.576824) (xy 88.611967 -386.586828)
			(xy 88.619626 -386.605312) (xy 88.633771 -386.619462) (xy 88.652252 -386.627129) (xy 88.662256 -386.627624)
			(xy 89.150444 -386.627624) (xy 89.160451 -386.627148) (xy 89.17894 -386.619479) (xy 89.19309 -386.605323)
			(xy 89.200752 -386.586832) (xy 89.201244 -386.576824) (xy 89.201244 -386.538724) (xy 89.199466 -386.53212)
			(xy 89.19426 -386.511751) (xy 89.188659 -386.470083) (xy 89.18829 -386.449062) (xy 89.189052 -386.426456)
			(xy 89.189814 -386.41655) (xy 89.183464 -386.397246) (xy 89.123266 -386.327904) (xy 89.105232 -386.31876)
			(xy 89.095326 -386.317998) (xy 89.071501 -386.315782) (xy 89.024872 -386.305058) (xy 88.980397 -386.287415)
			(xy 88.939096 -386.263258) (xy 88.901917 -386.233142) (xy 88.869711 -386.197757) (xy 88.843219 -386.157914)
			(xy 88.823046 -386.114528) (xy 88.815926 -386.091684) (xy 88.814402 -386.085842) (xy 88.493854 -385.53136)
			(xy 88.48979 -385.527042) (xy 88.47372 -385.509356) (xy 88.446526 -385.470065) (xy 88.425568 -385.427122)
			(xy 88.411325 -385.38151) (xy 88.404123 -385.334272) (xy 88.403684 -385.31038) (xy 88.404199 -385.285592)
			(xy 88.411957 -385.236627) (xy 88.427277 -385.189478) (xy 88.449784 -385.145306) (xy 88.478923 -385.105198)
			(xy 88.513977 -385.070141) (xy 88.554082 -385.040999) (xy 88.598253 -385.018488) (xy 88.6454 -385.003163)
			(xy 88.694364 -384.995402) (xy 88.719152 -384.994912) (xy 88.744601 -384.995383) (xy 88.79484 -385.003541)
			(xy 88.843119 -385.019652) (xy 88.888189 -385.0433) (xy 88.928881 -385.073871) (xy 88.964142 -385.110575)
			(xy 88.993059 -385.15246) (xy 89.014881 -385.198442) (xy 89.022428 -385.22275) (xy 89.023952 -385.228592)
			(xy 89.343738 -385.78155) (xy 89.347802 -385.785868) (xy 89.363949 -385.803579) (xy 89.391296 -385.842935)
			(xy 89.412378 -385.885973) (xy 89.426711 -385.931704) (xy 89.433966 -385.979076) (xy 89.434416 -386.003038)
			(xy 89.434416 -386.003546) (xy 89.433908 -386.023866) (xy 89.433146 -386.033772) (xy 89.439496 -386.052822)
			(xy 89.500202 -386.122164) (xy 89.517982 -386.131054) (xy 89.528142 -386.131816) (xy 89.553117 -386.134029)
			(xy 89.601974 -386.145278) (xy 89.648461 -386.164054) (xy 89.691427 -386.189891) (xy 89.729806 -386.22215)
			(xy 89.746582 -386.240782) (xy 89.749041 -386.243558) (xy 89.754656 -386.248402) (xy 89.757758 -386.250434)
			(xy 89.769783 -386.258519) (xy 89.789678 -386.279575) (xy 89.803688 -386.304929) (xy 89.810927 -386.332978)
			(xy 89.811352 -386.347462) (xy 89.811352 -386.3594) (xy 89.81313 -386.366004) (xy 89.818322 -386.386376)
			(xy 89.823932 -386.428042) (xy 89.824306 -386.449062) (xy 89.823924 -386.470082) (xy 89.818324 -386.511748)
			(xy 89.81313 -386.53212) (xy 89.811352 -386.538724) (xy 89.811352 -386.576824) (xy 89.811867 -386.586827)
			(xy 89.819526 -386.60531) (xy 89.833669 -386.619461) (xy 89.852149 -386.627128) (xy 89.862152 -386.627624)
			(xy 90.36304 -386.627624) (xy 90.372589 -386.627681) (xy 90.391652 -386.628827) (xy 90.40114 -386.62991)
			(xy 90.40114 -386.538724) (xy 90.399362 -386.53212) (xy 90.394156 -386.511751) (xy 90.388555 -386.470083)
			(xy 90.388186 -386.449062) (xy 90.388948 -386.426456) (xy 90.38971 -386.416296) (xy 90.383614 -386.3975)
			(xy 90.33002 -386.335524) (xy 90.323086 -386.32827) (xy 90.305179 -386.319252) (xy 90.295222 -386.317998)
			(xy 90.271412 -386.315787) (xy 90.22482 -386.30503) (xy 90.180384 -386.287365) (xy 90.139123 -386.263197)
			(xy 90.101981 -386.233081) (xy 90.069809 -386.197704) (xy 90.043343 -386.157878) (xy 90.023189 -386.114515)
			(xy 90.016076 -386.091684) (xy 90.014552 -386.085842) (xy 89.694258 -385.532122) (xy 89.690194 -385.527804)
			(xy 89.674049 -385.510125) (xy 89.646727 -385.470812) (xy 89.625656 -385.427823) (xy 89.611319 -385.382145)
			(xy 89.604045 -385.334825) (xy 89.60358 -385.310888) (xy 89.60358 -385.31038) (xy 89.603975 -385.285585)
			(xy 89.611736 -385.236607) (xy 89.627063 -385.189447) (xy 89.64958 -385.145264) (xy 89.678732 -385.105149)
			(xy 89.713801 -385.070088) (xy 89.753923 -385.040945) (xy 89.79811 -385.018437) (xy 89.845274 -385.00312)
			(xy 89.894253 -384.995369) (xy 89.919048 -384.994912) (xy 89.944445 -384.995353) (xy 89.994582 -385.003492)
			(xy 90.04277 -385.019552) (xy 90.087765 -385.043119) (xy 90.128408 -385.073584) (xy 90.163649 -385.110164)
			(xy 90.192581 -385.151912) (xy 90.214455 -385.197754) (xy 90.22207 -385.221988) (xy 90.223594 -385.22783)
			(xy 90.543888 -385.78155) (xy 90.547952 -385.785868) (xy 90.564159 -385.803539) (xy 90.591556 -385.842889)
			(xy 90.612686 -385.885931) (xy 90.627062 -385.931674) (xy 90.634354 -385.979064) (xy 90.63482 -386.003038)
			(xy 90.63482 -386.003546) (xy 90.634058 -386.023866) (xy 90.633296 -386.033772) (xy 90.639646 -386.052822)
			(xy 90.700352 -386.122164) (xy 90.718132 -386.131054) (xy 90.728292 -386.131816) (xy 90.753241 -386.134038)
			(xy 90.802041 -386.145318) (xy 90.848471 -386.164104) (xy 90.891383 -386.189933) (xy 90.929719 -386.222167)
			(xy 90.946478 -386.240782) (xy 90.948938 -386.243557) (xy 90.954552 -386.248402) (xy 90.957654 -386.250434)
			(xy 90.969678 -386.258521) (xy 90.989573 -386.279576) (xy 91.003584 -386.30493) (xy 91.010823 -386.332978)
			(xy 91.011248 -386.347462) (xy 91.011248 -386.3594) (xy 91.013026 -386.366004) (xy 91.018217 -386.386377)
			(xy 91.023828 -386.428042) (xy 91.024202 -386.449062) (xy 91.023821 -386.470082) (xy 91.01822 -386.511748)
			(xy 91.013026 -386.53212) (xy 91.011248 -386.538724) (xy 91.011248 -386.62102) (xy 91.011605 -386.631049)
			(xy 91.01929 -386.649575) (xy 91.033482 -386.663748) (xy 91.052019 -386.671409) (xy 91.062048 -386.67182)
			(xy 91.401646 -386.67182) (xy 91.414092 -386.668518) (xy 91.41968 -386.66547) (xy 91.446621 -386.651341)
			(xy 91.504587 -386.632912) (xy 91.534742 -386.628894) (xy 91.543649 -386.627614) (xy 91.559785 -386.619673)
			(xy 91.566238 -386.6134) (xy 91.587066 -386.591302) (xy 91.593432 -386.583973) (xy 91.600608 -386.565949)
			(xy 91.601036 -386.55625) (xy 91.601036 -386.538724) (xy 91.599512 -386.53212) (xy 91.594307 -386.511751)
			(xy 91.588705 -386.470083) (xy 91.588336 -386.449062) (xy 91.589098 -386.426456) (xy 91.58986 -386.41655)
			(xy 91.58351 -386.397246) (xy 91.523312 -386.327904) (xy 91.505278 -386.31876) (xy 91.495372 -386.317998)
			(xy 91.471551 -386.315745) (xy 91.424923 -386.305027) (xy 91.380448 -386.287391) (xy 91.339147 -386.26324)
			(xy 91.301967 -386.233129) (xy 91.26976 -386.197748) (xy 91.243266 -386.157909) (xy 91.223093 -386.114526)
			(xy 91.215972 -386.091684) (xy 91.214448 -386.085842) (xy 90.894154 -385.532122) (xy 90.89009 -385.527804)
			(xy 90.873944 -385.510126) (xy 90.846622 -385.470812) (xy 90.825551 -385.427823) (xy 90.811215 -385.382145)
			(xy 90.803941 -385.334825) (xy 90.803476 -385.310888) (xy 90.803476 -385.31038) (xy 90.803875 -385.285586)
			(xy 90.811636 -385.236608) (xy 90.826963 -385.189448) (xy 90.84948 -385.145266) (xy 90.878631 -385.10515)
			(xy 90.913699 -385.070089) (xy 90.95382 -385.040946) (xy 90.998007 -385.018439) (xy 91.04517 -385.003121)
			(xy 91.09415 -384.99537) (xy 91.118944 -384.994912) (xy 91.144341 -384.995357) (xy 91.194478 -385.003495)
			(xy 91.242665 -385.019554) (xy 91.287661 -385.04312) (xy 91.328304 -385.073586) (xy 91.363545 -385.110164)
			(xy 91.392476 -385.151913) (xy 91.414351 -385.197754) (xy 91.421966 -385.221988) (xy 91.42349 -385.22783)
			(xy 91.47124 -385.31038) (xy 92.003372 -385.31038) (xy 92.003799 -385.285601) (xy 92.011551 -385.236652)
			(xy 92.026861 -385.189517) (xy 92.049354 -385.145356) (xy 92.078474 -385.105255) (xy 92.113507 -385.070201)
			(xy 92.15359 -385.041055) (xy 92.197737 -385.018536) (xy 92.244863 -385.003196) (xy 92.293807 -384.995414)
			(xy 92.318586 -384.994912) (xy 92.319094 -384.994912) (xy 92.344489 -384.995401) (xy 92.394624 -385.003531)
			(xy 92.442811 -385.019583) (xy 92.487806 -385.043143) (xy 92.528449 -385.073602) (xy 92.563692 -385.110175)
			(xy 92.592624 -385.151919) (xy 92.614501 -385.197756) (xy 92.622116 -385.221988) (xy 92.62364 -385.22783)
			(xy 92.67139 -385.31038) (xy 93.203268 -385.31038) (xy 93.203699 -385.285601) (xy 93.211451 -385.236652)
			(xy 93.226761 -385.189518) (xy 93.249253 -385.145357) (xy 93.278373 -385.105256) (xy 93.313406 -385.070202)
			(xy 93.353488 -385.041057) (xy 93.397635 -385.018537) (xy 93.444759 -385.003197) (xy 93.493703 -384.995414)
			(xy 93.518482 -384.994912) (xy 93.51899 -384.994912) (xy 93.544385 -384.995404) (xy 93.59452 -385.003534)
			(xy 93.642707 -385.019585) (xy 93.687702 -385.043144) (xy 93.728345 -385.073603) (xy 93.763588 -385.110176)
			(xy 93.79252 -385.151919) (xy 93.814397 -385.197756) (xy 93.822012 -385.221988) (xy 93.823536 -385.22783)
			(xy 93.871286 -385.31038) (xy 94.403672 -385.31038) (xy 94.404075 -385.285586) (xy 94.411836 -385.236609)
			(xy 94.427163 -385.189449) (xy 94.449679 -385.145267) (xy 94.47883 -385.105152) (xy 94.513897 -385.070091)
			(xy 94.554018 -385.040948) (xy 94.598204 -385.01844) (xy 94.645367 -385.003121) (xy 94.694346 -384.99537)
			(xy 94.71914 -384.994912) (xy 94.744588 -384.995394) (xy 94.794827 -385.003549) (xy 94.843106 -385.019659)
			(xy 94.888176 -385.043305) (xy 94.928868 -385.073875) (xy 94.96413 -385.110578) (xy 94.993046 -385.152462)
			(xy 95.014869 -385.198442) (xy 95.022416 -385.22275) (xy 95.02394 -385.228592) (xy 95.071533 -385.310888)
			(xy 95.603568 -385.310888) (xy 95.603568 -385.31038) (xy 95.603975 -385.285586) (xy 95.611735 -385.236609)
			(xy 95.627062 -385.189449) (xy 95.649578 -385.145268) (xy 95.678729 -385.105153) (xy 95.713796 -385.070092)
			(xy 95.753916 -385.040949) (xy 95.798101 -385.018441) (xy 95.845264 -385.003122) (xy 95.894242 -384.99537)
			(xy 95.919036 -384.994912) (xy 95.944432 -384.995364) (xy 95.994569 -385.003501) (xy 96.042757 -385.019559)
			(xy 96.087752 -385.043124) (xy 96.128395 -385.073588) (xy 96.163637 -385.110166) (xy 96.192568 -385.151914)
			(xy 96.214443 -385.197755) (xy 96.222058 -385.221988) (xy 96.223582 -385.22783) (xy 96.271332 -385.31038)
			(xy 96.803464 -385.31038) (xy 96.803899 -385.285601) (xy 96.811651 -385.236653) (xy 96.826961 -385.189519)
			(xy 96.849452 -385.145358) (xy 96.878572 -385.105258) (xy 96.913604 -385.070203) (xy 96.953686 -385.041058)
			(xy 96.997832 -385.018538) (xy 97.044956 -385.003198) (xy 97.093899 -384.995415) (xy 97.118678 -384.994912)
			(xy 97.119186 -384.994912) (xy 97.144633 -384.995441) (xy 97.194869 -385.003589) (xy 97.243147 -385.01969)
			(xy 97.288217 -385.043329) (xy 97.32891 -385.073893) (xy 97.364172 -385.110589) (xy 97.39309 -385.152468)
			(xy 97.414914 -385.198444) (xy 97.422462 -385.22275) (xy 97.423986 -385.228592) (xy 97.743772 -385.78155)
			(xy 97.747836 -385.785868) (xy 97.764041 -385.803542) (xy 97.791439 -385.842891) (xy 97.812569 -385.885932)
			(xy 97.826946 -385.931674) (xy 97.834238 -385.979064) (xy 97.834704 -386.003038) (xy 97.834704 -386.003546)
			(xy 97.833942 -386.023866) (xy 97.83318 -386.033772) (xy 97.83953 -386.052822) (xy 97.900236 -386.122164)
			(xy 97.918016 -386.131054) (xy 97.928176 -386.131816) (xy 97.953153 -386.134009) (xy 98.002011 -386.145263)
			(xy 98.048498 -386.164043) (xy 98.091463 -386.189885) (xy 98.12984 -386.222148) (xy 98.146616 -386.240782)
			(xy 98.149083 -386.24355) (xy 98.154692 -386.248399) (xy 98.157792 -386.250434) (xy 98.169874 -386.258467)
			(xy 98.189826 -386.27952) (xy 98.203895 -386.304886) (xy 98.21119 -386.33296) (xy 98.21164 -386.347462)
			(xy 98.21164 -386.3594) (xy 98.213164 -386.366004) (xy 98.218356 -386.386376) (xy 98.223966 -386.428042)
			(xy 98.22434 -386.449062) (xy 98.223957 -386.470082) (xy 98.218358 -386.511748) (xy 98.213164 -386.53212)
			(xy 98.21164 -386.538724) (xy 98.21164 -386.652262) (xy 98.211133 -386.667257) (xy 98.20339 -386.69623)
			(xy 98.188418 -386.722216) (xy 98.167238 -386.743448) (xy 98.141288 -386.758483) (xy 98.112334 -386.766297)
			(xy 98.09734 -386.766816) (xy 97.915222 -386.766816) (xy 97.914714 -386.76707) (xy 97.89795 -386.76707)
			(xy 97.897442 -386.766816) (xy 97.715832 -386.766816) (xy 97.700805 -386.766292) (xy 97.671771 -386.758531)
			(xy 97.645729 -386.743529) (xy 97.624451 -386.722305) (xy 97.609382 -386.696302) (xy 97.601547 -386.667288)
			(xy 97.601024 -386.652262) (xy 97.601024 -386.538724) (xy 97.5995 -386.53212) (xy 97.594294 -386.511751)
			(xy 97.588693 -386.470083) (xy 97.588324 -386.449062) (xy 97.589086 -386.426456) (xy 97.589848 -386.41655)
			(xy 97.583498 -386.397246) (xy 97.5233 -386.327904) (xy 97.505266 -386.31876) (xy 97.49536 -386.317998)
			(xy 97.471538 -386.315755) (xy 97.42491 -386.305035) (xy 97.380435 -386.287397) (xy 97.339134 -386.263245)
			(xy 97.301954 -386.233132) (xy 97.269748 -386.19775) (xy 97.243254 -386.15791) (xy 97.223081 -386.114526)
			(xy 97.21596 -386.091684) (xy 97.214436 -386.085842) (xy 96.893888 -385.53136) (xy 96.889824 -385.527042)
			(xy 96.873691 -385.509398) (xy 96.846448 -385.470112) (xy 96.825443 -385.427165) (xy 96.811158 -385.381541)
			(xy 96.803919 -385.334284) (xy 96.803464 -385.31038) (xy 96.271332 -385.31038) (xy 96.543876 -385.78155)
			(xy 96.54794 -385.785868) (xy 96.564145 -385.803541) (xy 96.591543 -385.842891) (xy 96.612673 -385.885932)
			(xy 96.62705 -385.931674) (xy 96.634342 -385.979064) (xy 96.634808 -386.003038) (xy 96.634808 -386.003546)
			(xy 96.634046 -386.023866) (xy 96.633284 -386.033772) (xy 96.639634 -386.052822) (xy 96.70034 -386.122164)
			(xy 96.71812 -386.131054) (xy 96.72828 -386.131816) (xy 96.753257 -386.134006) (xy 96.802115 -386.145261)
			(xy 96.848602 -386.164042) (xy 96.891567 -386.189884) (xy 96.929944 -386.222148) (xy 96.94672 -386.240782)
			(xy 96.949187 -386.243551) (xy 96.954796 -386.2484) (xy 96.957896 -386.250434) (xy 96.969957 -386.258496)
			(xy 96.989918 -386.279536) (xy 97.003994 -386.304893) (xy 97.011293 -386.332962) (xy 97.011744 -386.347462)
			(xy 97.011744 -386.3594) (xy 97.013268 -386.366004) (xy 97.01846 -386.386376) (xy 97.02407 -386.428042)
			(xy 97.024444 -386.449062) (xy 97.024061 -386.470082) (xy 97.018462 -386.511748) (xy 97.013268 -386.53212)
			(xy 97.011744 -386.538724) (xy 97.011744 -386.652262) (xy 97.011234 -386.667257) (xy 97.00349 -386.696229)
			(xy 96.988519 -386.722215) (xy 96.96734 -386.743447) (xy 96.941391 -386.758481) (xy 96.912438 -386.766296)
			(xy 96.897444 -386.766816) (xy 96.715326 -386.766816) (xy 96.714818 -386.76707) (xy 96.698054 -386.76707)
			(xy 96.697546 -386.766816) (xy 96.515936 -386.766816) (xy 96.500909 -386.766288) (xy 96.471875 -386.758529)
			(xy 96.445833 -386.743527) (xy 96.424555 -386.722304) (xy 96.409486 -386.696301) (xy 96.401651 -386.667287)
			(xy 96.401128 -386.652262) (xy 96.401128 -386.538724) (xy 96.399604 -386.53212) (xy 96.394399 -386.511751)
			(xy 96.388797 -386.470083) (xy 96.388428 -386.449062) (xy 96.38919 -386.426456) (xy 96.389952 -386.41655)
			(xy 96.383602 -386.397246) (xy 96.323404 -386.327904) (xy 96.30537 -386.31876) (xy 96.295464 -386.317998)
			(xy 96.271643 -386.315751) (xy 96.225014 -386.305032) (xy 96.18054 -386.287395) (xy 96.139238 -386.263243)
			(xy 96.102058 -386.233131) (xy 96.069852 -386.197749) (xy 96.043358 -386.15791) (xy 96.023185 -386.114526)
			(xy 96.016064 -386.091684) (xy 96.01454 -386.085842) (xy 95.694246 -385.532122) (xy 95.690182 -385.527804)
			(xy 95.674035 -385.510127) (xy 95.646713 -385.470813) (xy 95.625643 -385.427823) (xy 95.611307 -385.382145)
			(xy 95.604033 -385.334825) (xy 95.603568 -385.310888) (xy 95.071533 -385.310888) (xy 95.343726 -385.78155)
			(xy 95.34779 -385.785868) (xy 95.363952 -385.803566) (xy 95.391293 -385.842927) (xy 95.412371 -385.885969)
			(xy 95.426701 -385.931702) (xy 95.433954 -385.979075) (xy 95.434404 -386.003038) (xy 95.434404 -386.003546)
			(xy 95.433896 -386.023866) (xy 95.433134 -386.033772) (xy 95.439484 -386.052822) (xy 95.50019 -386.122164)
			(xy 95.51797 -386.131054) (xy 95.52813 -386.131816) (xy 95.553104 -386.134037) (xy 95.601961 -386.145284)
			(xy 95.648448 -386.164057) (xy 95.691414 -386.189893) (xy 95.729793 -386.22215) (xy 95.74657 -386.240782)
			(xy 95.74903 -386.243557) (xy 95.754644 -386.248402) (xy 95.757746 -386.250434) (xy 95.76979 -386.258493)
			(xy 95.789677 -386.27956) (xy 95.803681 -386.304923) (xy 95.810916 -386.332976) (xy 95.81134 -386.347462)
			(xy 95.81134 -386.3594) (xy 95.813118 -386.366004) (xy 95.818309 -386.386377) (xy 95.82392 -386.428042)
			(xy 95.824294 -386.449062) (xy 95.823913 -386.470082) (xy 95.818312 -386.511748) (xy 95.813118 -386.53212)
			(xy 95.81134 -386.538724) (xy 95.81134 -386.652262) (xy 95.810875 -386.667284) (xy 95.803106 -386.696306)
			(xy 95.788089 -386.722328) (xy 95.766847 -386.743574) (xy 95.740829 -386.758597) (xy 95.711808 -386.766371)
			(xy 95.696786 -386.766816) (xy 95.515176 -386.766816) (xy 95.514668 -386.76707) (xy 95.497904 -386.76707)
			(xy 95.497396 -386.766816) (xy 95.315786 -386.766816) (xy 95.30076 -386.76642) (xy 95.271732 -386.758637)
			(xy 95.245708 -386.743605) (xy 95.224463 -386.72235) (xy 95.209443 -386.69632) (xy 95.201674 -386.667289)
			(xy 95.201232 -386.652262) (xy 95.201232 -386.538724) (xy 95.199454 -386.53212) (xy 95.194248 -386.511751)
			(xy 95.188647 -386.470083) (xy 95.188278 -386.449062) (xy 95.18904 -386.426456) (xy 95.189802 -386.41655)
			(xy 95.183452 -386.397246) (xy 95.123254 -386.327904) (xy 95.10522 -386.31876) (xy 95.095314 -386.317998)
			(xy 95.071488 -386.315792) (xy 95.024859 -386.305065) (xy 94.980384 -386.287421) (xy 94.939083 -386.263263)
			(xy 94.901904 -386.233145) (xy 94.869698 -386.197759) (xy 94.843206 -386.157915) (xy 94.823034 -386.114528)
			(xy 94.815914 -386.091684) (xy 94.81439 -386.085842) (xy 94.493842 -385.53136) (xy 94.489778 -385.527042)
			(xy 94.473706 -385.509358) (xy 94.446513 -385.470066) (xy 94.425555 -385.427123) (xy 94.411313 -385.38151)
			(xy 94.404111 -385.334272) (xy 94.403672 -385.31038) (xy 93.871286 -385.31038) (xy 94.14383 -385.78155)
			(xy 94.147894 -385.785868) (xy 94.16404 -385.80358) (xy 94.191387 -385.842936) (xy 94.21247 -385.885974)
			(xy 94.226803 -385.931704) (xy 94.234058 -385.979076) (xy 94.234508 -386.003038) (xy 94.234508 -386.003546)
			(xy 94.234 -386.023866) (xy 94.233238 -386.033772) (xy 94.239588 -386.052822) (xy 94.300294 -386.122164)
			(xy 94.318074 -386.131054) (xy 94.328234 -386.131816) (xy 94.353208 -386.134034) (xy 94.402065 -386.145282)
			(xy 94.448553 -386.164056) (xy 94.491518 -386.189892) (xy 94.529897 -386.22215) (xy 94.546674 -386.240782)
			(xy 94.549134 -386.243557) (xy 94.554748 -386.248402) (xy 94.55785 -386.250434) (xy 94.569895 -386.258491)
			(xy 94.589781 -386.27956) (xy 94.603785 -386.304923) (xy 94.61102 -386.332976) (xy 94.611444 -386.347462)
			(xy 94.611444 -386.3594) (xy 94.613222 -386.366004) (xy 94.618413 -386.386377) (xy 94.624024 -386.428042)
			(xy 94.624398 -386.449062) (xy 94.624017 -386.470082) (xy 94.618416 -386.511748) (xy 94.613222 -386.53212)
			(xy 94.611444 -386.538724) (xy 94.611444 -386.652262) (xy 94.610975 -386.667284) (xy 94.603206 -386.696305)
			(xy 94.58819 -386.722326) (xy 94.566949 -386.743573) (xy 94.540931 -386.758596) (xy 94.511912 -386.766371)
			(xy 94.49689 -386.766816) (xy 94.31528 -386.766816) (xy 94.314772 -386.76707) (xy 94.298008 -386.76707)
			(xy 94.2975 -386.766816) (xy 94.11589 -386.766816) (xy 94.100864 -386.766416) (xy 94.071836 -386.758634)
			(xy 94.045813 -386.743604) (xy 94.024567 -386.722349) (xy 94.009547 -386.696319) (xy 94.001778 -386.667288)
			(xy 94.001336 -386.652262) (xy 94.001336 -386.538724) (xy 93.999558 -386.53212) (xy 93.994352 -386.511751)
			(xy 93.988751 -386.470083) (xy 93.988382 -386.449062) (xy 93.989144 -386.426456) (xy 93.989906 -386.41655)
			(xy 93.983556 -386.397246) (xy 93.923358 -386.327904) (xy 93.905324 -386.31876) (xy 93.895418 -386.317998)
			(xy 93.871593 -386.315789) (xy 93.824963 -386.305063) (xy 93.780488 -386.287419) (xy 93.739187 -386.263261)
			(xy 93.702008 -386.233144) (xy 93.669803 -386.197758) (xy 93.64331 -386.157915) (xy 93.623138 -386.114528)
			(xy 93.616018 -386.091684) (xy 93.614494 -386.085842) (xy 93.2942 -385.532122) (xy 93.290136 -385.527804)
			(xy 93.273897 -385.510127) (xy 93.24648 -385.470726) (xy 93.225345 -385.427629) (xy 93.21098 -385.381828)
			(xy 93.203714 -385.33438) (xy 93.203268 -385.31038) (xy 92.67139 -385.31038) (xy 92.943934 -385.78155)
			(xy 92.947998 -385.785868) (xy 92.964145 -385.803579) (xy 92.991492 -385.842935) (xy 93.012574 -385.885973)
			(xy 93.026907 -385.931704) (xy 93.034162 -385.979076) (xy 93.034612 -386.003038) (xy 93.034612 -386.003546)
			(xy 93.034104 -386.023866) (xy 93.033342 -386.033772) (xy 93.039692 -386.052822) (xy 93.100398 -386.122164)
			(xy 93.118178 -386.131054) (xy 93.128338 -386.131816) (xy 93.15329 -386.13401) (xy 93.202091 -386.145297)
			(xy 93.24852 -386.16409) (xy 93.291432 -386.189925) (xy 93.329766 -386.222165) (xy 93.346524 -386.240782)
			(xy 93.34899 -386.243551) (xy 93.3546 -386.2484) (xy 93.3577 -386.250434) (xy 93.369762 -386.258495)
			(xy 93.389723 -386.279535) (xy 93.403798 -386.304893) (xy 93.411097 -386.332962) (xy 93.411548 -386.347462)
			(xy 93.411548 -386.3594) (xy 93.413072 -386.366004) (xy 93.418264 -386.386376) (xy 93.423874 -386.428042)
			(xy 93.424248 -386.449062) (xy 93.423865 -386.470082) (xy 93.418265 -386.511748) (xy 93.413072 -386.53212)
			(xy 93.411548 -386.538724) (xy 93.411548 -386.652262) (xy 93.410903 -386.670382) (xy 93.399639 -386.704828)
			(xy 93.38945 -386.719826) (xy 93.384934 -386.726485) (xy 93.379901 -386.741759) (xy 93.379544 -386.749798)
			(xy 93.379544 -386.783326) (xy 93.379839 -386.791374) (xy 93.384893 -386.806658) (xy 93.38945 -386.813298)
			(xy 93.399546 -386.828342) (xy 93.410795 -386.862759) (xy 93.411548 -386.880862) (xy 93.411548 -386.9944)
			(xy 93.413072 -387.001004) (xy 93.418264 -387.021376) (xy 93.423874 -387.063042) (xy 93.424248 -387.084062)
			(xy 93.423865 -387.105082) (xy 93.418265 -387.146748) (xy 93.413072 -387.16712) (xy 93.411548 -387.173724)
			(xy 93.411548 -387.185662) (xy 93.410998 -387.201044) (xy 93.402798 -387.230698) (xy 93.387052 -387.25713)
			(xy 93.36488 -387.27846) (xy 93.351604 -387.286246) (xy 93.347794 -387.290818) (xy 93.340483 -387.300283)
			(xy 93.334801 -387.323487) (xy 93.336872 -387.335268) (xy 93.343984 -387.367018) (xy 93.347263 -387.378529)
			(xy 93.362502 -387.396945) (xy 93.373194 -387.402324) (xy 93.394624 -387.412055) (xy 93.434575 -387.436934)
			(xy 93.470423 -387.46743) (xy 93.486224 -387.484874) (xy 93.488691 -387.487642) (xy 93.4943 -387.492491)
			(xy 93.4974 -387.494526) (xy 93.509556 -387.502591) (xy 93.529641 -387.523737) (xy 93.543784 -387.549243)
			(xy 93.55108 -387.57748) (xy 93.551502 -387.592062) (xy 93.551502 -387.604508) (xy 93.55328 -387.610858)
			(xy 93.558414 -387.631172) (xy 93.563888 -387.672712) (xy 93.564202 -387.693662) (xy 93.563869 -387.714611)
			(xy 93.558393 -387.756148) (xy 93.55328 -387.776466) (xy 93.551502 -387.782816) (xy 93.551502 -388.239508)
			(xy 93.55328 -388.245858) (xy 93.558414 -388.266172) (xy 93.563888 -388.307712) (xy 93.564202 -388.328662)
			(xy 94.128336 -388.328662) (xy 94.128701 -388.307641) (xy 94.134312 -388.265975) (xy 94.139512 -388.245604)
			(xy 94.141036 -388.239) (xy 94.141036 -388.125462) (xy 94.141499 -388.110465) (xy 94.149259 -388.081493)
			(xy 94.164242 -388.05551) (xy 94.18543 -388.03428) (xy 94.211383 -388.019246) (xy 94.24034 -388.011429)
			(xy 94.255336 -388.010908) (xy 94.437454 -388.010908) (xy 94.437962 -388.010654) (xy 94.454726 -388.010654)
			(xy 94.455234 -388.010908) (xy 94.636844 -388.010908) (xy 94.651876 -388.011342) (xy 94.680917 -388.019122)
			(xy 94.706961 -388.034144) (xy 94.728238 -388.055385) (xy 94.743303 -388.081403) (xy 94.751133 -388.110431)
			(xy 94.751652 -388.125462) (xy 94.751652 -388.239) (xy 94.753176 -388.245604) (xy 94.758368 -388.265976)
			(xy 94.763978 -388.307642) (xy 94.764352 -388.328662) (xy 95.328232 -388.328662) (xy 95.328597 -388.307641)
			(xy 95.334208 -388.265975) (xy 95.339408 -388.245604) (xy 95.340932 -388.239) (xy 95.340932 -388.125462)
			(xy 95.341399 -388.110466) (xy 95.349159 -388.081494) (xy 95.364141 -388.055511) (xy 95.385328 -388.034281)
			(xy 95.411281 -388.019247) (xy 95.440237 -388.01143) (xy 95.455232 -388.010908) (xy 95.63735 -388.010908)
			(xy 95.637858 -388.010654) (xy 95.654622 -388.010654) (xy 95.65513 -388.010908) (xy 95.83674 -388.010908)
			(xy 95.851772 -388.011345) (xy 95.880813 -388.019125) (xy 95.906856 -388.034145) (xy 95.928134 -388.055386)
			(xy 95.943199 -388.081404) (xy 95.951029 -388.110431) (xy 95.951548 -388.125462) (xy 95.951548 -388.239)
			(xy 95.953072 -388.245604) (xy 95.958264 -388.265976) (xy 95.963874 -388.307642) (xy 95.964248 -388.328662)
			(xy 96.528382 -388.328662) (xy 96.528749 -388.307641) (xy 96.534359 -388.265975) (xy 96.539558 -388.245604)
			(xy 96.541336 -388.239) (xy 96.541336 -388.125462) (xy 96.541803 -388.110444) (xy 96.549584 -388.081434)
			(xy 96.564607 -388.055425) (xy 96.585848 -388.03419) (xy 96.61186 -388.019173) (xy 96.640872 -388.011399)
			(xy 96.65589 -388.010908) (xy 96.8375 -388.010908) (xy 96.838008 -388.010654) (xy 96.854772 -388.010654)
			(xy 96.85528 -388.010908) (xy 97.03689 -388.010908) (xy 97.051903 -388.011445) (xy 97.080907 -388.019212)
			(xy 97.106913 -388.034221) (xy 97.12815 -388.055448) (xy 97.143169 -388.081448) (xy 97.150949 -388.110449)
			(xy 97.151444 -388.125462) (xy 97.151444 -388.239) (xy 97.153222 -388.245604) (xy 97.158413 -388.265977)
			(xy 97.164024 -388.307642) (xy 97.164398 -388.328662) (xy 97.728278 -388.328662) (xy 97.728645 -388.307641)
			(xy 97.734255 -388.265975) (xy 97.739454 -388.245604) (xy 97.741232 -388.239) (xy 97.741232 -388.125462)
			(xy 97.741702 -388.110445) (xy 97.749484 -388.081435) (xy 97.764506 -388.055427) (xy 97.785746 -388.034191)
			(xy 97.811757 -388.019174) (xy 97.840769 -388.011399) (xy 97.855786 -388.010908) (xy 98.037396 -388.010908)
			(xy 98.037904 -388.010654) (xy 98.054668 -388.010654) (xy 98.055176 -388.010908) (xy 98.236786 -388.010908)
			(xy 98.251799 -388.011448) (xy 98.280803 -388.019215) (xy 98.306809 -388.034223) (xy 98.328045 -388.055449)
			(xy 98.343065 -388.081449) (xy 98.350845 -388.110449) (xy 98.35134 -388.125462) (xy 98.35134 -388.239)
			(xy 98.353118 -388.245604) (xy 98.358309 -388.265977) (xy 98.36392 -388.307642) (xy 98.364294 -388.328662)
			(xy 98.364294 -388.32917) (xy 98.364124 -388.343795) (xy 98.361457 -388.372924) (xy 98.35896 -388.387336)
			(xy 98.357602 -388.39651) (xy 98.360872 -388.414751) (xy 98.36531 -388.422896) (xy 98.38182 -388.44982)
			(xy 98.386998 -388.457592) (xy 98.401718 -388.469057) (xy 98.410522 -388.472172) (xy 98.435407 -388.480227)
			(xy 98.482285 -388.503418) (xy 98.524697 -388.534024) (xy 98.56148 -388.571206) (xy 98.591626 -388.613946)
			(xy 98.61431 -388.661072) (xy 98.622104 -388.68604) (xy 98.623628 -388.691882) (xy 98.943922 -389.245602)
			(xy 98.947986 -389.24992) (xy 98.964156 -389.267577) (xy 98.991472 -389.306898) (xy 99.012537 -389.349892)
			(xy 99.026868 -389.395575) (xy 99.034137 -389.442898) (xy 99.0346 -389.466836) (xy 99.0346 -389.467344)
			(xy 99.034123 -389.492133) (xy 99.026361 -389.5411) (xy 99.011036 -389.588251) (xy 98.988525 -389.632424)
			(xy 98.959382 -389.672533) (xy 98.924324 -389.70759) (xy 98.884214 -389.736731) (xy 98.84004 -389.759241)
			(xy 98.792889 -389.774564) (xy 98.743921 -389.782324) (xy 98.719132 -389.782812) (xy 98.693739 -389.782283)
			(xy 98.643606 -389.774158) (xy 98.595421 -389.758111) (xy 98.550427 -389.734557) (xy 98.509784 -389.704103)
			(xy 98.474541 -389.667536) (xy 98.445606 -389.625797) (xy 98.423727 -389.579965) (xy 98.41611 -389.555736)
			(xy 98.414586 -389.549894) (xy 98.094292 -388.996174) (xy 98.090228 -388.991856) (xy 98.07403 -388.974143)
			(xy 98.046603 -388.934754) (xy 98.025459 -388.891666) (xy 98.011084 -388.845873) (xy 98.003811 -388.79843)
			(xy 98.00336 -388.774432) (xy 98.003538 -388.760384) (xy 98.006082 -388.732402) (xy 98.00844 -388.718552)
			(xy 98.009724 -388.709296) (xy 98.006329 -388.690933) (xy 98.001836 -388.682738) (xy 97.985072 -388.655814)
			(xy 97.979886 -388.648098) (xy 97.965149 -388.636781) (xy 97.95637 -388.633716) (xy 97.934746 -388.626908)
			(xy 97.893532 -388.608029) (xy 97.855411 -388.583495) (xy 97.821154 -388.553804) (xy 97.806002 -388.536942)
			(xy 97.803542 -388.534167) (xy 97.797928 -388.529322) (xy 97.794826 -388.52729) (xy 97.782808 -388.519195)
			(xy 97.762914 -388.498141) (xy 97.748902 -388.47279) (xy 97.74166 -388.444745) (xy 97.741232 -388.430262)
			(xy 97.741232 -388.418324) (xy 97.739454 -388.41172) (xy 97.734248 -388.391351) (xy 97.728647 -388.349683)
			(xy 97.728278 -388.328662) (xy 97.164398 -388.328662) (xy 97.164398 -388.32917) (xy 97.164228 -388.343795)
			(xy 97.161561 -388.372924) (xy 97.159064 -388.387336) (xy 97.157706 -388.39651) (xy 97.160976 -388.414751)
			(xy 97.165414 -388.422896) (xy 97.181924 -388.44982) (xy 97.187101 -388.457593) (xy 97.201822 -388.469058)
			(xy 97.210626 -388.472172) (xy 97.23555 -388.480306) (xy 97.282516 -388.5036) (xy 97.324995 -388.534322)
			(xy 97.361825 -388.57163) (xy 97.391995 -388.614504) (xy 97.414679 -388.661766) (xy 97.422462 -388.686802)
			(xy 97.423986 -388.692644) (xy 97.743772 -389.245602) (xy 97.747836 -389.24992) (xy 97.764034 -389.267633)
			(xy 97.791458 -389.307023) (xy 97.812601 -389.350112) (xy 97.826976 -389.395904) (xy 97.834252 -389.443346)
			(xy 97.834704 -389.467344) (xy 97.834223 -389.492807) (xy 97.826024 -389.543068) (xy 97.809862 -389.591361)
			(xy 97.786155 -389.636433) (xy 97.75552 -389.677114) (xy 97.718751 -389.712349) (xy 97.698052 -389.727186)
			(xy 97.689519 -389.733633) (xy 97.678308 -389.751821) (xy 97.675463 -389.772996) (xy 97.681477 -389.793498)
			(xy 97.695309 -389.809781) (xy 97.714568 -389.819032) (xy 97.72523 -389.819896) (xy 97.734882 -389.819388)
			(xy 97.743396 -389.818098) (xy 97.760561 -389.816697) (xy 97.769172 -389.816594) (xy 97.769426 -389.816848)
			(xy 98.068638 -389.816848) (xy 98.068892 -389.816594) (xy 98.089955 -389.81697) (xy 98.131315 -389.82493)
			(xy 98.170314 -389.84084) (xy 98.205439 -389.864082) (xy 98.23533 -389.893756) (xy 98.258828 -389.928712)
			(xy 98.275021 -389.967594) (xy 98.283282 -390.008895) (xy 98.283776 -390.029954) (xy 98.283776 -390.233916)
			(xy 98.908616 -390.233916) (xy 98.908616 -390.029954) (xy 98.909173 -390.008911) (xy 98.917404 -389.967638)
			(xy 98.933559 -389.928776) (xy 98.957012 -389.89383) (xy 98.986854 -389.864154) (xy 99.021931 -389.840897)
			(xy 99.060882 -389.82496) (xy 99.102201 -389.816959) (xy 99.123246 -389.816594) (xy 99.1235 -389.816848)
			(xy 99.422712 -389.816848) (xy 99.422966 -389.816594) (xy 99.444013 -389.816973) (xy 99.485335 -389.824974)
			(xy 99.52429 -389.84091) (xy 99.559372 -389.864164) (xy 99.589222 -389.893836) (xy 99.612686 -389.928778)
			(xy 99.628856 -389.967637) (xy 99.637104 -390.00891) (xy 99.637596 -390.029954) (xy 99.637596 -390.284716)
			(xy 99.628452 -390.284716) (xy 99.618439 -390.285149) (xy 99.599943 -390.292828) (xy 99.585792 -390.306997)
			(xy 99.578137 -390.325503) (xy 99.577652 -390.335516) (xy 99.577652 -390.499092) (xy 99.577273 -390.509119)
			(xy 99.569597 -390.527645) (xy 99.555411 -390.541819) (xy 99.536879 -390.549481) (xy 99.526852 -390.549892)
			(xy 99.01936 -390.549892) (xy 99.009349 -390.549444) (xy 98.990855 -390.54177) (xy 98.976703 -390.527605)
			(xy 98.969046 -390.509104) (xy 98.96856 -390.499092) (xy 98.96856 -390.284716) (xy 98.959416 -390.284716)
			(xy 98.949411 -390.284199) (xy 98.930923 -390.276548) (xy 98.91677 -390.262404) (xy 98.909107 -390.24392)
			(xy 98.908616 -390.233916) (xy 98.283776 -390.233916) (xy 98.283776 -390.284716) (xy 98.274632 -390.284716)
			(xy 98.264611 -390.285146) (xy 98.246092 -390.292809) (xy 98.231918 -390.306978) (xy 98.224249 -390.325495)
			(xy 98.223832 -390.335516) (xy 98.223832 -390.499092) (xy 98.223306 -390.509095) (xy 98.215655 -390.527581)
			(xy 98.201514 -390.541733) (xy 98.183035 -390.549398) (xy 98.173032 -390.549892) (xy 97.665032 -390.549892)
			(xy 97.655012 -390.549454) (xy 97.636494 -390.541793) (xy 97.62232 -390.527626) (xy 97.614651 -390.509112)
			(xy 97.614232 -390.499092) (xy 97.614232 -390.284716) (xy 97.605088 -390.284716) (xy 97.595082 -390.284222)
			(xy 97.576593 -390.276561) (xy 97.562441 -390.262411) (xy 97.554779 -390.243922) (xy 97.554288 -390.233916)
			(xy 97.554288 -390.029954) (xy 97.554636 -390.012721) (xy 97.560206 -389.978709) (xy 97.571177 -389.946036)
			(xy 97.578926 -389.93064) (xy 97.584768 -389.91921) (xy 97.584514 -389.89381) (xy 97.53092 -389.796782)
			(xy 97.50933 -389.783066) (xy 97.496376 -389.78205) (xy 97.472475 -389.779971) (xy 97.425687 -389.769363)
			(xy 97.381046 -389.751789) (xy 97.339582 -389.727656) (xy 97.302253 -389.697519) (xy 97.26992 -389.662075)
			(xy 97.24333 -389.622143) (xy 97.223096 -389.578642) (xy 97.21596 -389.555736) (xy 97.214436 -389.549894)
			(xy 96.893888 -388.995412) (xy 96.889824 -388.991094) (xy 96.873716 -388.973429) (xy 96.846469 -388.934148)
			(xy 96.82546 -388.891207) (xy 96.811169 -388.845587) (xy 96.803922 -388.798334) (xy 96.803464 -388.774432)
			(xy 96.803642 -388.760384) (xy 96.806186 -388.732402) (xy 96.808544 -388.718552) (xy 96.809828 -388.709296)
			(xy 96.806433 -388.690933) (xy 96.80194 -388.682738) (xy 96.785176 -388.655814) (xy 96.779988 -388.648099)
			(xy 96.765253 -388.636782) (xy 96.756474 -388.633716) (xy 96.734851 -388.626906) (xy 96.693636 -388.608028)
			(xy 96.655515 -388.583495) (xy 96.621258 -388.553804) (xy 96.606106 -388.536942) (xy 96.603646 -388.534167)
			(xy 96.598032 -388.529322) (xy 96.59493 -388.52729) (xy 96.582913 -388.519193) (xy 96.563019 -388.498141)
			(xy 96.549007 -388.47279) (xy 96.541764 -388.444745) (xy 96.541336 -388.430262) (xy 96.541336 -388.418324)
			(xy 96.539558 -388.41172) (xy 96.534352 -388.391351) (xy 96.528751 -388.349683) (xy 96.528382 -388.328662)
			(xy 95.964248 -388.328662) (xy 95.964248 -388.32917) (xy 95.964078 -388.343795) (xy 95.961411 -388.372924)
			(xy 95.958914 -388.387336) (xy 95.957549 -388.39651) (xy 95.960822 -388.414752) (xy 95.965264 -388.422896)
			(xy 95.981774 -388.44982) (xy 95.986933 -388.457607) (xy 96.001666 -388.469064) (xy 96.010476 -388.472172)
			(xy 96.035352 -388.480253) (xy 96.082231 -388.503438) (xy 96.124645 -388.534038) (xy 96.161429 -388.571215)
			(xy 96.191578 -388.61395) (xy 96.214263 -388.661074) (xy 96.222058 -388.68604) (xy 96.223582 -388.691882)
			(xy 96.543876 -389.245602) (xy 96.54794 -389.24992) (xy 96.564138 -389.267633) (xy 96.591562 -389.307023)
			(xy 96.612705 -389.350111) (xy 96.62708 -389.395904) (xy 96.634356 -389.443346) (xy 96.634808 -389.467344)
			(xy 96.634325 -389.492807) (xy 96.626126 -389.543068) (xy 96.609964 -389.591361) (xy 96.586258 -389.636433)
			(xy 96.555623 -389.677114) (xy 96.518855 -389.712348) (xy 96.498156 -389.727186) (xy 96.489621 -389.733631)
			(xy 96.478408 -389.751819) (xy 96.475563 -389.772996) (xy 96.481577 -389.793498) (xy 96.49541 -389.809783)
			(xy 96.514671 -389.819033) (xy 96.525334 -389.819896) (xy 96.534986 -389.819388) (xy 96.5435 -389.818098)
			(xy 96.560665 -389.816697) (xy 96.569276 -389.816594) (xy 96.56953 -389.816848) (xy 96.868742 -389.816848)
			(xy 96.868996 -389.816594) (xy 96.890059 -389.816966) (xy 96.931419 -389.824927) (xy 96.970418 -389.840837)
			(xy 97.005543 -389.86408) (xy 97.035434 -389.893755) (xy 97.058932 -389.928711) (xy 97.075125 -389.967593)
			(xy 97.083386 -390.008894) (xy 97.08388 -390.029954) (xy 97.08388 -390.284716) (xy 97.074736 -390.284716)
			(xy 97.064715 -390.285149) (xy 97.046196 -390.292811) (xy 97.032022 -390.306979) (xy 97.024353 -390.325495)
			(xy 97.023936 -390.335516) (xy 97.023936 -390.499092) (xy 97.023406 -390.509095) (xy 97.015756 -390.527579)
			(xy 97.001616 -390.541731) (xy 96.983138 -390.549398) (xy 96.973136 -390.549892) (xy 96.465136 -390.549892)
			(xy 96.455116 -390.549451) (xy 96.436598 -390.541791) (xy 96.422425 -390.527625) (xy 96.414755 -390.509112)
			(xy 96.414336 -390.499092) (xy 96.414336 -390.284716) (xy 96.405192 -390.284716) (xy 96.395186 -390.284219)
			(xy 96.376697 -390.27656) (xy 96.362545 -390.26241) (xy 96.354883 -390.243922) (xy 96.354392 -390.233916)
			(xy 96.354392 -390.029954) (xy 96.35474 -390.012721) (xy 96.36031 -389.978709) (xy 96.37128 -389.946036)
			(xy 96.37903 -389.93064) (xy 96.384872 -389.91921) (xy 96.384618 -389.89381) (xy 96.331024 -389.796782)
			(xy 96.309434 -389.783066) (xy 96.29648 -389.78205) (xy 96.27258 -389.779968) (xy 96.225791 -389.76936)
			(xy 96.18115 -389.751787) (xy 96.139686 -389.727654) (xy 96.102357 -389.697518) (xy 96.070024 -389.662075)
			(xy 96.043434 -389.622142) (xy 96.0232 -389.578642) (xy 96.016064 -389.555736) (xy 96.01454 -389.549894)
			(xy 95.694246 -388.996174) (xy 95.690182 -388.991856) (xy 95.674027 -388.974118) (xy 95.646657 -388.934717)
			(xy 95.625565 -388.891629) (xy 95.611237 -388.845845) (xy 95.604002 -388.798419) (xy 95.603568 -388.774432)
			(xy 95.603749 -388.760384) (xy 95.60629 -388.732402) (xy 95.608648 -388.718552) (xy 95.609978 -388.709273)
			(xy 95.606447 -388.690874) (xy 95.60179 -388.682738) (xy 95.585026 -388.655814) (xy 95.579821 -388.648113)
			(xy 95.565098 -388.636788) (xy 95.556324 -388.633716) (xy 95.534694 -388.626926) (xy 95.493481 -388.608041)
			(xy 95.455361 -388.583502) (xy 95.421107 -388.553807) (xy 95.405956 -388.536942) (xy 95.40349 -388.534173)
			(xy 95.39788 -388.529325) (xy 95.39478 -388.52729) (xy 95.382725 -388.51922) (xy 95.362765 -388.498182)
			(xy 95.348688 -388.472827) (xy 95.341386 -388.444761) (xy 95.340932 -388.430262) (xy 95.340932 -388.418324)
			(xy 95.339408 -388.41172) (xy 95.334203 -388.391351) (xy 95.328601 -388.349683) (xy 95.328232 -388.328662)
			(xy 94.764352 -388.328662) (xy 94.764352 -388.32917) (xy 94.764182 -388.343795) (xy 94.761515 -388.372924)
			(xy 94.759018 -388.387336) (xy 94.757652 -388.39651) (xy 94.760926 -388.414752) (xy 94.765368 -388.422896)
			(xy 94.781878 -388.44982) (xy 94.787035 -388.457608) (xy 94.80177 -388.469065) (xy 94.81058 -388.472172)
			(xy 94.835515 -388.480276) (xy 94.882479 -388.503577) (xy 94.924957 -388.534306) (xy 94.961784 -388.57162)
			(xy 94.991952 -388.614498) (xy 95.014634 -388.661765) (xy 95.022416 -388.686802) (xy 95.02394 -388.692644)
			(xy 95.343726 -389.245602) (xy 95.34779 -389.24992) (xy 95.363961 -389.267576) (xy 95.391276 -389.306897)
			(xy 95.412341 -389.349892) (xy 95.426672 -389.395575) (xy 95.433941 -389.442898) (xy 95.434404 -389.466836)
			(xy 95.434404 -389.467344) (xy 95.433951 -389.492796) (xy 95.425778 -389.543039) (xy 95.409651 -389.59132)
			(xy 95.385987 -389.636389) (xy 95.355399 -389.677078) (xy 95.31868 -389.712333) (xy 95.298006 -389.727186)
			(xy 95.289496 -389.733654) (xy 95.278301 -389.751836) (xy 95.275462 -389.772999) (xy 95.28147 -389.793489)
			(xy 95.295288 -389.809767) (xy 95.314529 -389.819024) (xy 95.325184 -389.819896) (xy 95.334836 -389.819388)
			(xy 95.343349 -389.818092) (xy 95.360515 -389.816695) (xy 95.369126 -389.816594) (xy 95.36938 -389.816848)
			(xy 95.668592 -389.816848) (xy 95.668846 -389.816594) (xy 95.689892 -389.816992) (xy 95.731213 -389.824989)
			(xy 95.770168 -389.840922) (xy 95.80525 -389.864173) (xy 95.835101 -389.893842) (xy 95.858565 -389.928782)
			(xy 95.874735 -389.967639) (xy 95.882984 -390.00891) (xy 95.883476 -390.029954) (xy 95.883476 -390.284716)
			(xy 95.874332 -390.284716) (xy 95.864311 -390.285146) (xy 95.845792 -390.292809) (xy 95.831618 -390.306978)
			(xy 95.823949 -390.325495) (xy 95.823532 -390.335516) (xy 95.823532 -390.499092) (xy 95.823006 -390.509095)
			(xy 95.815355 -390.527581) (xy 95.801214 -390.541733) (xy 95.782735 -390.549398) (xy 95.772732 -390.549892)
			(xy 95.26524 -390.549892) (xy 95.25522 -390.549447) (xy 95.236703 -390.541789) (xy 95.222529 -390.527624)
			(xy 95.214859 -390.509111) (xy 95.21444 -390.499092) (xy 95.21444 -390.335516) (xy 95.2139 -390.325514)
			(xy 95.206253 -390.307031) (xy 95.192117 -390.292878) (xy 95.173641 -390.285211) (xy 95.16364 -390.284716)
			(xy 95.154496 -390.284716) (xy 95.154496 -390.029446) (xy 95.155282 -390.003724) (xy 95.167614 -389.953778)
			(xy 95.17888 -389.93064) (xy 95.184722 -389.91921) (xy 95.184468 -389.89381) (xy 95.130874 -389.796782)
			(xy 95.109284 -389.783066) (xy 95.09633 -389.78205) (xy 95.072434 -389.779927) (xy 95.025647 -389.769327)
			(xy 94.981006 -389.751761) (xy 94.939542 -389.727634) (xy 94.902212 -389.697503) (xy 94.869877 -389.662065)
			(xy 94.843286 -389.622137) (xy 94.82305 -389.578641) (xy 94.815914 -389.555736) (xy 94.81439 -389.549894)
			(xy 94.493842 -388.995412) (xy 94.489778 -388.991094) (xy 94.473683 -388.973429) (xy 94.446493 -388.934132)
			(xy 94.42554 -388.891184) (xy 94.411303 -388.845567) (xy 94.404107 -388.798325) (xy 94.403672 -388.774432)
			(xy 94.403853 -388.760384) (xy 94.406394 -388.732402) (xy 94.408752 -388.718552) (xy 94.410081 -388.709273)
			(xy 94.40655 -388.690874) (xy 94.401894 -388.682738) (xy 94.38513 -388.655814) (xy 94.379924 -388.648114)
			(xy 94.365201 -388.636788) (xy 94.356428 -388.633716) (xy 94.334799 -388.626925) (xy 94.293585 -388.60804)
			(xy 94.255466 -388.583502) (xy 94.221211 -388.553806) (xy 94.20606 -388.536942) (xy 94.203593 -388.534174)
			(xy 94.197984 -388.529325) (xy 94.194884 -388.52729) (xy 94.18283 -388.519219) (xy 94.16287 -388.498181)
			(xy 94.148793 -388.472827) (xy 94.14149 -388.444761) (xy 94.141036 -388.430262) (xy 94.141036 -388.418324)
			(xy 94.139512 -388.41172) (xy 94.134307 -388.391351) (xy 94.128705 -388.349683) (xy 94.128336 -388.328662)
			(xy 93.564202 -388.328662) (xy 93.564062 -388.343415) (xy 93.561386 -388.372799) (xy 93.558868 -388.387336)
			(xy 93.557509 -388.39651) (xy 93.560779 -388.414752) (xy 93.565218 -388.422896) (xy 93.581728 -388.44982)
			(xy 93.586903 -388.457594) (xy 93.601625 -388.469058) (xy 93.61043 -388.472172) (xy 93.635316 -388.480222)
			(xy 93.682195 -388.503415) (xy 93.724606 -388.534022) (xy 93.761389 -388.571205) (xy 93.791535 -388.613945)
			(xy 93.814219 -388.661072) (xy 93.822012 -388.68604) (xy 93.823536 -388.691882) (xy 94.14383 -389.245602)
			(xy 94.147894 -389.24992) (xy 94.164049 -389.267591) (xy 94.19137 -389.306906) (xy 94.212439 -389.349897)
			(xy 94.226774 -389.395577) (xy 94.234045 -389.442898) (xy 94.234508 -389.466836) (xy 94.234508 -389.467344)
			(xy 94.234053 -389.492796) (xy 94.22588 -389.543039) (xy 94.209753 -389.59132) (xy 94.18609 -389.636389)
			(xy 94.155502 -389.677078) (xy 94.118784 -389.712333) (xy 94.09811 -389.727186) (xy 94.089598 -389.733652)
			(xy 94.078401 -389.751835) (xy 94.075562 -389.772999) (xy 94.081571 -389.793489) (xy 94.09539 -389.809768)
			(xy 94.114633 -389.819025) (xy 94.125288 -389.819896) (xy 94.13494 -389.819388) (xy 94.143453 -389.818091)
			(xy 94.160619 -389.816694) (xy 94.16923 -389.816594) (xy 94.169484 -389.816848) (xy 94.468696 -389.816848)
			(xy 94.46895 -389.816594) (xy 94.489997 -389.816988) (xy 94.531317 -389.824986) (xy 94.570273 -389.840919)
			(xy 94.605355 -389.864171) (xy 94.635205 -389.893841) (xy 94.65867 -389.928781) (xy 94.674839 -389.967639)
			(xy 94.683088 -390.00891) (xy 94.68358 -390.029954) (xy 94.68358 -390.284716) (xy 94.674436 -390.284716)
			(xy 94.664415 -390.285149) (xy 94.645896 -390.292811) (xy 94.631722 -390.306979) (xy 94.624053 -390.325495)
			(xy 94.623636 -390.335516) (xy 94.623636 -390.499092) (xy 94.623106 -390.509095) (xy 94.615456 -390.527579)
			(xy 94.601316 -390.541731) (xy 94.582838 -390.549398) (xy 94.572836 -390.549892) (xy 94.065344 -390.549892)
			(xy 94.055325 -390.549444) (xy 94.036807 -390.541787) (xy 94.022633 -390.527623) (xy 94.014963 -390.509111)
			(xy 94.014544 -390.499092) (xy 94.014544 -390.284716) (xy 94.0054 -390.284716) (xy 93.995394 -390.284212)
			(xy 93.976906 -390.276556) (xy 93.962753 -390.262408) (xy 93.955091 -390.243922) (xy 93.9546 -390.233916)
			(xy 93.9546 -390.029446) (xy 93.955386 -390.003724) (xy 93.967718 -389.953778) (xy 93.978984 -389.93064)
			(xy 93.984826 -389.91921) (xy 93.984572 -389.89381) (xy 93.930978 -389.796782) (xy 93.909388 -389.783066)
			(xy 93.896434 -389.78205) (xy 93.872538 -389.779924) (xy 93.825751 -389.769324) (xy 93.78111 -389.751759)
			(xy 93.739646 -389.727632) (xy 93.702316 -389.697502) (xy 93.669982 -389.662064) (xy 93.64339 -389.622136)
			(xy 93.623154 -389.57864) (xy 93.616018 -389.555736) (xy 93.614494 -389.549894) (xy 93.2942 -388.996174)
			(xy 93.290136 -388.991856) (xy 93.273922 -388.974157) (xy 93.246502 -388.934763) (xy 93.225362 -388.891671)
			(xy 93.21099 -388.845875) (xy 93.203718 -388.798431) (xy 93.203268 -388.774432) (xy 93.203447 -388.760384)
			(xy 93.20599 -388.732402) (xy 93.208348 -388.718552) (xy 93.209631 -388.709296) (xy 93.206237 -388.690933)
			(xy 93.201744 -388.682738) (xy 93.18498 -388.655814) (xy 93.179791 -388.6481) (xy 93.165056 -388.636782)
			(xy 93.156278 -388.633716) (xy 93.134703 -388.626961) (xy 93.093578 -388.608188) (xy 93.055524 -388.583782)
			(xy 93.021308 -388.554236) (xy 93.006164 -388.53745) (xy 93.003696 -388.534683) (xy 92.998087 -388.529833)
			(xy 92.994988 -388.527798) (xy 92.98284 -388.519722) (xy 92.962755 -388.498579) (xy 92.94861 -388.473077)
			(xy 92.94131 -388.444843) (xy 92.940886 -388.430262) (xy 92.940886 -388.417816) (xy 92.939108 -388.411466)
			(xy 92.933978 -388.391151) (xy 92.928502 -388.349612) (xy 92.928186 -388.328662) (xy 92.928524 -388.307714)
			(xy 92.933997 -388.266176) (xy 92.939108 -388.245858) (xy 92.940886 -388.239508) (xy 92.940886 -387.782816)
			(xy 92.939108 -387.776466) (xy 92.933978 -387.756151) (xy 92.928502 -387.714612) (xy 92.928186 -387.693662)
			(xy 92.928524 -387.672714) (xy 92.933997 -387.631176) (xy 92.939108 -387.610858) (xy 92.940886 -387.604508)
			(xy 92.940886 -387.592062) (xy 92.9414 -387.576601) (xy 92.949623 -387.546791) (xy 92.965445 -387.520221)
			(xy 92.987736 -387.498789) (xy 93.001084 -387.49097) (xy 93.00464 -387.486906) (xy 93.011997 -387.477387)
			(xy 93.01769 -387.454044) (xy 93.015562 -387.442202) (xy 93.00845 -387.410706) (xy 93.005191 -387.399188)
			(xy 92.989936 -387.380777) (xy 92.97924 -387.3754) (xy 92.957749 -387.365595) (xy 92.917686 -387.34057)
			(xy 92.881771 -387.309889) (xy 92.865956 -387.292342) (xy 92.86349 -387.289573) (xy 92.85788 -387.284725)
			(xy 92.85478 -387.28269) (xy 92.842725 -387.27462) (xy 92.822765 -387.253582) (xy 92.808688 -387.228227)
			(xy 92.801386 -387.200161) (xy 92.800932 -387.185662) (xy 92.800932 -387.173724) (xy 92.799408 -387.16712)
			(xy 92.794203 -387.146751) (xy 92.788601 -387.105083) (xy 92.788232 -387.084062) (xy 92.788597 -387.063041)
			(xy 92.794208 -387.021375) (xy 92.799408 -387.001004) (xy 92.800932 -386.9944) (xy 92.800932 -386.880862)
			(xy 92.801591 -386.862743) (xy 92.812846 -386.828297) (xy 92.82303 -386.813298) (xy 92.827534 -386.806632)
			(xy 92.832575 -386.791363) (xy 92.832936 -386.783326) (xy 92.832936 -386.749798) (xy 92.832634 -386.74175)
			(xy 92.827586 -386.726467) (xy 92.82303 -386.719826) (xy 92.812951 -386.704772) (xy 92.80169 -386.670362)
			(xy 92.800932 -386.652262) (xy 92.800932 -386.538724) (xy 92.799408 -386.53212) (xy 92.794203 -386.511751)
			(xy 92.788601 -386.470083) (xy 92.788232 -386.449062) (xy 92.788994 -386.426456) (xy 92.789756 -386.416296)
			(xy 92.78366 -386.3975) (xy 92.730066 -386.335524) (xy 92.723115 -386.328288) (xy 92.705221 -386.31926)
			(xy 92.695268 -386.317998) (xy 92.671462 -386.31575) (xy 92.624871 -386.304999) (xy 92.580436 -386.28734)
			(xy 92.539174 -386.263179) (xy 92.502032 -386.233067) (xy 92.469858 -386.197695) (xy 92.443391 -386.157873)
			(xy 92.423236 -386.114513) (xy 92.416122 -386.091684) (xy 92.414598 -386.085842) (xy 92.094304 -385.532122)
			(xy 92.09024 -385.527804) (xy 92.074002 -385.510126) (xy 92.046585 -385.470726) (xy 92.025449 -385.427629)
			(xy 92.011084 -385.381828) (xy 92.003818 -385.33438) (xy 92.003372 -385.31038) (xy 91.47124 -385.31038)
			(xy 91.743784 -385.78155) (xy 91.747848 -385.785868) (xy 91.764055 -385.80354) (xy 91.791452 -385.84289)
			(xy 91.812582 -385.885931) (xy 91.826958 -385.931674) (xy 91.83425 -385.979064) (xy 91.834716 -386.003038)
			(xy 91.834716 -386.003546) (xy 91.833954 -386.023866) (xy 91.833192 -386.033772) (xy 91.839542 -386.052822)
			(xy 91.900248 -386.122164) (xy 91.918028 -386.131054) (xy 91.928188 -386.131816) (xy 91.953166 -386.134002)
			(xy 92.002024 -386.145257) (xy 92.048511 -386.16404) (xy 92.091475 -386.189883) (xy 92.129853 -386.222147)
			(xy 92.146628 -386.240782) (xy 92.149094 -386.243552) (xy 92.154704 -386.2484) (xy 92.157804 -386.250434)
			(xy 92.169867 -386.258494) (xy 92.189827 -386.279535) (xy 92.203902 -386.304893) (xy 92.211201 -386.332962)
			(xy 92.211652 -386.347462) (xy 92.211652 -386.3594) (xy 92.213176 -386.366004) (xy 92.218368 -386.386376)
			(xy 92.223978 -386.428042) (xy 92.224352 -386.449062) (xy 92.223969 -386.470082) (xy 92.218369 -386.511748)
			(xy 92.213176 -386.53212) (xy 92.211652 -386.538724) (xy 92.211652 -386.639562) (xy 92.212084 -386.649631)
			(xy 92.219798 -386.66823) (xy 92.226638 -386.67563) (xy 92.461588 -386.91058) (xy 92.461588 -386.918454)
			(xy 92.494608 -386.951474) (xy 92.501317 -386.958943) (xy 92.5089 -386.977511) (xy 92.50934 -386.987542)
			(xy 92.50934 -387.360414) (xy 92.517214 -387.378956) (xy 92.517722 -387.379464) (xy 92.524542 -387.38688)
			(xy 92.532273 -387.405467) (xy 92.532708 -387.415532) (xy 92.532708 -388.520686) (xy 92.533122 -388.530479)
			(xy 92.540447 -388.548641) (xy 92.546932 -388.555992) (xy 92.564092 -388.57458) (xy 92.592831 -388.616212)
			(xy 92.614557 -388.661897) (xy 92.622116 -388.68604) (xy 92.62364 -388.691882) (xy 92.838016 -389.062214)
			(xy 92.84589 -389.072628) (xy 92.949776 -389.176768) (xy 92.948506 -389.178038) (xy 92.941035 -389.18635)
			(xy 92.93338 -389.207315) (xy 92.935301 -389.229552) (xy 92.940378 -389.239506) (xy 92.943934 -389.245602)
			(xy 92.947998 -389.24992) (xy 92.964153 -389.26759) (xy 92.991474 -389.306906) (xy 93.012544 -389.349897)
			(xy 93.026878 -389.395577) (xy 93.034149 -389.442898) (xy 93.034612 -389.466836) (xy 93.034612 -389.467344)
			(xy 93.034099 -389.49206) (xy 93.026389 -389.540888) (xy 93.011166 -389.587919) (xy 92.988799 -389.632002)
			(xy 92.959837 -389.672062) (xy 92.924987 -389.70712) (xy 92.905326 -389.722106) (xy 92.896144 -389.729755)
			(xy 92.885404 -389.751068) (xy 92.884752 -389.763) (xy 92.884752 -389.767826) (xy 92.885265 -389.777829)
			(xy 92.892925 -389.796313) (xy 92.907069 -389.810463) (xy 92.925549 -389.81813) (xy 92.935552 -389.818626)
			(xy 92.9386 -389.818626) (xy 92.941648 -389.818372) (xy 92.96908 -389.816594) (xy 92.969334 -389.816848)
			(xy 93.268546 -389.816848) (xy 93.2688 -389.816594) (xy 93.289863 -389.816962) (xy 93.331223 -389.824924)
			(xy 93.370222 -389.840835) (xy 93.405348 -389.864079) (xy 93.435239 -389.893754) (xy 93.458736 -389.92871)
			(xy 93.474929 -389.967593) (xy 93.48319 -390.008894) (xy 93.483684 -390.029954) (xy 93.483684 -390.284716)
			(xy 93.47454 -390.284716) (xy 93.464519 -390.285153) (xy 93.446 -390.292812) (xy 93.431826 -390.30698)
			(xy 93.424157 -390.325496) (xy 93.42374 -390.335516) (xy 93.42374 -390.499092) (xy 93.423206 -390.509094)
			(xy 93.415557 -390.527578) (xy 93.401418 -390.54173) (xy 93.382942 -390.549397) (xy 93.37294 -390.549892)
			(xy 92.919296 -390.549892) (xy 92.909289 -390.550385) (xy 92.890799 -390.558044) (xy 92.876646 -390.572195)
			(xy 92.868986 -390.590685) (xy 92.868496 -390.600692) (xy 92.868496 -393.292838) (xy 93.162628 -393.292838)
			(xy 93.162628 -392.429238) (xy 93.163057 -392.403718) (xy 93.169847 -392.353132) (xy 93.183323 -392.303904)
			(xy 93.203246 -392.256913) (xy 93.229258 -392.213) (xy 93.260895 -392.172948) (xy 93.27896 -392.154918)
			(xy 93.285564 -392.148568) (xy 93.293438 -392.131804) (xy 93.300296 -392.04646) (xy 93.295216 -392.02868)
			(xy 93.289628 -392.021314) (xy 93.274777 -392.000566) (xy 93.251142 -391.955352) (xy 93.235041 -391.906941)
			(xy 93.226888 -391.856577) (xy 93.226382 -391.831068) (xy 93.226382 -391.830814) (xy 93.226872 -391.805825)
			(xy 93.234691 -391.756462) (xy 93.250135 -391.70893) (xy 93.272825 -391.664398) (xy 93.302201 -391.623965)
			(xy 93.337541 -391.588625) (xy 93.377974 -391.559249) (xy 93.422506 -391.536559) (xy 93.470038 -391.521115)
			(xy 93.519401 -391.513296) (xy 93.569379 -391.513296) (xy 93.618742 -391.521115) (xy 93.666274 -391.536559)
			(xy 93.710806 -391.559249) (xy 93.751239 -391.588625) (xy 93.786579 -391.623965) (xy 93.815955 -391.664398)
			(xy 93.838645 -391.70893) (xy 93.854089 -391.756462) (xy 93.861908 -391.805825) (xy 93.862398 -391.830814)
			(xy 93.862398 -391.831068) (xy 93.861905 -391.856577) (xy 93.853728 -391.906937) (xy 93.837626 -391.955348)
			(xy 93.81401 -392.000572) (xy 93.799152 -392.021314) (xy 93.793564 -392.02868) (xy 93.788484 -392.04646)
			(xy 93.795342 -392.131804) (xy 93.803216 -392.148568) (xy 93.80982 -392.154918) (xy 93.827848 -392.172983)
			(xy 93.85948 -392.213032) (xy 93.885493 -392.25694) (xy 93.905422 -392.303923) (xy 93.918912 -392.353142)
			(xy 93.925722 -392.403721) (xy 93.926152 -392.429238) (xy 93.926152 -393.292838) (xy 94.362524 -393.292838)
			(xy 94.362524 -392.429238) (xy 94.362954 -392.403718) (xy 94.369744 -392.353132) (xy 94.38322 -392.303904)
			(xy 94.403142 -392.256913) (xy 94.429154 -392.213) (xy 94.460791 -392.172948) (xy 94.478856 -392.154918)
			(xy 94.48546 -392.148568) (xy 94.493334 -392.131804) (xy 94.500192 -392.04646) (xy 94.495112 -392.02868)
			(xy 94.489524 -392.021314) (xy 94.474673 -392.000567) (xy 94.451038 -391.955352) (xy 94.434937 -391.906941)
			(xy 94.426784 -391.856578) (xy 94.426278 -391.831068) (xy 94.426278 -391.830814) (xy 94.426768 -391.805825)
			(xy 94.434587 -391.756462) (xy 94.450031 -391.70893) (xy 94.472721 -391.664398) (xy 94.502097 -391.623965)
			(xy 94.537437 -391.588625) (xy 94.57787 -391.559249) (xy 94.622402 -391.536559) (xy 94.669934 -391.521115)
			(xy 94.719297 -391.513296) (xy 94.769275 -391.513296) (xy 94.818638 -391.521115) (xy 94.86617 -391.536559)
			(xy 94.910702 -391.559249) (xy 94.951135 -391.588625) (xy 94.986475 -391.623965) (xy 95.015851 -391.664398)
			(xy 95.038541 -391.70893) (xy 95.053985 -391.756462) (xy 95.061804 -391.805825) (xy 95.062294 -391.830814)
			(xy 95.062294 -391.831068) (xy 95.061802 -391.856577) (xy 95.053625 -391.906937) (xy 95.037522 -391.955348)
			(xy 95.013907 -392.000572) (xy 94.999048 -392.021314) (xy 94.99346 -392.02868) (xy 94.98838 -392.04646)
			(xy 94.995238 -392.131804) (xy 95.003112 -392.148568) (xy 95.009716 -392.154918) (xy 95.027743 -392.172984)
			(xy 95.059376 -392.213033) (xy 95.085389 -392.25694) (xy 95.105318 -392.303923) (xy 95.118808 -392.353142)
			(xy 95.125618 -392.403721) (xy 95.126048 -392.429238) (xy 95.126048 -393.292838) (xy 95.56242 -393.292838)
			(xy 95.56242 -392.429238) (xy 95.562851 -392.403718) (xy 95.569641 -392.353132) (xy 95.583117 -392.303904)
			(xy 95.603039 -392.256914) (xy 95.629051 -392.213) (xy 95.660688 -392.172949) (xy 95.678752 -392.154918)
			(xy 95.685356 -392.148568) (xy 95.69323 -392.131804) (xy 95.700088 -392.04646) (xy 95.695008 -392.02868)
			(xy 95.68942 -392.021314) (xy 95.674568 -392.000567) (xy 95.650933 -391.955353) (xy 95.634832 -391.906941)
			(xy 95.62668 -391.856578) (xy 95.626174 -391.831068) (xy 95.626174 -391.830814) (xy 95.626664 -391.805825)
			(xy 95.634483 -391.756462) (xy 95.649927 -391.70893) (xy 95.672617 -391.664398) (xy 95.701993 -391.623965)
			(xy 95.737333 -391.588625) (xy 95.777766 -391.559249) (xy 95.822298 -391.536559) (xy 95.86983 -391.521115)
			(xy 95.919193 -391.513296) (xy 95.969171 -391.513296) (xy 96.018534 -391.521115) (xy 96.066066 -391.536559)
			(xy 96.110598 -391.559249) (xy 96.151031 -391.588625) (xy 96.186371 -391.623965) (xy 96.215747 -391.664398)
			(xy 96.238437 -391.70893) (xy 96.253881 -391.756462) (xy 96.2617 -391.805825) (xy 96.26219 -391.830814)
			(xy 96.26219 -391.831068) (xy 96.261679 -391.856576) (xy 96.253505 -391.906934) (xy 96.237407 -391.955345)
			(xy 96.213799 -392.000571) (xy 96.198944 -392.021314) (xy 96.193356 -392.02868) (xy 96.188276 -392.04646)
			(xy 96.195134 -392.131804) (xy 96.203008 -392.148568) (xy 96.209612 -392.154918) (xy 96.227638 -392.172984)
			(xy 96.259271 -392.213033) (xy 96.285284 -392.25694) (xy 96.305214 -392.303923) (xy 96.318704 -392.353142)
			(xy 96.325514 -392.403721) (xy 96.325944 -392.429238) (xy 96.325944 -393.292838) (xy 96.762824 -393.292838)
			(xy 96.762824 -392.42873) (xy 96.763257 -392.403262) (xy 96.77006 -392.352782) (xy 96.783521 -392.303656)
			(xy 96.803403 -392.25676) (xy 96.82935 -392.212927) (xy 96.8609 -392.172939) (xy 96.878902 -392.154918)
			(xy 96.885506 -392.148568) (xy 96.89338 -392.131804) (xy 96.900238 -392.04646) (xy 96.895158 -392.02868)
			(xy 96.88957 -392.021314) (xy 96.874724 -392.000563) (xy 96.851087 -391.95535) (xy 96.834984 -391.90694)
			(xy 96.82683 -391.856577) (xy 96.826324 -391.831068) (xy 96.826324 -391.830814) (xy 96.826814 -391.805825)
			(xy 96.834633 -391.756462) (xy 96.850077 -391.70893) (xy 96.872767 -391.664398) (xy 96.902143 -391.623965)
			(xy 96.937483 -391.588625) (xy 96.977916 -391.559249) (xy 97.022448 -391.536559) (xy 97.06998 -391.521115)
			(xy 97.119343 -391.513296) (xy 97.169321 -391.513296) (xy 97.218684 -391.521115) (xy 97.266216 -391.536559)
			(xy 97.310748 -391.559249) (xy 97.351181 -391.588625) (xy 97.386521 -391.623965) (xy 97.415897 -391.664398)
			(xy 97.438587 -391.70893) (xy 97.454031 -391.756462) (xy 97.46185 -391.805825) (xy 97.46234 -391.830814)
			(xy 97.46234 -391.831068) (xy 97.461839 -391.856577) (xy 97.453663 -391.906935) (xy 97.437563 -391.955347)
			(xy 97.413951 -392.000572) (xy 97.399094 -392.021314) (xy 97.393506 -392.02868) (xy 97.388426 -392.04646)
			(xy 97.395284 -392.131804) (xy 97.403158 -392.148568) (xy 97.409762 -392.154918) (xy 97.427763 -392.172939)
			(xy 97.459304 -392.212933) (xy 97.485244 -392.256767) (xy 97.505123 -392.303662) (xy 97.518588 -392.352785)
			(xy 97.525399 -392.403263) (xy 97.52584 -392.42873) (xy 97.52584 -393.292838) (xy 97.52583 -393.293346)
			(xy 97.96272 -393.293346) (xy 97.96272 -392.42873) (xy 97.963154 -392.403262) (xy 97.969957 -392.352782)
			(xy 97.983418 -392.303656) (xy 98.003299 -392.25676) (xy 98.029246 -392.212928) (xy 98.060796 -392.172939)
			(xy 98.078798 -392.154918) (xy 98.085402 -392.148568) (xy 98.093276 -392.131804) (xy 98.100134 -392.04646)
			(xy 98.095054 -392.02868) (xy 98.089466 -392.021314) (xy 98.07462 -392.000563) (xy 98.050982 -391.955351)
			(xy 98.03488 -391.90694) (xy 98.026726 -391.856577) (xy 98.02622 -391.831068) (xy 98.02622 -391.830814)
			(xy 98.02671 -391.805825) (xy 98.034529 -391.756462) (xy 98.049973 -391.70893) (xy 98.072663 -391.664398)
			(xy 98.102039 -391.623965) (xy 98.137379 -391.588625) (xy 98.177812 -391.559249) (xy 98.222344 -391.536559)
			(xy 98.269876 -391.521115) (xy 98.319239 -391.513296) (xy 98.369217 -391.513296) (xy 98.41858 -391.521115)
			(xy 98.466112 -391.536559) (xy 98.510644 -391.559249) (xy 98.551077 -391.588625) (xy 98.586417 -391.623965)
			(xy 98.615793 -391.664398) (xy 98.638483 -391.70893) (xy 98.653927 -391.756462) (xy 98.661746 -391.805825)
			(xy 98.662236 -391.830814) (xy 98.662236 -391.831068) (xy 98.661736 -391.856577) (xy 98.65356 -391.906936)
			(xy 98.637459 -391.955347) (xy 98.613847 -392.000572) (xy 98.59899 -392.021314) (xy 98.593402 -392.02868)
			(xy 98.588322 -392.04646) (xy 98.59518 -392.131804) (xy 98.603054 -392.148568) (xy 98.609658 -392.154918)
			(xy 98.627658 -392.172939) (xy 98.659199 -392.212933) (xy 98.68514 -392.256767) (xy 98.705019 -392.303663)
			(xy 98.718484 -392.352785) (xy 98.725295 -392.403263) (xy 98.725736 -392.42873) (xy 98.725736 -392.815826)
			(xy 100.039168 -392.815826) (xy 100.043239 -392.760204) (xy 100.055365 -392.705767) (xy 100.075288 -392.653676)
			(xy 100.102584 -392.605041) (xy 100.13667 -392.560898) (xy 100.176819 -392.522189) (xy 100.222177 -392.489738)
			(xy 100.271777 -392.464237) (xy 100.324561 -392.44623) (xy 100.379404 -392.4361) (xy 100.435138 -392.434063)
			(xy 100.490575 -392.440163) (xy 100.544532 -392.454269) (xy 100.595861 -392.476081) (xy 100.643467 -392.505135)
			(xy 100.686335 -392.54081) (xy 100.723552 -392.582347) (xy 100.754325 -392.62886) (xy 100.777997 -392.679357)
			(xy 100.794065 -392.732764) (xy 100.802185 -392.78794) (xy 100.802694 -392.815826) (xy 100.802185 -392.843712)
			(xy 100.794065 -392.898888) (xy 100.777997 -392.952295) (xy 100.754325 -393.002792) (xy 100.723552 -393.049305)
			(xy 100.686335 -393.090842) (xy 100.643467 -393.126517) (xy 100.595861 -393.155571) (xy 100.544532 -393.177383)
			(xy 100.490575 -393.191489) (xy 100.435138 -393.197589) (xy 100.379404 -393.195552) (xy 100.324561 -393.185422)
			(xy 100.271777 -393.167415) (xy 100.222177 -393.141914) (xy 100.176819 -393.109463) (xy 100.13667 -393.070754)
			(xy 100.102584 -393.026611) (xy 100.075288 -392.977976) (xy 100.055365 -392.925885) (xy 100.043239 -392.871448)
			(xy 100.039168 -392.815826) (xy 98.725736 -392.815826) (xy 98.725736 -393.094718) (xy 98.726108 -393.103827)
			(xy 98.732456 -393.120903) (xy 98.744353 -393.134702) (xy 98.752152 -393.139422) (xy 98.830638 -393.182348)
			(xy 98.838735 -393.186295) (xy 98.856551 -393.188851) (xy 98.874151 -393.185082) (xy 98.881946 -393.18057)
			(xy 98.882454 -393.18057) (xy 98.90477 -393.166831) (xy 98.952471 -393.14513) (xy 99.002759 -393.130388)
			(xy 99.054626 -393.122902) (xy 99.080828 -393.122404) (xy 99.108427 -393.122898) (xy 99.163009 -393.131128)
			(xy 99.215754 -393.147402) (xy 99.265485 -393.171354) (xy 99.31109 -393.202451) (xy 99.351552 -393.239997)
			(xy 99.385967 -393.283154) (xy 99.413565 -393.330958) (xy 99.415152 -393.335002) (xy 100.761036 -393.335002)
			(xy 100.765107 -393.27938) (xy 100.777233 -393.224943) (xy 100.797156 -393.172852) (xy 100.824452 -393.124217)
			(xy 100.858538 -393.080074) (xy 100.898687 -393.041365) (xy 100.944045 -393.008914) (xy 100.993645 -392.983413)
			(xy 101.046429 -392.965406) (xy 101.101272 -392.955276) (xy 101.157006 -392.953239) (xy 101.212443 -392.959339)
			(xy 101.2664 -392.973445) (xy 101.317729 -392.995257) (xy 101.365335 -393.024311) (xy 101.408203 -393.059986)
			(xy 101.44542 -393.101523) (xy 101.476193 -393.148036) (xy 101.499865 -393.198533) (xy 101.515933 -393.25194)
			(xy 101.524053 -393.307116) (xy 101.524562 -393.335002) (xy 101.524053 -393.362888) (xy 101.515933 -393.418064)
			(xy 101.499865 -393.471471) (xy 101.476193 -393.521968) (xy 101.44542 -393.568481) (xy 101.408203 -393.610018)
			(xy 101.365335 -393.645693) (xy 101.317729 -393.674747) (xy 101.2664 -393.696559) (xy 101.212443 -393.710665)
			(xy 101.157006 -393.716765) (xy 101.101272 -393.714728) (xy 101.046429 -393.704598) (xy 100.993645 -393.686591)
			(xy 100.944045 -393.66109) (xy 100.898687 -393.628639) (xy 100.858538 -393.58993) (xy 100.824452 -393.545787)
			(xy 100.797156 -393.497152) (xy 100.777233 -393.445061) (xy 100.765107 -393.390624) (xy 100.761036 -393.335002)
			(xy 99.415152 -393.335002) (xy 99.43373 -393.382341) (xy 99.446012 -393.436156) (xy 99.450137 -393.4912)
			(xy 99.446012 -393.546244) (xy 99.43373 -393.600059) (xy 99.413565 -393.651442) (xy 99.385967 -393.699246)
			(xy 99.351552 -393.742403) (xy 99.31109 -393.779949) (xy 99.265485 -393.811046) (xy 99.215754 -393.834998)
			(xy 99.163009 -393.851272) (xy 99.108427 -393.859502) (xy 99.080828 -393.86002) (xy 99.052856 -393.859494)
			(xy 98.997556 -393.851021) (xy 98.94417 -393.834296) (xy 98.893921 -393.809703) (xy 98.847961 -393.777804)
			(xy 98.807345 -393.739332) (xy 98.773002 -393.695168) (xy 98.745722 -393.646325) (xy 98.726129 -393.593924)
			(xy 98.719894 -393.56665) (xy 98.717173 -393.556426) (xy 98.704824 -393.539276) (xy 98.686627 -393.528531)
			(xy 98.665646 -393.526) (xy 98.655378 -393.52855) (xy 98.648528 -393.530962) (xy 98.636404 -393.538941)
			(xy 98.631502 -393.544298) (xy 98.628708 -393.547346) (xy 98.622866 -393.55395) (xy 98.616008 -393.570714)
			(xy 98.613976 -393.645136) (xy 98.614079 -393.654042) (xy 98.61968 -393.670936) (xy 98.624898 -393.678156)
			(xy 98.625152 -393.67841) (xy 98.639884 -393.697541) (xy 98.664637 -393.738999) (xy 98.683613 -393.7834)
			(xy 98.696469 -393.829942) (xy 98.702974 -393.877788) (xy 98.703384 -393.90193) (xy 98.703384 -393.902438)
			(xy 98.702882 -393.929315) (xy 98.69487 -393.98247) (xy 98.679026 -394.033836) (xy 98.655702 -394.082268)
			(xy 98.625421 -394.126682) (xy 98.588859 -394.166087) (xy 98.546831 -394.199603) (xy 98.500278 -394.22648)
			(xy 98.450239 -394.246119) (xy 98.397832 -394.25808) (xy 98.344228 -394.262098) (xy 98.290624 -394.25808)
			(xy 98.238217 -394.246119) (xy 98.188178 -394.22648) (xy 98.141625 -394.199603) (xy 98.099597 -394.166087)
			(xy 98.063035 -394.126682) (xy 98.032754 -394.082268) (xy 98.00943 -394.033836) (xy 97.993586 -393.98247)
			(xy 97.985574 -393.929315) (xy 97.985072 -393.902438) (xy 97.985072 -393.90193) (xy 97.985466 -393.877787)
			(xy 97.991972 -393.82994) (xy 98.00483 -393.783396) (xy 98.023809 -393.738995) (xy 98.048566 -393.697538)
			(xy 98.063304 -393.67841) (xy 98.063558 -393.678156) (xy 98.068832 -393.67097) (xy 98.074414 -393.654051)
			(xy 98.07448 -393.645136) (xy 98.072448 -393.570714) (xy 98.06559 -393.55395) (xy 98.059748 -393.547346)
			(xy 98.041614 -393.526252) (xy 98.010972 -393.47983) (xy 97.987391 -393.429452) (xy 97.971369 -393.376185)
			(xy 97.963248 -393.321157) (xy 97.96272 -393.293346) (xy 97.52583 -393.293346) (xy 97.525283 -393.321991)
			(xy 97.516413 -393.379619) (xy 97.498885 -393.435228) (xy 97.473106 -393.487526) (xy 97.439676 -393.535297)
			(xy 97.419922 -393.556744) (xy 97.413756 -393.563821) (xy 97.406604 -393.581161) (xy 97.405952 -393.590526)
			(xy 97.404174 -393.659106) (xy 97.404324 -393.668362) (xy 97.410454 -393.685815) (xy 97.416112 -393.693142)
			(xy 97.41662 -393.69365) (xy 97.432939 -393.713279) (xy 97.46041 -393.756303) (xy 97.481512 -393.802783)
			(xy 97.495819 -393.851783) (xy 97.503042 -393.902315) (xy 97.503488 -393.927838) (xy 97.502986 -393.954715)
			(xy 97.494974 -394.00787) (xy 97.47913 -394.059236) (xy 97.455806 -394.107668) (xy 97.425525 -394.152082)
			(xy 97.388963 -394.191487) (xy 97.346935 -394.225003) (xy 97.300382 -394.25188) (xy 97.250343 -394.271519)
			(xy 97.197936 -394.28348) (xy 97.144332 -394.287498) (xy 97.090728 -394.28348) (xy 97.038321 -394.271519)
			(xy 96.988282 -394.25188) (xy 96.941729 -394.225003) (xy 96.899701 -394.191487) (xy 96.863139 -394.152082)
			(xy 96.832858 -394.107668) (xy 96.809534 -394.059236) (xy 96.79369 -394.00787) (xy 96.785678 -393.954715)
			(xy 96.785176 -393.927838) (xy 96.785642 -393.902281) (xy 96.792879 -393.851681) (xy 96.807225 -393.802621)
			(xy 96.828391 -393.756094) (xy 96.855947 -393.713043) (xy 96.872298 -393.693396) (xy 96.872552 -393.693142)
			(xy 96.878214 -393.68582) (xy 96.884326 -393.668362) (xy 96.88449 -393.659106) (xy 96.882458 -393.580874)
			(xy 96.875346 -393.563856) (xy 96.868742 -393.556744) (xy 96.849014 -393.535273) (xy 96.815573 -393.487512)
			(xy 96.789786 -393.43522) (xy 96.772252 -393.379615) (xy 96.763379 -393.32199) (xy 96.762824 -393.292838)
			(xy 96.325944 -393.292838) (xy 96.325386 -393.322002) (xy 96.316465 -393.379644) (xy 96.298881 -393.435258)
			(xy 96.273044 -393.487552) (xy 96.239555 -393.535308) (xy 96.219772 -393.556744) (xy 96.213612 -393.563826)
			(xy 96.206456 -393.581162) (xy 96.205802 -393.590526) (xy 96.204024 -393.659106) (xy 96.204162 -393.668363)
			(xy 96.210299 -393.685816) (xy 96.215962 -393.693142) (xy 96.21647 -393.69365) (xy 96.23283 -393.713258)
			(xy 96.26036 -393.756269) (xy 96.281516 -393.802748) (xy 96.295869 -393.851757) (xy 96.303131 -393.902305)
			(xy 96.303592 -393.927838) (xy 96.30309 -393.954734) (xy 96.295072 -394.007926) (xy 96.279216 -394.059329)
			(xy 96.255877 -394.107795) (xy 96.225574 -394.152241) (xy 96.188986 -394.191674) (xy 96.146929 -394.225213)
			(xy 96.100343 -394.252109) (xy 96.050269 -394.271762) (xy 95.997824 -394.283732) (xy 95.944182 -394.287752)
			(xy 95.89054 -394.283732) (xy 95.838095 -394.271762) (xy 95.788021 -394.252109) (xy 95.741435 -394.225213)
			(xy 95.699378 -394.191674) (xy 95.66279 -394.152241) (xy 95.632487 -394.107795) (xy 95.609148 -394.059329)
			(xy 95.593292 -394.007926) (xy 95.585274 -393.954734) (xy 95.584772 -393.927838) (xy 95.585243 -393.90227)
			(xy 95.59252 -393.851654) (xy 95.606917 -393.802587) (xy 95.628141 -393.756063) (xy 95.655763 -393.713029)
			(xy 95.672148 -393.693396) (xy 95.672402 -393.693142) (xy 95.67807 -393.685824) (xy 95.684177 -393.668362)
			(xy 95.68434 -393.659106) (xy 95.682308 -393.580874) (xy 95.675196 -393.563856) (xy 95.668592 -393.556744)
			(xy 95.648805 -393.535312) (xy 95.615314 -393.487557) (xy 95.589479 -393.435262) (xy 95.571902 -393.379646)
			(xy 95.562991 -393.322002) (xy 95.56242 -393.292838) (xy 95.126048 -393.292838) (xy 95.125529 -393.321291)
			(xy 95.117081 -393.377566) (xy 95.100377 -393.431966) (xy 95.075786 -393.483284) (xy 95.043854 -393.530387)
			(xy 95.024956 -393.551664) (xy 95.019062 -393.558653) (xy 95.012155 -393.575566) (xy 95.011494 -393.584684)
			(xy 95.010478 -393.615418) (xy 95.01061 -393.624589) (xy 95.016597 -393.641909) (xy 95.022162 -393.6492)
			(xy 95.03753 -393.668533) (xy 95.063343 -393.710638) (xy 95.083137 -393.755886) (xy 95.096539 -393.80342)
			(xy 95.103294 -393.852344) (xy 95.103696 -393.877038) (xy 95.103194 -393.903934) (xy 95.095176 -393.957126)
			(xy 95.07932 -394.008529) (xy 95.055981 -394.056995) (xy 95.025678 -394.101441) (xy 94.98909 -394.140874)
			(xy 94.947033 -394.174413) (xy 94.900447 -394.201309) (xy 94.850373 -394.220962) (xy 94.797928 -394.232932)
			(xy 94.744286 -394.236952) (xy 94.690644 -394.232932) (xy 94.638199 -394.220962) (xy 94.588125 -394.201309)
			(xy 94.541539 -394.174413) (xy 94.499482 -394.140874) (xy 94.462894 -394.101441) (xy 94.432591 -394.056995)
			(xy 94.409252 -394.008529) (xy 94.393396 -393.957126) (xy 94.385378 -393.903934) (xy 94.384876 -393.877038)
			(xy 94.385322 -393.852349) (xy 94.392108 -393.803438) (xy 94.405517 -393.755915) (xy 94.425297 -393.710671)
			(xy 94.451077 -393.668556) (xy 94.46641 -393.6492) (xy 94.471937 -393.641888) (xy 94.477931 -393.624582)
			(xy 94.478094 -393.615418) (xy 94.477078 -393.584684) (xy 94.476444 -393.575558) (xy 94.469546 -393.55863)
			(xy 94.463616 -393.551664) (xy 94.444695 -393.530403) (xy 94.412733 -393.483313) (xy 94.388131 -393.431992)
			(xy 94.371439 -393.377582) (xy 94.363026 -393.321295) (xy 94.362524 -393.292838) (xy 93.926152 -393.292838)
			(xy 93.925592 -393.322002) (xy 93.916671 -393.379643) (xy 93.899087 -393.435258) (xy 93.873251 -393.487552)
			(xy 93.839763 -393.535308) (xy 93.81998 -393.556744) (xy 93.813821 -393.563827) (xy 93.806664 -393.581162)
			(xy 93.80601 -393.590526) (xy 93.804232 -393.659106) (xy 93.804369 -393.668363) (xy 93.810507 -393.685817)
			(xy 93.81617 -393.693142) (xy 93.816678 -393.69365) (xy 93.833039 -393.713257) (xy 93.860569 -393.756269)
			(xy 93.881724 -393.802748) (xy 93.896077 -393.851756) (xy 93.903339 -393.902305) (xy 93.9038 -393.927838)
			(xy 93.903298 -393.954734) (xy 93.89528 -394.007926) (xy 93.879424 -394.059329) (xy 93.856085 -394.107795)
			(xy 93.825782 -394.152241) (xy 93.789194 -394.191674) (xy 93.747137 -394.225213) (xy 93.700551 -394.252109)
			(xy 93.650477 -394.271762) (xy 93.598032 -394.283732) (xy 93.54439 -394.287752) (xy 93.490748 -394.283732)
			(xy 93.438303 -394.271762) (xy 93.388229 -394.252109) (xy 93.341643 -394.225213) (xy 93.299586 -394.191674)
			(xy 93.262998 -394.152241) (xy 93.232695 -394.107795) (xy 93.209356 -394.059329) (xy 93.1935 -394.007926)
			(xy 93.185482 -393.954734) (xy 93.18498 -393.927838) (xy 93.185449 -393.90227) (xy 93.192726 -393.851654)
			(xy 93.207123 -393.802586) (xy 93.228348 -393.756063) (xy 93.25597 -393.713029) (xy 93.272356 -393.693396)
			(xy 93.27261 -393.693142) (xy 93.278279 -393.685824) (xy 93.284386 -393.668363) (xy 93.284548 -393.659106)
			(xy 93.282516 -393.580874) (xy 93.275404 -393.563856) (xy 93.2688 -393.556744) (xy 93.249014 -393.535311)
			(xy 93.215523 -393.487556) (xy 93.189687 -393.435262) (xy 93.17211 -393.379645) (xy 93.163199 -393.322002)
			(xy 93.162628 -393.292838) (xy 92.868496 -393.292838) (xy 92.868496 -394.428218) (xy 92.868108 -394.438292)
			(xy 92.860364 -394.456891) (xy 92.85351 -394.464286) (xy 92.56776 -394.750036) (xy 92.560372 -394.756891)
			(xy 92.541763 -394.764601) (xy 92.531692 -394.765022) (xy 85.71484 -394.765022) (xy 85.70477 -394.764597)
			(xy 85.686171 -394.756878) (xy 85.678772 -394.750036) (xy 85.227922 -394.299186) (xy 85.219407 -394.291469)
			(xy 85.197729 -394.283922) (xy 85.186266 -394.284708) (xy 85.185758 -394.284708) (xy 85.175446 -394.285867)
			(xy 85.154732 -394.287138) (xy 85.144356 -394.287248) (xy 85.118711 -394.286841) (xy 85.067945 -394.279539)
			(xy 85.018733 -394.26509) (xy 84.972076 -394.243788) (xy 84.928924 -394.216067) (xy 84.890154 -394.182489)
			(xy 84.856555 -394.143738) (xy 84.828809 -394.100601) (xy 84.807481 -394.053957) (xy 84.793004 -394.004753)
			(xy 84.785674 -393.95399) (xy 84.7852 -393.928346) (xy 84.7852 -393.927838) (xy 84.78566 -393.90228)
			(xy 84.792898 -393.85168) (xy 84.807245 -393.80262) (xy 84.828412 -393.756093) (xy 84.85597 -393.713043)
			(xy 84.872322 -393.693396) (xy 84.872576 -393.693142) (xy 84.878241 -393.685821) (xy 84.884351 -393.668362)
			(xy 84.884514 -393.659106) (xy 84.882482 -393.580874) (xy 84.87537 -393.563856) (xy 84.868766 -393.556744)
			(xy 84.849025 -393.535285) (xy 84.815589 -393.487519) (xy 84.789806 -393.435224) (xy 84.772274 -393.379617)
			(xy 84.763403 -393.321991) (xy 84.762848 -393.292838) (xy 84.762848 -392.42873) (xy 84.763274 -392.403262)
			(xy 84.770077 -392.352781) (xy 84.78354 -392.303655) (xy 84.803422 -392.256758) (xy 84.829371 -392.212926)
			(xy 84.860923 -392.172938) (xy 84.878926 -392.154918) (xy 84.88553 -392.148568) (xy 84.893404 -392.131804)
			(xy 84.900262 -392.04646) (xy 84.895182 -392.02868) (xy 84.889594 -392.021314) (xy 84.874739 -392.000569)
			(xy 84.851106 -391.955354) (xy 84.835006 -391.906941) (xy 84.826854 -391.856578) (xy 84.826348 -391.831068)
			(xy 84.826348 -391.830814) (xy 84.82681 -391.807126) (xy 84.833824 -391.760273) (xy 84.847713 -391.714979)
			(xy 84.868169 -391.672248) (xy 84.89474 -391.633026) (xy 84.926837 -391.598181) (xy 84.96375 -391.568485)
			(xy 85.00466 -391.544595) (xy 85.0265 -391.535412) (xy 85.040978 -391.52957) (xy 85.058504 -391.503916)
			(xy 85.058504 -390.815576) (xy 85.058116 -390.805502) (xy 85.050372 -390.786903) (xy 85.043518 -390.779508)
			(xy 84.828634 -390.564878) (xy 84.821219 -390.558057) (xy 84.802631 -390.550327) (xy 84.792566 -390.549892)
			(xy 84.46516 -390.549892) (xy 84.455149 -390.549444) (xy 84.436655 -390.54177) (xy 84.422503 -390.527605)
			(xy 84.414846 -390.509104) (xy 84.41436 -390.499092) (xy 84.41436 -390.284716) (xy 84.405216 -390.284716)
			(xy 84.395211 -390.284199) (xy 84.376723 -390.276548) (xy 84.36257 -390.262404) (xy 84.354907 -390.24392)
			(xy 84.354416 -390.233916) (xy 84.354416 -390.029954) (xy 84.354953 -390.007777) (xy 84.364103 -389.964379)
			(xy 84.382039 -389.923815) (xy 84.394548 -389.905494) (xy 84.399374 -389.899144) (xy 84.4042 -389.883904)
			(xy 84.4042 -389.854694) (xy 84.403854 -389.843994) (xy 84.395286 -389.824393) (xy 84.38769 -389.816848)
			(xy 84.364322 -389.795766) (xy 84.35678 -389.789609) (xy 84.338498 -389.782956) (xy 84.328762 -389.782812)
			(xy 84.31911 -389.782812) (xy 84.293716 -389.782303) (xy 84.243583 -389.774174) (xy 84.195397 -389.758124)
			(xy 84.150403 -389.734567) (xy 84.10976 -389.70411) (xy 84.074517 -389.66754) (xy 84.045583 -389.6258)
			(xy 84.023705 -389.579966) (xy 84.016088 -389.555736) (xy 84.014564 -389.549894) (xy 83.69427 -388.996174)
			(xy 83.690206 -388.991856) (xy 83.674039 -388.974129) (xy 83.646673 -388.934724) (xy 83.625585 -388.891633)
			(xy 83.611259 -388.845846) (xy 83.604026 -388.79842) (xy 83.603592 -388.774432) (xy 83.603773 -388.760384)
			(xy 83.606314 -388.732402) (xy 83.608672 -388.718552) (xy 83.609998 -388.709273) (xy 83.606469 -388.690875)
			(xy 83.601814 -388.682738) (xy 83.58505 -388.655814) (xy 83.579836 -388.648119) (xy 83.565119 -388.636791)
			(xy 83.556348 -388.633716) (xy 83.534721 -388.626917) (xy 83.493507 -388.608035) (xy 83.455387 -388.583499)
			(xy 83.421131 -388.553806) (xy 83.40598 -388.536942) (xy 83.403511 -388.534176) (xy 83.397903 -388.529325)
			(xy 83.394804 -388.52729) (xy 83.382754 -388.519213) (xy 83.362792 -388.498178) (xy 83.348714 -388.472825)
			(xy 83.34141 -388.444761) (xy 83.340956 -388.430262) (xy 83.340956 -388.418324) (xy 83.339432 -388.41172)
			(xy 83.334225 -388.391351) (xy 83.328625 -388.349683) (xy 83.328256 -388.328662) (xy 82.764376 -388.328662)
			(xy 82.764376 -388.32917) (xy 82.764206 -388.343795) (xy 82.761539 -388.372924) (xy 82.759042 -388.387336)
			(xy 82.757673 -388.39651) (xy 82.760948 -388.414753) (xy 82.765392 -388.422896) (xy 82.781902 -388.44982)
			(xy 82.787051 -388.457615) (xy 82.801791 -388.469068) (xy 82.810604 -388.472172) (xy 82.835524 -388.480319)
			(xy 82.88249 -388.503609) (xy 82.92497 -388.534328) (xy 82.961801 -388.571634) (xy 82.991972 -388.614506)
			(xy 83.014657 -388.661767) (xy 83.02244 -388.686802) (xy 83.023964 -388.692644) (xy 83.34375 -389.245602)
			(xy 83.347814 -389.24992) (xy 83.363972 -389.267588) (xy 83.391292 -389.306904) (xy 83.412361 -389.349896)
			(xy 83.426694 -389.395577) (xy 83.433965 -389.442898) (xy 83.434428 -389.466836) (xy 83.434428 -389.467344)
			(xy 83.433965 -389.492795) (xy 83.425792 -389.543037) (xy 83.409666 -389.591318) (xy 83.386004 -389.636387)
			(xy 83.355419 -389.677076) (xy 83.318703 -389.712332) (xy 83.29803 -389.727186) (xy 83.289508 -389.733643)
			(xy 83.278304 -389.751828) (xy 83.275463 -389.772997) (xy 83.281474 -389.793493) (xy 83.295299 -389.809775)
			(xy 83.314549 -389.819028) (xy 83.325208 -389.819896) (xy 83.33486 -389.819388) (xy 83.343373 -389.818089)
			(xy 83.360539 -389.816694) (xy 83.36915 -389.816594) (xy 83.369404 -389.816848) (xy 83.668616 -389.816848)
			(xy 83.66887 -389.816594) (xy 83.689917 -389.816969) (xy 83.731239 -389.824971) (xy 83.770194 -389.840908)
			(xy 83.805276 -389.864162) (xy 83.835127 -389.893835) (xy 83.858591 -389.928777) (xy 83.87476 -389.967636)
			(xy 83.883008 -390.008909) (xy 83.8835 -390.029954) (xy 83.8835 -390.284716) (xy 83.874356 -390.284716)
			(xy 83.864344 -390.285153) (xy 83.845848 -390.29283) (xy 83.831696 -390.306998) (xy 83.824041 -390.325503)
			(xy 83.823556 -390.335516) (xy 83.823556 -390.499092) (xy 83.823173 -390.509118) (xy 83.815497 -390.527643)
			(xy 83.801313 -390.541818) (xy 83.782783 -390.54948) (xy 83.772756 -390.549892) (xy 83.265264 -390.549892)
			(xy 83.255253 -390.549441) (xy 83.236759 -390.541768) (xy 83.222607 -390.527604) (xy 83.21495 -390.509103)
			(xy 83.214464 -390.499092) (xy 83.214464 -390.335516) (xy 83.214067 -390.325491) (xy 83.206395 -390.306968)
			(xy 83.192215 -390.292794) (xy 83.173689 -390.285129) (xy 83.163664 -390.284716) (xy 83.15452 -390.284716)
			(xy 83.15452 -390.029446) (xy 83.155304 -390.003724) (xy 83.167637 -389.953777) (xy 83.178904 -389.93064)
			(xy 83.184746 -389.91921) (xy 83.184492 -389.89381) (xy 83.130898 -389.796782) (xy 83.109308 -389.783066)
			(xy 83.096354 -389.78205) (xy 83.07246 -389.779908) (xy 83.025673 -389.769311) (xy 82.981033 -389.751748)
			(xy 82.939568 -389.727624) (xy 82.902238 -389.697496) (xy 82.869903 -389.66206) (xy 82.843311 -389.622134)
			(xy 82.823075 -389.57864) (xy 82.815938 -389.555736) (xy 82.814414 -389.549894) (xy 82.493866 -388.995412)
			(xy 82.489802 -388.991094) (xy 82.473695 -388.973441) (xy 82.446509 -388.934139) (xy 82.42556 -388.891188)
			(xy 82.411325 -388.845569) (xy 82.404131 -388.798326) (xy 82.403696 -388.774432) (xy 82.403877 -388.760384)
			(xy 82.406418 -388.732402) (xy 82.408776 -388.718552) (xy 82.410102 -388.709273) (xy 82.406573 -388.690875)
			(xy 82.401918 -388.682738) (xy 82.385154 -388.655814) (xy 82.379939 -388.648121) (xy 82.365223 -388.636792)
			(xy 82.356452 -388.633716) (xy 82.334826 -388.626915) (xy 82.293612 -388.608034) (xy 82.255491 -388.583498)
			(xy 82.221235 -388.553805) (xy 82.206084 -388.536942) (xy 82.203614 -388.534176) (xy 82.198007 -388.529325)
			(xy 82.194908 -388.52729) (xy 82.182837 -388.519242) (xy 82.162884 -388.498194) (xy 82.148812 -388.472832)
			(xy 82.141513 -388.444763) (xy 82.14106 -388.430262) (xy 82.14106 -388.418324) (xy 82.139536 -388.41172)
			(xy 82.134329 -388.391351) (xy 82.128729 -388.349683) (xy 82.12836 -388.328662) (xy 81.564226 -388.328662)
			(xy 81.564226 -388.32917) (xy 81.564055 -388.343795) (xy 81.561388 -388.372924) (xy 81.558892 -388.387336)
			(xy 81.55753 -388.39651) (xy 81.560802 -388.414752) (xy 81.565242 -388.422896) (xy 81.581752 -388.44982)
			(xy 81.586919 -388.457601) (xy 81.601647 -388.469061) (xy 81.610454 -388.472172) (xy 81.635345 -388.480209)
			(xy 81.682223 -388.503405) (xy 81.724634 -388.534015) (xy 81.761415 -388.5712) (xy 81.79156 -388.613942)
			(xy 81.814243 -388.661071) (xy 81.822036 -388.68604) (xy 81.82356 -388.691882) (xy 82.143854 -389.245602)
			(xy 82.147918 -389.24992) (xy 82.164077 -389.267587) (xy 82.191396 -389.306904) (xy 82.212465 -389.349896)
			(xy 82.226798 -389.395577) (xy 82.234069 -389.442898) (xy 82.234532 -389.466836) (xy 82.234532 -389.467344)
			(xy 82.23404 -389.492793) (xy 82.225868 -389.543031) (xy 82.209744 -389.591307) (xy 82.186084 -389.636372)
			(xy 82.155502 -389.677057) (xy 82.118789 -389.712311) (xy 82.098134 -389.727186) (xy 82.08961 -389.733641)
			(xy 82.078405 -389.751827) (xy 82.075563 -389.772997) (xy 82.081574 -389.793494) (xy 82.095401 -389.809776)
			(xy 82.114653 -389.819029) (xy 82.125312 -389.819896) (xy 82.134964 -389.819388) (xy 82.143477 -389.818089)
			(xy 82.160643 -389.816693) (xy 82.169254 -389.816594) (xy 82.169508 -389.816848) (xy 82.46872 -389.816848)
			(xy 82.468974 -389.816594) (xy 82.490021 -389.816966) (xy 82.531343 -389.824968) (xy 82.570299 -389.840905)
			(xy 82.605381 -389.86416) (xy 82.635231 -389.893833) (xy 82.658695 -389.928776) (xy 82.674864 -389.967636)
			(xy 82.683112 -390.008909) (xy 82.683604 -390.029954) (xy 82.683604 -390.284716) (xy 82.67446 -390.284716)
			(xy 82.664448 -390.285156) (xy 82.645952 -390.292831) (xy 82.6318 -390.306999) (xy 82.624145 -390.325503)
			(xy 82.62366 -390.335516) (xy 82.62366 -390.499092) (xy 82.623273 -390.509118) (xy 82.615598 -390.527642)
			(xy 82.601415 -390.541816) (xy 82.582886 -390.549479) (xy 82.57286 -390.549892) (xy 82.065368 -390.549892)
			(xy 82.055357 -390.549438) (xy 82.036863 -390.541766) (xy 82.022711 -390.527603) (xy 82.015054 -390.509103)
			(xy 82.014568 -390.499092) (xy 82.014568 -390.335516) (xy 82.014167 -390.325492) (xy 82.006496 -390.306969)
			(xy 81.992318 -390.292795) (xy 81.973792 -390.28513) (xy 81.963768 -390.284716) (xy 81.954624 -390.284716)
			(xy 81.954624 -390.029446) (xy 81.955407 -390.003724) (xy 81.967741 -389.953777) (xy 81.979008 -389.93064)
			(xy 81.98485 -389.91921) (xy 81.984596 -389.89381) (xy 81.931002 -389.796782) (xy 81.909412 -389.783066)
			(xy 81.896458 -389.78205) (xy 81.872564 -389.779904) (xy 81.825778 -389.769309) (xy 81.781137 -389.751746)
			(xy 81.739673 -389.727623) (xy 81.702342 -389.697495) (xy 81.670007 -389.66206) (xy 81.643415 -389.622134)
			(xy 81.623179 -389.57864) (xy 81.616042 -389.555736) (xy 81.614518 -389.549894) (xy 81.294224 -388.996174)
			(xy 81.29016 -388.991856) (xy 81.27395 -388.974153) (xy 81.246528 -388.93476) (xy 81.225387 -388.891669)
			(xy 81.211015 -388.845874) (xy 81.203742 -388.798431) (xy 81.203292 -388.774432) (xy 81.203471 -388.760384)
			(xy 81.206014 -388.732402) (xy 81.208372 -388.718552) (xy 81.209666 -388.709296) (xy 81.206266 -388.690931)
			(xy 81.201768 -388.682738) (xy 81.185004 -388.655814) (xy 81.179806 -388.648107) (xy 81.165078 -388.636785)
			(xy 81.156302 -388.633716) (xy 81.134682 -388.626896) (xy 81.093467 -388.60802) (xy 81.055345 -388.583491)
			(xy 81.021087 -388.553803) (xy 81.005934 -388.536942) (xy 81.00347 -388.534171) (xy 80.997859 -388.529324)
			(xy 80.994758 -388.52729) (xy 80.982726 -388.519215) (xy 80.962838 -388.498153) (xy 80.948831 -388.472795)
			(xy 80.941591 -388.444746) (xy 80.941164 -388.430262) (xy 80.941164 -388.418324) (xy 80.939386 -388.41172)
			(xy 80.93418 -388.391351) (xy 80.928579 -388.349683) (xy 80.92821 -388.328662) (xy 80.36433 -388.328662)
			(xy 80.36433 -388.32917) (xy 80.364161 -388.343795) (xy 80.361493 -388.372924) (xy 80.358996 -388.387336)
			(xy 80.357633 -388.39651) (xy 80.360905 -388.414752) (xy 80.365346 -388.422896) (xy 80.381856 -388.44982)
			(xy 80.387021 -388.457602) (xy 80.40175 -388.469062) (xy 80.410558 -388.472172) (xy 80.43545 -388.480206)
			(xy 80.482328 -388.503403) (xy 80.524738 -388.534014) (xy 80.56152 -388.571199) (xy 80.591665 -388.613942)
			(xy 80.614347 -388.661071) (xy 80.62214 -388.68604) (xy 80.623664 -388.691882) (xy 80.943958 -389.245602)
			(xy 80.948022 -389.24992) (xy 80.964181 -389.267586) (xy 80.991501 -389.306904) (xy 81.012569 -389.349896)
			(xy 81.026903 -389.395576) (xy 81.034173 -389.442898) (xy 81.034636 -389.466836) (xy 81.034636 -389.467344)
			(xy 81.034142 -389.492793) (xy 81.025971 -389.54303) (xy 81.009846 -389.591307) (xy 80.986187 -389.636371)
			(xy 80.955605 -389.677057) (xy 80.918893 -389.712311) (xy 80.898238 -389.727186) (xy 80.889721 -389.733618)
			(xy 80.87852 -389.751762) (xy 80.875647 -389.772891) (xy 80.881597 -389.793367) (xy 80.895345 -389.809665)
			(xy 80.914526 -389.818981) (xy 80.925162 -389.819896) (xy 80.935068 -389.819388) (xy 80.943518 -389.818096)
			(xy 80.960556 -389.816701) (xy 80.969104 -389.816594) (xy 80.969358 -389.816848) (xy 81.26857 -389.816848)
			(xy 81.268824 -389.816594) (xy 81.289888 -389.81694) (xy 81.331249 -389.824906) (xy 81.370248 -389.840821)
			(xy 81.405374 -389.864068) (xy 81.435264 -389.893746) (xy 81.458761 -389.928705) (xy 81.474954 -389.96759)
			(xy 81.483215 -390.008893) (xy 81.483708 -390.029954) (xy 81.483708 -390.284716) (xy 81.474564 -390.284716)
			(xy 81.464552 -390.285159) (xy 81.446056 -390.292833) (xy 81.431904 -390.307) (xy 81.424249 -390.325504)
			(xy 81.423764 -390.335516) (xy 81.423764 -390.499092) (xy 81.423373 -390.509117) (xy 81.415699 -390.527641)
			(xy 81.401517 -390.541815) (xy 81.382989 -390.549479) (xy 81.372964 -390.549892) (xy 80.864964 -390.549892)
			(xy 80.854953 -390.549441) (xy 80.836459 -390.541768) (xy 80.822307 -390.527604) (xy 80.81465 -390.509103)
			(xy 80.814164 -390.499092) (xy 80.814164 -390.284716) (xy 80.80502 -390.284716) (xy 80.795002 -390.284264)
			(xy 80.776489 -390.276604) (xy 80.762316 -390.262442) (xy 80.754643 -390.243934) (xy 80.75422 -390.233916)
			(xy 80.75422 -390.029954) (xy 80.754565 -390.012721) (xy 80.760135 -389.978708) (xy 80.771107 -389.946035)
			(xy 80.778858 -389.93064) (xy 80.7847 -389.91921) (xy 80.784446 -389.89381) (xy 80.736948 -389.808212)
			(xy 80.730236 -389.797426) (xy 80.708905 -389.783691) (xy 80.696308 -389.78205) (xy 80.672433 -389.779877)
			(xy 80.625689 -389.769245) (xy 80.581092 -389.751661) (xy 80.539671 -389.72753) (xy 80.502379 -389.697407)
			(xy 80.470076 -389.661987) (xy 80.443506 -389.622086) (xy 80.423282 -389.578623) (xy 80.416146 -389.555736)
			(xy 80.414622 -389.549894) (xy 80.094328 -388.996174) (xy 80.090264 -388.991856) (xy 80.074055 -388.974153)
			(xy 80.046633 -388.93476) (xy 80.025492 -388.891669) (xy 80.011119 -388.845874) (xy 80.003846 -388.798431)
			(xy 80.003396 -388.774432) (xy 80.003575 -388.760384) (xy 80.006118 -388.732402) (xy 80.008476 -388.718552)
			(xy 80.009769 -388.709296) (xy 80.00637 -388.690932) (xy 80.001872 -388.682738) (xy 79.985108 -388.655814)
			(xy 79.979909 -388.648108) (xy 79.965181 -388.636786) (xy 79.956406 -388.633716) (xy 79.934774 -388.626933)
			(xy 79.893561 -388.608045) (xy 79.855442 -388.583505) (xy 79.821188 -388.553807) (xy 79.806038 -388.536942)
			(xy 79.803574 -388.534171) (xy 79.797963 -388.529324) (xy 79.794862 -388.52729) (xy 79.782831 -388.519214)
			(xy 79.762942 -388.498152) (xy 79.748935 -388.472795) (xy 79.741695 -388.444746) (xy 79.741268 -388.430262)
			(xy 79.741268 -388.418324) (xy 79.73949 -388.41172) (xy 79.734284 -388.391351) (xy 79.728683 -388.349683)
			(xy 79.728314 -388.328662) (xy 77.961968 -388.328662) (xy 77.955277 -388.371845) (xy 77.948028 -388.396226)
			(xy 77.945488 -388.403846) (xy 77.945488 -388.494778) (xy 77.944891 -388.511456) (xy 77.936264 -388.543676)
			(xy 77.919592 -388.572567) (xy 77.896011 -388.596158) (xy 77.867128 -388.612842) (xy 77.834912 -388.621483)
			(xy 77.818234 -388.622032) (xy 77.68844 -388.622032) (xy 77.68463 -388.622794) (xy 77.671825 -388.624704)
			(xy 77.646014 -388.626737) (xy 77.633068 -388.626858) (xy 77.63256 -388.626858) (xy 77.619615 -388.626714)
			(xy 77.593805 -388.624683) (xy 77.580998 -388.622794) (xy 77.577188 -388.622032) (xy 77.437234 -388.622032)
			(xy 77.420546 -388.621528) (xy 77.388305 -388.612896) (xy 77.359398 -388.596211) (xy 77.335796 -388.572612)
			(xy 77.319108 -388.543706) (xy 77.310473 -388.511466) (xy 77.30998 -388.494778) (xy 77.30998 -388.367524)
			(xy 77.30871 -388.362444) (xy 77.305602 -388.346047) (xy 77.302291 -388.312838) (xy 77.302106 -388.29615)
			(xy 77.100148 -388.29615) (xy 77.100176 -388.297674) (xy 77.099667 -388.32556) (xy 77.091547 -388.380736)
			(xy 77.075479 -388.434143) (xy 77.051807 -388.48464) (xy 77.021034 -388.531153) (xy 76.983817 -388.57269)
			(xy 76.940949 -388.608365) (xy 76.893343 -388.637419) (xy 76.842014 -388.659231) (xy 76.788057 -388.673337)
			(xy 76.73262 -388.679437) (xy 76.676886 -388.6774) (xy 76.622043 -388.66727) (xy 76.569259 -388.649263)
			(xy 76.519659 -388.623762) (xy 76.474301 -388.591311) (xy 76.434152 -388.552602) (xy 76.400066 -388.508459)
			(xy 76.37277 -388.459824) (xy 76.352847 -388.407733) (xy 76.340721 -388.353296) (xy 76.33665 -388.297674)
			(xy 75.261724 -388.297674) (xy 75.261724 -388.353554) (xy 75.26221 -388.364299) (xy 75.27104 -388.38389)
			(xy 75.278742 -388.3914) (xy 75.303052 -388.413749) (xy 75.346276 -388.463673) (xy 75.382677 -388.518769)
			(xy 75.411644 -388.578112) (xy 75.43269 -388.640704) (xy 75.445462 -388.705493) (xy 75.449744 -388.771389)
			(xy 75.445465 -388.837286) (xy 75.432696 -388.902075) (xy 75.411652 -388.964668) (xy 75.382688 -389.024012)
			(xy 75.346289 -389.07911) (xy 75.303067 -389.129036) (xy 75.278742 -389.151368) (xy 75.271122 -389.158934)
			(xy 75.262318 -389.178493) (xy 75.261724 -389.189214) (xy 75.261724 -390.626092) (xy 77.290422 -390.626092)
			(xy 77.290828 -390.602858) (xy 77.297322 -390.556848) (xy 77.310196 -390.5122) (xy 77.329196 -390.469795)
			(xy 77.353948 -390.430469) (xy 77.368654 -390.412478) (xy 77.374496 -390.40562) (xy 77.380846 -390.388602)
			(xy 77.380846 -390.304782) (xy 77.374496 -390.287764) (xy 77.368654 -390.280906) (xy 77.353942 -390.262919)
			(xy 77.329194 -390.22359) (xy 77.310195 -390.181184) (xy 77.297317 -390.136536) (xy 77.290815 -390.090526)
			(xy 77.290422 -390.067292) (xy 77.290932 -390.041305) (xy 77.299062 -389.98997) (xy 77.315123 -389.94054)
			(xy 77.338719 -389.89423) (xy 77.369269 -389.852182) (xy 77.40602 -389.815431) (xy 77.448068 -389.784881)
			(xy 77.494378 -389.761285) (xy 77.543808 -389.745224) (xy 77.595143 -389.737094) (xy 77.647117 -389.737094)
			(xy 77.698452 -389.745224) (xy 77.747882 -389.761285) (xy 77.794192 -389.784881) (xy 77.83624 -389.815431)
			(xy 77.872991 -389.852182) (xy 77.903541 -389.89423) (xy 77.927137 -389.94054) (xy 77.943198 -389.98997)
			(xy 77.951328 -390.041305) (xy 77.951838 -390.067292) (xy 77.951467 -390.090527) (xy 77.944962 -390.136538)
			(xy 77.932079 -390.181186) (xy 77.913072 -390.22359) (xy 77.906571 -390.233916) (xy 79.554324 -390.233916)
			(xy 79.554324 -390.029954) (xy 79.554873 -390.00891) (xy 79.563105 -389.967636) (xy 79.579261 -389.928774)
			(xy 79.602714 -389.893828) (xy 79.632558 -389.864151) (xy 79.667635 -389.840895) (xy 79.706588 -389.824958)
			(xy 79.747908 -389.816958) (xy 79.768954 -389.816594) (xy 79.769208 -389.816848) (xy 80.06842 -389.816848)
			(xy 80.068674 -389.816594) (xy 80.089721 -389.816966) (xy 80.131043 -389.824968) (xy 80.169999 -389.840905)
			(xy 80.205081 -389.86416) (xy 80.234931 -389.893833) (xy 80.258395 -389.928776) (xy 80.274564 -389.967636)
			(xy 80.282812 -390.008909) (xy 80.283304 -390.029954) (xy 80.283304 -390.284716) (xy 80.27416 -390.284716)
			(xy 80.264148 -390.285156) (xy 80.245652 -390.292831) (xy 80.2315 -390.306999) (xy 80.223845 -390.325503)
			(xy 80.22336 -390.335516) (xy 80.22336 -390.499092) (xy 80.222973 -390.509118) (xy 80.215298 -390.527642)
			(xy 80.201115 -390.541816) (xy 80.182586 -390.549479) (xy 80.17256 -390.549892) (xy 79.665068 -390.549892)
			(xy 79.655057 -390.549438) (xy 79.636563 -390.541766) (xy 79.622411 -390.527603) (xy 79.614754 -390.509103)
			(xy 79.614268 -390.499092) (xy 79.614268 -390.284716) (xy 79.605124 -390.284716) (xy 79.595106 -390.284261)
			(xy 79.576593 -390.276602) (xy 79.562421 -390.262441) (xy 79.554747 -390.243933) (xy 79.554324 -390.233916)
			(xy 77.906571 -390.233916) (xy 77.888315 -390.262916) (xy 77.873606 -390.280906) (xy 77.867764 -390.287764)
			(xy 77.861414 -390.304782) (xy 77.861414 -390.388602) (xy 77.867764 -390.40562) (xy 77.873606 -390.412478)
			(xy 77.88832 -390.430463) (xy 77.913065 -390.469794) (xy 77.932063 -390.5122) (xy 77.944941 -390.556848)
			(xy 77.951444 -390.602858) (xy 77.951838 -390.626092) (xy 77.951838 -390.626346) (xy 77.951406 -390.650396)
			(xy 77.944415 -390.697986) (xy 77.930618 -390.744065) (xy 77.92085 -390.766046) (xy 77.915516 -390.777476)
			(xy 77.916786 -390.802622) (xy 77.96657 -390.88568) (xy 77.97352 -390.896033) (xy 77.994817 -390.908948)
			(xy 78.00721 -390.910318) (xy 78.03221 -390.912121) (xy 78.081255 -390.922459) (xy 78.128179 -390.94008)
			(xy 78.171908 -390.964578) (xy 78.21144 -390.995393) (xy 78.24587 -391.03182) (xy 78.274409 -391.073025)
			(xy 78.296406 -391.118064) (xy 78.311355 -391.165906) (xy 78.318914 -391.215456) (xy 78.319376 -391.240518)
			(xy 78.318866 -391.266505) (xy 78.310736 -391.31784) (xy 78.294675 -391.36727) (xy 78.271079 -391.41358)
			(xy 78.240529 -391.455628) (xy 78.203778 -391.492379) (xy 78.16173 -391.522929) (xy 78.11542 -391.546525)
			(xy 78.06599 -391.562586) (xy 78.014655 -391.570716) (xy 77.962681 -391.570716) (xy 77.911346 -391.562586)
			(xy 77.861916 -391.546525) (xy 77.815606 -391.522929) (xy 77.773558 -391.492379) (xy 77.736807 -391.455628)
			(xy 77.706257 -391.41358) (xy 77.682661 -391.36727) (xy 77.6666 -391.31784) (xy 77.65847 -391.266505)
			(xy 77.65796 -391.240518) (xy 77.65796 -391.240264) (xy 77.658396 -391.216214) (xy 77.665385 -391.168625)
			(xy 77.679181 -391.122546) (xy 77.688948 -391.100564) (xy 77.694282 -391.089134) (xy 77.693012 -391.063988)
			(xy 77.643228 -390.98093) (xy 77.636277 -390.970578) (xy 77.614981 -390.957662) (xy 77.602588 -390.956292)
			(xy 77.577589 -390.954481) (xy 77.528544 -390.944143) (xy 77.481621 -390.926523) (xy 77.437893 -390.902025)
			(xy 77.398362 -390.871211) (xy 77.363932 -390.834785) (xy 77.335392 -390.793581) (xy 77.313395 -390.748543)
			(xy 77.298445 -390.700702) (xy 77.290884 -390.651153) (xy 77.290422 -390.626092) (xy 75.261724 -390.626092)
			(xy 75.261724 -391.146284) (xy 75.261218 -391.156334) (xy 75.253495 -391.174894) (xy 75.246738 -391.182352)
			(xy 75.04557 -391.38352) (xy 75.038174 -391.39037) (xy 75.019575 -391.398107) (xy 75.009502 -391.398506)
			(xy 74.700384 -391.398506) (xy 74.690315 -391.398932) (xy 74.671716 -391.406651) (xy 74.664316 -391.413492)
			(xy 74.605896 -391.472166) (xy 74.598499 -391.479015) (xy 74.579901 -391.486754) (xy 74.569828 -391.487152)
			(xy 73.740264 -391.487152) (xy 73.730231 -391.487588) (xy 73.711657 -391.495164) (xy 73.704196 -391.501884)
			(xy 73.688448 -391.517632) (xy 73.681602 -391.52503) (xy 73.673871 -391.543629) (xy 73.673462 -391.5537)
			(xy 73.673462 -392.251946) (xy 76.590906 -392.251946) (xy 76.591392 -392.224695) (xy 76.599148 -392.170747)
			(xy 76.614503 -392.118452) (xy 76.637145 -392.068875) (xy 76.666611 -392.023025) (xy 76.702302 -391.981834)
			(xy 76.743493 -391.946143) (xy 76.789343 -391.916677) (xy 76.83892 -391.894035) (xy 76.891215 -391.87868)
			(xy 76.945163 -391.870924) (xy 76.999665 -391.870924) (xy 76.999818 -391.870946) (xy 78.650592 -391.870946)
			(xy 78.650592 -391.616184) (xy 78.659736 -391.616184) (xy 78.669748 -391.615741) (xy 78.688244 -391.608067)
			(xy 78.702396 -391.5939) (xy 78.710051 -391.575396) (xy 78.710536 -391.565384) (xy 78.710536 -391.401808)
			(xy 78.710927 -391.391783) (xy 78.718601 -391.373259) (xy 78.732783 -391.359085) (xy 78.751311 -391.351421)
			(xy 78.761336 -391.351008) (xy 79.268828 -391.351008) (xy 79.278838 -391.351465) (xy 79.297332 -391.359136)
			(xy 79.311485 -391.373298) (xy 79.319142 -391.391797) (xy 79.319628 -391.401808) (xy 79.319628 -391.616184)
			(xy 79.328772 -391.616184) (xy 79.338789 -391.616642) (xy 79.357303 -391.6243) (xy 79.371475 -391.63846)
			(xy 79.379149 -391.656967) (xy 79.379572 -391.666984) (xy 79.379572 -391.870946) (xy 79.379012 -391.893538)
			(xy 79.369548 -391.937718) (xy 79.351011 -391.978923) (xy 79.324229 -392.015312) (xy 79.30769 -392.030712)
			(xy 79.300832 -392.036808) (xy 79.292196 -392.05281) (xy 79.282036 -392.12774) (xy 79.28116 -392.136623)
			(xy 79.284921 -392.154058) (xy 79.289402 -392.161776) (xy 79.289656 -392.161776) (xy 79.289656 -392.162284)
			(xy 79.301708 -392.181648) (xy 79.320775 -392.22308) (xy 79.333725 -392.266812) (xy 79.340292 -392.311946)
			(xy 79.34071 -392.33475) (xy 79.34022 -392.359739) (xy 79.332401 -392.409102) (xy 79.316957 -392.456634)
			(xy 79.294267 -392.501166) (xy 79.264891 -392.541599) (xy 79.229551 -392.576939) (xy 79.189118 -392.606315)
			(xy 79.144586 -392.629005) (xy 79.097054 -392.644449) (xy 79.047691 -392.652268) (xy 78.997713 -392.652268)
			(xy 78.94835 -392.644449) (xy 78.900818 -392.629005) (xy 78.856286 -392.606315) (xy 78.815853 -392.576939)
			(xy 78.780513 -392.541599) (xy 78.751137 -392.501166) (xy 78.728447 -392.456634) (xy 78.713003 -392.409102)
			(xy 78.705184 -392.359739) (xy 78.704694 -392.33475) (xy 78.705374 -392.305549) (xy 78.716023 -392.248127)
			(xy 78.736973 -392.193613) (xy 78.751684 -392.16838) (xy 78.756152 -392.160382) (xy 78.759672 -392.142419)
			(xy 78.758542 -392.133328) (xy 78.747112 -392.067034) (xy 78.74526 -392.058214) (xy 78.736266 -392.042606)
			(xy 78.729586 -392.036554) (xy 78.729078 -392.0363) (xy 78.714676 -392.024009) (xy 78.690027 -391.995274)
			(xy 78.67083 -391.962643) (xy 78.657685 -391.92714) (xy 78.651004 -391.889875) (xy 78.650592 -391.870946)
			(xy 76.999818 -391.870946) (xy 77.053613 -391.87868) (xy 77.105908 -391.894035) (xy 77.155485 -391.916677)
			(xy 77.201335 -391.946143) (xy 77.242526 -391.981834) (xy 77.278217 -392.023025) (xy 77.307683 -392.068875)
			(xy 77.330325 -392.118452) (xy 77.34568 -392.170747) (xy 77.353436 -392.224695) (xy 77.353922 -392.251946)
			(xy 77.352652 -392.284204) (xy 77.35189 -392.293602) (xy 77.35697 -392.31189) (xy 77.404722 -392.373866)
			(xy 77.410782 -392.381044) (xy 77.426809 -392.390811) (xy 77.435964 -392.392916) (xy 77.436218 -392.392916)
			(xy 77.462371 -392.39802) (xy 77.513047 -392.414482) (xy 77.560939 -392.437837) (xy 77.605115 -392.46763)
			(xy 77.644714 -392.503281) (xy 77.678967 -392.544097) (xy 77.707205 -392.589282) (xy 77.72888 -392.637957)
			(xy 77.743569 -392.689176) (xy 77.750987 -392.74194) (xy 77.751432 -392.768582) (xy 77.750946 -392.795833)
			(xy 77.74319 -392.849781) (xy 77.727835 -392.902076) (xy 77.705193 -392.951653) (xy 77.675727 -392.997503)
			(xy 77.640036 -393.038694) (xy 77.598845 -393.074385) (xy 77.552995 -393.103851) (xy 77.503418 -393.126493)
			(xy 77.451123 -393.141848) (xy 77.397175 -393.149604) (xy 77.342673 -393.149604) (xy 77.288725 -393.141848)
			(xy 77.23643 -393.126493) (xy 77.186853 -393.103851) (xy 77.141003 -393.074385) (xy 77.099812 -393.038694)
			(xy 77.064121 -392.997503) (xy 77.034655 -392.951653) (xy 77.012013 -392.902076) (xy 76.996658 -392.849781)
			(xy 76.988902 -392.795833) (xy 76.988416 -392.768582) (xy 76.989686 -392.736324) (xy 76.990448 -392.726926)
			(xy 76.985368 -392.708638) (xy 76.937616 -392.646662) (xy 76.931538 -392.639502) (xy 76.915524 -392.629724)
			(xy 76.906374 -392.627612) (xy 76.90612 -392.627612) (xy 76.879958 -392.622548) (xy 76.829277 -392.606087)
			(xy 76.78138 -392.582731) (xy 76.737201 -392.552935) (xy 76.6976 -392.517279) (xy 76.663347 -392.476458)
			(xy 76.635111 -392.431267) (xy 76.61344 -392.382585) (xy 76.598756 -392.33136) (xy 76.591346 -392.27859)
			(xy 76.590906 -392.251946) (xy 73.673462 -392.251946) (xy 73.673462 -392.662156) (xy 73.673897 -392.67222)
			(xy 73.681633 -392.690804) (xy 73.688448 -392.698224) (xy 73.82637 -392.835892) (xy 73.833221 -392.843289)
			(xy 73.840963 -392.861887) (xy 73.841356 -392.87196) (xy 73.841356 -393.293346) (xy 79.962756 -393.293346)
			(xy 79.962756 -392.42873) (xy 79.963179 -392.403261) (xy 79.969983 -392.35278) (xy 79.983446 -392.303654)
			(xy 80.003329 -392.256758) (xy 80.029278 -392.212926) (xy 80.060831 -392.172938) (xy 80.078834 -392.154918)
			(xy 80.085438 -392.148568) (xy 80.093312 -392.131804) (xy 80.10017 -392.04646) (xy 80.09509 -392.02868)
			(xy 80.089502 -392.021314) (xy 80.074648 -392.000569) (xy 80.051014 -391.955353) (xy 80.034914 -391.906941)
			(xy 80.026762 -391.856578) (xy 80.026256 -391.831068) (xy 80.026256 -391.830814) (xy 80.026746 -391.805825)
			(xy 80.034565 -391.756462) (xy 80.050009 -391.70893) (xy 80.072699 -391.664398) (xy 80.102075 -391.623965)
			(xy 80.137415 -391.588625) (xy 80.177848 -391.559249) (xy 80.22238 -391.536559) (xy 80.269912 -391.521115)
			(xy 80.319275 -391.513296) (xy 80.369253 -391.513296) (xy 80.418616 -391.521115) (xy 80.466148 -391.536559)
			(xy 80.51068 -391.559249) (xy 80.551113 -391.588625) (xy 80.586453 -391.623965) (xy 80.615829 -391.664398)
			(xy 80.638519 -391.70893) (xy 80.653963 -391.756462) (xy 80.661782 -391.805825) (xy 80.662272 -391.830814)
			(xy 80.662272 -391.831068) (xy 80.661765 -391.856576) (xy 80.65359 -391.906935) (xy 80.637491 -391.955345)
			(xy 80.613881 -392.000571) (xy 80.599026 -392.021314) (xy 80.593438 -392.02868) (xy 80.588358 -392.04646)
			(xy 80.595216 -392.131804) (xy 80.60309 -392.148568) (xy 80.609694 -392.154918) (xy 80.627701 -392.172933)
			(xy 80.65924 -392.212929) (xy 80.685179 -392.256765) (xy 80.705057 -392.303661) (xy 80.718521 -392.352785)
			(xy 80.725331 -392.403263) (xy 80.725772 -392.42873) (xy 80.725772 -393.293346) (xy 81.162652 -393.293346)
			(xy 81.162652 -392.42873) (xy 81.163076 -392.403262) (xy 81.16988 -392.352781) (xy 81.183343 -392.303655)
			(xy 81.203225 -392.256758) (xy 81.229174 -392.212926) (xy 81.260727 -392.172938) (xy 81.27873 -392.154918)
			(xy 81.285588 -392.148568) (xy 81.293462 -392.131804) (xy 81.299558 -392.05535) (xy 81.299913 -392.046285)
			(xy 81.294967 -392.028843) (xy 81.289906 -392.021314) (xy 81.289652 -392.02106) (xy 81.274786 -392.000323)
			(xy 81.251163 -391.955102) (xy 81.235067 -391.906688) (xy 81.226914 -391.856324) (xy 81.226406 -391.830814)
			(xy 81.226896 -391.805825) (xy 81.234715 -391.756462) (xy 81.250159 -391.70893) (xy 81.272849 -391.664398)
			(xy 81.302225 -391.623965) (xy 81.337565 -391.588625) (xy 81.377998 -391.559249) (xy 81.42253 -391.536559)
			(xy 81.470062 -391.521115) (xy 81.519425 -391.513296) (xy 81.569403 -391.513296) (xy 81.618766 -391.521115)
			(xy 81.666298 -391.536559) (xy 81.71083 -391.559249) (xy 81.751263 -391.588625) (xy 81.786603 -391.623965)
			(xy 81.815979 -391.664398) (xy 81.838669 -391.70893) (xy 81.854113 -391.756462) (xy 81.861932 -391.805825)
			(xy 81.862422 -391.830814) (xy 81.861913 -391.856367) (xy 81.853725 -391.906813) (xy 81.837563 -391.955296)
			(xy 81.813844 -392.000564) (xy 81.798922 -392.021314) (xy 81.793334 -392.02868) (xy 81.788254 -392.04646)
			(xy 81.79435 -392.122914) (xy 81.795439 -392.131915) (xy 81.803116 -392.148323) (xy 81.809336 -392.154918)
			(xy 81.80959 -392.155172) (xy 81.827588 -392.173225) (xy 81.859151 -392.213253) (xy 81.885105 -392.257126)
			(xy 81.904988 -392.304063) (xy 81.918446 -392.35323) (xy 81.92524 -392.40375) (xy 81.925668 -392.429238)
			(xy 81.925668 -393.292838) (xy 82.362548 -393.292838) (xy 82.362548 -392.429238) (xy 82.362971 -392.403718)
			(xy 82.369761 -392.353131) (xy 82.383238 -392.303903) (xy 82.403162 -392.256912) (xy 82.429175 -392.212999)
			(xy 82.460814 -392.172948) (xy 82.47888 -392.154918) (xy 82.485484 -392.148568) (xy 82.493358 -392.131804)
			(xy 82.500216 -392.04646) (xy 82.495136 -392.02868) (xy 82.489548 -392.021314) (xy 82.4747 -392.000564)
			(xy 82.451063 -391.955351) (xy 82.434961 -391.90694) (xy 82.426808 -391.856577) (xy 82.426302 -391.831068)
			(xy 82.426302 -391.830814) (xy 82.426792 -391.805825) (xy 82.434611 -391.756462) (xy 82.450055 -391.70893)
			(xy 82.472745 -391.664398) (xy 82.502121 -391.623965) (xy 82.537461 -391.588625) (xy 82.577894 -391.559249)
			(xy 82.622426 -391.536559) (xy 82.669958 -391.521115) (xy 82.719321 -391.513296) (xy 82.769299 -391.513296)
			(xy 82.818662 -391.521115) (xy 82.866194 -391.536559) (xy 82.910726 -391.559249) (xy 82.951159 -391.588625)
			(xy 82.986499 -391.623965) (xy 83.015875 -391.664398) (xy 83.038565 -391.70893) (xy 83.054009 -391.756462)
			(xy 83.061828 -391.805825) (xy 83.062318 -391.830814) (xy 83.062318 -391.831068) (xy 83.061821 -391.856577)
			(xy 83.053645 -391.906936) (xy 83.037543 -391.955347) (xy 83.01393 -392.000572) (xy 82.999072 -392.021314)
			(xy 82.993484 -392.02868) (xy 82.988404 -392.04646) (xy 82.995262 -392.131804) (xy 83.003136 -392.148568)
			(xy 83.00974 -392.154918) (xy 83.027771 -392.172979) (xy 83.059403 -392.21303) (xy 83.085415 -392.256938)
			(xy 83.105343 -392.303922) (xy 83.118832 -392.353142) (xy 83.125642 -392.403721) (xy 83.126072 -392.429238)
			(xy 83.126072 -393.292838) (xy 83.562444 -393.292838) (xy 83.562444 -392.429238) (xy 83.562868 -392.403718)
			(xy 83.569658 -392.353132) (xy 83.583135 -392.303903) (xy 83.603058 -392.256912) (xy 83.629072 -392.212999)
			(xy 83.660711 -392.172948) (xy 83.678776 -392.154918) (xy 83.68538 -392.148568) (xy 83.693254 -392.131804)
			(xy 83.700112 -392.04646) (xy 83.695032 -392.02868) (xy 83.689444 -392.021314) (xy 83.674595 -392.000565)
			(xy 83.650959 -391.955352) (xy 83.634857 -391.90694) (xy 83.626704 -391.856577) (xy 83.626198 -391.831068)
			(xy 83.626198 -391.830814) (xy 83.626688 -391.805825) (xy 83.634507 -391.756462) (xy 83.649951 -391.70893)
			(xy 83.672641 -391.664398) (xy 83.702017 -391.623965) (xy 83.737357 -391.588625) (xy 83.77779 -391.559249)
			(xy 83.822322 -391.536559) (xy 83.869854 -391.521115) (xy 83.919217 -391.513296) (xy 83.969195 -391.513296)
			(xy 84.018558 -391.521115) (xy 84.06609 -391.536559) (xy 84.110622 -391.559249) (xy 84.151055 -391.588625)
			(xy 84.186395 -391.623965) (xy 84.215771 -391.664398) (xy 84.238461 -391.70893) (xy 84.253905 -391.756462)
			(xy 84.261724 -391.805825) (xy 84.262214 -391.830814) (xy 84.262214 -391.831068) (xy 84.261718 -391.856577)
			(xy 84.253541 -391.906936) (xy 84.23744 -391.955347) (xy 84.213826 -392.000572) (xy 84.198968 -392.021314)
			(xy 84.19338 -392.02868) (xy 84.1883 -392.04646) (xy 84.195158 -392.131804) (xy 84.203032 -392.148568)
			(xy 84.209636 -392.154918) (xy 84.227667 -392.17298) (xy 84.259298 -392.21303) (xy 84.28531 -392.256939)
			(xy 84.305239 -392.303922) (xy 84.318728 -392.353142) (xy 84.325538 -392.403721) (xy 84.325968 -392.429238)
			(xy 84.325968 -393.292838) (xy 84.325444 -393.321291) (xy 84.316996 -393.377566) (xy 84.300293 -393.431965)
			(xy 84.275704 -393.483284) (xy 84.243773 -393.530386) (xy 84.224876 -393.551664) (xy 84.218971 -393.558645)
			(xy 84.212073 -393.575564) (xy 84.211414 -393.584684) (xy 84.210398 -393.615418) (xy 84.210547 -393.624587)
			(xy 84.216525 -393.641907) (xy 84.222082 -393.6492) (xy 84.237453 -393.668531) (xy 84.263265 -393.710637)
			(xy 84.283058 -393.755885) (xy 84.296459 -393.80342) (xy 84.303214 -393.852344) (xy 84.303616 -393.877038)
			(xy 84.303114 -393.903934) (xy 84.295096 -393.957126) (xy 84.27924 -394.008529) (xy 84.255901 -394.056995)
			(xy 84.225598 -394.101441) (xy 84.18901 -394.140874) (xy 84.146953 -394.174413) (xy 84.100367 -394.201309)
			(xy 84.050293 -394.220962) (xy 83.997848 -394.232932) (xy 83.944206 -394.236952) (xy 83.890564 -394.232932)
			(xy 83.838119 -394.220962) (xy 83.788045 -394.201309) (xy 83.741459 -394.174413) (xy 83.699402 -394.140874)
			(xy 83.662814 -394.101441) (xy 83.632511 -394.056995) (xy 83.609172 -394.008529) (xy 83.593316 -393.957126)
			(xy 83.585298 -393.903934) (xy 83.584796 -393.877038) (xy 83.585237 -393.852349) (xy 83.592024 -393.803438)
			(xy 83.605434 -393.755914) (xy 83.625215 -393.71067) (xy 83.650997 -393.668555) (xy 83.66633 -393.6492)
			(xy 83.671859 -393.64189) (xy 83.677851 -393.624582) (xy 83.678014 -393.615418) (xy 83.676998 -393.584684)
			(xy 83.67636 -393.575558) (xy 83.669464 -393.558631) (xy 83.663536 -393.551664) (xy 83.644618 -393.5304)
			(xy 83.612655 -393.483311) (xy 83.588053 -393.431991) (xy 83.571359 -393.377582) (xy 83.562946 -393.321295)
			(xy 83.562444 -393.292838) (xy 83.126072 -393.292838) (xy 83.125506 -393.322001) (xy 83.116586 -393.379642)
			(xy 83.099003 -393.435257) (xy 83.073168 -393.487551) (xy 83.039682 -393.535308) (xy 83.0199 -393.556744)
			(xy 83.013744 -393.563829) (xy 83.006585 -393.581163) (xy 83.00593 -393.590526) (xy 83.004152 -393.659106)
			(xy 83.004285 -393.668364) (xy 83.010425 -393.685817) (xy 83.01609 -393.693142) (xy 83.016598 -393.69365)
			(xy 83.032947 -393.713267) (xy 83.060481 -393.756275) (xy 83.08164 -393.802751) (xy 83.095996 -393.851758)
			(xy 83.103259 -393.902305) (xy 83.10372 -393.927838) (xy 83.103218 -393.954734) (xy 83.0952 -394.007926)
			(xy 83.079344 -394.059329) (xy 83.056005 -394.107795) (xy 83.025702 -394.152241) (xy 82.989114 -394.191674)
			(xy 82.947057 -394.225213) (xy 82.900471 -394.252109) (xy 82.850397 -394.271762) (xy 82.797952 -394.283732)
			(xy 82.74431 -394.287752) (xy 82.690668 -394.283732) (xy 82.638223 -394.271762) (xy 82.588149 -394.252109)
			(xy 82.541563 -394.225213) (xy 82.499506 -394.191674) (xy 82.462918 -394.152241) (xy 82.432615 -394.107795)
			(xy 82.409276 -394.059329) (xy 82.39342 -394.007926) (xy 82.385402 -393.954734) (xy 82.3849 -393.927838)
			(xy 82.385389 -393.902271) (xy 82.392664 -393.851657) (xy 82.407058 -393.80259) (xy 82.428278 -393.756066)
			(xy 82.455894 -393.71303) (xy 82.472276 -393.693396) (xy 82.47253 -393.693142) (xy 82.478201 -393.685826)
			(xy 82.484306 -393.668363) (xy 82.484468 -393.659106) (xy 82.482436 -393.580874) (xy 82.475324 -393.563856)
			(xy 82.46872 -393.556744) (xy 82.448937 -393.535308) (xy 82.415445 -393.487555) (xy 82.389609 -393.435261)
			(xy 82.37203 -393.379645) (xy 82.363119 -393.322002) (xy 82.362548 -393.292838) (xy 81.925668 -393.292838)
			(xy 81.925668 -393.293346) (xy 81.925175 -393.321161) (xy 81.91707 -393.376198) (xy 81.901053 -393.429473)
			(xy 81.877464 -393.479855) (xy 81.846804 -393.526274) (xy 81.82864 -393.547346) (xy 81.822798 -393.55395)
			(xy 81.81594 -393.570714) (xy 81.813908 -393.645136) (xy 81.814024 -393.654041) (xy 81.819618 -393.670934)
			(xy 81.82483 -393.678156) (xy 81.825084 -393.67841) (xy 81.839807 -393.697548) (xy 81.864563 -393.739003)
			(xy 81.883542 -393.783402) (xy 81.8964 -393.829943) (xy 81.902906 -393.877788) (xy 81.903316 -393.90193)
			(xy 81.903316 -393.902438) (xy 81.902814 -393.929315) (xy 81.894802 -393.98247) (xy 81.878958 -394.033836)
			(xy 81.855634 -394.082268) (xy 81.825353 -394.126682) (xy 81.788791 -394.166087) (xy 81.746763 -394.199603)
			(xy 81.70021 -394.22648) (xy 81.650171 -394.246119) (xy 81.597764 -394.25808) (xy 81.54416 -394.262098)
			(xy 81.490556 -394.25808) (xy 81.438149 -394.246119) (xy 81.38811 -394.22648) (xy 81.341557 -394.199603)
			(xy 81.299529 -394.166087) (xy 81.262967 -394.126682) (xy 81.232686 -394.082268) (xy 81.209362 -394.033836)
			(xy 81.193518 -393.98247) (xy 81.185506 -393.929315) (xy 81.185004 -393.902438) (xy 81.185004 -393.90193)
			(xy 81.185413 -393.877787) (xy 81.191917 -393.829942) (xy 81.204773 -393.783399) (xy 81.223748 -393.738998)
			(xy 81.248501 -393.697539) (xy 81.263236 -393.67841) (xy 81.26349 -393.678156) (xy 81.268757 -393.670965)
			(xy 81.274345 -393.65405) (xy 81.274412 -393.645136) (xy 81.27238 -393.570714) (xy 81.265522 -393.55395)
			(xy 81.25968 -393.547346) (xy 81.241552 -393.526248) (xy 81.210907 -393.479827) (xy 81.187324 -393.42945)
			(xy 81.171302 -393.376184) (xy 81.16318 -393.321157) (xy 81.162652 -393.293346) (xy 80.725772 -393.293346)
			(xy 80.725278 -393.321161) (xy 80.717173 -393.376198) (xy 80.701156 -393.429473) (xy 80.677567 -393.479855)
			(xy 80.646908 -393.526274) (xy 80.628744 -393.547346) (xy 80.622902 -393.55395) (xy 80.616044 -393.570714)
			(xy 80.614012 -393.645136) (xy 80.614127 -393.654041) (xy 80.619722 -393.670934) (xy 80.624934 -393.678156)
			(xy 80.625188 -393.67841) (xy 80.639911 -393.697548) (xy 80.664668 -393.739003) (xy 80.683646 -393.783402)
			(xy 80.696504 -393.829943) (xy 80.70301 -393.877788) (xy 80.70342 -393.90193) (xy 80.70342 -393.902438)
			(xy 80.702918 -393.929315) (xy 80.694906 -393.98247) (xy 80.679062 -394.033836) (xy 80.655738 -394.082268)
			(xy 80.625457 -394.126682) (xy 80.588895 -394.166087) (xy 80.546867 -394.199603) (xy 80.500314 -394.22648)
			(xy 80.450275 -394.246119) (xy 80.397868 -394.25808) (xy 80.344264 -394.262098) (xy 80.29066 -394.25808)
			(xy 80.238253 -394.246119) (xy 80.188214 -394.22648) (xy 80.141661 -394.199603) (xy 80.099633 -394.166087)
			(xy 80.063071 -394.126682) (xy 80.03279 -394.082268) (xy 80.009466 -394.033836) (xy 79.993622 -393.98247)
			(xy 79.98561 -393.929315) (xy 79.985108 -393.902438) (xy 79.985108 -393.90193) (xy 79.985516 -393.877787)
			(xy 79.992021 -393.829942) (xy 80.004877 -393.783399) (xy 80.023852 -393.738997) (xy 80.048605 -393.697539)
			(xy 80.06334 -393.67841) (xy 80.063594 -393.678156) (xy 80.068861 -393.670966) (xy 80.074449 -393.65405)
			(xy 80.074516 -393.645136) (xy 80.072484 -393.570714) (xy 80.065626 -393.55395) (xy 80.059784 -393.547346)
			(xy 80.041656 -393.526247) (xy 80.011012 -393.479827) (xy 79.987429 -393.42945) (xy 79.971406 -393.376184)
			(xy 79.963284 -393.321157) (xy 79.962756 -393.293346) (xy 73.841356 -393.293346) (xy 73.841356 -393.484608)
			(xy 73.841864 -393.485116) (xy 73.841864 -393.51331) (xy 73.842291 -393.523378) (xy 73.850015 -393.541974)
			(xy 73.85685 -393.549378) (xy 74.27849 -393.971272) (xy 74.285326 -393.978674) (xy 74.293036 -393.997272)
			(xy 74.293476 -394.00734) (xy 74.293476 -394.352018) (xy 78.732886 -394.352018) (xy 78.736957 -394.296396)
			(xy 78.749083 -394.241959) (xy 78.769006 -394.189868) (xy 78.796302 -394.141233) (xy 78.830388 -394.09709)
			(xy 78.870537 -394.058381) (xy 78.915895 -394.02593) (xy 78.965495 -394.000429) (xy 79.018279 -393.982422)
			(xy 79.073122 -393.972292) (xy 79.128856 -393.970255) (xy 79.184293 -393.976355) (xy 79.23825 -393.990461)
			(xy 79.289579 -394.012273) (xy 79.337185 -394.041327) (xy 79.380053 -394.077002) (xy 79.41727 -394.118539)
			(xy 79.448043 -394.165052) (xy 79.471715 -394.215549) (xy 79.487783 -394.268956) (xy 79.495903 -394.324132)
			(xy 79.496412 -394.352018) (xy 79.495903 -394.379904) (xy 79.487783 -394.43508) (xy 79.471715 -394.488487)
			(xy 79.448043 -394.538984) (xy 79.41727 -394.585497) (xy 79.380053 -394.627034) (xy 79.337185 -394.662709)
			(xy 79.289579 -394.691763) (xy 79.23825 -394.713575) (xy 79.184293 -394.727681) (xy 79.128856 -394.733781)
			(xy 79.073122 -394.731744) (xy 79.018279 -394.721614) (xy 78.965495 -394.703607) (xy 78.915895 -394.678106)
			(xy 78.870537 -394.645655) (xy 78.830388 -394.606946) (xy 78.796302 -394.562803) (xy 78.769006 -394.514168)
			(xy 78.749083 -394.462077) (xy 78.736957 -394.40764) (xy 78.732886 -394.352018) (xy 74.293476 -394.352018)
			(xy 74.293476 -394.811504) (xy 74.293052 -394.821573) (xy 74.285333 -394.840175) (xy 74.27849 -394.847572)
			(xy 74.243438 -394.882624) (xy 74.236591 -394.890022) (xy 74.228859 -394.90862) (xy 74.228452 -394.918692)
			(xy 74.228452 -396.79245) (xy 74.228886 -396.802515) (xy 74.236619 -396.821101) (xy 74.243438 -396.828518)
			(xy 75.558396 -398.143476) (xy 75.565793 -398.150326) (xy 75.584391 -398.158065) (xy 75.594464 -398.158462)
		)
		(stroke
			(width 0)
			(type solid)
		)
		(fill yes)
		(layer "B.Cu")
		(net "P0V9_CPU1_RT1_2A")
	)
	(gr_poly
		(pts
			(xy 424.73499 -406.540462) (xy 424.74506 -406.54004) (xy 424.763664 -406.532324) (xy 424.771058 -406.525476)
			(xy 424.901614 -406.39492) (xy 424.908457 -406.387521) (xy 424.916176 -406.368922) (xy 424.9166 -406.358852)
			(xy 424.9166 -403.220174) (xy 424.916172 -403.210106) (xy 424.908451 -403.191508) (xy 424.901614 -403.184106)
			(xy 424.488102 -402.770848) (xy 424.471335 -402.753406) (xy 424.442903 -402.714264) (xy 424.420944 -402.671156)
			(xy 424.405999 -402.625143) (xy 424.398436 -402.577359) (xy 424.397932 -402.55317) (xy 424.397932 -402.197062)
			(xy 424.39745 -402.186314) (xy 424.388632 -402.166712) (xy 424.380914 -402.159216) (xy 424.316398 -402.101558)
			(xy 424.296078 -402.094954) (xy 424.285156 -402.096224) (xy 424.274649 -402.097303) (xy 424.253555 -402.098444)
			(xy 424.242992 -402.09851) (xy 424.215741 -402.098024) (xy 424.161794 -402.090266) (xy 424.1095 -402.07491)
			(xy 424.059923 -402.052269) (xy 424.014074 -402.022802) (xy 423.972884 -401.98711) (xy 423.937193 -401.94592)
			(xy 423.907728 -401.90007) (xy 423.885087 -401.850493) (xy 423.869732 -401.798198) (xy 423.861976 -401.744251)
			(xy 423.861976 -401.689749) (xy 423.869732 -401.635802) (xy 423.885087 -401.583507) (xy 423.907728 -401.53393)
			(xy 423.937193 -401.48808) (xy 423.972884 -401.44689) (xy 424.014074 -401.411198) (xy 424.059923 -401.381731)
			(xy 424.1095 -401.35909) (xy 424.161794 -401.343734) (xy 424.215741 -401.335976) (xy 424.242992 -401.335494)
			(xy 424.266482 -401.335902) (xy 424.313096 -401.34176) (xy 424.335956 -401.347178) (xy 424.344887 -401.349007)
			(xy 424.362987 -401.346937) (xy 424.371262 -401.343114) (xy 424.398948 -401.329144) (xy 424.406766 -401.324825)
			(xy 424.418981 -401.311808) (xy 424.422824 -401.303744) (xy 424.434934 -401.276902) (xy 424.467803 -401.22805)
			(xy 424.488102 -401.206716) (xy 425.009818 -400.685254) (xy 425.016666 -400.677857) (xy 425.024397 -400.659258)
			(xy 425.024804 -400.649186) (xy 425.024804 -399.518124) (xy 425.024367 -399.50806) (xy 425.016634 -399.489475)
			(xy 425.009818 -399.482056) (xy 424.612562 -399.085054) (xy 424.605164 -399.078208) (xy 424.586565 -399.070479)
			(xy 424.576494 -399.070068) (xy 423.75963 -399.070068) (xy 423.749207 -399.070573) (xy 423.730065 -399.078833)
			(xy 423.722546 -399.08607) (xy 423.671746 -399.140172) (xy 423.664996 -399.148223) (xy 423.658032 -399.168024)
			(xy 423.658284 -399.178526) (xy 423.659046 -399.200878) (xy 423.659046 -399.201132) (xy 423.658536 -399.227119)
			(xy 423.650406 -399.278454) (xy 423.634345 -399.327884) (xy 423.610749 -399.374194) (xy 423.580199 -399.416242)
			(xy 423.543448 -399.452993) (xy 423.5014 -399.483543) (xy 423.45509 -399.507139) (xy 423.40566 -399.5232)
			(xy 423.354325 -399.53133) (xy 423.302351 -399.53133) (xy 423.251016 -399.5232) (xy 423.201586 -399.507139)
			(xy 423.155276 -399.483543) (xy 423.113228 -399.452993) (xy 423.076477 -399.416242) (xy 423.045927 -399.374194)
			(xy 423.022331 -399.327884) (xy 423.00627 -399.278454) (xy 422.99814 -399.227119) (xy 422.99763 -399.201132)
			(xy 422.998189 -399.173561) (xy 423.007356 -399.119185) (xy 423.025423 -399.067086) (xy 423.05189 -399.018711)
			(xy 423.086021 -398.9754) (xy 423.12687 -398.938358) (xy 423.149776 -398.923002) (xy 423.157275 -398.917717)
			(xy 423.168211 -398.903004) (xy 423.171112 -398.8943) (xy 423.179748 -398.864074) (xy 423.181885 -398.855184)
			(xy 423.180438 -398.836969) (xy 423.176954 -398.828514) (xy 423.167173 -398.806493) (xy 423.153367 -398.760329)
			(xy 423.146394 -398.712652) (xy 423.145966 -398.68856) (xy 423.146381 -398.664787) (xy 423.153197 -398.617733)
			(xy 423.166683 -398.572141) (xy 423.18656 -398.52895) (xy 423.212419 -398.489052) (xy 423.227754 -398.470882)
			(xy 423.233432 -398.463759) (xy 423.239808 -398.446709) (xy 423.2402 -398.437608) (xy 423.2402 -398.406112)
			(xy 423.239822 -398.397009) (xy 423.233436 -398.379961) (xy 423.227754 -398.372838) (xy 423.212404 -398.354679)
			(xy 423.186536 -398.314783) (xy 423.166658 -398.271591) (xy 423.153179 -398.225993) (xy 423.14638 -398.178934)
			(xy 423.145966 -398.15516) (xy 423.146502 -398.127721) (xy 423.155553 -398.073595) (xy 423.173416 -398.021706)
			(xy 423.199602 -397.973479) (xy 423.233391 -397.930237) (xy 423.273856 -397.893167) (xy 423.319886 -397.863287)
			(xy 423.344848 -397.851884) (xy 423.355791 -397.846298) (xy 423.371168 -397.827187) (xy 423.374312 -397.815308)
			(xy 423.38625 -397.756888) (xy 423.374566 -397.745966) (xy 423.345356 -397.716502) (xy 423.337228 -397.712692)
			(xy 423.313143 -397.700889) (xy 423.268826 -397.67068) (xy 423.229964 -397.633717) (xy 423.197575 -397.590969)
			(xy 423.172507 -397.543555) (xy 423.155416 -397.492717) (xy 423.146752 -397.439788) (xy 423.14622 -397.412972)
			(xy 423.146777 -397.385352) (xy 423.155955 -397.330879) (xy 423.174053 -397.278687) (xy 423.200566 -397.230225)
			(xy 423.23476 -397.186839) (xy 423.275683 -397.149734) (xy 423.29862 -397.134334) (xy 423.31005 -397.127222)
			(xy 423.322496 -397.103346) (xy 423.31894 -396.9893) (xy 423.305224 -396.966694) (xy 423.293286 -396.96009)
			(xy 423.271592 -396.947458) (xy 423.231948 -396.916663) (xy 423.197412 -396.880232) (xy 423.168777 -396.839)
			(xy 423.146702 -396.793915) (xy 423.131692 -396.746012) (xy 423.124093 -396.696392) (xy 423.123614 -396.671292)
			(xy 423.124136 -396.644475) (xy 423.132795 -396.591546) (xy 423.149885 -396.540709) (xy 423.174957 -396.493297)
			(xy 423.207354 -396.450554) (xy 423.246225 -396.413601) (xy 423.290552 -396.383409) (xy 423.314622 -396.371572)
			(xy 423.32275 -396.367762) (xy 423.621962 -396.068296) (xy 423.639366 -396.051574) (xy 423.67842 -396.023219)
			(xy 423.721428 -396.00132) (xy 423.767332 -395.986416) (xy 423.815001 -395.978873) (xy 423.839132 -395.97838)
			(xy 423.86758 -395.97838) (xy 423.877602 -395.977963) (xy 423.896123 -395.970296) (xy 423.910296 -395.956123)
			(xy 423.917963 -395.937602) (xy 423.91838 -395.92758) (xy 423.91838 -395.054582) (xy 423.917939 -395.044792)
			(xy 423.910636 -395.026626) (xy 423.904156 -395.019276) (xy 423.883074 -394.997432) (xy 423.876424 -394.991149)
			(xy 423.859892 -394.983341) (xy 423.850816 -394.982192) (xy 423.822538 -394.979348) (xy 423.767214 -394.96635)
			(xy 423.71443 -394.945289) (xy 423.665355 -394.916629) (xy 423.621074 -394.881006) (xy 423.582569 -394.839208)
			(xy 423.550691 -394.79216) (xy 423.526145 -394.740904) (xy 423.509476 -394.686572) (xy 423.501051 -394.630369)
			(xy 423.50055 -394.601954) (xy 423.501043 -394.574243) (xy 423.509062 -394.519405) (xy 423.524938 -394.466307)
			(xy 423.548337 -394.416068) (xy 423.578766 -394.369747) (xy 423.596816 -394.348716) (xy 423.60342 -394.341096)
			(xy 423.610024 -394.322554) (xy 423.605706 -394.231622) (xy 423.597324 -394.213588) (xy 423.590212 -394.206984)
			(xy 423.569742 -394.187155) (xy 423.534328 -394.142507) (xy 423.505951 -394.093086) (xy 423.485241 -394.039995)
			(xy 423.472659 -393.984413) (xy 423.47007 -393.956032) (xy 423.47007 -393.955524) (xy 423.469001 -393.946367)
			(xy 423.461189 -393.929686) (xy 423.45483 -393.923012) (xy 423.399712 -393.869418) (xy 423.382694 -393.862052)
			(xy 423.373296 -393.861798) (xy 423.348075 -393.860219) (xy 423.298513 -393.85036) (xy 423.251029 -393.833075)
			(xy 423.206729 -393.808765) (xy 423.166644 -393.777996) (xy 423.131708 -393.741486) (xy 423.102735 -393.700085)
			(xy 423.080399 -393.654757) (xy 423.065221 -393.606558) (xy 423.057555 -393.55661) (xy 423.057066 -393.531344)
			(xy 423.057066 -393.53109) (xy 423.05751 -393.506217) (xy 423.064955 -393.457032) (xy 423.079692 -393.409519)
			(xy 423.101386 -393.364754) (xy 423.129547 -393.323747) (xy 423.14622 -393.305284) (xy 423.15257 -393.298426)
			(xy 423.159682 -393.281408) (xy 423.161968 -393.195048) (xy 423.155872 -393.177522) (xy 423.149776 -393.17041)
			(xy 423.135032 -393.152406) (xy 423.110211 -393.113043) (xy 423.091153 -393.07059) (xy 423.078232 -393.025884)
			(xy 423.071704 -392.979809) (xy 423.07129 -392.956542) (xy 423.07184 -392.928964) (xy 423.080991 -392.874574)
			(xy 423.099047 -392.822457) (xy 423.125507 -392.774063) (xy 423.142156 -392.752072) (xy 423.147355 -392.744856)
			(xy 423.152828 -392.727945) (xy 423.152824 -392.719052) (xy 423.152062 -392.68908) (xy 423.151306 -392.679487)
			(xy 423.14359 -392.661875) (xy 423.137076 -392.65479) (xy 422.636696 -392.15441) (xy 422.629298 -392.147563)
			(xy 422.6107 -392.139829) (xy 422.600628 -392.139424) (xy 422.47947 -392.139424) (xy 422.469402 -392.138996)
			(xy 422.450803 -392.131277) (xy 422.443402 -392.124438) (xy 422.110662 -391.791698) (xy 422.103809 -391.784302)
			(xy 422.096065 -391.765704) (xy 422.095676 -391.75563) (xy 422.095676 -391.001504) (xy 422.096098 -390.991433)
			(xy 422.103808 -390.972825) (xy 422.110662 -390.965436) (xy 422.2242 -390.851898) (xy 422.231046 -390.844499)
			(xy 422.23878 -390.825901) (xy 422.239186 -390.81583) (xy 422.239186 -390.262872) (xy 422.238757 -390.252804)
			(xy 422.231034 -390.234209) (xy 422.2242 -390.226804) (xy 422.187878 -390.190736) (xy 422.181033 -390.183338)
			(xy 422.17331 -390.164739) (xy 422.172892 -390.154668) (xy 422.172892 -387.999732) (xy 422.172456 -387.989667)
			(xy 422.164724 -387.971082) (xy 422.157906 -387.963664) (xy 421.963596 -387.769354) (xy 421.9562 -387.762502)
			(xy 421.937601 -387.754761) (xy 421.927528 -387.754368) (xy 416.280854 -387.754368) (xy 416.27082 -387.754804)
			(xy 416.25224 -387.762373) (xy 416.244786 -387.7691) (xy 416.145472 -387.868414) (xy 416.13862 -387.87581)
			(xy 416.130879 -387.894409) (xy 416.130486 -387.904482) (xy 416.130486 -391.001758) (xy 416.130052 -391.011823)
			(xy 416.122321 -391.030411) (xy 416.1155 -391.037826) (xy 415.892409 -391.260917) (xy 416.31413 -391.260917)
			(xy 416.31413 -391.208943) (xy 416.32226 -391.157608) (xy 416.338321 -391.108178) (xy 416.361917 -391.061868)
			(xy 416.392467 -391.01982) (xy 416.429218 -390.983069) (xy 416.471266 -390.952519) (xy 416.517576 -390.928923)
			(xy 416.567006 -390.912862) (xy 416.618341 -390.904732) (xy 416.670315 -390.904732) (xy 416.72165 -390.912862)
			(xy 416.77108 -390.928923) (xy 416.81739 -390.952519) (xy 416.859438 -390.983069) (xy 416.896189 -391.01982)
			(xy 416.926739 -391.061868) (xy 416.950335 -391.108178) (xy 416.966396 -391.157608) (xy 416.974526 -391.208943)
			(xy 416.975036 -391.23493) (xy 416.974526 -391.260917) (xy 417.514026 -391.260917) (xy 417.514026 -391.208943)
			(xy 417.522156 -391.157608) (xy 417.538217 -391.108178) (xy 417.561813 -391.061868) (xy 417.592363 -391.01982)
			(xy 417.629114 -390.983069) (xy 417.671162 -390.952519) (xy 417.717472 -390.928923) (xy 417.766902 -390.912862)
			(xy 417.818237 -390.904732) (xy 417.870211 -390.904732) (xy 417.921546 -390.912862) (xy 417.970976 -390.928923)
			(xy 418.017286 -390.952519) (xy 418.059334 -390.983069) (xy 418.096085 -391.01982) (xy 418.126635 -391.061868)
			(xy 418.150231 -391.108178) (xy 418.166292 -391.157608) (xy 418.174422 -391.208943) (xy 418.174932 -391.23493)
			(xy 418.174422 -391.260917) (xy 418.713922 -391.260917) (xy 418.713922 -391.208943) (xy 418.722052 -391.157608)
			(xy 418.738113 -391.108178) (xy 418.761709 -391.061868) (xy 418.792259 -391.01982) (xy 418.82901 -390.983069)
			(xy 418.871058 -390.952519) (xy 418.917368 -390.928923) (xy 418.966798 -390.912862) (xy 419.018133 -390.904732)
			(xy 419.070107 -390.904732) (xy 419.121442 -390.912862) (xy 419.170872 -390.928923) (xy 419.217182 -390.952519)
			(xy 419.25923 -390.983069) (xy 419.295981 -391.01982) (xy 419.326531 -391.061868) (xy 419.350127 -391.108178)
			(xy 419.366188 -391.157608) (xy 419.374318 -391.208943) (xy 419.374828 -391.23493) (xy 419.374318 -391.260917)
			(xy 419.914072 -391.260917) (xy 419.914072 -391.208943) (xy 419.922202 -391.157608) (xy 419.938263 -391.108178)
			(xy 419.961859 -391.061868) (xy 419.992409 -391.01982) (xy 420.02916 -390.983069) (xy 420.071208 -390.952519)
			(xy 420.117518 -390.928923) (xy 420.166948 -390.912862) (xy 420.218283 -390.904732) (xy 420.270257 -390.904732)
			(xy 420.321592 -390.912862) (xy 420.371022 -390.928923) (xy 420.417332 -390.952519) (xy 420.45938 -390.983069)
			(xy 420.496131 -391.01982) (xy 420.526681 -391.061868) (xy 420.550277 -391.108178) (xy 420.566338 -391.157608)
			(xy 420.574468 -391.208943) (xy 420.574978 -391.23493) (xy 420.574468 -391.260917) (xy 421.113968 -391.260917)
			(xy 421.113968 -391.208943) (xy 421.122098 -391.157608) (xy 421.138159 -391.108178) (xy 421.161755 -391.061868)
			(xy 421.192305 -391.01982) (xy 421.229056 -390.983069) (xy 421.271104 -390.952519) (xy 421.317414 -390.928923)
			(xy 421.366844 -390.912862) (xy 421.418179 -390.904732) (xy 421.470153 -390.904732) (xy 421.521488 -390.912862)
			(xy 421.570918 -390.928923) (xy 421.617228 -390.952519) (xy 421.659276 -390.983069) (xy 421.696027 -391.01982)
			(xy 421.726577 -391.061868) (xy 421.750173 -391.108178) (xy 421.766234 -391.157608) (xy 421.774364 -391.208943)
			(xy 421.774874 -391.23493) (xy 421.774364 -391.260917) (xy 421.766234 -391.312252) (xy 421.750173 -391.361682)
			(xy 421.726577 -391.407992) (xy 421.696027 -391.45004) (xy 421.659276 -391.486791) (xy 421.617228 -391.517341)
			(xy 421.570918 -391.540937) (xy 421.521488 -391.556998) (xy 421.470153 -391.565128) (xy 421.418179 -391.565128)
			(xy 421.366844 -391.556998) (xy 421.317414 -391.540937) (xy 421.271104 -391.517341) (xy 421.229056 -391.486791)
			(xy 421.192305 -391.45004) (xy 421.161755 -391.407992) (xy 421.138159 -391.361682) (xy 421.122098 -391.312252)
			(xy 421.113968 -391.260917) (xy 420.574468 -391.260917) (xy 420.566338 -391.312252) (xy 420.550277 -391.361682)
			(xy 420.526681 -391.407992) (xy 420.496131 -391.45004) (xy 420.45938 -391.486791) (xy 420.417332 -391.517341)
			(xy 420.371022 -391.540937) (xy 420.321592 -391.556998) (xy 420.270257 -391.565128) (xy 420.218283 -391.565128)
			(xy 420.166948 -391.556998) (xy 420.117518 -391.540937) (xy 420.071208 -391.517341) (xy 420.02916 -391.486791)
			(xy 419.992409 -391.45004) (xy 419.961859 -391.407992) (xy 419.938263 -391.361682) (xy 419.922202 -391.312252)
			(xy 419.914072 -391.260917) (xy 419.374318 -391.260917) (xy 419.366188 -391.312252) (xy 419.350127 -391.361682)
			(xy 419.326531 -391.407992) (xy 419.295981 -391.45004) (xy 419.25923 -391.486791) (xy 419.217182 -391.517341)
			(xy 419.170872 -391.540937) (xy 419.121442 -391.556998) (xy 419.070107 -391.565128) (xy 419.018133 -391.565128)
			(xy 418.966798 -391.556998) (xy 418.917368 -391.540937) (xy 418.871058 -391.517341) (xy 418.82901 -391.486791)
			(xy 418.792259 -391.45004) (xy 418.761709 -391.407992) (xy 418.738113 -391.361682) (xy 418.722052 -391.312252)
			(xy 418.713922 -391.260917) (xy 418.174422 -391.260917) (xy 418.166292 -391.312252) (xy 418.150231 -391.361682)
			(xy 418.126635 -391.407992) (xy 418.096085 -391.45004) (xy 418.059334 -391.486791) (xy 418.017286 -391.517341)
			(xy 417.970976 -391.540937) (xy 417.921546 -391.556998) (xy 417.870211 -391.565128) (xy 417.818237 -391.565128)
			(xy 417.766902 -391.556998) (xy 417.717472 -391.540937) (xy 417.671162 -391.517341) (xy 417.629114 -391.486791)
			(xy 417.592363 -391.45004) (xy 417.561813 -391.407992) (xy 417.538217 -391.361682) (xy 417.522156 -391.312252)
			(xy 417.514026 -391.260917) (xy 416.974526 -391.260917) (xy 416.966396 -391.312252) (xy 416.950335 -391.361682)
			(xy 416.926739 -391.407992) (xy 416.896189 -391.45004) (xy 416.859438 -391.486791) (xy 416.81739 -391.517341)
			(xy 416.77108 -391.540937) (xy 416.72165 -391.556998) (xy 416.670315 -391.565128) (xy 416.618341 -391.565128)
			(xy 416.567006 -391.556998) (xy 416.517576 -391.540937) (xy 416.471266 -391.517341) (xy 416.429218 -391.486791)
			(xy 416.392467 -391.45004) (xy 416.361917 -391.407992) (xy 416.338321 -391.361682) (xy 416.32226 -391.312252)
			(xy 416.31413 -391.260917) (xy 415.892409 -391.260917) (xy 415.571432 -391.581894) (xy 415.56403 -391.58873)
			(xy 415.545432 -391.596441) (xy 415.535364 -391.59688) (xy 409.285948 -391.59688) (xy 409.275882 -391.596447)
			(xy 409.257294 -391.588717) (xy 409.24988 -391.581894) (xy 409.239466 -391.57148) (xy 409.239466 -391.56894)
			(xy 409.099512 -391.428986) (xy 409.092667 -391.421587) (xy 409.084935 -391.402989) (xy 409.084526 -391.392918)
			(xy 409.084526 -387.861302) (xy 409.084104 -387.851231) (xy 409.076393 -387.832624) (xy 409.06954 -387.825234)
			(xy 409.013406 -387.7691) (xy 409.005982 -387.762321) (xy 408.987385 -387.754726) (xy 408.977338 -387.754368)
			(xy 401.825968 -387.754368) (xy 401.8159 -387.754796) (xy 401.797301 -387.762515) (xy 401.7899 -387.769354)
			(xy 401.589494 -387.96976) (xy 401.582658 -387.977162) (xy 401.574946 -387.99576) (xy 401.574508 -388.005828)
			(xy 401.574508 -389.153908) (xy 401.574084 -389.163978) (xy 401.566368 -389.182581) (xy 401.559522 -389.189976)
			(xy 401.537932 -389.211312) (xy 401.531084 -389.21871) (xy 401.523349 -389.237308) (xy 401.522946 -389.24738)
			(xy 401.522946 -390.775698) (xy 401.515326 -390.79424) (xy 401.51177 -390.797796) (xy 401.552664 -390.914382)
			(xy 401.556198 -390.923284) (xy 401.568685 -390.937789) (xy 401.585614 -390.946717) (xy 401.595082 -390.948164)
			(xy 401.620377 -390.951438) (xy 401.669609 -390.964764) (xy 401.716212 -390.98549) (xy 401.759081 -391.013125)
			(xy 401.77847 -391.029698) (xy 401.785074 -391.03554) (xy 401.801076 -391.042144) (xy 401.874228 -391.045192)
			(xy 401.882856 -391.04519) (xy 401.899334 -391.040114) (xy 401.906486 -391.035286) (xy 401.927195 -391.02053)
			(xy 401.972321 -390.997095) (xy 402.020599 -390.981134) (xy 402.0708 -390.973053) (xy 402.096224 -390.972548)
			(xy 402.121215 -390.97304) (xy 402.170582 -390.980863) (xy 402.218118 -390.996311) (xy 402.262652 -391.019005)
			(xy 402.303088 -391.048386) (xy 402.338429 -391.083731) (xy 402.367807 -391.124169) (xy 402.390498 -391.168704)
			(xy 402.405943 -391.216241) (xy 402.412861 -391.259919) (xy 403.126684 -391.259919) (xy 403.126684 -391.209941)
			(xy 403.134503 -391.160578) (xy 403.149947 -391.113046) (xy 403.172637 -391.068514) (xy 403.202013 -391.028081)
			(xy 403.237353 -390.992741) (xy 403.277786 -390.963365) (xy 403.322318 -390.940675) (xy 403.36985 -390.925231)
			(xy 403.419213 -390.917412) (xy 403.469191 -390.917412) (xy 403.518554 -390.925231) (xy 403.566086 -390.940675)
			(xy 403.610618 -390.963365) (xy 403.651051 -390.992741) (xy 403.686391 -391.028081) (xy 403.715767 -391.068514)
			(xy 403.738457 -391.113046) (xy 403.753901 -391.160578) (xy 403.76172 -391.209941) (xy 403.76221 -391.23493)
			(xy 403.76172 -391.259919) (xy 403.761562 -391.260917) (xy 404.314154 -391.260917) (xy 404.314154 -391.208943)
			(xy 404.322284 -391.157608) (xy 404.338345 -391.108178) (xy 404.361941 -391.061868) (xy 404.392491 -391.01982)
			(xy 404.429242 -390.983069) (xy 404.47129 -390.952519) (xy 404.5176 -390.928923) (xy 404.56703 -390.912862)
			(xy 404.618365 -390.904732) (xy 404.670339 -390.904732) (xy 404.721674 -390.912862) (xy 404.771104 -390.928923)
			(xy 404.817414 -390.952519) (xy 404.859462 -390.983069) (xy 404.896213 -391.01982) (xy 404.926763 -391.061868)
			(xy 404.950359 -391.108178) (xy 404.96642 -391.157608) (xy 404.97455 -391.208943) (xy 404.97506 -391.23493)
			(xy 404.97455 -391.260917) (xy 405.51405 -391.260917) (xy 405.51405 -391.208943) (xy 405.52218 -391.157608)
			(xy 405.538241 -391.108178) (xy 405.561837 -391.061868) (xy 405.592387 -391.01982) (xy 405.629138 -390.983069)
			(xy 405.671186 -390.952519) (xy 405.717496 -390.928923) (xy 405.766926 -390.912862) (xy 405.818261 -390.904732)
			(xy 405.870235 -390.904732) (xy 405.92157 -390.912862) (xy 405.971 -390.928923) (xy 406.01731 -390.952519)
			(xy 406.059358 -390.983069) (xy 406.096109 -391.01982) (xy 406.126659 -391.061868) (xy 406.150255 -391.108178)
			(xy 406.166316 -391.157608) (xy 406.174446 -391.208943) (xy 406.174956 -391.23493) (xy 406.174446 -391.260917)
			(xy 406.713946 -391.260917) (xy 406.713946 -391.208943) (xy 406.722076 -391.157608) (xy 406.738137 -391.108178)
			(xy 406.761733 -391.061868) (xy 406.792283 -391.01982) (xy 406.829034 -390.983069) (xy 406.871082 -390.952519)
			(xy 406.917392 -390.928923) (xy 406.966822 -390.912862) (xy 407.018157 -390.904732) (xy 407.070131 -390.904732)
			(xy 407.121466 -390.912862) (xy 407.170896 -390.928923) (xy 407.217206 -390.952519) (xy 407.259254 -390.983069)
			(xy 407.296005 -391.01982) (xy 407.326555 -391.061868) (xy 407.350151 -391.108178) (xy 407.366212 -391.157608)
			(xy 407.374342 -391.208943) (xy 407.374852 -391.23493) (xy 407.374342 -391.260917) (xy 407.914096 -391.260917)
			(xy 407.914096 -391.208943) (xy 407.922226 -391.157608) (xy 407.938287 -391.108178) (xy 407.961883 -391.061868)
			(xy 407.992433 -391.01982) (xy 408.029184 -390.983069) (xy 408.071232 -390.952519) (xy 408.117542 -390.928923)
			(xy 408.166972 -390.912862) (xy 408.218307 -390.904732) (xy 408.270281 -390.904732) (xy 408.321616 -390.912862)
			(xy 408.371046 -390.928923) (xy 408.417356 -390.952519) (xy 408.459404 -390.983069) (xy 408.496155 -391.01982)
			(xy 408.526705 -391.061868) (xy 408.550301 -391.108178) (xy 408.566362 -391.157608) (xy 408.574492 -391.208943)
			(xy 408.575002 -391.23493) (xy 408.574492 -391.260917) (xy 408.566362 -391.312252) (xy 408.550301 -391.361682)
			(xy 408.526705 -391.407992) (xy 408.496155 -391.45004) (xy 408.459404 -391.486791) (xy 408.417356 -391.517341)
			(xy 408.371046 -391.540937) (xy 408.321616 -391.556998) (xy 408.270281 -391.565128) (xy 408.218307 -391.565128)
			(xy 408.166972 -391.556998) (xy 408.117542 -391.540937) (xy 408.071232 -391.517341) (xy 408.029184 -391.486791)
			(xy 407.992433 -391.45004) (xy 407.961883 -391.407992) (xy 407.938287 -391.361682) (xy 407.922226 -391.312252)
			(xy 407.914096 -391.260917) (xy 407.374342 -391.260917) (xy 407.366212 -391.312252) (xy 407.350151 -391.361682)
			(xy 407.326555 -391.407992) (xy 407.296005 -391.45004) (xy 407.259254 -391.486791) (xy 407.217206 -391.517341)
			(xy 407.170896 -391.540937) (xy 407.121466 -391.556998) (xy 407.070131 -391.565128) (xy 407.018157 -391.565128)
			(xy 406.966822 -391.556998) (xy 406.917392 -391.540937) (xy 406.871082 -391.517341) (xy 406.829034 -391.486791)
			(xy 406.792283 -391.45004) (xy 406.761733 -391.407992) (xy 406.738137 -391.361682) (xy 406.722076 -391.312252)
			(xy 406.713946 -391.260917) (xy 406.174446 -391.260917) (xy 406.166316 -391.312252) (xy 406.150255 -391.361682)
			(xy 406.126659 -391.407992) (xy 406.096109 -391.45004) (xy 406.059358 -391.486791) (xy 406.01731 -391.517341)
			(xy 405.971 -391.540937) (xy 405.92157 -391.556998) (xy 405.870235 -391.565128) (xy 405.818261 -391.565128)
			(xy 405.766926 -391.556998) (xy 405.717496 -391.540937) (xy 405.671186 -391.517341) (xy 405.629138 -391.486791)
			(xy 405.592387 -391.45004) (xy 405.561837 -391.407992) (xy 405.538241 -391.361682) (xy 405.52218 -391.312252)
			(xy 405.51405 -391.260917) (xy 404.97455 -391.260917) (xy 404.96642 -391.312252) (xy 404.950359 -391.361682)
			(xy 404.926763 -391.407992) (xy 404.896213 -391.45004) (xy 404.859462 -391.486791) (xy 404.817414 -391.517341)
			(xy 404.771104 -391.540937) (xy 404.721674 -391.556998) (xy 404.670339 -391.565128) (xy 404.618365 -391.565128)
			(xy 404.56703 -391.556998) (xy 404.5176 -391.540937) (xy 404.47129 -391.517341) (xy 404.429242 -391.486791)
			(xy 404.392491 -391.45004) (xy 404.361941 -391.407992) (xy 404.338345 -391.361682) (xy 404.322284 -391.312252)
			(xy 404.314154 -391.260917) (xy 403.761562 -391.260917) (xy 403.753901 -391.309282) (xy 403.738457 -391.356814)
			(xy 403.715767 -391.401346) (xy 403.686391 -391.441779) (xy 403.651051 -391.477119) (xy 403.610618 -391.506495)
			(xy 403.566086 -391.529185) (xy 403.518554 -391.544629) (xy 403.469191 -391.552448) (xy 403.419213 -391.552448)
			(xy 403.36985 -391.544629) (xy 403.322318 -391.529185) (xy 403.277786 -391.506495) (xy 403.237353 -391.477119)
			(xy 403.202013 -391.441779) (xy 403.172637 -391.401346) (xy 403.149947 -391.356814) (xy 403.134503 -391.309282)
			(xy 403.126684 -391.259919) (xy 402.412861 -391.259919) (xy 402.413762 -391.265609) (xy 402.413762 -391.315591)
			(xy 402.405943 -391.364959) (xy 402.390498 -391.412496) (xy 402.367807 -391.457031) (xy 402.338429 -391.497469)
			(xy 402.303088 -391.532814) (xy 402.262652 -391.562195) (xy 402.218118 -391.584889) (xy 402.170582 -391.600337)
			(xy 402.121215 -391.60816) (xy 402.096224 -391.608564) (xy 402.09597 -391.608564) (xy 402.068562 -391.607958)
			(xy 402.014566 -391.598511) (xy 401.96298 -391.57997) (xy 401.915325 -391.55288) (xy 401.893786 -391.53592)
			(xy 401.886928 -391.530332) (xy 401.870418 -391.524236) (xy 401.79752 -391.523728) (xy 401.788939 -391.52402)
			(xy 401.772714 -391.529601) (xy 401.76577 -391.53465) (xy 401.765516 -391.534904) (xy 401.743355 -391.551929)
			(xy 401.694504 -391.579055) (xy 401.641784 -391.597573) (xy 401.586699 -391.606954) (xy 401.55876 -391.607548)
			(xy 401.53556 -391.607161) (xy 401.489615 -391.600687) (xy 401.445025 -391.587856) (xy 401.402665 -391.568921)
			(xy 401.363366 -391.544253) (xy 401.3454 -391.52957) (xy 401.338073 -391.523913) (xy 401.320619 -391.51779)
			(xy 401.311364 -391.517632) (xy 401.244562 -391.518902) (xy 401.235289 -391.519546) (xy 401.2181 -391.526579)
			(xy 401.211034 -391.532618) (xy 401.194105 -391.547665) (xy 401.156885 -391.573471) (xy 401.116495 -391.593965)
			(xy 401.09521 -391.601706) (xy 401.094956 -391.601706) (xy 401.085201 -391.605649) (xy 401.069785 -391.619933)
			(xy 401.061395 -391.639203) (xy 401.06092 -391.649712) (xy 401.06092 -392.03376) (xy 401.061355 -392.043825)
			(xy 401.069087 -392.062412) (xy 401.075906 -392.069828) (xy 401.246594 -392.240262) (xy 401.263366 -392.257702)
			(xy 401.29181 -392.296842) (xy 401.313782 -392.339949) (xy 401.328741 -392.385962) (xy 401.336318 -392.433748)
			(xy 401.336764 -392.45794) (xy 401.336764 -392.61796) (xy 401.339812 -392.626342) (xy 401.349026 -392.653557)
			(xy 401.358982 -392.710139) (xy 401.359624 -392.738864) (xy 401.359624 -392.739372) (xy 401.359173 -392.764219)
			(xy 401.351729 -392.813352) (xy 401.337021 -392.86082) (xy 401.315378 -392.905553) (xy 401.287288 -392.946547)
			(xy 401.253382 -392.982877) (xy 401.214424 -393.013728) (xy 401.195226 -393.024711) (xy 402.772608 -393.024711)
			(xy 402.772608 -392.974733) (xy 402.780427 -392.92537) (xy 402.795871 -392.877838) (xy 402.818561 -392.833306)
			(xy 402.847937 -392.792873) (xy 402.883277 -392.757533) (xy 402.92371 -392.728157) (xy 402.968242 -392.705467)
			(xy 403.015774 -392.690023) (xy 403.065137 -392.682204) (xy 403.115115 -392.682204) (xy 403.164478 -392.690023)
			(xy 403.21201 -392.705467) (xy 403.256542 -392.728157) (xy 403.296975 -392.757533) (xy 403.332315 -392.792873)
			(xy 403.361691 -392.833306) (xy 403.384381 -392.877838) (xy 403.399825 -392.92537) (xy 403.407644 -392.974733)
			(xy 403.408134 -392.999722) (xy 403.407644 -393.024711) (xy 403.407486 -393.025709) (xy 403.959824 -393.025709)
			(xy 403.959824 -392.973735) (xy 403.967954 -392.9224) (xy 403.984015 -392.87297) (xy 404.007611 -392.82666)
			(xy 404.038161 -392.784612) (xy 404.074912 -392.747861) (xy 404.11696 -392.717311) (xy 404.16327 -392.693715)
			(xy 404.2127 -392.677654) (xy 404.264035 -392.669524) (xy 404.316009 -392.669524) (xy 404.367344 -392.677654)
			(xy 404.416774 -392.693715) (xy 404.463084 -392.717311) (xy 404.505132 -392.747861) (xy 404.541883 -392.784612)
			(xy 404.572433 -392.82666) (xy 404.596029 -392.87297) (xy 404.61209 -392.9224) (xy 404.62022 -392.973735)
			(xy 404.62073 -392.999722) (xy 404.62022 -393.025709) (xy 405.159974 -393.025709) (xy 405.159974 -392.973735)
			(xy 405.168104 -392.9224) (xy 405.184165 -392.87297) (xy 405.207761 -392.82666) (xy 405.238311 -392.784612)
			(xy 405.275062 -392.747861) (xy 405.31711 -392.717311) (xy 405.36342 -392.693715) (xy 405.41285 -392.677654)
			(xy 405.464185 -392.669524) (xy 405.516159 -392.669524) (xy 405.567494 -392.677654) (xy 405.616924 -392.693715)
			(xy 405.663234 -392.717311) (xy 405.705282 -392.747861) (xy 405.742033 -392.784612) (xy 405.772583 -392.82666)
			(xy 405.796179 -392.87297) (xy 405.81224 -392.9224) (xy 405.82037 -392.973735) (xy 405.82088 -392.999722)
			(xy 405.82037 -393.025709) (xy 406.35987 -393.025709) (xy 406.35987 -392.973735) (xy 406.368 -392.9224)
			(xy 406.384061 -392.87297) (xy 406.407657 -392.82666) (xy 406.438207 -392.784612) (xy 406.474958 -392.747861)
			(xy 406.517006 -392.717311) (xy 406.563316 -392.693715) (xy 406.612746 -392.677654) (xy 406.664081 -392.669524)
			(xy 406.716055 -392.669524) (xy 406.76739 -392.677654) (xy 406.81682 -392.693715) (xy 406.86313 -392.717311)
			(xy 406.905178 -392.747861) (xy 406.941929 -392.784612) (xy 406.972479 -392.82666) (xy 406.996075 -392.87297)
			(xy 407.012136 -392.9224) (xy 407.020266 -392.973735) (xy 407.020776 -392.999722) (xy 407.020266 -393.025709)
			(xy 407.56002 -393.025709) (xy 407.56002 -392.973735) (xy 407.56815 -392.9224) (xy 407.584211 -392.87297)
			(xy 407.607807 -392.82666) (xy 407.638357 -392.784612) (xy 407.675108 -392.747861) (xy 407.717156 -392.717311)
			(xy 407.763466 -392.693715) (xy 407.812896 -392.677654) (xy 407.864231 -392.669524) (xy 407.916205 -392.669524)
			(xy 407.96754 -392.677654) (xy 408.01697 -392.693715) (xy 408.06328 -392.717311) (xy 408.105328 -392.747861)
			(xy 408.142079 -392.784612) (xy 408.172629 -392.82666) (xy 408.196225 -392.87297) (xy 408.212286 -392.9224)
			(xy 408.220416 -392.973735) (xy 408.220926 -392.999722) (xy 408.220416 -393.025709) (xy 408.759916 -393.025709)
			(xy 408.759916 -392.973735) (xy 408.768046 -392.9224) (xy 408.784107 -392.87297) (xy 408.807703 -392.82666)
			(xy 408.838253 -392.784612) (xy 408.875004 -392.747861) (xy 408.917052 -392.717311) (xy 408.963362 -392.693715)
			(xy 409.012792 -392.677654) (xy 409.064127 -392.669524) (xy 409.116101 -392.669524) (xy 409.167436 -392.677654)
			(xy 409.216866 -392.693715) (xy 409.263176 -392.717311) (xy 409.305224 -392.747861) (xy 409.341975 -392.784612)
			(xy 409.372525 -392.82666) (xy 409.396121 -392.87297) (xy 409.412182 -392.9224) (xy 409.420312 -392.973735)
			(xy 409.420822 -392.999722) (xy 409.420312 -393.025709) (xy 409.959812 -393.025709) (xy 409.959812 -392.973735)
			(xy 409.967942 -392.9224) (xy 409.984003 -392.87297) (xy 410.007599 -392.82666) (xy 410.038149 -392.784612)
			(xy 410.0749 -392.747861) (xy 410.116948 -392.717311) (xy 410.163258 -392.693715) (xy 410.212688 -392.677654)
			(xy 410.264023 -392.669524) (xy 410.315997 -392.669524) (xy 410.367332 -392.677654) (xy 410.416762 -392.693715)
			(xy 410.463072 -392.717311) (xy 410.50512 -392.747861) (xy 410.541871 -392.784612) (xy 410.572421 -392.82666)
			(xy 410.596017 -392.87297) (xy 410.612078 -392.9224) (xy 410.620208 -392.973735) (xy 410.620718 -392.999722)
			(xy 410.620208 -393.025709) (xy 411.159962 -393.025709) (xy 411.159962 -392.973735) (xy 411.168092 -392.9224)
			(xy 411.184153 -392.87297) (xy 411.207749 -392.82666) (xy 411.238299 -392.784612) (xy 411.27505 -392.747861)
			(xy 411.317098 -392.717311) (xy 411.363408 -392.693715) (xy 411.412838 -392.677654) (xy 411.464173 -392.669524)
			(xy 411.516147 -392.669524) (xy 411.567482 -392.677654) (xy 411.616912 -392.693715) (xy 411.663222 -392.717311)
			(xy 411.70527 -392.747861) (xy 411.742021 -392.784612) (xy 411.772571 -392.82666) (xy 411.796167 -392.87297)
			(xy 411.812228 -392.9224) (xy 411.820358 -392.973735) (xy 411.820868 -392.999722) (xy 411.820358 -393.025709)
			(xy 412.359858 -393.025709) (xy 412.359858 -392.973735) (xy 412.367988 -392.9224) (xy 412.384049 -392.87297)
			(xy 412.407645 -392.82666) (xy 412.438195 -392.784612) (xy 412.474946 -392.747861) (xy 412.516994 -392.717311)
			(xy 412.563304 -392.693715) (xy 412.612734 -392.677654) (xy 412.664069 -392.669524) (xy 412.716043 -392.669524)
			(xy 412.767378 -392.677654) (xy 412.816808 -392.693715) (xy 412.863118 -392.717311) (xy 412.905166 -392.747861)
			(xy 412.941917 -392.784612) (xy 412.972467 -392.82666) (xy 412.996063 -392.87297) (xy 413.012124 -392.9224)
			(xy 413.020254 -392.973735) (xy 413.020764 -392.999722) (xy 413.020254 -393.025709) (xy 413.560008 -393.025709)
			(xy 413.560008 -392.973735) (xy 413.568138 -392.9224) (xy 413.584199 -392.87297) (xy 413.607795 -392.82666)
			(xy 413.638345 -392.784612) (xy 413.675096 -392.747861) (xy 413.717144 -392.717311) (xy 413.763454 -392.693715)
			(xy 413.812884 -392.677654) (xy 413.864219 -392.669524) (xy 413.916193 -392.669524) (xy 413.967528 -392.677654)
			(xy 414.016958 -392.693715) (xy 414.063268 -392.717311) (xy 414.105316 -392.747861) (xy 414.142067 -392.784612)
			(xy 414.172617 -392.82666) (xy 414.196213 -392.87297) (xy 414.212274 -392.9224) (xy 414.220404 -392.973735)
			(xy 414.220914 -392.999722) (xy 414.220404 -393.025709) (xy 414.759904 -393.025709) (xy 414.759904 -392.973735)
			(xy 414.768034 -392.9224) (xy 414.784095 -392.87297) (xy 414.807691 -392.82666) (xy 414.838241 -392.784612)
			(xy 414.874992 -392.747861) (xy 414.91704 -392.717311) (xy 414.96335 -392.693715) (xy 415.01278 -392.677654)
			(xy 415.064115 -392.669524) (xy 415.116089 -392.669524) (xy 415.167424 -392.677654) (xy 415.216854 -392.693715)
			(xy 415.263164 -392.717311) (xy 415.305212 -392.747861) (xy 415.341963 -392.784612) (xy 415.372513 -392.82666)
			(xy 415.396109 -392.87297) (xy 415.41217 -392.9224) (xy 415.4203 -392.973735) (xy 415.42081 -392.999722)
			(xy 415.4203 -393.025709) (xy 415.9598 -393.025709) (xy 415.9598 -392.973735) (xy 415.96793 -392.9224)
			(xy 415.983991 -392.87297) (xy 416.007587 -392.82666) (xy 416.038137 -392.784612) (xy 416.074888 -392.747861)
			(xy 416.116936 -392.717311) (xy 416.163246 -392.693715) (xy 416.212676 -392.677654) (xy 416.264011 -392.669524)
			(xy 416.315985 -392.669524) (xy 416.36732 -392.677654) (xy 416.41675 -392.693715) (xy 416.46306 -392.717311)
			(xy 416.505108 -392.747861) (xy 416.541859 -392.784612) (xy 416.572409 -392.82666) (xy 416.596005 -392.87297)
			(xy 416.612066 -392.9224) (xy 416.620196 -392.973735) (xy 416.620706 -392.999722) (xy 416.620196 -393.025709)
			(xy 417.15995 -393.025709) (xy 417.15995 -392.973735) (xy 417.16808 -392.9224) (xy 417.184141 -392.87297)
			(xy 417.207737 -392.82666) (xy 417.238287 -392.784612) (xy 417.275038 -392.747861) (xy 417.317086 -392.717311)
			(xy 417.363396 -392.693715) (xy 417.412826 -392.677654) (xy 417.464161 -392.669524) (xy 417.516135 -392.669524)
			(xy 417.56747 -392.677654) (xy 417.6169 -392.693715) (xy 417.66321 -392.717311) (xy 417.705258 -392.747861)
			(xy 417.742009 -392.784612) (xy 417.772559 -392.82666) (xy 417.796155 -392.87297) (xy 417.812216 -392.9224)
			(xy 417.820346 -392.973735) (xy 417.820856 -392.999722) (xy 417.820346 -393.025709) (xy 418.359846 -393.025709)
			(xy 418.359846 -392.973735) (xy 418.367976 -392.9224) (xy 418.384037 -392.87297) (xy 418.407633 -392.82666)
			(xy 418.438183 -392.784612) (xy 418.474934 -392.747861) (xy 418.516982 -392.717311) (xy 418.563292 -392.693715)
			(xy 418.612722 -392.677654) (xy 418.664057 -392.669524) (xy 418.716031 -392.669524) (xy 418.767366 -392.677654)
			(xy 418.816796 -392.693715) (xy 418.863106 -392.717311) (xy 418.905154 -392.747861) (xy 418.941905 -392.784612)
			(xy 418.972455 -392.82666) (xy 418.996051 -392.87297) (xy 419.012112 -392.9224) (xy 419.020242 -392.973735)
			(xy 419.020752 -392.999722) (xy 419.020242 -393.025709) (xy 419.559996 -393.025709) (xy 419.559996 -392.973735)
			(xy 419.568126 -392.9224) (xy 419.584187 -392.87297) (xy 419.607783 -392.82666) (xy 419.638333 -392.784612)
			(xy 419.675084 -392.747861) (xy 419.717132 -392.717311) (xy 419.763442 -392.693715) (xy 419.812872 -392.677654)
			(xy 419.864207 -392.669524) (xy 419.916181 -392.669524) (xy 419.967516 -392.677654) (xy 420.016946 -392.693715)
			(xy 420.063256 -392.717311) (xy 420.105304 -392.747861) (xy 420.142055 -392.784612) (xy 420.172605 -392.82666)
			(xy 420.196201 -392.87297) (xy 420.212262 -392.9224) (xy 420.220392 -392.973735) (xy 420.220902 -392.999722)
			(xy 420.759382 -392.999722) (xy 420.759778 -392.978001) (xy 420.765506 -392.934937) (xy 420.770812 -392.91387)
			(xy 420.772336 -392.907266) (xy 420.772336 -392.799062) (xy 420.772854 -392.782401) (xy 420.781476 -392.750212)
			(xy 420.798123 -392.721345) (xy 420.821665 -392.697761) (xy 420.850502 -392.681063) (xy 420.882676 -392.672384)
			(xy 420.899336 -392.671808) (xy 421.04818 -392.671808) (xy 421.050974 -392.6713) (xy 421.060717 -392.670225)
			(xy 421.080288 -392.66908) (xy 421.09009 -392.669014) (xy 421.099892 -392.669078) (xy 421.119463 -392.67022)
			(xy 421.129206 -392.6713) (xy 421.132 -392.671808) (xy 421.280844 -392.671808) (xy 421.297541 -392.672296)
			(xy 421.329798 -392.680938) (xy 421.358725 -392.697624) (xy 421.382357 -392.72122) (xy 421.399087 -392.750122)
			(xy 421.407778 -392.782366) (xy 421.408352 -392.799062) (xy 421.408352 -392.909044) (xy 421.409876 -392.915394)
			(xy 421.416561 -392.943046) (xy 421.421436 -392.999721) (xy 421.416554 -393.056396) (xy 421.409876 -393.08405)
			(xy 421.408352 -393.0904) (xy 421.408352 -393.103862) (xy 421.4078 -393.120367) (xy 421.399316 -393.15227)
			(xy 421.382954 -393.180942) (xy 421.359803 -393.204475) (xy 421.345868 -393.213336) (xy 421.342659 -393.215304)
			(xy 421.336793 -393.220021) (xy 421.334184 -393.222734) (xy 421.315253 -393.242663) (xy 421.271999 -393.276572)
			(xy 421.223729 -393.302857) (xy 421.171776 -393.320793) (xy 421.117571 -393.329886) (xy 421.09009 -393.33043)
			(xy 421.062564 -393.329847) (xy 421.008282 -393.320669) (xy 420.956266 -393.302635) (xy 420.907953 -393.276242)
			(xy 420.864673 -393.242217) (xy 420.845742 -393.222226) (xy 420.843135 -393.219509) (xy 420.837275 -393.214784)
			(xy 420.834058 -393.212828) (xy 420.820288 -393.203927) (xy 420.797419 -393.180449) (xy 420.781261 -393.151933)
			(xy 420.772873 -393.120249) (xy 420.772336 -393.103862) (xy 420.772336 -393.092178) (xy 420.770812 -393.085574)
			(xy 420.765466 -393.064515) (xy 420.759738 -393.021446) (xy 420.759382 -392.999722) (xy 420.220902 -392.999722)
			(xy 420.220392 -393.025709) (xy 420.212262 -393.077044) (xy 420.196201 -393.126474) (xy 420.172605 -393.172784)
			(xy 420.142055 -393.214832) (xy 420.105304 -393.251583) (xy 420.063256 -393.282133) (xy 420.016946 -393.305729)
			(xy 419.967516 -393.32179) (xy 419.916181 -393.32992) (xy 419.864207 -393.32992) (xy 419.812872 -393.32179)
			(xy 419.763442 -393.305729) (xy 419.717132 -393.282133) (xy 419.675084 -393.251583) (xy 419.638333 -393.214832)
			(xy 419.607783 -393.172784) (xy 419.584187 -393.126474) (xy 419.568126 -393.077044) (xy 419.559996 -393.025709)
			(xy 419.020242 -393.025709) (xy 419.012112 -393.077044) (xy 418.996051 -393.126474) (xy 418.972455 -393.172784)
			(xy 418.941905 -393.214832) (xy 418.905154 -393.251583) (xy 418.863106 -393.282133) (xy 418.816796 -393.305729)
			(xy 418.767366 -393.32179) (xy 418.716031 -393.32992) (xy 418.664057 -393.32992) (xy 418.612722 -393.32179)
			(xy 418.563292 -393.305729) (xy 418.516982 -393.282133) (xy 418.474934 -393.251583) (xy 418.438183 -393.214832)
			(xy 418.407633 -393.172784) (xy 418.384037 -393.126474) (xy 418.367976 -393.077044) (xy 418.359846 -393.025709)
			(xy 417.820346 -393.025709) (xy 417.812216 -393.077044) (xy 417.796155 -393.126474) (xy 417.772559 -393.172784)
			(xy 417.742009 -393.214832) (xy 417.705258 -393.251583) (xy 417.66321 -393.282133) (xy 417.6169 -393.305729)
			(xy 417.56747 -393.32179) (xy 417.516135 -393.32992) (xy 417.464161 -393.32992) (xy 417.412826 -393.32179)
			(xy 417.363396 -393.305729) (xy 417.317086 -393.282133) (xy 417.275038 -393.251583) (xy 417.238287 -393.214832)
			(xy 417.207737 -393.172784) (xy 417.184141 -393.126474) (xy 417.16808 -393.077044) (xy 417.15995 -393.025709)
			(xy 416.620196 -393.025709) (xy 416.612066 -393.077044) (xy 416.596005 -393.126474) (xy 416.572409 -393.172784)
			(xy 416.541859 -393.214832) (xy 416.505108 -393.251583) (xy 416.46306 -393.282133) (xy 416.41675 -393.305729)
			(xy 416.36732 -393.32179) (xy 416.315985 -393.32992) (xy 416.264011 -393.32992) (xy 416.212676 -393.32179)
			(xy 416.163246 -393.305729) (xy 416.116936 -393.282133) (xy 416.074888 -393.251583) (xy 416.038137 -393.214832)
			(xy 416.007587 -393.172784) (xy 415.983991 -393.126474) (xy 415.96793 -393.077044) (xy 415.9598 -393.025709)
			(xy 415.4203 -393.025709) (xy 415.41217 -393.077044) (xy 415.396109 -393.126474) (xy 415.372513 -393.172784)
			(xy 415.341963 -393.214832) (xy 415.305212 -393.251583) (xy 415.263164 -393.282133) (xy 415.216854 -393.305729)
			(xy 415.167424 -393.32179) (xy 415.116089 -393.32992) (xy 415.064115 -393.32992) (xy 415.01278 -393.32179)
			(xy 414.96335 -393.305729) (xy 414.91704 -393.282133) (xy 414.874992 -393.251583) (xy 414.838241 -393.214832)
			(xy 414.807691 -393.172784) (xy 414.784095 -393.126474) (xy 414.768034 -393.077044) (xy 414.759904 -393.025709)
			(xy 414.220404 -393.025709) (xy 414.212274 -393.077044) (xy 414.196213 -393.126474) (xy 414.172617 -393.172784)
			(xy 414.142067 -393.214832) (xy 414.105316 -393.251583) (xy 414.063268 -393.282133) (xy 414.016958 -393.305729)
			(xy 413.967528 -393.32179) (xy 413.916193 -393.32992) (xy 413.864219 -393.32992) (xy 413.812884 -393.32179)
			(xy 413.763454 -393.305729) (xy 413.717144 -393.282133) (xy 413.675096 -393.251583) (xy 413.638345 -393.214832)
			(xy 413.607795 -393.172784) (xy 413.584199 -393.126474) (xy 413.568138 -393.077044) (xy 413.560008 -393.025709)
			(xy 413.020254 -393.025709) (xy 413.012124 -393.077044) (xy 412.996063 -393.126474) (xy 412.972467 -393.172784)
			(xy 412.941917 -393.214832) (xy 412.905166 -393.251583) (xy 412.863118 -393.282133) (xy 412.816808 -393.305729)
			(xy 412.767378 -393.32179) (xy 412.716043 -393.32992) (xy 412.664069 -393.32992) (xy 412.612734 -393.32179)
			(xy 412.563304 -393.305729) (xy 412.516994 -393.282133) (xy 412.474946 -393.251583) (xy 412.438195 -393.214832)
			(xy 412.407645 -393.172784) (xy 412.384049 -393.126474) (xy 412.367988 -393.077044) (xy 412.359858 -393.025709)
			(xy 411.820358 -393.025709) (xy 411.812228 -393.077044) (xy 411.796167 -393.126474) (xy 411.772571 -393.172784)
			(xy 411.742021 -393.214832) (xy 411.70527 -393.251583) (xy 411.663222 -393.282133) (xy 411.616912 -393.305729)
			(xy 411.567482 -393.32179) (xy 411.516147 -393.32992) (xy 411.464173 -393.32992) (xy 411.412838 -393.32179)
			(xy 411.363408 -393.305729) (xy 411.317098 -393.282133) (xy 411.27505 -393.251583) (xy 411.238299 -393.214832)
			(xy 411.207749 -393.172784) (xy 411.184153 -393.126474) (xy 411.168092 -393.077044) (xy 411.159962 -393.025709)
			(xy 410.620208 -393.025709) (xy 410.612078 -393.077044) (xy 410.596017 -393.126474) (xy 410.572421 -393.172784)
			(xy 410.541871 -393.214832) (xy 410.50512 -393.251583) (xy 410.463072 -393.282133) (xy 410.416762 -393.305729)
			(xy 410.367332 -393.32179) (xy 410.315997 -393.32992) (xy 410.264023 -393.32992) (xy 410.212688 -393.32179)
			(xy 410.163258 -393.305729) (xy 410.116948 -393.282133) (xy 410.0749 -393.251583) (xy 410.038149 -393.214832)
			(xy 410.007599 -393.172784) (xy 409.984003 -393.126474) (xy 409.967942 -393.077044) (xy 409.959812 -393.025709)
			(xy 409.420312 -393.025709) (xy 409.412182 -393.077044) (xy 409.396121 -393.126474) (xy 409.372525 -393.172784)
			(xy 409.341975 -393.214832) (xy 409.305224 -393.251583) (xy 409.263176 -393.282133) (xy 409.216866 -393.305729)
			(xy 409.167436 -393.32179) (xy 409.116101 -393.32992) (xy 409.064127 -393.32992) (xy 409.012792 -393.32179)
			(xy 408.963362 -393.305729) (xy 408.917052 -393.282133) (xy 408.875004 -393.251583) (xy 408.838253 -393.214832)
			(xy 408.807703 -393.172784) (xy 408.784107 -393.126474) (xy 408.768046 -393.077044) (xy 408.759916 -393.025709)
			(xy 408.220416 -393.025709) (xy 408.212286 -393.077044) (xy 408.196225 -393.126474) (xy 408.172629 -393.172784)
			(xy 408.142079 -393.214832) (xy 408.105328 -393.251583) (xy 408.06328 -393.282133) (xy 408.01697 -393.305729)
			(xy 407.96754 -393.32179) (xy 407.916205 -393.32992) (xy 407.864231 -393.32992) (xy 407.812896 -393.32179)
			(xy 407.763466 -393.305729) (xy 407.717156 -393.282133) (xy 407.675108 -393.251583) (xy 407.638357 -393.214832)
			(xy 407.607807 -393.172784) (xy 407.584211 -393.126474) (xy 407.56815 -393.077044) (xy 407.56002 -393.025709)
			(xy 407.020266 -393.025709) (xy 407.012136 -393.077044) (xy 406.996075 -393.126474) (xy 406.972479 -393.172784)
			(xy 406.941929 -393.214832) (xy 406.905178 -393.251583) (xy 406.86313 -393.282133) (xy 406.81682 -393.305729)
			(xy 406.76739 -393.32179) (xy 406.716055 -393.32992) (xy 406.664081 -393.32992) (xy 406.612746 -393.32179)
			(xy 406.563316 -393.305729) (xy 406.517006 -393.282133) (xy 406.474958 -393.251583) (xy 406.438207 -393.214832)
			(xy 406.407657 -393.172784) (xy 406.384061 -393.126474) (xy 406.368 -393.077044) (xy 406.35987 -393.025709)
			(xy 405.82037 -393.025709) (xy 405.81224 -393.077044) (xy 405.796179 -393.126474) (xy 405.772583 -393.172784)
			(xy 405.742033 -393.214832) (xy 405.705282 -393.251583) (xy 405.663234 -393.282133) (xy 405.616924 -393.305729)
			(xy 405.567494 -393.32179) (xy 405.516159 -393.32992) (xy 405.464185 -393.32992) (xy 405.41285 -393.32179)
			(xy 405.36342 -393.305729) (xy 405.31711 -393.282133) (xy 405.275062 -393.251583) (xy 405.238311 -393.214832)
			(xy 405.207761 -393.172784) (xy 405.184165 -393.126474) (xy 405.168104 -393.077044) (xy 405.159974 -393.025709)
			(xy 404.62022 -393.025709) (xy 404.61209 -393.077044) (xy 404.596029 -393.126474) (xy 404.572433 -393.172784)
			(xy 404.541883 -393.214832) (xy 404.505132 -393.251583) (xy 404.463084 -393.282133) (xy 404.416774 -393.305729)
			(xy 404.367344 -393.32179) (xy 404.316009 -393.32992) (xy 404.264035 -393.32992) (xy 404.2127 -393.32179)
			(xy 404.16327 -393.305729) (xy 404.11696 -393.282133) (xy 404.074912 -393.251583) (xy 404.038161 -393.214832)
			(xy 404.007611 -393.172784) (xy 403.984015 -393.126474) (xy 403.967954 -393.077044) (xy 403.959824 -393.025709)
			(xy 403.407486 -393.025709) (xy 403.399825 -393.074074) (xy 403.384381 -393.121606) (xy 403.361691 -393.166138)
			(xy 403.332315 -393.206571) (xy 403.296975 -393.241911) (xy 403.256542 -393.271287) (xy 403.21201 -393.293977)
			(xy 403.164478 -393.309421) (xy 403.115115 -393.31724) (xy 403.065137 -393.31724) (xy 403.015774 -393.309421)
			(xy 402.968242 -393.293977) (xy 402.92371 -393.271287) (xy 402.883277 -393.241911) (xy 402.847937 -393.206571)
			(xy 402.818561 -393.166138) (xy 402.795871 -393.121606) (xy 402.780427 -393.074074) (xy 402.772608 -393.024711)
			(xy 401.195226 -393.024711) (xy 401.17129 -393.038405) (xy 401.12495 -393.056352) (xy 401.100798 -393.062206)
			(xy 401.100544 -393.062206) (xy 401.089508 -393.065364) (xy 401.071568 -393.079635) (xy 401.061597 -393.100275)
			(xy 401.06092 -393.111736) (xy 401.06092 -393.205208) (xy 401.061428 -393.20851) (xy 401.063228 -393.223303)
			(xy 401.065137 -393.253044) (xy 401.065238 -393.267946) (xy 401.065136 -393.282848) (xy 401.063233 -393.31259)
			(xy 401.061428 -393.327382) (xy 401.06092 -393.330684) (xy 401.06092 -394.25753) (xy 402.46173 -394.25753)
			(xy 402.46229 -394.22995) (xy 402.47149 -394.175561) (xy 402.480018 -394.149326) (xy 402.482812 -394.141452)
			(xy 402.482812 -393.99718) (xy 402.483317 -393.980484) (xy 402.491954 -393.948227) (xy 402.508636 -393.919299)
			(xy 402.532229 -393.895667) (xy 402.561128 -393.878937) (xy 402.593371 -393.870246) (xy 402.610066 -393.869672)
			(xy 402.991066 -393.869672) (xy 403.000972 -393.87018) (xy 403.012748 -393.870524) (xy 403.034596 -393.86179)
			(xy 403.042882 -393.853416) (xy 403.104604 -393.784836) (xy 403.110954 -393.761976) (xy 403.110192 -393.758166)
			(xy 403.110192 -393.757404) (xy 403.107066 -393.741331) (xy 403.103757 -393.708753) (xy 403.103588 -393.69238)
			(xy 403.104099 -393.667592) (xy 403.111857 -393.618627) (xy 403.127178 -393.571478) (xy 403.149685 -393.527305)
			(xy 403.178824 -393.487197) (xy 403.213878 -393.45214) (xy 403.253985 -393.422997) (xy 403.298155 -393.400487)
			(xy 403.345303 -393.385162) (xy 403.394268 -393.377401) (xy 403.419056 -393.376912) (xy 403.442671 -393.377301)
			(xy 403.48937 -393.384357) (xy 403.534499 -393.398288) (xy 403.57705 -393.418784) (xy 403.616074 -393.445387)
			(xy 403.650703 -393.477505) (xy 403.680162 -393.514421) (xy 403.69236 -393.534646) (xy 403.701583 -393.551158)
			(xy 403.716485 -393.585921) (xy 403.722078 -393.603988) (xy 403.722586 -393.60602) (xy 403.723602 -393.610084)
			(xy 403.771521 -393.692888) (xy 404.303484 -393.692888) (xy 404.303484 -393.69238) (xy 404.303999 -393.667592)
			(xy 404.311757 -393.618627) (xy 404.327077 -393.571478) (xy 404.349584 -393.527306) (xy 404.378723 -393.487198)
			(xy 404.413777 -393.452141) (xy 404.453882 -393.422999) (xy 404.498053 -393.400488) (xy 404.5452 -393.385163)
			(xy 404.594164 -393.377402) (xy 404.618952 -393.376912) (xy 404.644346 -393.377438) (xy 404.694479 -393.385561)
			(xy 404.742665 -393.401607) (xy 404.78766 -393.425161) (xy 404.828304 -393.455616) (xy 404.863547 -393.492184)
			(xy 404.892481 -393.533924) (xy 404.914358 -393.579758) (xy 404.921974 -393.603988) (xy 404.923498 -393.60983)
			(xy 404.971248 -393.69238) (xy 405.50338 -393.69238) (xy 405.503799 -393.6676) (xy 405.511551 -393.61865)
			(xy 405.526862 -393.571515) (xy 405.549355 -393.527353) (xy 405.578477 -393.487252) (xy 405.613511 -393.452198)
			(xy 405.653595 -393.423053) (xy 405.697743 -393.400534) (xy 405.744869 -393.385195) (xy 405.793814 -393.377413)
			(xy 405.818594 -393.376912) (xy 405.819102 -393.376912) (xy 405.844549 -393.377427) (xy 405.894786 -393.385577)
			(xy 405.943065 -393.401681) (xy 405.988134 -393.425322) (xy 406.028827 -393.455888) (xy 406.064089 -393.492586)
			(xy 406.093007 -393.534466) (xy 406.11483 -393.580443) (xy 406.122378 -393.60475) (xy 406.123902 -393.610592)
			(xy 406.443688 -394.16355) (xy 406.447752 -394.167868) (xy 406.463959 -394.185539) (xy 406.491356 -394.224889)
			(xy 406.512486 -394.267931) (xy 406.526862 -394.313674) (xy 406.534154 -394.361064) (xy 406.53462 -394.385038)
			(xy 406.53462 -394.385546) (xy 406.533858 -394.405866) (xy 406.533096 -394.415772) (xy 406.539446 -394.434822)
			(xy 406.600152 -394.504164) (xy 406.617932 -394.513054) (xy 406.628092 -394.513816) (xy 406.65307 -394.515999)
			(xy 406.701928 -394.527256) (xy 406.748415 -394.546038) (xy 406.791379 -394.571882) (xy 406.829757 -394.604147)
			(xy 406.846532 -394.622782) (xy 406.848997 -394.625552) (xy 406.854608 -394.6304) (xy 406.857708 -394.632434)
			(xy 406.869772 -394.640492) (xy 406.889731 -394.661534) (xy 406.903806 -394.686892) (xy 406.911105 -394.714962)
			(xy 406.911556 -394.729462) (xy 406.911556 -394.7414) (xy 406.91308 -394.748004) (xy 406.918273 -394.768376)
			(xy 406.923882 -394.810042) (xy 406.924256 -394.831062) (xy 406.923873 -394.852082) (xy 406.918273 -394.893748)
			(xy 406.91308 -394.91412) (xy 406.911556 -394.920724) (xy 406.911556 -395.034262) (xy 406.911034 -395.049256)
			(xy 406.903291 -395.078227) (xy 406.888322 -395.104211) (xy 406.867145 -395.125443) (xy 406.841199 -395.140478)
			(xy 406.812249 -395.148295) (xy 406.797256 -395.148816) (xy 406.615138 -395.148816) (xy 406.61463 -395.14907)
			(xy 406.597866 -395.14907) (xy 406.597358 -395.148816) (xy 406.415748 -395.148816) (xy 406.400722 -395.148278)
			(xy 406.371688 -395.140521) (xy 406.345646 -395.125522) (xy 406.324368 -395.104301) (xy 406.309298 -395.0783)
			(xy 406.301463 -395.049287) (xy 406.30094 -395.034262) (xy 406.30094 -394.920724) (xy 406.299416 -394.91412)
			(xy 406.294209 -394.893751) (xy 406.288609 -394.852083) (xy 406.28824 -394.831062) (xy 406.289002 -394.808456)
			(xy 406.289764 -394.79855) (xy 406.283414 -394.779246) (xy 406.223216 -394.709904) (xy 406.205182 -394.70076)
			(xy 406.195276 -394.699998) (xy 406.171447 -394.697823) (xy 406.124817 -394.687091) (xy 406.080341 -394.669441)
			(xy 406.03904 -394.645279) (xy 406.001862 -394.615157) (xy 405.969657 -394.579767) (xy 405.943166 -394.53992)
			(xy 405.922995 -394.496529) (xy 405.915876 -394.473684) (xy 405.914352 -394.467842) (xy 405.593804 -393.91336)
			(xy 405.58974 -393.909042) (xy 405.57361 -393.891396) (xy 405.546366 -393.85211) (xy 405.52536 -393.809164)
			(xy 405.511074 -393.76354) (xy 405.503835 -393.716284) (xy 405.50338 -393.69238) (xy 404.971248 -393.69238)
			(xy 405.243792 -394.16355) (xy 405.247856 -394.167868) (xy 405.264064 -394.185538) (xy 405.291461 -394.224889)
			(xy 405.31259 -394.267931) (xy 405.326966 -394.313673) (xy 405.334258 -394.361064) (xy 405.334724 -394.385038)
			(xy 405.334724 -394.385546) (xy 405.333962 -394.405866) (xy 405.3332 -394.415772) (xy 405.33955 -394.434822)
			(xy 405.400256 -394.504164) (xy 405.418036 -394.513054) (xy 405.428196 -394.513816) (xy 405.453174 -394.515997)
			(xy 405.502033 -394.527254) (xy 405.548519 -394.546037) (xy 405.591484 -394.571881) (xy 405.629861 -394.604147)
			(xy 405.646636 -394.622782) (xy 405.649101 -394.625552) (xy 405.654711 -394.6304) (xy 405.657812 -394.632434)
			(xy 405.669876 -394.640491) (xy 405.689836 -394.661533) (xy 405.703911 -394.686892) (xy 405.711209 -394.714962)
			(xy 405.71166 -394.729462) (xy 405.71166 -394.7414) (xy 405.713184 -394.748004) (xy 405.718377 -394.768376)
			(xy 405.723986 -394.810042) (xy 405.72436 -394.831062) (xy 405.723977 -394.852082) (xy 405.718377 -394.893748)
			(xy 405.713184 -394.91412) (xy 405.71166 -394.920724) (xy 405.71166 -395.034262) (xy 405.711134 -395.049256)
			(xy 405.703392 -395.078226) (xy 405.688424 -395.10421) (xy 405.667247 -395.125441) (xy 405.641302 -395.140477)
			(xy 405.612352 -395.148294) (xy 405.59736 -395.148816) (xy 405.415242 -395.148816) (xy 405.414734 -395.14907)
			(xy 405.39797 -395.14907) (xy 405.397462 -395.148816) (xy 405.215852 -395.148816) (xy 405.200821 -395.148362)
			(xy 405.171784 -395.140582) (xy 405.145743 -395.125564) (xy 405.124467 -395.104328) (xy 405.1094 -395.078314)
			(xy 405.101566 -395.049292) (xy 405.101044 -395.034262) (xy 405.101044 -394.920724) (xy 405.09952 -394.91412)
			(xy 405.094313 -394.893751) (xy 405.088713 -394.852083) (xy 405.088344 -394.831062) (xy 405.089106 -394.808456)
			(xy 405.089868 -394.79855) (xy 405.083518 -394.779246) (xy 405.02332 -394.709904) (xy 405.005286 -394.70076)
			(xy 404.99538 -394.699998) (xy 404.971551 -394.69782) (xy 404.924921 -394.687088) (xy 404.880446 -394.669439)
			(xy 404.839145 -394.645277) (xy 404.801966 -394.615156) (xy 404.769762 -394.579766) (xy 404.74327 -394.539919)
			(xy 404.723099 -394.496529) (xy 404.71598 -394.473684) (xy 404.714456 -394.467842) (xy 404.394162 -393.914122)
			(xy 404.390098 -393.909804) (xy 404.373953 -393.892125) (xy 404.346631 -393.852811) (xy 404.32556 -393.809823)
			(xy 404.311223 -393.764145) (xy 404.303949 -393.716825) (xy 404.303484 -393.692888) (xy 403.771521 -393.692888)
			(xy 404.043896 -394.16355) (xy 404.04796 -394.167868) (xy 404.064169 -394.185538) (xy 404.091565 -394.224889)
			(xy 404.112694 -394.267931) (xy 404.12707 -394.313673) (xy 404.134362 -394.361064) (xy 404.134828 -394.385038)
			(xy 404.134828 -394.385546) (xy 404.134066 -394.405866) (xy 404.133304 -394.415772) (xy 404.139654 -394.434822)
			(xy 404.20036 -394.504164) (xy 404.21814 -394.513054) (xy 404.2283 -394.513816) (xy 404.253249 -394.516033)
			(xy 404.302049 -394.527314) (xy 404.348479 -394.546101) (xy 404.391392 -394.571932) (xy 404.429727 -394.604167)
			(xy 404.446486 -394.622782) (xy 404.448945 -394.625558) (xy 404.45456 -394.630402) (xy 404.457662 -394.632434)
			(xy 404.469688 -394.640518) (xy 404.489582 -394.661574) (xy 404.503592 -394.686929) (xy 404.510831 -394.714978)
			(xy 404.511256 -394.729462) (xy 404.511256 -394.7414) (xy 404.513034 -394.748004) (xy 404.518226 -394.768376)
			(xy 404.523836 -394.810042) (xy 404.52421 -394.831062) (xy 404.523828 -394.852082) (xy 404.518228 -394.893748)
			(xy 404.513034 -394.91412) (xy 404.511256 -394.920724) (xy 404.511256 -395.034262) (xy 404.510775 -395.049283)
			(xy 404.503008 -395.078303) (xy 404.487993 -395.104322) (xy 404.466754 -395.125568) (xy 404.44074 -395.140592)
			(xy 404.411723 -395.14837) (xy 404.396702 -395.148816) (xy 404.215092 -395.148816) (xy 404.214584 -395.14907)
			(xy 404.19782 -395.14907) (xy 404.197312 -395.148816) (xy 404.015702 -395.148816) (xy 404.000676 -395.148406)
			(xy 403.971649 -395.140627) (xy 403.945626 -395.125598) (xy 403.92438 -395.104346) (xy 403.909359 -395.078317)
			(xy 403.90159 -395.049288) (xy 403.901148 -395.034262) (xy 403.901148 -394.920724) (xy 403.89937 -394.91412)
			(xy 403.894164 -394.893751) (xy 403.888563 -394.852083) (xy 403.888194 -394.831062) (xy 403.888956 -394.808456)
			(xy 403.889718 -394.798296) (xy 403.883622 -394.7795) (xy 403.830028 -394.717524) (xy 403.823091 -394.710273)
			(xy 403.805186 -394.701254) (xy 403.79523 -394.699998) (xy 403.771421 -394.697781) (xy 403.724829 -394.687024)
			(xy 403.680393 -394.669361) (xy 403.639132 -394.645194) (xy 403.60199 -394.615078) (xy 403.569817 -394.579703)
			(xy 403.543351 -394.539877) (xy 403.523197 -394.496514) (xy 403.516084 -394.473684) (xy 403.51456 -394.467842)
			(xy 403.19706 -393.919202) (xy 403.190202 -393.909804) (xy 403.18182 -393.90066) (xy 403.141434 -393.924028)
			(xy 403.132771 -393.929616) (xy 403.120437 -393.946107) (xy 403.115572 -393.966117) (xy 403.116796 -393.976352)
			(xy 403.11832 -393.996926) (xy 403.11832 -393.997434) (xy 403.11832 -394.201904) (xy 403.119082 -394.205714)
			(xy 403.120985 -394.21852) (xy 403.123023 -394.24433) (xy 403.123146 -394.257276) (xy 403.123146 -394.25753)
			(xy 403.122975 -394.273119) (xy 403.120049 -394.30416) (xy 403.117304 -394.319506) (xy 403.116796 -394.321538)
			(xy 403.11324 -394.338048) (xy 403.112732 -394.339572) (xy 403.108239 -394.35621) (xy 403.096281 -394.388535)
			(xy 403.088856 -394.404088) (xy 403.088856 -394.404342) (xy 403.084856 -394.413623) (xy 403.083662 -394.43378)
			(xy 403.08657 -394.443458) (xy 403.11451 -394.522198) (xy 403.12848 -394.537184) (xy 403.137878 -394.541502)
			(xy 403.158454 -394.551347) (xy 403.196842 -394.57598) (xy 403.231335 -394.605824) (xy 403.24659 -394.622782)
			(xy 403.249048 -394.625559) (xy 403.254663 -394.630402) (xy 403.257766 -394.632434) (xy 403.269793 -394.640517)
			(xy 403.289687 -394.661574) (xy 403.303697 -394.686929) (xy 403.310935 -394.714978) (xy 403.31136 -394.729462)
			(xy 403.31136 -394.7414) (xy 403.313138 -394.748004) (xy 403.31833 -394.768376) (xy 403.32394 -394.810042)
			(xy 403.324314 -394.831062) (xy 403.323932 -394.852082) (xy 403.318332 -394.893748) (xy 403.313138 -394.91412)
			(xy 403.31136 -394.920724) (xy 403.31136 -395.034262) (xy 403.310875 -395.049282) (xy 403.303108 -395.078302)
			(xy 403.288094 -395.104321) (xy 403.266856 -395.125567) (xy 403.240842 -395.140591) (xy 403.211826 -395.148369)
			(xy 403.196806 -395.148816) (xy 403.015196 -395.148816) (xy 403.014688 -395.14907) (xy 402.997924 -395.14907)
			(xy 402.997416 -395.148816) (xy 402.815806 -395.148816) (xy 402.800781 -395.148402) (xy 402.771754 -395.140624)
			(xy 402.74573 -395.125597) (xy 402.724484 -395.104345) (xy 402.709464 -395.078317) (xy 402.701694 -395.049288)
			(xy 402.701252 -395.034262) (xy 402.701252 -394.920724) (xy 402.699474 -394.91412) (xy 402.694268 -394.893751)
			(xy 402.688667 -394.852083) (xy 402.688298 -394.831062) (xy 402.688665 -394.810041) (xy 402.694275 -394.768375)
			(xy 402.699474 -394.748004) (xy 402.701252 -394.7414) (xy 402.701252 -394.729462) (xy 402.701448 -394.718867)
			(xy 402.705281 -394.698029) (xy 402.708872 -394.68806) (xy 402.712428 -394.678916) (xy 402.712174 -394.659612)
			(xy 402.678138 -394.576554) (xy 402.665184 -394.562838) (xy 402.65604 -394.558774) (xy 402.631567 -394.547169)
			(xy 402.586528 -394.517088) (xy 402.546993 -394.48007) (xy 402.514019 -394.437103) (xy 402.488487 -394.389337)
			(xy 402.471082 -394.338049) (xy 402.462267 -394.284611) (xy 402.46173 -394.25753) (xy 401.06092 -394.25753)
			(xy 401.06092 -395.122908) (xy 401.060496 -395.132978) (xy 401.052782 -395.151582) (xy 401.045934 -395.158976)
			(xy 401.03933 -395.16558) (xy 401.051014 -395.196314) (xy 401.054923 -395.207272) (xy 401.059144 -395.230149)
			(xy 401.059396 -395.24178) (xy 401.059396 -395.377162) (xy 401.059904 -395.380972) (xy 401.061575 -395.393094)
			(xy 401.063352 -395.417503) (xy 401.06346 -395.42974) (xy 401.063371 -395.441977) (xy 401.061594 -395.466387)
			(xy 401.059904 -395.478508) (xy 401.059396 -395.482318) (xy 401.059396 -395.62278) (xy 401.058902 -395.639503)
			(xy 401.050249 -395.671809) (xy 401.033529 -395.700774) (xy 401.009881 -395.724424) (xy 400.980916 -395.741146)
			(xy 400.948611 -395.749801) (xy 400.931888 -395.750288) (xy 400.814794 -395.750288) (xy 400.808952 -395.751558)
			(xy 400.783886 -395.756993) (xy 400.732752 -395.760961) (xy 400.681618 -395.756993) (xy 400.656552 -395.751558)
			(xy 400.65071 -395.750288) (xy 400.627088 -395.750288) (xy 400.609781 -395.749705) (xy 400.57644 -395.740405)
			(xy 400.546821 -395.722492) (xy 400.523103 -395.697282) (xy 400.514566 -395.682216) (xy 400.512573 -395.678577)
			(xy 400.507595 -395.671941) (xy 400.50466 -395.669008) (xy 400.48562 -395.650172) (xy 400.453285 -395.60748)
			(xy 400.428258 -395.560132) (xy 400.411192 -395.509368) (xy 400.402534 -395.456517) (xy 400.402044 -395.42974)
			(xy 400.402175 -395.417821) (xy 400.403955 -395.394048) (xy 400.4056 -395.382242) (xy 400.4056 -395.381988)
			(xy 400.40661 -395.371112) (xy 400.400414 -395.35019) (xy 400.393662 -395.341602) (xy 400.34337 -395.283436)
			(xy 400.335819 -395.275518) (xy 400.315944 -395.266419) (xy 400.305016 -395.26591) (xy 398.98955 -395.26591)
			(xy 398.979484 -395.266343) (xy 398.960894 -395.274071) (xy 398.953482 -395.280896) (xy 398.376394 -395.857984)
			(xy 398.369562 -395.865387) (xy 398.361859 -395.883986) (xy 398.361408 -395.894052) (xy 398.361408 -396.679674)
			(xy 399.436588 -396.679674) (xy 399.440659 -396.624052) (xy 399.452785 -396.569615) (xy 399.472708 -396.517524)
			(xy 399.500004 -396.468889) (xy 399.53409 -396.424746) (xy 399.574239 -396.386037) (xy 399.619597 -396.353586)
			(xy 399.669197 -396.328085) (xy 399.721981 -396.310078) (xy 399.776824 -396.299948) (xy 399.832558 -396.297911)
			(xy 399.887995 -396.304011) (xy 399.941952 -396.318117) (xy 399.993281 -396.339929) (xy 400.040887 -396.368983)
			(xy 400.083755 -396.404658) (xy 400.120972 -396.446195) (xy 400.151745 -396.492708) (xy 400.175417 -396.543205)
			(xy 400.191485 -396.596612) (xy 400.199605 -396.651788) (xy 400.200086 -396.67815) (xy 400.402044 -396.67815)
			(xy 400.40222 -396.661462) (xy 400.405531 -396.628251) (xy 400.408648 -396.611856) (xy 400.409664 -396.606776)
			(xy 400.409664 -396.571978) (xy 400.410256 -396.554049) (xy 400.420214 -396.519603) (xy 400.439343 -396.489274)
			(xy 400.466138 -396.465446) (xy 400.482054 -396.45717) (xy 400.486061 -396.455152) (xy 400.49334 -396.449909)
			(xy 400.496532 -396.446756) (xy 400.515314 -396.428297) (xy 400.55765 -396.396981) (xy 400.604416 -396.372775)
			(xy 400.654428 -396.356292) (xy 400.706422 -396.347949) (xy 400.732752 -396.347442) (xy 400.760575 -396.347984)
			(xy 400.815435 -396.357312) (xy 400.867957 -396.375696) (xy 400.916659 -396.402617) (xy 400.960164 -396.437314)
			(xy 400.979132 -396.457678) (xy 400.988784 -396.46606) (xy 401.000782 -396.474608) (xy 401.020864 -396.496149)
			(xy 401.035493 -396.52171) (xy 401.043893 -396.549937) (xy 401.045172 -396.564612) (xy 401.047458 -396.577058)
			(xy 401.054903 -396.601666) (xy 401.062936 -396.652445) (xy 401.06346 -396.67815) (xy 401.063005 -396.703582)
			(xy 401.061908 -396.710662) (xy 402.828252 -396.710662) (xy 402.82862 -396.689641) (xy 402.83423 -396.647975)
			(xy 402.839428 -396.627604) (xy 402.840952 -396.621) (xy 402.840952 -396.507462) (xy 402.8414 -396.492464)
			(xy 402.849161 -396.463489) (xy 402.864146 -396.437504) (xy 402.885337 -396.416274) (xy 402.911294 -396.401242)
			(xy 402.940255 -396.393427) (xy 402.955252 -396.392908) (xy 403.13737 -396.392908) (xy 403.137878 -396.392654)
			(xy 403.154642 -396.392654) (xy 403.15515 -396.392908) (xy 403.33676 -396.392908) (xy 403.351789 -396.393415)
			(xy 403.380826 -396.401176) (xy 403.40687 -396.416181) (xy 403.428149 -396.437408) (xy 403.443217 -396.463416)
			(xy 403.451048 -396.492435) (xy 403.451568 -396.507462) (xy 403.451568 -396.621) (xy 403.453092 -396.627604)
			(xy 403.458283 -396.647977) (xy 403.463894 -396.689642) (xy 403.464268 -396.710662) (xy 404.028148 -396.710662)
			(xy 404.028516 -396.689641) (xy 404.034126 -396.647975) (xy 404.039324 -396.627604) (xy 404.040848 -396.621)
			(xy 404.040848 -396.507462) (xy 404.0413 -396.492464) (xy 404.04906 -396.46349) (xy 404.064045 -396.437506)
			(xy 404.085235 -396.416276) (xy 404.111192 -396.401243) (xy 404.140151 -396.393428) (xy 404.155148 -396.392908)
			(xy 404.337266 -396.392908) (xy 404.337774 -396.392654) (xy 404.354538 -396.392654) (xy 404.355046 -396.392908)
			(xy 404.536656 -396.392908) (xy 404.551684 -396.393419) (xy 404.580722 -396.401179) (xy 404.606766 -396.416182)
			(xy 404.628045 -396.437409) (xy 404.643113 -396.463416) (xy 404.650944 -396.492435) (xy 404.651464 -396.507462)
			(xy 404.651464 -396.621) (xy 404.652988 -396.627604) (xy 404.658179 -396.647977) (xy 404.66379 -396.689642)
			(xy 404.664164 -396.710662) (xy 405.228298 -396.710662) (xy 405.228665 -396.689641) (xy 405.234275 -396.647975)
			(xy 405.239474 -396.627604) (xy 405.241252 -396.621) (xy 405.241252 -396.507462) (xy 405.241703 -396.492443)
			(xy 405.249485 -396.46343) (xy 405.264511 -396.43742) (xy 405.285755 -396.416184) (xy 405.311771 -396.401169)
			(xy 405.340787 -396.393397) (xy 405.355806 -396.392908) (xy 405.537416 -396.392908) (xy 405.537924 -396.392654)
			(xy 405.554688 -396.392654) (xy 405.555196 -396.392908) (xy 405.736806 -396.392908) (xy 405.75182 -396.39343)
			(xy 405.780825 -396.401202) (xy 405.806831 -396.416214) (xy 405.828067 -396.437444) (xy 405.843086 -396.463445)
			(xy 405.850866 -396.492448) (xy 405.85136 -396.507462) (xy 405.85136 -396.621) (xy 405.853138 -396.627604)
			(xy 405.85833 -396.647976) (xy 405.86394 -396.689642) (xy 405.864314 -396.710662) (xy 406.428194 -396.710662)
			(xy 406.428561 -396.689641) (xy 406.434171 -396.647975) (xy 406.43937 -396.627604) (xy 406.441148 -396.621)
			(xy 406.441148 -396.507462) (xy 406.441603 -396.492443) (xy 406.449385 -396.463431) (xy 406.46441 -396.437421)
			(xy 406.485653 -396.416185) (xy 406.511669 -396.40117) (xy 406.540683 -396.393397) (xy 406.555702 -396.392908)
			(xy 406.737312 -396.392908) (xy 406.73782 -396.392654) (xy 406.754584 -396.392654) (xy 406.755092 -396.392908)
			(xy 406.936702 -396.392908) (xy 406.951716 -396.393434) (xy 406.98072 -396.401205) (xy 407.006726 -396.416216)
			(xy 407.027962 -396.437445) (xy 407.042982 -396.463446) (xy 407.050761 -396.492448) (xy 407.051256 -396.507462)
			(xy 407.051256 -396.621) (xy 407.053034 -396.627604) (xy 407.058226 -396.647976) (xy 407.063836 -396.689642)
			(xy 407.06421 -396.710662) (xy 407.06421 -396.71117) (xy 407.064039 -396.725795) (xy 407.061373 -396.754924)
			(xy 407.058876 -396.769336) (xy 407.057516 -396.77851) (xy 407.060787 -396.796752) (xy 407.065226 -396.804896)
			(xy 407.081736 -396.83182) (xy 407.086908 -396.839596) (xy 407.101633 -396.851059) (xy 407.110438 -396.854172)
			(xy 407.135326 -396.862218) (xy 407.182204 -396.885411) (xy 407.224616 -396.916019) (xy 407.261398 -396.953203)
			(xy 407.291543 -396.995944) (xy 407.314227 -397.043072) (xy 407.32202 -397.06804) (xy 407.323544 -397.073882)
			(xy 407.417778 -397.236696) (xy 407.449528 -397.249904) (xy 407.466292 -397.245586) (xy 407.476923 -397.242126)
			(xy 407.494007 -397.227748) (xy 407.503371 -397.207477) (xy 407.503884 -397.19631) (xy 407.503884 -396.0495)
			(xy 407.517346 -396.0495) (xy 407.517346 -395.877542) (xy 407.517781 -395.867474) (xy 407.525494 -395.848875)
			(xy 407.532332 -395.841474) (xy 407.596594 -395.777212) (xy 407.603318 -395.769841) (xy 407.610952 -395.751425)
			(xy 407.611014 -395.73149) (xy 407.603495 -395.713027) (xy 407.596848 -395.705584) (xy 407.595578 -395.704314)
			(xy 407.594562 -395.703298) (xy 407.586979 -395.696475) (xy 407.572617 -395.681984) (xy 407.56586 -395.674342)
			(xy 407.563393 -395.671574) (xy 407.557784 -395.666725) (xy 407.554684 -395.66469) (xy 407.54263 -395.656619)
			(xy 407.52267 -395.635581) (xy 407.508593 -395.610227) (xy 407.50129 -395.582161) (xy 407.500836 -395.567662)
			(xy 407.500836 -395.555724) (xy 407.499312 -395.54912) (xy 407.494107 -395.528751) (xy 407.488505 -395.487083)
			(xy 407.488136 -395.466062) (xy 407.488501 -395.445041) (xy 407.494112 -395.403375) (xy 407.499312 -395.383004)
			(xy 407.500836 -395.3764) (xy 407.500836 -395.262862) (xy 407.501495 -395.244743) (xy 407.512749 -395.210297)
			(xy 407.522934 -395.195298) (xy 407.527439 -395.188632) (xy 407.53248 -395.173364) (xy 407.53284 -395.165326)
			(xy 407.53284 -395.131798) (xy 407.532537 -395.12375) (xy 407.52749 -395.108467) (xy 407.522934 -395.101826)
			(xy 407.512856 -395.086771) (xy 407.501594 -395.052362) (xy 407.500836 -395.034262) (xy 407.500836 -394.920724)
			(xy 407.499312 -394.91412) (xy 407.494107 -394.893751) (xy 407.488505 -394.852083) (xy 407.488136 -394.831062)
			(xy 407.488898 -394.808456) (xy 407.48966 -394.798296) (xy 407.483564 -394.7795) (xy 407.42997 -394.717524)
			(xy 407.423054 -394.71025) (xy 407.405134 -394.701244) (xy 407.395172 -394.699998) (xy 407.371366 -394.697746)
			(xy 407.324775 -394.686996) (xy 407.28034 -394.669338) (xy 407.239079 -394.645177) (xy 407.201936 -394.615066)
			(xy 407.169762 -394.579694) (xy 407.143295 -394.539872) (xy 407.123141 -394.496513) (xy 407.116026 -394.473684)
			(xy 407.114502 -394.467842) (xy 406.794208 -393.914122) (xy 406.790144 -393.909804) (xy 406.773907 -393.892125)
			(xy 406.746489 -393.852726) (xy 406.725354 -393.809629) (xy 406.710988 -393.763828) (xy 406.703722 -393.71638)
			(xy 406.703276 -393.69238) (xy 406.703699 -393.6676) (xy 406.711451 -393.618651) (xy 406.726762 -393.571516)
			(xy 406.749254 -393.527355) (xy 406.778376 -393.487254) (xy 406.813409 -393.452199) (xy 406.853492 -393.423054)
			(xy 406.89764 -393.400535) (xy 406.944766 -393.385195) (xy 406.993711 -393.377414) (xy 407.01849 -393.376912)
			(xy 407.018998 -393.376912) (xy 407.044393 -393.377397) (xy 407.094528 -393.385528) (xy 407.142715 -393.401581)
			(xy 407.187711 -393.425141) (xy 407.228354 -393.455601) (xy 407.263596 -393.492174) (xy 407.292529 -393.533918)
			(xy 407.314405 -393.579756) (xy 407.32202 -393.603988) (xy 407.323544 -393.60983) (xy 407.643838 -394.16355)
			(xy 407.647902 -394.167868) (xy 407.664049 -394.185579) (xy 407.691396 -394.224935) (xy 407.712478 -394.267973)
			(xy 407.726811 -394.313704) (xy 407.734066 -394.361076) (xy 407.734516 -394.385038) (xy 407.734516 -394.385546)
			(xy 407.734008 -394.405866) (xy 407.733246 -394.415772) (xy 407.739596 -394.434822) (xy 407.800302 -394.504164)
			(xy 407.818082 -394.513054) (xy 407.828242 -394.513816) (xy 407.853194 -394.516008) (xy 407.901995 -394.527295)
			(xy 407.948424 -394.546089) (xy 407.991336 -394.571924) (xy 408.02967 -394.604165) (xy 408.046428 -394.622782)
			(xy 408.048894 -394.625552) (xy 408.054504 -394.6304) (xy 408.057604 -394.632434) (xy 408.069667 -394.640494)
			(xy 408.089627 -394.661535) (xy 408.103702 -394.686893) (xy 408.111001 -394.714962) (xy 408.111452 -394.729462)
			(xy 408.111452 -394.7414) (xy 408.112976 -394.748004) (xy 408.118168 -394.768376) (xy 408.123778 -394.810042)
			(xy 408.124152 -394.831062) (xy 408.123769 -394.852082) (xy 408.118169 -394.893748) (xy 408.112976 -394.91412)
			(xy 408.111452 -394.920724) (xy 408.111452 -394.980922) (xy 408.111969 -394.990925) (xy 408.119627 -395.009408)
			(xy 408.13377 -395.023559) (xy 408.152249 -395.031226) (xy 408.162252 -395.031722) (xy 408.166062 -395.031722)
			(xy 408.169872 -395.031214) (xy 408.181541 -395.029461) (xy 408.205063 -395.027553) (xy 408.216862 -395.027404)
			(xy 408.65044 -395.027404) (xy 408.66045 -395.026945) (xy 408.678942 -395.019273) (xy 408.693093 -395.005111)
			(xy 408.700752 -394.986614) (xy 408.70124 -394.976604) (xy 408.70124 -394.920724) (xy 408.699462 -394.91412)
			(xy 408.694256 -394.893751) (xy 408.688655 -394.852083) (xy 408.688286 -394.831062) (xy 408.689048 -394.808456)
			(xy 408.68981 -394.79855) (xy 408.68346 -394.779246) (xy 408.623262 -394.709904) (xy 408.605228 -394.70076)
			(xy 408.595322 -394.699998) (xy 408.571497 -394.697785) (xy 408.524868 -394.68706) (xy 408.480393 -394.669417)
			(xy 408.439092 -394.64526) (xy 408.401912 -394.615143) (xy 408.369707 -394.579757) (xy 408.343214 -394.539914)
			(xy 408.323042 -394.496528) (xy 408.315922 -394.473684) (xy 408.314398 -394.467842) (xy 407.994104 -393.914122)
			(xy 407.99004 -393.909804) (xy 407.973802 -393.892126) (xy 407.946385 -393.852726) (xy 407.925249 -393.809629)
			(xy 407.910884 -393.763828) (xy 407.903618 -393.71638) (xy 407.903172 -393.69238) (xy 407.903599 -393.667601)
			(xy 407.911351 -393.618652) (xy 407.926661 -393.571517) (xy 407.949154 -393.527356) (xy 407.978274 -393.487255)
			(xy 408.013307 -393.452201) (xy 408.05339 -393.423055) (xy 408.097537 -393.400536) (xy 408.144663 -393.385196)
			(xy 408.193607 -393.377414) (xy 408.218386 -393.376912) (xy 408.218894 -393.376912) (xy 408.244289 -393.377401)
			(xy 408.294424 -393.385531) (xy 408.342611 -393.401583) (xy 408.387606 -393.425143) (xy 408.428249 -393.455602)
			(xy 408.463492 -393.492175) (xy 408.492424 -393.533919) (xy 408.514301 -393.579756) (xy 408.521916 -393.603988)
			(xy 408.52344 -393.60983) (xy 408.843734 -394.16355) (xy 408.847798 -394.167868) (xy 408.863945 -394.185579)
			(xy 408.891292 -394.224935) (xy 408.912374 -394.267973) (xy 408.926707 -394.313704) (xy 408.933962 -394.361076)
			(xy 408.934412 -394.385038) (xy 408.934412 -394.385546) (xy 408.933904 -394.405866) (xy 408.933142 -394.415772)
			(xy 408.939492 -394.434822) (xy 409.000198 -394.504164) (xy 409.017978 -394.513054) (xy 409.028138 -394.513816)
			(xy 409.053112 -394.516032) (xy 409.10197 -394.52728) (xy 409.148457 -394.546055) (xy 409.191422 -394.571892)
			(xy 409.229801 -394.60415) (xy 409.246578 -394.622782) (xy 409.249038 -394.625557) (xy 409.254652 -394.630402)
			(xy 409.257754 -394.632434) (xy 409.269778 -394.640521) (xy 409.289673 -394.661576) (xy 409.303684 -394.68693)
			(xy 409.310923 -394.714978) (xy 409.311348 -394.729462) (xy 409.311348 -394.7414) (xy 409.313126 -394.748004)
			(xy 409.318317 -394.768377) (xy 409.323928 -394.810042) (xy 409.324302 -394.831062) (xy 409.323921 -394.852082)
			(xy 409.31832 -394.893748) (xy 409.313126 -394.91412) (xy 409.311348 -394.920724) (xy 409.311348 -394.976604)
			(xy 409.311717 -394.986632) (xy 409.319398 -395.005158) (xy 409.333586 -395.019332) (xy 409.35212 -395.026993)
			(xy 409.362148 -395.027404) (xy 409.438856 -395.027404) (xy 409.468316 -395.028128) (xy 409.526128 -395.039513)
			(xy 409.553664 -395.05001) (xy 409.563062 -395.05382) (xy 409.864052 -395.05382) (xy 409.870411 -395.053656)
			(xy 409.882748 -395.050571) (xy 409.888436 -395.047724) (xy 409.901136 -395.04112) (xy 409.901136 -394.920724)
			(xy 409.899358 -394.91412) (xy 409.894152 -394.893751) (xy 409.888551 -394.852083) (xy 409.888182 -394.831062)
			(xy 409.888944 -394.808456) (xy 409.889706 -394.798296) (xy 409.88361 -394.7795) (xy 409.830016 -394.717524)
			(xy 409.823083 -394.710268) (xy 409.805175 -394.701251) (xy 409.795218 -394.699998) (xy 409.771408 -394.69779)
			(xy 409.724815 -394.687032) (xy 409.68038 -394.669367) (xy 409.639119 -394.645199) (xy 409.601977 -394.615082)
			(xy 409.569804 -394.579705) (xy 409.543339 -394.539878) (xy 409.523185 -394.496515) (xy 409.516072 -394.473684)
			(xy 409.514548 -394.467842) (xy 409.194254 -393.914122) (xy 409.19019 -393.909804) (xy 409.174044 -393.892126)
			(xy 409.146722 -393.852812) (xy 409.125651 -393.809823) (xy 409.111315 -393.764145) (xy 409.104041 -393.716825)
			(xy 409.103576 -393.692888) (xy 409.103576 -393.69238) (xy 409.103975 -393.667586) (xy 409.111736 -393.618608)
			(xy 409.127063 -393.571448) (xy 409.14958 -393.527266) (xy 409.178731 -393.48715) (xy 409.213799 -393.452089)
			(xy 409.25392 -393.422946) (xy 409.298107 -393.400439) (xy 409.34527 -393.385121) (xy 409.39425 -393.37737)
			(xy 409.419044 -393.376912) (xy 409.444441 -393.377357) (xy 409.494578 -393.385495) (xy 409.542765 -393.401554)
			(xy 409.587761 -393.42512) (xy 409.628404 -393.455586) (xy 409.663645 -393.492164) (xy 409.692576 -393.533913)
			(xy 409.714451 -393.579754) (xy 409.722066 -393.603988) (xy 409.72359 -393.60983) (xy 410.043884 -394.16355)
			(xy 410.047948 -394.167868) (xy 410.064155 -394.18554) (xy 410.091552 -394.22489) (xy 410.112682 -394.267931)
			(xy 410.127058 -394.313674) (xy 410.13435 -394.361064) (xy 410.134816 -394.385038) (xy 410.134816 -394.385546)
			(xy 410.134054 -394.405866) (xy 410.133292 -394.415772) (xy 410.139642 -394.434822) (xy 410.200348 -394.504164)
			(xy 410.218128 -394.513054) (xy 410.228288 -394.513816) (xy 410.253237 -394.516041) (xy 410.302036 -394.527319)
			(xy 410.348466 -394.546105) (xy 410.391379 -394.571934) (xy 410.429715 -394.604167) (xy 410.446474 -394.622782)
			(xy 410.448934 -394.625557) (xy 410.454548 -394.630402) (xy 410.45765 -394.632434) (xy 410.469695 -394.640491)
			(xy 410.489581 -394.66156) (xy 410.503585 -394.686923) (xy 410.51082 -394.714976) (xy 410.511244 -394.729462)
			(xy 410.511244 -394.7414) (xy 410.513022 -394.748004) (xy 410.518213 -394.768377) (xy 410.523824 -394.810042)
			(xy 410.524198 -394.831062) (xy 410.523817 -394.852082) (xy 410.518216 -394.893748) (xy 410.513022 -394.91412)
			(xy 410.511244 -394.920724) (xy 410.511244 -394.958316) (xy 410.511608 -394.968344) (xy 410.519291 -394.986869)
			(xy 410.533481 -395.001043) (xy 410.552016 -395.008704) (xy 410.562044 -395.009116) (xy 411.050232 -395.009116)
			(xy 411.06024 -395.008639) (xy 411.078729 -395.000971) (xy 411.09288 -394.986816) (xy 411.100542 -394.968324)
			(xy 411.101032 -394.958316) (xy 411.101032 -394.920724) (xy 411.099508 -394.91412) (xy 411.094303 -394.893751)
			(xy 411.088701 -394.852083) (xy 411.088332 -394.831062) (xy 411.089094 -394.808456) (xy 411.089856 -394.79855)
			(xy 411.083506 -394.779246) (xy 411.023308 -394.709904) (xy 411.005274 -394.70076) (xy 410.995368 -394.699998)
			(xy 410.971547 -394.697748) (xy 410.924919 -394.68703) (xy 410.880444 -394.669393) (xy 410.839143 -394.645241)
			(xy 410.801963 -394.61513) (xy 410.769756 -394.579749) (xy 410.743262 -394.539909) (xy 410.723089 -394.496526)
			(xy 410.715968 -394.473684) (xy 410.714444 -394.467842) (xy 410.39415 -393.914122) (xy 410.390086 -393.909804)
			(xy 410.373939 -393.892126) (xy 410.346618 -393.852812) (xy 410.325547 -393.809823) (xy 410.311211 -393.764145)
			(xy 410.303937 -393.716825) (xy 410.303472 -393.692888) (xy 410.303472 -393.69238) (xy 410.303875 -393.667586)
			(xy 410.311636 -393.618609) (xy 410.326963 -393.571449) (xy 410.349479 -393.527267) (xy 410.37863 -393.487152)
			(xy 410.413697 -393.452091) (xy 410.453818 -393.422948) (xy 410.498004 -393.40044) (xy 410.545167 -393.385121)
			(xy 410.594146 -393.37737) (xy 410.61894 -393.376912) (xy 410.644336 -393.37736) (xy 410.694473 -393.385498)
			(xy 410.742661 -393.401556) (xy 410.787657 -393.425122) (xy 410.828299 -393.455587) (xy 410.863541 -393.492165)
			(xy 410.892472 -393.533913) (xy 410.914347 -393.579755) (xy 410.921962 -393.603988) (xy 410.923486 -393.60983)
			(xy 411.24378 -394.16355) (xy 411.247844 -394.167868) (xy 411.26405 -394.18554) (xy 411.291447 -394.22489)
			(xy 411.312578 -394.267932) (xy 411.326954 -394.313674) (xy 411.334246 -394.361064) (xy 411.334712 -394.385038)
			(xy 411.334712 -394.385546) (xy 411.33395 -394.405866) (xy 411.333188 -394.415772) (xy 411.339538 -394.434822)
			(xy 411.400244 -394.504164) (xy 411.418024 -394.513054) (xy 411.428184 -394.513816) (xy 411.453161 -394.516004)
			(xy 411.50202 -394.527259) (xy 411.548507 -394.546041) (xy 411.591471 -394.571884) (xy 411.629849 -394.604147)
			(xy 411.646624 -394.622782) (xy 411.64909 -394.625551) (xy 411.6547 -394.6304) (xy 411.6578 -394.632434)
			(xy 411.669862 -394.640495) (xy 411.689823 -394.661535) (xy 411.703898 -394.686893) (xy 411.711197 -394.714962)
			(xy 411.711648 -394.729462) (xy 411.711648 -394.7414) (xy 411.713172 -394.748004) (xy 411.718364 -394.768376)
			(xy 411.723974 -394.810042) (xy 411.724348 -394.831062) (xy 411.723965 -394.852082) (xy 411.718365 -394.893748)
			(xy 411.713172 -394.91412) (xy 411.711648 -394.920724) (xy 411.711648 -394.958316) (xy 411.712008 -394.968344)
			(xy 411.719692 -394.986871) (xy 411.733883 -395.001044) (xy 411.752419 -395.008705) (xy 411.762448 -395.009116)
			(xy 412.250128 -395.009116) (xy 412.260135 -395.008635) (xy 412.278625 -395.00097) (xy 412.292776 -394.986815)
			(xy 412.300438 -394.968324) (xy 412.300928 -394.958316) (xy 412.300928 -394.920724) (xy 412.299404 -394.91412)
			(xy 412.294199 -394.893751) (xy 412.288597 -394.852083) (xy 412.288228 -394.831062) (xy 412.28899 -394.808456)
			(xy 412.289752 -394.79855) (xy 412.283402 -394.779246) (xy 412.223204 -394.709904) (xy 412.20517 -394.70076)
			(xy 412.195264 -394.699998) (xy 412.171443 -394.697751) (xy 412.124814 -394.687032) (xy 412.08034 -394.669395)
			(xy 412.039038 -394.645243) (xy 412.001858 -394.615131) (xy 411.969652 -394.579749) (xy 411.943158 -394.53991)
			(xy 411.922985 -394.496526) (xy 411.915864 -394.473684) (xy 411.91434 -394.467842) (xy 411.593792 -393.91336)
			(xy 411.589728 -393.909042) (xy 411.573596 -393.891398) (xy 411.546352 -393.852111) (xy 411.525347 -393.809165)
			(xy 411.511062 -393.763541) (xy 411.503823 -393.716284) (xy 411.503368 -393.69238) (xy 411.503799 -393.667601)
			(xy 411.511551 -393.618652) (xy 411.526861 -393.571518) (xy 411.549353 -393.527357) (xy 411.578473 -393.487256)
			(xy 411.613506 -393.452202) (xy 411.653588 -393.423057) (xy 411.697735 -393.400537) (xy 411.744859 -393.385197)
			(xy 411.793803 -393.377414) (xy 411.818582 -393.376912) (xy 411.81909 -393.376912) (xy 411.844537 -393.377438)
			(xy 411.894773 -393.385586) (xy 411.943052 -393.401688) (xy 411.988121 -393.425327) (xy 412.028814 -393.455892)
			(xy 412.064076 -393.492589) (xy 412.092994 -393.534468) (xy 412.114818 -393.580444) (xy 412.122366 -393.60475)
			(xy 412.12389 -393.610592) (xy 412.443676 -394.16355) (xy 412.44774 -394.167868) (xy 412.463945 -394.185541)
			(xy 412.491343 -394.224891) (xy 412.512473 -394.267932) (xy 412.52685 -394.313674) (xy 412.534142 -394.361064)
			(xy 412.534608 -394.385038) (xy 412.534608 -394.385546) (xy 412.533846 -394.405866) (xy 412.533084 -394.415772)
			(xy 412.539434 -394.434822) (xy 412.60014 -394.504164) (xy 412.61792 -394.513054) (xy 412.62808 -394.513816)
			(xy 412.653057 -394.516006) (xy 412.701915 -394.527261) (xy 412.748402 -394.546042) (xy 412.791367 -394.571884)
			(xy 412.829744 -394.604148) (xy 412.84652 -394.622782) (xy 412.848987 -394.625551) (xy 412.854596 -394.6304)
			(xy 412.857696 -394.632434) (xy 412.869757 -394.640496) (xy 412.889718 -394.661536) (xy 412.903794 -394.686893)
			(xy 412.911093 -394.714962) (xy 412.911544 -394.729462) (xy 412.911544 -394.7414) (xy 412.913068 -394.748004)
			(xy 412.91826 -394.768376) (xy 412.92387 -394.810042) (xy 412.924244 -394.831062) (xy 412.923861 -394.852082)
			(xy 412.918262 -394.893748) (xy 412.913068 -394.91412) (xy 412.911544 -394.920724) (xy 412.911544 -394.958316)
			(xy 412.911908 -394.968344) (xy 412.919591 -394.986869) (xy 412.933781 -395.001043) (xy 412.952316 -395.008704)
			(xy 412.962344 -395.009116) (xy 413.46247 -395.009116) (xy 413.472086 -395.009235) (xy 413.491277 -395.010504)
			(xy 413.500824 -395.011656) (xy 413.500824 -394.920724) (xy 413.4993 -394.91412) (xy 413.494094 -394.893751)
			(xy 413.488493 -394.852083) (xy 413.488124 -394.831062) (xy 413.488886 -394.808456) (xy 413.489648 -394.798296)
			(xy 413.483552 -394.7795) (xy 413.429958 -394.717524) (xy 413.42301 -394.710285) (xy 413.405113 -394.701259)
			(xy 413.39516 -394.699998) (xy 413.371353 -394.697756) (xy 413.324762 -394.687004) (xy 413.280327 -394.669345)
			(xy 413.239066 -394.645182) (xy 413.201923 -394.615069) (xy 413.16975 -394.579696) (xy 413.143283 -394.539874)
			(xy 413.123128 -394.496513) (xy 413.116014 -394.473684) (xy 413.11449 -394.467842) (xy 412.794196 -393.914122)
			(xy 412.790132 -393.909804) (xy 412.773893 -393.892127) (xy 412.746476 -393.852727) (xy 412.725341 -393.809629)
			(xy 412.710975 -393.763828) (xy 412.70371 -393.71638) (xy 412.703264 -393.69238) (xy 412.703699 -393.667601)
			(xy 412.711451 -393.618653) (xy 412.726761 -393.571519) (xy 412.749252 -393.527358) (xy 412.778372 -393.487258)
			(xy 412.813404 -393.452203) (xy 412.853486 -393.423058) (xy 412.897632 -393.400538) (xy 412.944756 -393.385198)
			(xy 412.993699 -393.377415) (xy 413.018478 -393.376912) (xy 413.018986 -393.376912) (xy 413.044381 -393.377408)
			(xy 413.094516 -393.385537) (xy 413.142702 -393.401588) (xy 413.187698 -393.425146) (xy 413.228341 -393.455605)
			(xy 413.263583 -393.492177) (xy 413.292516 -393.53392) (xy 413.314393 -393.579757) (xy 413.322008 -393.603988)
			(xy 413.323532 -393.60983) (xy 413.643826 -394.16355) (xy 413.64789 -394.167868) (xy 413.664052 -394.185566)
			(xy 413.691393 -394.224927) (xy 413.712471 -394.267969) (xy 413.726801 -394.313702) (xy 413.734054 -394.361075)
			(xy 413.734504 -394.385038) (xy 413.734504 -394.385546) (xy 413.733996 -394.405866) (xy 413.733234 -394.415772)
			(xy 413.739584 -394.434822) (xy 413.80029 -394.504164) (xy 413.81807 -394.513054) (xy 413.82823 -394.513816)
			(xy 413.853181 -394.516015) (xy 413.901982 -394.5273) (xy 413.948412 -394.546092) (xy 413.991323 -394.571927)
			(xy 414.029658 -394.604165) (xy 414.046416 -394.622782) (xy 414.048883 -394.62555) (xy 414.054492 -394.630399)
			(xy 414.057592 -394.632434) (xy 414.069674 -394.640467) (xy 414.089626 -394.66152) (xy 414.103695 -394.686886)
			(xy 414.11099 -394.71496) (xy 414.11144 -394.729462) (xy 414.11144 -394.7414) (xy 414.112964 -394.748004)
			(xy 414.118156 -394.768376) (xy 414.123766 -394.810042) (xy 414.12414 -394.831062) (xy 414.123757 -394.852082)
			(xy 414.118158 -394.893748) (xy 414.112964 -394.91412) (xy 414.11144 -394.920724) (xy 414.11144 -395.00302)
			(xy 414.111804 -395.013048) (xy 414.119488 -395.031573) (xy 414.133678 -395.045745) (xy 414.152212 -395.053408)
			(xy 414.16224 -395.05382) (xy 414.50133 -395.05382) (xy 414.513776 -395.050518) (xy 414.519364 -395.04747)
			(xy 414.546425 -395.033305) (xy 414.604652 -395.014885) (xy 414.634934 -395.010894) (xy 414.643772 -395.00957)
			(xy 414.659772 -395.001633) (xy 414.666176 -394.9954) (xy 414.687258 -394.973302) (xy 414.693623 -394.965972)
			(xy 414.7008 -394.947949) (xy 414.701228 -394.93825) (xy 414.701228 -394.920724) (xy 414.69945 -394.91412)
			(xy 414.694243 -394.893751) (xy 414.688643 -394.852083) (xy 414.688274 -394.831062) (xy 414.689036 -394.808456)
			(xy 414.689798 -394.79855) (xy 414.683448 -394.779246) (xy 414.62325 -394.709904) (xy 414.605216 -394.70076)
			(xy 414.59531 -394.699998) (xy 414.571484 -394.697795) (xy 414.524854 -394.687068) (xy 414.480379 -394.669423)
			(xy 414.439078 -394.645265) (xy 414.401899 -394.615147) (xy 414.369694 -394.57976) (xy 414.343202 -394.539916)
			(xy 414.32303 -394.496528) (xy 414.31591 -394.473684) (xy 414.314386 -394.467842) (xy 413.994092 -393.914122)
			(xy 413.990028 -393.909804) (xy 413.973805 -393.892113) (xy 413.946382 -393.852718) (xy 413.925242 -393.809624)
			(xy 413.910873 -393.763826) (xy 413.903607 -393.71638) (xy 413.90316 -393.69238) (xy 413.903599 -393.667601)
			(xy 413.91135 -393.618653) (xy 413.92666 -393.57152) (xy 413.949152 -393.527359) (xy 413.978271 -393.487259)
			(xy 414.013302 -393.452205) (xy 414.053383 -393.423059) (xy 414.097529 -393.400539) (xy 414.144653 -393.385199)
			(xy 414.193595 -393.377415) (xy 414.218374 -393.376912) (xy 414.218882 -393.376912) (xy 414.244277 -393.377411)
			(xy 414.294411 -393.38554) (xy 414.342598 -393.40159) (xy 414.387593 -393.425148) (xy 414.428236 -393.455606)
			(xy 414.463479 -393.492178) (xy 414.492412 -393.53392) (xy 414.514289 -393.579757) (xy 414.521904 -393.603988)
			(xy 414.523428 -393.60983) (xy 414.571472 -393.692888) (xy 415.103564 -393.692888) (xy 415.103564 -393.69238)
			(xy 415.103975 -393.667586) (xy 415.111735 -393.61861) (xy 415.127062 -393.57145) (xy 415.149578 -393.527269)
			(xy 415.178727 -393.487154) (xy 415.213794 -393.452094) (xy 415.253914 -393.42295) (xy 415.298098 -393.400442)
			(xy 415.34526 -393.385123) (xy 415.394238 -393.377371) (xy 415.419032 -393.376912) (xy 415.444428 -393.377367)
			(xy 415.494565 -393.385503) (xy 415.542752 -393.401561) (xy 415.587748 -393.425126) (xy 415.628391 -393.45559)
			(xy 415.663632 -393.492167) (xy 415.692564 -393.533914) (xy 415.714439 -393.579755) (xy 415.722054 -393.603988)
			(xy 415.723578 -393.60983) (xy 415.771622 -393.692888) (xy 416.30346 -393.692888) (xy 416.30346 -393.69238)
			(xy 416.303875 -393.667586) (xy 416.311635 -393.61861) (xy 416.326962 -393.571451) (xy 416.349477 -393.52727)
			(xy 416.378626 -393.487156) (xy 416.413692 -393.452095) (xy 416.453811 -393.422952) (xy 416.497996 -393.400443)
			(xy 416.545157 -393.385124) (xy 416.594134 -393.377371) (xy 416.618928 -393.376912) (xy 416.644324 -393.377371)
			(xy 416.694461 -393.385506) (xy 416.742648 -393.401563) (xy 416.787643 -393.425127) (xy 416.828286 -393.455591)
			(xy 416.863528 -393.492168) (xy 416.89246 -393.533915) (xy 416.914335 -393.579755) (xy 416.92195 -393.603988)
			(xy 416.923474 -393.60983) (xy 416.971224 -393.69238) (xy 417.503356 -393.69238) (xy 417.503799 -393.667601)
			(xy 417.51155 -393.618654) (xy 417.52686 -393.571521) (xy 417.549351 -393.527361) (xy 417.57847 -393.48726)
			(xy 417.6135 -393.452206) (xy 417.653581 -393.423061) (xy 417.697726 -393.40054) (xy 417.744849 -393.385199)
			(xy 417.793792 -393.377415) (xy 417.81857 -393.376912) (xy 417.819078 -393.376912) (xy 417.844527 -393.37736)
			(xy 417.894767 -393.385522) (xy 417.943048 -393.401637) (xy 417.988117 -393.425288) (xy 418.02881 -393.455863)
			(xy 418.06407 -393.49257) (xy 418.092986 -393.534457) (xy 418.114807 -393.580441) (xy 418.122354 -393.60475)
			(xy 418.123878 -393.610592) (xy 418.171178 -393.69238) (xy 418.703252 -393.69238) (xy 418.703699 -393.667602)
			(xy 418.71145 -393.618654) (xy 418.726759 -393.571521) (xy 418.74925 -393.527362) (xy 418.778369 -393.487262)
			(xy 418.813399 -393.452208) (xy 418.853479 -393.423062) (xy 418.897623 -393.400542) (xy 418.944746 -393.3852)
			(xy 418.993688 -393.377415) (xy 419.018466 -393.376912) (xy 419.018974 -393.376912) (xy 419.044368 -393.377418)
			(xy 419.094503 -393.385545) (xy 419.142689 -393.401595) (xy 419.187684 -393.425152) (xy 419.228328 -393.455608)
			(xy 419.263571 -393.49218) (xy 419.292504 -393.533921) (xy 419.31438 -393.579757) (xy 419.321996 -393.603988)
			(xy 419.32352 -393.60983) (xy 419.37127 -393.69238) (xy 419.903656 -393.69238) (xy 419.904075 -393.667587)
			(xy 419.911835 -393.618611) (xy 419.927161 -393.571452) (xy 419.949676 -393.527272) (xy 419.978825 -393.487157)
			(xy 420.013891 -393.452097) (xy 420.054009 -393.422953) (xy 420.098193 -393.400444) (xy 420.145354 -393.385125)
			(xy 420.194331 -393.377371) (xy 420.219124 -393.376912) (xy 420.244572 -393.377408) (xy 420.29481 -393.385561)
			(xy 420.343089 -393.401668) (xy 420.388158 -393.425312) (xy 420.428851 -393.455881) (xy 420.464113 -393.492581)
			(xy 420.493029 -393.534464) (xy 420.514853 -393.580443) (xy 420.5224 -393.60475) (xy 420.523924 -393.610592)
			(xy 420.571517 -393.692888) (xy 421.103552 -393.692888) (xy 421.103552 -393.69238) (xy 421.104 -393.667589)
			(xy 421.111759 -393.618617) (xy 421.127084 -393.571463) (xy 421.149597 -393.527286) (xy 421.178743 -393.487175)
			(xy 421.213805 -393.452117) (xy 421.25392 -393.422976) (xy 421.2981 -393.400469) (xy 421.345256 -393.38515)
			(xy 421.394229 -393.377396) (xy 421.41902 -393.376912) (xy 421.444416 -393.377378) (xy 421.494552 -393.385512)
			(xy 421.542739 -393.401568) (xy 421.587735 -393.425131) (xy 421.628378 -393.455593) (xy 421.66362 -393.49217)
			(xy 421.692551 -393.533916) (xy 421.714427 -393.579755) (xy 421.722042 -393.603988) (xy 421.723566 -393.60983)
			(xy 422.04386 -394.16355) (xy 422.047924 -394.167868) (xy 422.064127 -394.185543) (xy 422.091525 -394.224892)
			(xy 422.112656 -394.267933) (xy 422.127034 -394.313674) (xy 422.134326 -394.361064) (xy 422.134792 -394.385038)
			(xy 422.134792 -394.385546) (xy 422.13403 -394.405612) (xy 422.133865 -394.41566) (xy 422.140391 -394.434646)
			(xy 422.14673 -394.442442) (xy 422.20134 -394.504164) (xy 422.219374 -394.513054) (xy 422.229534 -394.513562)
			(xy 422.254914 -394.515512) (xy 422.304621 -394.526467) (xy 422.35195 -394.545197) (xy 422.395693 -394.571223)
			(xy 422.434734 -394.603881) (xy 422.451784 -394.622782) (xy 422.454243 -394.625558) (xy 422.459858 -394.630402)
			(xy 422.46296 -394.632434) (xy 422.475035 -394.640476) (xy 422.49499 -394.661525) (xy 422.509061 -394.686888)
			(xy 422.516358 -394.71496) (xy 422.516808 -394.729462) (xy 422.516808 -394.7414) (xy 422.518332 -394.748004)
			(xy 422.523524 -394.768376) (xy 422.529134 -394.810042) (xy 422.529508 -394.831062) (xy 422.529126 -394.852082)
			(xy 422.523526 -394.893748) (xy 422.518332 -394.91412) (xy 422.516808 -394.920724) (xy 422.516808 -395.034262)
			(xy 422.516333 -395.04926) (xy 422.508586 -395.078238) (xy 422.49361 -395.104227) (xy 422.472423 -395.12546)
			(xy 422.446466 -395.140492) (xy 422.417505 -395.148301) (xy 422.402508 -395.148816) (xy 422.22039 -395.148816)
			(xy 422.219882 -395.14907) (xy 422.203118 -395.14907) (xy 422.20261 -395.148816) (xy 422.021 -395.148816)
			(xy 422.005972 -395.14832) (xy 421.976936 -395.140552) (xy 421.950895 -395.125543) (xy 421.929617 -395.104314)
			(xy 421.914549 -395.078307) (xy 421.906714 -395.049289) (xy 421.906192 -395.034262) (xy 421.906192 -394.920724)
			(xy 421.904668 -394.91412) (xy 421.899462 -394.893751) (xy 421.893861 -394.852083) (xy 421.893492 -394.831062)
			(xy 421.894254 -394.80871) (xy 421.895016 -394.79855) (xy 421.888666 -394.7795) (xy 421.827452 -394.70965)
			(xy 421.809418 -394.70076) (xy 421.799258 -394.700252) (xy 421.775173 -394.698281) (xy 421.727968 -394.687952)
			(xy 421.68289 -394.670545) (xy 421.640994 -394.646467) (xy 421.60326 -394.616281) (xy 421.570572 -394.580693)
			(xy 421.543693 -394.540537) (xy 421.523253 -394.49675) (xy 421.516048 -394.473684) (xy 421.514524 -394.467842)
			(xy 421.19423 -393.914122) (xy 421.190166 -393.909804) (xy 421.174016 -393.892129) (xy 421.146696 -393.852814)
			(xy 421.125626 -393.809824) (xy 421.11129 -393.764145) (xy 421.104017 -393.716825) (xy 421.103552 -393.692888)
			(xy 420.571517 -393.692888) (xy 420.84371 -394.16355) (xy 420.847774 -394.167868) (xy 420.863933 -394.185568)
			(xy 420.891276 -394.224928) (xy 420.912354 -394.267969) (xy 420.926685 -394.313702) (xy 420.933938 -394.361075)
			(xy 420.934388 -394.385038) (xy 420.934388 -394.385546) (xy 420.93388 -394.405866) (xy 420.933118 -394.415772)
			(xy 420.939468 -394.434822) (xy 421.000174 -394.504164) (xy 421.017954 -394.513054) (xy 421.028114 -394.513816)
			(xy 421.053093 -394.515986) (xy 421.101952 -394.527246) (xy 421.148439 -394.546032) (xy 421.191403 -394.571878)
			(xy 421.229779 -394.604146) (xy 421.246554 -394.622782) (xy 421.249016 -394.625555) (xy 421.254629 -394.630401)
			(xy 421.25773 -394.632434) (xy 421.269771 -394.640497) (xy 421.289659 -394.661563) (xy 421.303664 -394.686924)
			(xy 421.3109 -394.714977) (xy 421.311324 -394.729462) (xy 421.311324 -394.7414) (xy 421.313102 -394.748004)
			(xy 421.318293 -394.768377) (xy 421.323904 -394.810042) (xy 421.324278 -394.831062) (xy 421.323897 -394.852082)
			(xy 421.318297 -394.893749) (xy 421.313102 -394.91412) (xy 421.311324 -394.920724) (xy 421.311324 -395.034262)
			(xy 421.310874 -395.049285) (xy 421.303105 -395.07831) (xy 421.288085 -395.104333) (xy 421.266839 -395.12558)
			(xy 421.240817 -395.140601) (xy 421.211793 -395.148373) (xy 421.19677 -395.148816) (xy 421.01516 -395.148816)
			(xy 421.014652 -395.14907) (xy 420.997888 -395.14907) (xy 420.99738 -395.148816) (xy 420.81577 -395.148816)
			(xy 420.800743 -395.148434) (xy 420.771715 -395.140647) (xy 420.745691 -395.125612) (xy 420.724446 -395.104355)
			(xy 420.709427 -395.078322) (xy 420.701657 -395.049289) (xy 420.701216 -395.034262) (xy 420.701216 -394.920724)
			(xy 420.699438 -394.91412) (xy 420.694231 -394.893751) (xy 420.688631 -394.852083) (xy 420.688262 -394.831062)
			(xy 420.689024 -394.808456) (xy 420.689786 -394.79855) (xy 420.683436 -394.779246) (xy 420.623238 -394.709904)
			(xy 420.605204 -394.70076) (xy 420.595298 -394.699998) (xy 420.571471 -394.697805) (xy 420.524841 -394.687076)
			(xy 420.480366 -394.669429) (xy 420.439065 -394.645269) (xy 420.401886 -394.61515) (xy 420.369681 -394.579762)
			(xy 420.343189 -394.539917) (xy 420.323018 -394.496528) (xy 420.315898 -394.473684) (xy 420.314374 -394.467842)
			(xy 419.993826 -393.91336) (xy 419.989762 -393.909042) (xy 419.973688 -393.89136) (xy 419.946495 -393.852067)
			(xy 419.925539 -393.809123) (xy 419.911296 -393.763511) (xy 419.904094 -393.716272) (xy 419.903656 -393.69238)
			(xy 419.37127 -393.69238) (xy 419.643814 -394.16355) (xy 419.647878 -394.167868) (xy 419.664038 -394.185567)
			(xy 419.69138 -394.224928) (xy 419.712459 -394.267969) (xy 419.726789 -394.313702) (xy 419.734042 -394.361075)
			(xy 419.734492 -394.385038) (xy 419.734492 -394.385546) (xy 419.733984 -394.405866) (xy 419.733222 -394.415772)
			(xy 419.739572 -394.434822) (xy 419.800278 -394.504164) (xy 419.818058 -394.513054) (xy 419.828218 -394.513816)
			(xy 419.853198 -394.515983) (xy 419.902056 -394.527244) (xy 419.948543 -394.54603) (xy 419.991507 -394.571878)
			(xy 420.029883 -394.604145) (xy 420.046658 -394.622782) (xy 420.04912 -394.625555) (xy 420.054733 -394.630401)
			(xy 420.057834 -394.632434) (xy 420.069875 -394.640496) (xy 420.089764 -394.661562) (xy 420.103768 -394.686924)
			(xy 420.111004 -394.714977) (xy 420.111428 -394.729462) (xy 420.111428 -394.7414) (xy 420.113206 -394.748004)
			(xy 420.118397 -394.768377) (xy 420.124008 -394.810042) (xy 420.124382 -394.831062) (xy 420.124001 -394.852082)
			(xy 420.1184 -394.893749) (xy 420.113206 -394.91412) (xy 420.111428 -394.920724) (xy 420.111428 -395.034262)
			(xy 420.110974 -395.049285) (xy 420.103205 -395.078309) (xy 420.088186 -395.104332) (xy 420.066941 -395.125578)
			(xy 420.04092 -395.1406) (xy 420.011897 -395.148373) (xy 419.996874 -395.148816) (xy 419.815264 -395.148816)
			(xy 419.814756 -395.14907) (xy 419.797992 -395.14907) (xy 419.797484 -395.148816) (xy 419.615874 -395.148816)
			(xy 419.600847 -395.14843) (xy 419.571819 -395.140644) (xy 419.545796 -395.125611) (xy 419.52455 -395.104353)
			(xy 419.509531 -395.078321) (xy 419.501762 -395.049289) (xy 419.50132 -395.034262) (xy 419.50132 -394.920724)
			(xy 419.499542 -394.91412) (xy 419.494335 -394.893751) (xy 419.488735 -394.852083) (xy 419.488366 -394.831062)
			(xy 419.489128 -394.808456) (xy 419.48989 -394.79855) (xy 419.48354 -394.779246) (xy 419.423342 -394.709904)
			(xy 419.405308 -394.70076) (xy 419.395402 -394.699998) (xy 419.371575 -394.697801) (xy 419.324946 -394.687073)
			(xy 419.28047 -394.669427) (xy 419.23917 -394.645268) (xy 419.20199 -394.615149) (xy 419.169786 -394.579761)
			(xy 419.143294 -394.539916) (xy 419.123122 -394.496528) (xy 419.116002 -394.473684) (xy 419.114478 -394.467842)
			(xy 418.794184 -393.914122) (xy 418.79012 -393.909804) (xy 418.773895 -393.892114) (xy 418.746473 -393.852719)
			(xy 418.725334 -393.809625) (xy 418.710965 -393.763826) (xy 418.703699 -393.71638) (xy 418.703252 -393.69238)
			(xy 418.171178 -393.69238) (xy 418.443664 -394.16355) (xy 418.447728 -394.167868) (xy 418.463931 -394.185543)
			(xy 418.49133 -394.224892) (xy 418.512461 -394.267932) (xy 418.526838 -394.313674) (xy 418.53413 -394.361064)
			(xy 418.534596 -394.385038) (xy 418.534596 -394.385546) (xy 418.533834 -394.405866) (xy 418.533072 -394.415772)
			(xy 418.539422 -394.434822) (xy 418.600128 -394.504164) (xy 418.617908 -394.513054) (xy 418.628068 -394.513816)
			(xy 418.653044 -394.516014) (xy 418.701902 -394.527266) (xy 418.748389 -394.546046) (xy 418.791354 -394.571886)
			(xy 418.829732 -394.604148) (xy 418.846508 -394.622782) (xy 418.848976 -394.625549) (xy 418.854585 -394.630399)
			(xy 418.857684 -394.632434) (xy 418.869764 -394.640469) (xy 418.889717 -394.661522) (xy 418.903786 -394.686887)
			(xy 418.911082 -394.71496) (xy 418.911532 -394.729462) (xy 418.911532 -394.7414) (xy 418.913056 -394.748004)
			(xy 418.918248 -394.768376) (xy 418.923858 -394.810042) (xy 418.924232 -394.831062) (xy 418.92385 -394.852082)
			(xy 418.91825 -394.893748) (xy 418.913056 -394.91412) (xy 418.911532 -394.920724) (xy 418.911532 -395.034262)
			(xy 418.911033 -395.049258) (xy 418.903289 -395.078232) (xy 418.888316 -395.104219) (xy 418.867134 -395.125451)
			(xy 418.841183 -395.140485) (xy 418.812227 -395.148298) (xy 418.797232 -395.148816) (xy 418.615114 -395.148816)
			(xy 418.614606 -395.14907) (xy 418.597842 -395.14907) (xy 418.597334 -395.148816) (xy 418.415724 -395.148816)
			(xy 418.400697 -395.148299) (xy 418.371662 -395.140536) (xy 418.345621 -395.125532) (xy 418.324342 -395.104307)
			(xy 418.309274 -395.078303) (xy 418.301439 -395.049288) (xy 418.300916 -395.034262) (xy 418.300916 -394.920724)
			(xy 418.299392 -394.91412) (xy 418.294186 -394.893751) (xy 418.288585 -394.852083) (xy 418.288216 -394.831062)
			(xy 418.288978 -394.808456) (xy 418.28974 -394.79855) (xy 418.28339 -394.779246) (xy 418.223192 -394.709904)
			(xy 418.205158 -394.70076) (xy 418.195252 -394.699998) (xy 418.17143 -394.697761) (xy 418.124801 -394.68704)
			(xy 418.080326 -394.669401) (xy 418.039025 -394.645248) (xy 418.001845 -394.615134) (xy 417.969639 -394.579752)
			(xy 417.943146 -394.539911) (xy 417.922972 -394.496527) (xy 417.915852 -394.473684) (xy 417.914328 -394.467842)
			(xy 417.59378 -393.91336) (xy 417.589716 -393.909042) (xy 417.573599 -393.891384) (xy 417.54635 -393.852103)
			(xy 417.525341 -393.80916) (xy 417.511052 -393.763538) (xy 417.503811 -393.716283) (xy 417.503356 -393.69238)
			(xy 416.971224 -393.69238) (xy 417.243768 -394.16355) (xy 417.247832 -394.167868) (xy 417.264036 -394.185542)
			(xy 417.291434 -394.224891) (xy 417.312565 -394.267932) (xy 417.326942 -394.313674) (xy 417.334234 -394.361064)
			(xy 417.3347 -394.385038) (xy 417.3347 -394.385546) (xy 417.333938 -394.405866) (xy 417.333176 -394.415772)
			(xy 417.339526 -394.434822) (xy 417.400232 -394.504164) (xy 417.418012 -394.513054) (xy 417.428172 -394.513816)
			(xy 417.453149 -394.516011) (xy 417.502007 -394.527265) (xy 417.548494 -394.546044) (xy 417.591458 -394.571886)
			(xy 417.629836 -394.604148) (xy 417.646612 -394.622782) (xy 417.64908 -394.62555) (xy 417.654688 -394.630399)
			(xy 417.657788 -394.632434) (xy 417.669869 -394.640468) (xy 417.689822 -394.661521) (xy 417.703891 -394.686886)
			(xy 417.711186 -394.71496) (xy 417.711636 -394.729462) (xy 417.711636 -394.7414) (xy 417.71316 -394.748004)
			(xy 417.718352 -394.768376) (xy 417.723962 -394.810042) (xy 417.724336 -394.831062) (xy 417.723953 -394.852082)
			(xy 417.718354 -394.893748) (xy 417.71316 -394.91412) (xy 417.711636 -394.920724) (xy 417.711636 -395.034262)
			(xy 417.711133 -395.049258) (xy 417.703389 -395.078231) (xy 417.688417 -395.104218) (xy 417.667236 -395.12545)
			(xy 417.641286 -395.140484) (xy 417.61233 -395.148297) (xy 417.597336 -395.148816) (xy 417.415218 -395.148816)
			(xy 417.41471 -395.14907) (xy 417.397946 -395.14907) (xy 417.397438 -395.148816) (xy 417.215828 -395.148816)
			(xy 417.200801 -395.148295) (xy 417.171766 -395.140534) (xy 417.145725 -395.125531) (xy 417.124447 -395.104306)
			(xy 417.109378 -395.078303) (xy 417.101543 -395.049288) (xy 417.10102 -395.034262) (xy 417.10102 -394.920724)
			(xy 417.099496 -394.91412) (xy 417.09429 -394.893751) (xy 417.088689 -394.852083) (xy 417.08832 -394.831062)
			(xy 417.089082 -394.808456) (xy 417.089844 -394.79855) (xy 417.083494 -394.779246) (xy 417.023296 -394.709904)
			(xy 417.005262 -394.70076) (xy 416.995356 -394.699998) (xy 416.971534 -394.697758) (xy 416.924906 -394.687038)
			(xy 416.880431 -394.669399) (xy 416.839129 -394.645246) (xy 416.801949 -394.615133) (xy 416.769743 -394.579751)
			(xy 416.74325 -394.539911) (xy 416.723076 -394.496527) (xy 416.715956 -394.473684) (xy 416.714432 -394.467842)
			(xy 416.394138 -393.914122) (xy 416.390074 -393.909804) (xy 416.373925 -393.892128) (xy 416.346605 -393.852814)
			(xy 416.325534 -393.809824) (xy 416.311198 -393.764145) (xy 416.303925 -393.716825) (xy 416.30346 -393.692888)
			(xy 415.771622 -393.692888) (xy 416.043872 -394.16355) (xy 416.047936 -394.167868) (xy 416.064141 -394.185542)
			(xy 416.091539 -394.224891) (xy 416.112669 -394.267932) (xy 416.127046 -394.313674) (xy 416.134338 -394.361064)
			(xy 416.134804 -394.385038) (xy 416.134804 -394.385546) (xy 416.134042 -394.405866) (xy 416.13328 -394.415772)
			(xy 416.13963 -394.434822) (xy 416.200336 -394.504164) (xy 416.218116 -394.513054) (xy 416.228276 -394.513816)
			(xy 416.253224 -394.516048) (xy 416.302024 -394.527325) (xy 416.348453 -394.546109) (xy 416.391366 -394.571936)
			(xy 416.429702 -394.604168) (xy 416.446462 -394.622782) (xy 416.448923 -394.625556) (xy 416.454536 -394.630401)
			(xy 416.457638 -394.632434) (xy 416.46968 -394.640495) (xy 416.489568 -394.661562) (xy 416.503572 -394.686923)
			(xy 416.510808 -394.714977) (xy 416.511232 -394.729462) (xy 416.511232 -394.7414) (xy 416.51301 -394.748004)
			(xy 416.518201 -394.768377) (xy 416.523812 -394.810042) (xy 416.524186 -394.831062) (xy 416.523805 -394.852082)
			(xy 416.518204 -394.893749) (xy 416.51301 -394.91412) (xy 416.511232 -394.920724) (xy 416.511232 -395.034262)
			(xy 416.510589 -395.052383) (xy 416.499324 -395.086828) (xy 416.489134 -395.101826) (xy 416.484647 -395.108489)
			(xy 416.479725 -395.123769) (xy 416.479482 -395.131798) (xy 416.479482 -395.165326) (xy 416.479795 -395.173344)
			(xy 416.484703 -395.188609) (xy 416.489134 -395.195298) (xy 416.499228 -395.210343) (xy 416.510479 -395.24476)
			(xy 416.511232 -395.262862) (xy 416.511232 -395.3764) (xy 416.51301 -395.383004) (xy 416.518201 -395.403377)
			(xy 416.523812 -395.445042) (xy 416.524186 -395.466062) (xy 416.523805 -395.487082) (xy 416.518204 -395.528749)
			(xy 416.51301 -395.54912) (xy 416.511232 -395.555724) (xy 416.511232 -395.567662) (xy 416.510743 -395.583032)
			(xy 416.502614 -395.612678) (xy 416.486926 -395.639114) (xy 416.4648 -395.660454) (xy 416.451542 -395.668246)
			(xy 416.447732 -395.672818) (xy 416.440424 -395.682285) (xy 416.434739 -395.705487) (xy 416.43681 -395.717268)
			(xy 416.443922 -395.749018) (xy 416.447229 -395.760518) (xy 416.462449 -395.778938) (xy 416.473132 -395.784324)
			(xy 416.494554 -395.794071) (xy 416.534508 -395.818943) (xy 416.570359 -395.849433) (xy 416.586162 -395.866874)
			(xy 416.588625 -395.869646) (xy 416.594237 -395.874493) (xy 416.597338 -395.876526) (xy 416.609502 -395.884579)
			(xy 416.629584 -395.90573) (xy 416.643724 -395.93124) (xy 416.651019 -395.959479) (xy 416.65144 -395.974062)
			(xy 416.65144 -395.986508) (xy 416.653218 -395.992858) (xy 416.658351 -396.013172) (xy 416.663826 -396.054712)
			(xy 416.66414 -396.075662) (xy 416.663806 -396.096611) (xy 416.65833 -396.138148) (xy 416.653218 -396.158466)
			(xy 416.65144 -396.164816) (xy 416.65144 -396.621508) (xy 416.653218 -396.627858) (xy 416.658351 -396.648172)
			(xy 416.663826 -396.689712) (xy 416.66414 -396.710662) (xy 417.228274 -396.710662) (xy 417.228641 -396.689641)
			(xy 417.234251 -396.647975) (xy 417.23945 -396.627604) (xy 417.241228 -396.621) (xy 417.241228 -396.507462)
			(xy 417.241702 -396.492445) (xy 417.249483 -396.463436) (xy 417.264505 -396.437428) (xy 417.285744 -396.416192)
			(xy 417.311755 -396.401175) (xy 417.340765 -396.3934) (xy 417.355782 -396.392908) (xy 417.537392 -396.392908)
			(xy 417.5379 -396.392654) (xy 417.554664 -396.392654) (xy 417.555172 -396.392908) (xy 417.736782 -396.392908)
			(xy 417.751795 -396.393452) (xy 417.780799 -396.401217) (xy 417.806805 -396.416224) (xy 417.828041 -396.437451)
			(xy 417.843061 -396.463449) (xy 417.850841 -396.492449) (xy 417.851336 -396.507462) (xy 417.851336 -396.621)
			(xy 417.853114 -396.627604) (xy 417.858305 -396.647977) (xy 417.863916 -396.689642) (xy 417.86429 -396.710662)
			(xy 418.42817 -396.710662) (xy 418.428537 -396.689641) (xy 418.434147 -396.647975) (xy 418.439346 -396.627604)
			(xy 418.441124 -396.621) (xy 418.441124 -396.507462) (xy 418.441602 -396.492445) (xy 418.449383 -396.463437)
			(xy 418.464404 -396.437429) (xy 418.485642 -396.416194) (xy 418.511652 -396.401177) (xy 418.540661 -396.3934)
			(xy 418.555678 -396.392908) (xy 418.737288 -396.392908) (xy 418.737796 -396.392654) (xy 418.75456 -396.392654)
			(xy 418.755068 -396.392908) (xy 418.936678 -396.392908) (xy 418.951691 -396.393455) (xy 418.980694 -396.40122)
			(xy 419.006701 -396.416226) (xy 419.027937 -396.437452) (xy 419.042957 -396.46345) (xy 419.050737 -396.49245)
			(xy 419.051232 -396.507462) (xy 419.051232 -396.621) (xy 419.05301 -396.627604) (xy 419.058201 -396.647977)
			(xy 419.063812 -396.689642) (xy 419.064186 -396.710662) (xy 419.62832 -396.710662) (xy 419.628686 -396.689641)
			(xy 419.634297 -396.647975) (xy 419.639496 -396.627604) (xy 419.64102 -396.621) (xy 419.64102 -396.507462)
			(xy 419.641499 -396.492467) (xy 419.649258 -396.463497) (xy 419.664238 -396.437515) (xy 419.685422 -396.416286)
			(xy 419.711372 -396.401251) (xy 419.740326 -396.393431) (xy 419.75532 -396.392908) (xy 419.937438 -396.392908)
			(xy 419.937946 -396.392654) (xy 419.95471 -396.392654) (xy 419.955218 -396.392908) (xy 420.136828 -396.392908)
			(xy 420.15186 -396.393356) (xy 420.1809 -396.401133) (xy 420.206944 -396.416151) (xy 420.228221 -396.437389)
			(xy 420.243287 -396.463405) (xy 420.251117 -396.492431) (xy 420.251636 -396.507462) (xy 420.251636 -396.621)
			(xy 420.25316 -396.627604) (xy 420.258352 -396.647976) (xy 420.263962 -396.689642) (xy 420.264336 -396.710662)
			(xy 420.828216 -396.710662) (xy 420.828582 -396.689641) (xy 420.834193 -396.647975) (xy 420.839392 -396.627604)
			(xy 420.840916 -396.621) (xy 420.840916 -396.507462) (xy 420.841399 -396.492467) (xy 420.849157 -396.463498)
			(xy 420.864137 -396.437516) (xy 420.88532 -396.416287) (xy 420.911269 -396.401252) (xy 420.940222 -396.393432)
			(xy 420.955216 -396.392908) (xy 421.137334 -396.392908) (xy 421.137842 -396.392654) (xy 421.154606 -396.392654)
			(xy 421.155114 -396.392908) (xy 421.336724 -396.392908) (xy 421.351755 -396.393359) (xy 421.380796 -396.401135)
			(xy 421.406839 -396.416152) (xy 421.428117 -396.43739) (xy 421.443183 -396.463406) (xy 421.451013 -396.492431)
			(xy 421.451532 -396.507462) (xy 421.451532 -396.621) (xy 421.453056 -396.627604) (xy 421.458248 -396.647976)
			(xy 421.463858 -396.689642) (xy 421.464232 -396.710662) (xy 421.464232 -396.71117) (xy 421.464063 -396.725795)
			(xy 421.461395 -396.754924) (xy 421.458898 -396.769336) (xy 421.457535 -396.77851) (xy 421.460807 -396.796752)
			(xy 421.465248 -396.804896) (xy 421.481758 -396.83182) (xy 421.486922 -396.839602) (xy 421.501652 -396.851062)
			(xy 421.51046 -396.854172) (xy 421.535352 -396.862205) (xy 421.58223 -396.885402) (xy 421.624641 -396.916013)
			(xy 421.661422 -396.953199) (xy 421.691567 -396.995942) (xy 421.714249 -397.043071) (xy 421.722042 -397.06804)
			(xy 421.723566 -397.073882) (xy 422.04386 -397.627602) (xy 422.047924 -397.63192) (xy 422.06412 -397.649635)
			(xy 422.091544 -397.689024) (xy 422.112688 -397.732112) (xy 422.127064 -397.777905) (xy 422.13434 -397.825346)
			(xy 422.134792 -397.849344) (xy 422.134324 -397.874121) (xy 422.12657 -397.923065) (xy 422.11126 -397.970194)
			(xy 422.08877 -398.014351) (xy 422.059654 -398.054449) (xy 422.024627 -398.089502) (xy 421.984551 -398.118648)
			(xy 421.940411 -398.14117) (xy 421.893292 -398.156515) (xy 421.844355 -398.164305) (xy 421.819578 -398.164812)
			(xy 421.81907 -398.164812) (xy 421.793675 -398.164338) (xy 421.74354 -398.156203) (xy 421.695354 -398.140147)
			(xy 421.650359 -398.116585) (xy 421.609717 -398.086123) (xy 421.574475 -398.049549) (xy 421.545542 -398.007805)
			(xy 421.523664 -397.961968) (xy 421.516048 -397.937736) (xy 421.514524 -397.931894) (xy 421.19423 -397.378174)
			(xy 421.190166 -397.373856) (xy 421.174009 -397.35612) (xy 421.14664 -397.316719) (xy 421.125548 -397.27363)
			(xy 421.111221 -397.227845) (xy 421.103986 -397.180419) (xy 421.103552 -397.156432) (xy 421.103733 -397.142384)
			(xy 421.106274 -397.114402) (xy 421.108632 -397.100552) (xy 421.10995 -397.091272) (xy 421.106424 -397.072876)
			(xy 421.101774 -397.064738) (xy 421.08501 -397.037814) (xy 421.07981 -397.030109) (xy 421.065083 -397.018786)
			(xy 421.056308 -397.015716) (xy 421.034676 -397.008932) (xy 420.993463 -396.990045) (xy 420.955344 -396.965505)
			(xy 420.92109 -396.935807) (xy 420.90594 -396.918942) (xy 420.903476 -396.916171) (xy 420.897865 -396.911324)
			(xy 420.894764 -396.90929) (xy 420.882705 -396.901225) (xy 420.862747 -396.880184) (xy 420.848672 -396.854828)
			(xy 420.84137 -396.826761) (xy 420.840916 -396.812262) (xy 420.840916 -396.800324) (xy 420.839392 -396.79372)
			(xy 420.834186 -396.773351) (xy 420.828585 -396.731683) (xy 420.828216 -396.710662) (xy 420.264336 -396.710662)
			(xy 420.264336 -396.71117) (xy 420.264167 -396.725795) (xy 420.261499 -396.754924) (xy 420.259002 -396.769336)
			(xy 420.257639 -396.77851) (xy 420.260911 -396.796752) (xy 420.265352 -396.804896) (xy 420.281862 -396.83182)
			(xy 420.287025 -396.839603) (xy 420.301756 -396.851063) (xy 420.310564 -396.854172) (xy 420.335496 -396.862285)
			(xy 420.38246 -396.885584) (xy 420.424939 -396.916311) (xy 420.461766 -396.953623) (xy 420.491935 -396.9965)
			(xy 420.514618 -397.043765) (xy 420.5224 -397.068802) (xy 420.523924 -397.074644) (xy 420.84371 -397.627602)
			(xy 420.847774 -397.63192) (xy 420.863942 -397.649579) (xy 420.891258 -397.688899) (xy 420.912324 -397.731893)
			(xy 420.926656 -397.777575) (xy 420.933925 -397.824898) (xy 420.934388 -397.848836) (xy 420.934388 -397.849344)
			(xy 420.933872 -397.874792) (xy 420.925702 -397.925027) (xy 420.90958 -397.973302) (xy 420.885925 -398.018366)
			(xy 420.855349 -398.059053) (xy 420.818642 -398.094309) (xy 420.79799 -398.109186) (xy 420.789488 -398.115662)
			(xy 420.778298 -398.133842) (xy 420.775462 -398.155) (xy 420.781468 -398.175485) (xy 420.795281 -398.191762)
			(xy 420.814516 -398.201021) (xy 420.825168 -398.201896) (xy 420.83482 -398.201388) (xy 420.843334 -398.200094)
			(xy 420.860499 -398.198695) (xy 420.86911 -398.198594) (xy 420.869364 -398.198848) (xy 421.168576 -398.198848)
			(xy 421.16883 -398.198594) (xy 421.189876 -398.199006) (xy 421.231196 -398.207001) (xy 421.270151 -398.222931)
			(xy 421.305233 -398.246179) (xy 421.335084 -398.275847) (xy 421.358549 -398.310785) (xy 421.374719 -398.349641)
			(xy 421.382968 -398.390911) (xy 421.38346 -398.411954) (xy 421.38346 -398.615916) (xy 422.0083 -398.615916)
			(xy 422.0083 -398.411954) (xy 422.008873 -398.390896) (xy 422.017116 -398.349595) (xy 422.033293 -398.31071)
			(xy 422.056777 -398.275749) (xy 422.086658 -398.246068) (xy 422.121775 -398.222819) (xy 422.160767 -398.206903)
			(xy 422.202123 -398.198937) (xy 422.223184 -398.198594) (xy 422.223438 -398.198848) (xy 422.52265 -398.198848)
			(xy 422.522904 -398.198594) (xy 422.543967 -398.198959) (xy 422.585328 -398.206921) (xy 422.624326 -398.222833)
			(xy 422.659452 -398.246077) (xy 422.689343 -398.275753) (xy 422.71284 -398.310709) (xy 422.729033 -398.349592)
			(xy 422.737294 -398.390894) (xy 422.737788 -398.411954) (xy 422.737788 -398.666716) (xy 422.728644 -398.666716)
			(xy 422.718624 -398.667156) (xy 422.700105 -398.674814) (xy 422.68593 -398.688981) (xy 422.678261 -398.707496)
			(xy 422.677844 -398.717516) (xy 422.677844 -398.881092) (xy 422.677306 -398.891094) (xy 422.669658 -398.909577)
			(xy 422.655521 -398.923729) (xy 422.637045 -398.931396) (xy 422.627044 -398.931892) (xy 422.119044 -398.931892)
			(xy 422.109025 -398.931444) (xy 422.090507 -398.923787) (xy 422.076333 -398.909623) (xy 422.068663 -398.891111)
			(xy 422.068244 -398.881092) (xy 422.068244 -398.666716) (xy 422.0591 -398.666716) (xy 422.049094 -398.666212)
			(xy 422.030606 -398.658556) (xy 422.016453 -398.644408) (xy 422.008791 -398.625922) (xy 422.0083 -398.615916)
			(xy 421.38346 -398.615916) (xy 421.38346 -398.666716) (xy 421.374316 -398.666716) (xy 421.364294 -398.667133)
			(xy 421.345774 -398.674801) (xy 421.331601 -398.688974) (xy 421.323933 -398.707494) (xy 421.323516 -398.717516)
			(xy 421.323516 -398.881092) (xy 421.323006 -398.891097) (xy 421.315352 -398.909586) (xy 421.301206 -398.923738)
			(xy 421.282721 -398.931401) (xy 421.272716 -398.931892) (xy 420.765224 -398.931892) (xy 420.755203 -398.93146)
			(xy 420.736685 -398.923797) (xy 420.722512 -398.909628) (xy 420.714843 -398.891113) (xy 420.714424 -398.881092)
			(xy 420.714424 -398.717516) (xy 420.713899 -398.707512) (xy 420.70625 -398.689025) (xy 420.692108 -398.674873)
			(xy 420.673627 -398.667208) (xy 420.663624 -398.666716) (xy 420.65448 -398.666716) (xy 420.65448 -398.411446)
			(xy 420.655268 -398.385724) (xy 420.667599 -398.335778) (xy 420.678864 -398.31264) (xy 420.684706 -398.30121)
			(xy 420.684452 -398.27581) (xy 420.630858 -398.178782) (xy 420.609268 -398.165066) (xy 420.596314 -398.16405)
			(xy 420.572417 -398.16194) (xy 420.525629 -398.151338) (xy 420.480988 -398.133769) (xy 420.439524 -398.10964)
			(xy 420.402194 -398.079508) (xy 420.36986 -398.044068) (xy 420.343269 -398.004138) (xy 420.323034 -397.960641)
			(xy 420.315898 -397.937736) (xy 420.314374 -397.931894) (xy 419.993826 -397.377412) (xy 419.989762 -397.373094)
			(xy 419.973665 -397.355432) (xy 419.946476 -397.316133) (xy 419.925523 -397.273185) (xy 419.911286 -397.227568)
			(xy 419.904091 -397.180326) (xy 419.903656 -397.156432) (xy 419.903837 -397.142384) (xy 419.906378 -397.114402)
			(xy 419.908736 -397.100552) (xy 419.910053 -397.091272) (xy 419.906528 -397.072876) (xy 419.901878 -397.064738)
			(xy 419.885114 -397.037814) (xy 419.879913 -397.03011) (xy 419.865187 -397.018787) (xy 419.856412 -397.015716)
			(xy 419.834781 -397.008931) (xy 419.793567 -396.990044) (xy 419.755449 -396.965504) (xy 419.721194 -396.935807)
			(xy 419.706044 -396.918942) (xy 419.703579 -396.916172) (xy 419.697968 -396.911324) (xy 419.694868 -396.90929)
			(xy 419.68281 -396.901224) (xy 419.662852 -396.880184) (xy 419.648776 -396.854828) (xy 419.641474 -396.826761)
			(xy 419.64102 -396.812262) (xy 419.64102 -396.800324) (xy 419.639496 -396.79372) (xy 419.63429 -396.773351)
			(xy 419.628689 -396.731683) (xy 419.62832 -396.710662) (xy 419.064186 -396.710662) (xy 419.064186 -396.71117)
			(xy 419.064016 -396.725795) (xy 419.061349 -396.754924) (xy 419.058852 -396.769336) (xy 419.057481 -396.77851)
			(xy 419.060757 -396.796753) (xy 419.065202 -396.804896) (xy 419.081712 -396.83182) (xy 419.086893 -396.839589)
			(xy 419.101611 -396.851056) (xy 419.110414 -396.854172) (xy 419.135297 -396.862231) (xy 419.182176 -396.885422)
			(xy 419.224588 -396.916027) (xy 419.261371 -396.953208) (xy 419.291518 -396.995947) (xy 419.314202 -397.043072)
			(xy 419.321996 -397.06804) (xy 419.32352 -397.073882) (xy 419.643814 -397.627602) (xy 419.647878 -397.63192)
			(xy 419.664047 -397.649578) (xy 419.691363 -397.688899) (xy 419.712428 -397.731893) (xy 419.72676 -397.777575)
			(xy 419.734029 -397.824898) (xy 419.734492 -397.848836) (xy 419.734492 -397.849344) (xy 419.733974 -397.874792)
			(xy 419.725804 -397.925027) (xy 419.709683 -397.973301) (xy 419.686028 -398.018365) (xy 419.655452 -398.059052)
			(xy 419.618746 -398.094308) (xy 419.598094 -398.109186) (xy 419.58959 -398.11566) (xy 419.578399 -398.13384)
			(xy 419.575562 -398.155) (xy 419.581569 -398.175486) (xy 419.595382 -398.191763) (xy 419.614619 -398.201022)
			(xy 419.625272 -398.201896) (xy 419.634924 -398.201388) (xy 419.643438 -398.200093) (xy 419.660603 -398.198695)
			(xy 419.669214 -398.198594) (xy 419.669468 -398.198848) (xy 419.96868 -398.198848) (xy 419.968934 -398.198594)
			(xy 419.98998 -398.199002) (xy 420.0313 -398.206998) (xy 420.070255 -398.222928) (xy 420.105337 -398.246178)
			(xy 420.135188 -398.275846) (xy 420.158653 -398.310784) (xy 420.174823 -398.349641) (xy 420.183072 -398.390911)
			(xy 420.183564 -398.411954) (xy 420.183564 -398.666716) (xy 420.17442 -398.666716) (xy 420.164398 -398.667137)
			(xy 420.145879 -398.674803) (xy 420.131705 -398.688975) (xy 420.124037 -398.707494) (xy 420.12362 -398.717516)
			(xy 420.12362 -398.881092) (xy 420.123106 -398.891097) (xy 420.115453 -398.909584) (xy 420.101308 -398.923737)
			(xy 420.082824 -398.9314) (xy 420.07282 -398.931892) (xy 419.565328 -398.931892) (xy 419.555308 -398.931457)
			(xy 419.53679 -398.923795) (xy 419.522616 -398.909627) (xy 419.514947 -398.891112) (xy 419.514528 -398.881092)
			(xy 419.514528 -398.717516) (xy 419.514 -398.707513) (xy 419.506351 -398.689027) (xy 419.49221 -398.674874)
			(xy 419.473731 -398.667209) (xy 419.463728 -398.666716) (xy 419.454584 -398.666716) (xy 419.454584 -398.411446)
			(xy 419.455372 -398.385724) (xy 419.467703 -398.335778) (xy 419.478968 -398.31264) (xy 419.48481 -398.30121)
			(xy 419.484556 -398.27581) (xy 419.430962 -398.178782) (xy 419.409372 -398.165066) (xy 419.396418 -398.16405)
			(xy 419.372521 -398.161937) (xy 419.325734 -398.151335) (xy 419.281093 -398.133767) (xy 419.239628 -398.109639)
			(xy 419.202299 -398.079507) (xy 419.169965 -398.044067) (xy 419.143373 -398.004138) (xy 419.123138 -397.960641)
			(xy 419.116002 -397.937736) (xy 419.114478 -397.931894) (xy 418.794184 -397.378174) (xy 418.79012 -397.373856)
			(xy 418.77392 -397.356144) (xy 418.746495 -397.316755) (xy 418.725351 -397.273666) (xy 418.710976 -397.227873)
			(xy 418.703702 -397.18043) (xy 418.703252 -397.156432) (xy 418.70343 -397.142384) (xy 418.705974 -397.114402)
			(xy 418.708332 -397.100552) (xy 418.709618 -397.091296) (xy 418.706222 -397.072932) (xy 418.701728 -397.064738)
			(xy 418.684964 -397.037814) (xy 418.679745 -397.030123) (xy 418.665032 -397.018793) (xy 418.656262 -397.015716)
			(xy 418.634637 -397.008911) (xy 418.593423 -396.990031) (xy 418.555302 -396.965497) (xy 418.521046 -396.935805)
			(xy 418.505894 -396.918942) (xy 418.503423 -396.916177) (xy 418.497817 -396.911326) (xy 418.494718 -396.90929)
			(xy 418.482698 -396.901197) (xy 418.462805 -396.880143) (xy 418.448794 -396.854791) (xy 418.441551 -396.826745)
			(xy 418.441124 -396.812262) (xy 418.441124 -396.800324) (xy 418.439346 -396.79372) (xy 418.434139 -396.773351)
			(xy 418.428539 -396.731683) (xy 418.42817 -396.710662) (xy 417.86429 -396.710662) (xy 417.86429 -396.71117)
			(xy 417.86412 -396.725795) (xy 417.861453 -396.754924) (xy 417.858956 -396.769336) (xy 417.857585 -396.77851)
			(xy 417.860861 -396.796753) (xy 417.865306 -396.804896) (xy 417.881816 -396.83182) (xy 417.886996 -396.83959)
			(xy 417.901715 -396.851057) (xy 417.910518 -396.854172) (xy 417.935441 -396.862311) (xy 417.982406 -396.885603)
			(xy 418.024886 -396.916324) (xy 418.061716 -396.953632) (xy 418.091886 -396.996504) (xy 418.114571 -397.043767)
			(xy 418.122354 -397.068802) (xy 418.123878 -397.074644) (xy 418.443664 -397.627602) (xy 418.447728 -397.63192)
			(xy 418.463924 -397.649634) (xy 418.491349 -397.689024) (xy 418.512492 -397.732112) (xy 418.526868 -397.777905)
			(xy 418.534144 -397.825346) (xy 418.534596 -397.849344) (xy 418.534119 -397.874807) (xy 418.525919 -397.925069)
			(xy 418.509756 -397.973362) (xy 418.486049 -398.018434) (xy 418.455413 -398.059115) (xy 418.418643 -398.094349)
			(xy 418.397944 -398.109186) (xy 418.389415 -398.115636) (xy 418.378206 -398.133823) (xy 418.375363 -398.154996)
			(xy 418.381376 -398.175496) (xy 418.395205 -398.191779) (xy 418.414461 -398.201031) (xy 418.425122 -398.201896)
			(xy 418.434774 -398.201388) (xy 418.443288 -398.200099) (xy 418.460453 -398.198697) (xy 418.469064 -398.198594)
			(xy 418.469318 -398.198848) (xy 418.76853 -398.198848) (xy 418.768784 -398.198594) (xy 418.789847 -398.198977)
			(xy 418.831206 -398.206936) (xy 418.870205 -398.222844) (xy 418.905331 -398.246085) (xy 418.935222 -398.275759)
			(xy 418.95872 -398.310713) (xy 418.974913 -398.349594) (xy 418.983174 -398.390895) (xy 418.983668 -398.411954)
			(xy 418.983668 -398.666716) (xy 418.974524 -398.666716) (xy 418.964502 -398.66714) (xy 418.945983 -398.674805)
			(xy 418.931809 -398.688976) (xy 418.924141 -398.707494) (xy 418.923724 -398.717516) (xy 418.923724 -398.881092)
			(xy 418.923206 -398.891096) (xy 418.915554 -398.909583) (xy 418.90141 -398.923736) (xy 418.882928 -398.9314)
			(xy 418.872924 -398.931892) (xy 418.364924 -398.931892) (xy 418.354903 -398.93146) (xy 418.336385 -398.923797)
			(xy 418.322212 -398.909628) (xy 418.314543 -398.891113) (xy 418.314124 -398.881092) (xy 418.314124 -398.666716)
			(xy 418.30498 -398.666716) (xy 418.294973 -398.666229) (xy 418.276484 -398.658566) (xy 418.262332 -398.644413)
			(xy 418.25467 -398.625923) (xy 418.25418 -398.615916) (xy 418.25418 -398.411954) (xy 418.254529 -398.394721)
			(xy 418.260099 -398.360709) (xy 418.271069 -398.328036) (xy 418.278818 -398.31264) (xy 418.28466 -398.30121)
			(xy 418.284406 -398.27581) (xy 418.230812 -398.178782) (xy 418.209222 -398.165066) (xy 418.196268 -398.16405)
			(xy 418.172375 -398.161896) (xy 418.125589 -398.151302) (xy 418.080948 -398.133741) (xy 418.039484 -398.109619)
			(xy 418.002153 -398.079492) (xy 417.969818 -398.044058) (xy 417.943225 -398.004133) (xy 417.922989 -397.960639)
			(xy 417.915852 -397.937736) (xy 417.914328 -397.931894) (xy 417.59378 -397.377412) (xy 417.589716 -397.373094)
			(xy 417.573624 -397.355415) (xy 417.546371 -397.316139) (xy 417.525358 -397.273202) (xy 417.511063 -397.227585)
			(xy 417.503815 -397.180334) (xy 417.503356 -397.156432) (xy 417.503534 -397.142384) (xy 417.506078 -397.114402)
			(xy 417.508436 -397.100552) (xy 417.509721 -397.091296) (xy 417.506326 -397.072933) (xy 417.501832 -397.064738)
			(xy 417.485068 -397.037814) (xy 417.479848 -397.030125) (xy 417.465135 -397.018794) (xy 417.456366 -397.015716)
			(xy 417.434742 -397.00891) (xy 417.393527 -396.99003) (xy 417.355407 -396.965496) (xy 417.32115 -396.935804)
			(xy 417.305998 -396.918942) (xy 417.303539 -396.916166) (xy 417.297924 -396.911322) (xy 417.294822 -396.90929)
			(xy 417.282803 -396.901196) (xy 417.262909 -396.880142) (xy 417.248898 -396.854791) (xy 417.241655 -396.826745)
			(xy 417.241228 -396.812262) (xy 417.241228 -396.800324) (xy 417.23945 -396.79372) (xy 417.234243 -396.773351)
			(xy 417.228643 -396.731683) (xy 417.228274 -396.710662) (xy 416.66414 -396.710662) (xy 416.664 -396.725415)
			(xy 416.661324 -396.754799) (xy 416.658806 -396.769336) (xy 416.657442 -396.77851) (xy 416.660715 -396.796752)
			(xy 416.665156 -396.804896) (xy 416.681666 -396.83182) (xy 416.686828 -396.839604) (xy 416.701559 -396.851063)
			(xy 416.710368 -396.854172) (xy 416.735242 -396.862257) (xy 416.782122 -396.885441) (xy 416.824536 -396.91604)
			(xy 416.86132 -396.953216) (xy 416.891469 -396.995951) (xy 416.914155 -397.043074) (xy 416.92195 -397.06804)
			(xy 416.923474 -397.073882) (xy 417.243768 -397.627602) (xy 417.247832 -397.63192) (xy 417.264029 -397.649634)
			(xy 417.291453 -397.689024) (xy 417.312597 -397.732112) (xy 417.326972 -397.777905) (xy 417.334248 -397.825346)
			(xy 417.3347 -397.849344) (xy 417.334221 -397.874807) (xy 417.326022 -397.925069) (xy 417.309859 -397.973362)
			(xy 417.286152 -398.018433) (xy 417.255517 -398.059114) (xy 417.218747 -398.094349) (xy 417.198048 -398.109186)
			(xy 417.189517 -398.115635) (xy 417.178307 -398.133822) (xy 417.175463 -398.154996) (xy 417.181476 -398.175497)
			(xy 417.195307 -398.19178) (xy 417.214564 -398.201031) (xy 417.225226 -398.201896) (xy 417.234878 -398.201388)
			(xy 417.243392 -398.200099) (xy 417.260557 -398.198697) (xy 417.269168 -398.198594) (xy 417.269422 -398.198848)
			(xy 417.568634 -398.198848) (xy 417.568888 -398.198594) (xy 417.589951 -398.198973) (xy 417.631311 -398.206933)
			(xy 417.670309 -398.222842) (xy 417.705435 -398.246084) (xy 417.735326 -398.275757) (xy 417.758824 -398.310712)
			(xy 417.775017 -398.349594) (xy 417.783278 -398.390895) (xy 417.783772 -398.411954) (xy 417.783772 -398.666716)
			(xy 417.774628 -398.666716) (xy 417.764607 -398.667143) (xy 417.746087 -398.674807) (xy 417.731913 -398.688977)
			(xy 417.724245 -398.707495) (xy 417.723828 -398.717516) (xy 417.723828 -398.881092) (xy 417.723306 -398.891096)
			(xy 417.715654 -398.909582) (xy 417.701512 -398.923734) (xy 417.683031 -398.931399) (xy 417.673028 -398.931892)
			(xy 417.165028 -398.931892) (xy 417.155008 -398.931457) (xy 417.13649 -398.923795) (xy 417.122316 -398.909627)
			(xy 417.114647 -398.891112) (xy 417.114228 -398.881092) (xy 417.114228 -398.666716) (xy 417.105084 -398.666716)
			(xy 417.095077 -398.666226) (xy 417.076588 -398.658564) (xy 417.062436 -398.644412) (xy 417.054774 -398.625923)
			(xy 417.054284 -398.615916) (xy 417.054284 -398.411954) (xy 417.054633 -398.394721) (xy 417.060202 -398.360709)
			(xy 417.071173 -398.328036) (xy 417.078922 -398.31264) (xy 417.084764 -398.30121) (xy 417.08451 -398.27581)
			(xy 417.030916 -398.178782) (xy 417.009326 -398.165066) (xy 416.996372 -398.16405) (xy 416.972471 -398.161974)
			(xy 416.925683 -398.151366) (xy 416.881041 -398.133791) (xy 416.839577 -398.109657) (xy 416.802248 -398.07952)
			(xy 416.769916 -398.044076) (xy 416.743325 -398.004143) (xy 416.723092 -397.960642) (xy 416.715956 -397.937736)
			(xy 416.714432 -397.931894) (xy 416.394138 -397.378174) (xy 416.390074 -397.373856) (xy 416.373918 -397.356119)
			(xy 416.346549 -397.316718) (xy 416.325457 -397.273629) (xy 416.311129 -397.227845) (xy 416.303894 -397.180419)
			(xy 416.30346 -397.156432) (xy 416.303641 -397.142384) (xy 416.306182 -397.114402) (xy 416.30854 -397.100552)
			(xy 416.309871 -397.091273) (xy 416.306339 -397.072874) (xy 416.301682 -397.064738) (xy 416.284918 -397.037814)
			(xy 416.279715 -397.030111) (xy 416.26499 -397.018787) (xy 416.256216 -397.015716) (xy 416.234646 -397.008947)
			(xy 416.19352 -396.990178) (xy 416.155465 -396.965777) (xy 416.121247 -396.936234) (xy 416.106102 -396.91945)
			(xy 416.103642 -396.916676) (xy 416.098028 -396.91183) (xy 416.094926 -396.909798) (xy 416.082786 -396.90171)
			(xy 416.062698 -396.880573) (xy 416.048551 -396.855074) (xy 416.041249 -396.826842) (xy 416.040824 -396.812262)
			(xy 416.040824 -396.799816) (xy 416.039046 -396.793466) (xy 416.033917 -396.773151) (xy 416.02844 -396.731612)
			(xy 416.028124 -396.710662) (xy 416.028461 -396.689714) (xy 416.033934 -396.648176) (xy 416.039046 -396.627858)
			(xy 416.040824 -396.621508) (xy 416.040824 -396.164816) (xy 416.039046 -396.158466) (xy 416.033917 -396.138151)
			(xy 416.02844 -396.096612) (xy 416.028124 -396.075662) (xy 416.028461 -396.054714) (xy 416.033934 -396.013176)
			(xy 416.039046 -395.992858) (xy 416.040824 -395.986508) (xy 416.040824 -395.974062) (xy 416.041319 -395.958599)
			(xy 416.049545 -395.928786) (xy 416.065372 -395.902216) (xy 416.08767 -395.880786) (xy 416.101022 -395.87297)
			(xy 416.104578 -395.868906) (xy 416.111931 -395.859383) (xy 416.11763 -395.836043) (xy 416.1155 -395.824202)
			(xy 416.108388 -395.792706) (xy 416.105111 -395.781195) (xy 416.089868 -395.762782) (xy 416.079178 -395.7574)
			(xy 416.057692 -395.747585) (xy 416.017628 -395.722564) (xy 415.98171 -395.691887) (xy 415.965894 -395.674342)
			(xy 415.963423 -395.671577) (xy 415.957817 -395.666726) (xy 415.954718 -395.66469) (xy 415.942698 -395.656597)
			(xy 415.922805 -395.635543) (xy 415.908794 -395.610191) (xy 415.901551 -395.582145) (xy 415.901124 -395.567662)
			(xy 415.901124 -395.555724) (xy 415.899346 -395.54912) (xy 415.894139 -395.528751) (xy 415.888539 -395.487083)
			(xy 415.88817 -395.466062) (xy 415.888537 -395.445041) (xy 415.894147 -395.403375) (xy 415.899346 -395.383004)
			(xy 415.901124 -395.3764) (xy 415.901124 -395.262862) (xy 415.901785 -395.244743) (xy 415.913038 -395.210298)
			(xy 415.923222 -395.195298) (xy 415.927695 -395.188627) (xy 415.932627 -395.173353) (xy 415.932874 -395.165326)
			(xy 415.932874 -395.131798) (xy 415.932558 -395.12378) (xy 415.927653 -395.108514) (xy 415.923222 -395.101826)
			(xy 415.913143 -395.086772) (xy 415.901882 -395.052362) (xy 415.901124 -395.034262) (xy 415.901124 -394.920724)
			(xy 415.899346 -394.91412) (xy 415.894139 -394.893751) (xy 415.888539 -394.852083) (xy 415.88817 -394.831062)
			(xy 415.888932 -394.808456) (xy 415.889694 -394.798296) (xy 415.883598 -394.7795) (xy 415.830004 -394.717524)
			(xy 415.823075 -394.710263) (xy 415.805164 -394.701249) (xy 415.795206 -394.699998) (xy 415.771395 -394.6978)
			(xy 415.724802 -394.68704) (xy 415.680366 -394.669373) (xy 415.639105 -394.645204) (xy 415.601964 -394.615085)
			(xy 415.569792 -394.579707) (xy 415.543326 -394.53988) (xy 415.523173 -394.496515) (xy 415.51606 -394.473684)
			(xy 415.514536 -394.467842) (xy 415.194242 -393.914122) (xy 415.190178 -393.909804) (xy 415.17403 -393.892128)
			(xy 415.146709 -393.852813) (xy 415.125639 -393.809824) (xy 415.111302 -393.764145) (xy 415.104029 -393.716825)
			(xy 415.103564 -393.692888) (xy 414.571472 -393.692888) (xy 414.843722 -394.16355) (xy 414.847786 -394.167868)
			(xy 414.863947 -394.185566) (xy 414.891289 -394.224927) (xy 414.912367 -394.267969) (xy 414.926697 -394.313702)
			(xy 414.93395 -394.361075) (xy 414.9344 -394.385038) (xy 414.9344 -394.385546) (xy 414.933892 -394.405866)
			(xy 414.93313 -394.415772) (xy 414.93948 -394.434822) (xy 415.000186 -394.504164) (xy 415.017966 -394.513054)
			(xy 415.028126 -394.513816) (xy 415.053106 -394.515979) (xy 415.101965 -394.52724) (xy 415.148452 -394.546028)
			(xy 415.191415 -394.571876) (xy 415.229791 -394.604145) (xy 415.246566 -394.622782) (xy 415.249027 -394.625556)
			(xy 415.25464 -394.630402) (xy 415.257742 -394.632434) (xy 415.269785 -394.640494) (xy 415.289673 -394.661561)
			(xy 415.303677 -394.686923) (xy 415.310912 -394.714976) (xy 415.311336 -394.729462) (xy 415.311336 -394.7414)
			(xy 415.313114 -394.748004) (xy 415.318305 -394.768377) (xy 415.323916 -394.810042) (xy 415.32429 -394.831062)
			(xy 415.323909 -394.852082) (xy 415.318308 -394.893748) (xy 415.313114 -394.91412) (xy 415.311336 -394.920724)
			(xy 415.311336 -394.958316) (xy 415.311707 -394.968343) (xy 415.319389 -394.986867) (xy 415.333577 -395.00104)
			(xy 415.352109 -395.008703) (xy 415.362136 -395.009116) (xy 415.376868 -395.009116) (xy 415.386936 -395.009554)
			(xy 415.405534 -395.017265) (xy 415.412936 -395.024102) (xy 415.618422 -395.229334) (xy 415.625273 -395.236726)
			(xy 415.632986 -395.255331) (xy 415.633408 -395.265402) (xy 415.633408 -396.903448) (xy 415.633792 -396.913154)
			(xy 415.640989 -396.931182) (xy 415.647378 -396.9385) (xy 415.664416 -396.957039) (xy 415.692949 -396.998522)
			(xy 415.714537 -397.044009) (xy 415.722054 -397.06804) (xy 415.723578 -397.073882) (xy 415.91103 -397.397986)
			(xy 415.919158 -397.408654) (xy 416.06343 -397.552926) (xy 416.059366 -397.55699) (xy 416.051746 -397.57477)
			(xy 416.050984 -397.61541) (xy 416.051182 -397.624452) (xy 416.057169 -397.641504) (xy 416.062668 -397.648684)
			(xy 416.079554 -397.670024) (xy 416.106452 -397.717325) (xy 416.124853 -397.768534) (xy 416.134214 -397.822137)
			(xy 416.134804 -397.849344) (xy 416.134339 -397.87328) (xy 416.127051 -397.920596) (xy 416.11271 -397.966271)
			(xy 416.091644 -398.009261) (xy 416.064334 -398.048581) (xy 416.04819 -398.06626) (xy 416.0422 -398.073119)
			(xy 416.035072 -398.089862) (xy 416.034291 -398.108041) (xy 416.03676 -398.116806) (xy 416.039837 -398.126681)
			(xy 416.044794 -398.146765) (xy 416.046666 -398.156938) (xy 416.046666 -398.157192) (xy 416.049462 -398.168712)
			(xy 416.063697 -398.187626) (xy 416.084869 -398.198215) (xy 416.096704 -398.198848) (xy 416.368484 -398.198848)
			(xy 416.368738 -398.198594) (xy 416.389784 -398.198999) (xy 416.431105 -398.206995) (xy 416.47006 -398.222926)
			(xy 416.505142 -398.246176) (xy 416.534993 -398.275844) (xy 416.558457 -398.310783) (xy 416.574627 -398.34964)
			(xy 416.582876 -398.390911) (xy 416.583368 -398.411954) (xy 416.583368 -398.666716) (xy 416.574224 -398.666716)
			(xy 416.564202 -398.66714) (xy 416.545683 -398.674805) (xy 416.531509 -398.688976) (xy 416.523841 -398.707494)
			(xy 416.523424 -398.717516) (xy 416.523424 -398.881092) (xy 416.522906 -398.891096) (xy 416.515254 -398.909583)
			(xy 416.50111 -398.923736) (xy 416.482628 -398.9314) (xy 416.472624 -398.931892) (xy 416.066224 -398.931892)
			(xy 416.056205 -398.932339) (xy 416.03769 -398.94) (xy 416.023518 -398.954164) (xy 416.015846 -398.972674)
			(xy 416.015424 -398.982692) (xy 416.015424 -399.853404) (xy 416.014824 -399.879869) (xy 416.00567 -399.932004)
			(xy 415.987689 -399.981789) (xy 415.975038 -400.005042) (xy 415.971736 -400.010884) (xy 415.96818 -400.023584)
			(xy 415.96818 -401.029932) (xy 415.971736 -401.042632) (xy 415.975038 -401.048474) (xy 415.98774 -401.0718)
			(xy 416.005781 -401.121747) (xy 416.014894 -401.174066) (xy 416.015424 -401.20062) (xy 416.015424 -401.285456)
			(xy 416.014892 -401.312009) (xy 416.005769 -401.364326) (xy 415.98774 -401.414277) (xy 415.975038 -401.437602)
			(xy 415.971736 -401.443444) (xy 415.96818 -401.456144) (xy 415.96818 -401.674838) (xy 416.26282 -401.674838)
			(xy 416.26282 -400.81073) (xy 416.263254 -400.785262) (xy 416.270057 -400.734782) (xy 416.283518 -400.685656)
			(xy 416.303399 -400.63876) (xy 416.329346 -400.594928) (xy 416.360896 -400.554939) (xy 416.378898 -400.536918)
			(xy 416.385502 -400.530568) (xy 416.393376 -400.513804) (xy 416.400234 -400.42846) (xy 416.395154 -400.41068)
			(xy 416.389566 -400.403314) (xy 416.37472 -400.382563) (xy 416.351082 -400.337351) (xy 416.33498 -400.28894)
			(xy 416.326826 -400.238577) (xy 416.32632 -400.213068) (xy 416.32632 -400.212814) (xy 416.32681 -400.187825)
			(xy 416.334629 -400.138462) (xy 416.350073 -400.09093) (xy 416.372763 -400.046398) (xy 416.402139 -400.005965)
			(xy 416.437479 -399.970625) (xy 416.477912 -399.941249) (xy 416.522444 -399.918559) (xy 416.569976 -399.903115)
			(xy 416.619339 -399.895296) (xy 416.669317 -399.895296) (xy 416.71868 -399.903115) (xy 416.766212 -399.918559)
			(xy 416.810744 -399.941249) (xy 416.851177 -399.970625) (xy 416.886517 -400.005965) (xy 416.915893 -400.046398)
			(xy 416.938583 -400.09093) (xy 416.954027 -400.138462) (xy 416.961846 -400.187825) (xy 416.962336 -400.212814)
			(xy 416.962336 -400.213068) (xy 416.961836 -400.238577) (xy 416.95366 -400.288936) (xy 416.937559 -400.337347)
			(xy 416.913947 -400.382572) (xy 416.89909 -400.403314) (xy 416.893502 -400.41068) (xy 416.888422 -400.42846)
			(xy 416.89528 -400.513804) (xy 416.903154 -400.530568) (xy 416.909758 -400.536918) (xy 416.927758 -400.554939)
			(xy 416.959299 -400.594933) (xy 416.98524 -400.638767) (xy 417.005119 -400.685663) (xy 417.018584 -400.734785)
			(xy 417.025395 -400.785263) (xy 417.025836 -400.81073) (xy 417.025836 -401.674838) (xy 417.025826 -401.675346)
			(xy 417.462716 -401.675346) (xy 417.462716 -400.81073) (xy 417.463151 -400.785262) (xy 417.469954 -400.734782)
			(xy 417.483415 -400.685657) (xy 417.503296 -400.63876) (xy 417.529242 -400.594928) (xy 417.560792 -400.554939)
			(xy 417.578794 -400.536918) (xy 417.585398 -400.530568) (xy 417.593272 -400.513804) (xy 417.60013 -400.42846)
			(xy 417.59505 -400.41068) (xy 417.589462 -400.403314) (xy 417.574615 -400.382563) (xy 417.550978 -400.337351)
			(xy 417.534875 -400.28894) (xy 417.526722 -400.238577) (xy 417.526216 -400.213068) (xy 417.526216 -400.212814)
			(xy 417.526706 -400.187825) (xy 417.534525 -400.138462) (xy 417.549969 -400.09093) (xy 417.572659 -400.046398)
			(xy 417.602035 -400.005965) (xy 417.637375 -399.970625) (xy 417.677808 -399.941249) (xy 417.72234 -399.918559)
			(xy 417.769872 -399.903115) (xy 417.819235 -399.895296) (xy 417.869213 -399.895296) (xy 417.918576 -399.903115)
			(xy 417.966108 -399.918559) (xy 418.01064 -399.941249) (xy 418.051073 -399.970625) (xy 418.086413 -400.005965)
			(xy 418.115789 -400.046398) (xy 418.138479 -400.09093) (xy 418.153923 -400.138462) (xy 418.161742 -400.187825)
			(xy 418.162232 -400.212814) (xy 418.162232 -400.213068) (xy 418.161733 -400.238577) (xy 418.153556 -400.288936)
			(xy 418.137456 -400.337347) (xy 418.113843 -400.382572) (xy 418.098986 -400.403314) (xy 418.093398 -400.41068)
			(xy 418.088318 -400.42846) (xy 418.095176 -400.513804) (xy 418.10305 -400.530568) (xy 418.109654 -400.536918)
			(xy 418.127653 -400.55494) (xy 418.159194 -400.594934) (xy 418.185135 -400.638768) (xy 418.205015 -400.685663)
			(xy 418.21848 -400.734786) (xy 418.225291 -400.785263) (xy 418.225732 -400.81073) (xy 418.225732 -401.674838)
			(xy 418.662612 -401.674838) (xy 418.662612 -400.81073) (xy 418.663048 -400.785262) (xy 418.669851 -400.734782)
			(xy 418.683312 -400.685657) (xy 418.703193 -400.638761) (xy 418.729139 -400.594928) (xy 418.760689 -400.554939)
			(xy 418.77869 -400.536918) (xy 418.785294 -400.530568) (xy 418.793168 -400.513804) (xy 418.800026 -400.42846)
			(xy 418.794946 -400.41068) (xy 418.789358 -400.403314) (xy 418.774511 -400.382564) (xy 418.750874 -400.337351)
			(xy 418.734771 -400.28894) (xy 418.726618 -400.238577) (xy 418.726112 -400.213068) (xy 418.726112 -400.212814)
			(xy 418.726602 -400.187825) (xy 418.734421 -400.138462) (xy 418.749865 -400.09093) (xy 418.772555 -400.046398)
			(xy 418.801931 -400.005965) (xy 418.837271 -399.970625) (xy 418.877704 -399.941249) (xy 418.922236 -399.918559)
			(xy 418.969768 -399.903115) (xy 419.019131 -399.895296) (xy 419.069109 -399.895296) (xy 419.118472 -399.903115)
			(xy 419.166004 -399.918559) (xy 419.210536 -399.941249) (xy 419.250969 -399.970625) (xy 419.286309 -400.005965)
			(xy 419.315685 -400.046398) (xy 419.338375 -400.09093) (xy 419.353819 -400.138462) (xy 419.361638 -400.187825)
			(xy 419.362128 -400.212814) (xy 419.362128 -400.213068) (xy 419.36163 -400.238577) (xy 419.353453 -400.288936)
			(xy 419.337352 -400.337347) (xy 419.313739 -400.382572) (xy 419.298882 -400.403314) (xy 419.293294 -400.41068)
			(xy 419.288214 -400.42846) (xy 419.295072 -400.513804) (xy 419.302946 -400.530568) (xy 419.30955 -400.536918)
			(xy 419.327548 -400.554941) (xy 419.35909 -400.594934) (xy 419.385031 -400.638768) (xy 419.404911 -400.685663)
			(xy 419.418376 -400.734786) (xy 419.425187 -400.785263) (xy 419.425628 -400.81073) (xy 419.425628 -401.674838)
			(xy 419.862508 -401.674838) (xy 419.862508 -400.811238) (xy 419.862943 -400.785718) (xy 419.869732 -400.735133)
			(xy 419.883208 -400.685905) (xy 419.903129 -400.638914) (xy 419.92914 -400.595001) (xy 419.960776 -400.554949)
			(xy 419.97884 -400.536918) (xy 419.985444 -400.530568) (xy 419.993318 -400.513804) (xy 420.000176 -400.42846)
			(xy 419.995096 -400.41068) (xy 419.989508 -400.403314) (xy 419.974655 -400.382568) (xy 419.951021 -400.337353)
			(xy 419.93492 -400.288941) (xy 419.926768 -400.238578) (xy 419.926262 -400.213068) (xy 419.926262 -400.212814)
			(xy 419.926752 -400.187825) (xy 419.934571 -400.138462) (xy 419.950015 -400.09093) (xy 419.972705 -400.046398)
			(xy 420.002081 -400.005965) (xy 420.037421 -399.970625) (xy 420.077854 -399.941249) (xy 420.122386 -399.918559)
			(xy 420.169918 -399.903115) (xy 420.219281 -399.895296) (xy 420.269259 -399.895296) (xy 420.318622 -399.903115)
			(xy 420.366154 -399.918559) (xy 420.410686 -399.941249) (xy 420.451119 -399.970625) (xy 420.486459 -400.005965)
			(xy 420.515835 -400.046398) (xy 420.538525 -400.09093) (xy 420.553969 -400.138462) (xy 420.561788 -400.187825)
			(xy 420.562278 -400.212814) (xy 420.562278 -400.213068) (xy 420.56177 -400.238576) (xy 420.553595 -400.288934)
			(xy 420.537497 -400.337345) (xy 420.513887 -400.382571) (xy 420.499032 -400.403314) (xy 420.493444 -400.41068)
			(xy 420.488364 -400.42846) (xy 420.495222 -400.513804) (xy 420.503096 -400.530568) (xy 420.5097 -400.536918)
			(xy 420.527742 -400.554968) (xy 420.559371 -400.595022) (xy 420.58538 -400.638934) (xy 420.605306 -400.685919)
			(xy 420.618793 -400.73514) (xy 420.625602 -400.78572) (xy 420.626032 -400.811238) (xy 420.626032 -401.674838)
			(xy 421.062404 -401.674838) (xy 421.062404 -400.811238) (xy 421.06284 -400.785718) (xy 421.069629 -400.735133)
			(xy 421.083105 -400.685905) (xy 421.103026 -400.638915) (xy 421.129037 -400.595001) (xy 421.160672 -400.554949)
			(xy 421.178736 -400.536918) (xy 421.18534 -400.530568) (xy 421.193214 -400.513804) (xy 421.200072 -400.42846)
			(xy 421.194992 -400.41068) (xy 421.189404 -400.403314) (xy 421.17455 -400.382568) (xy 421.150916 -400.337353)
			(xy 421.134816 -400.288941) (xy 421.126664 -400.238578) (xy 421.126158 -400.213068) (xy 421.126158 -400.212814)
			(xy 421.126648 -400.187825) (xy 421.134467 -400.138462) (xy 421.149911 -400.09093) (xy 421.172601 -400.046398)
			(xy 421.201977 -400.005965) (xy 421.237317 -399.970625) (xy 421.27775 -399.941249) (xy 421.322282 -399.918559)
			(xy 421.369814 -399.903115) (xy 421.419177 -399.895296) (xy 421.469155 -399.895296) (xy 421.518518 -399.903115)
			(xy 421.56605 -399.918559) (xy 421.610582 -399.941249) (xy 421.651015 -399.970625) (xy 421.686355 -400.005965)
			(xy 421.715731 -400.046398) (xy 421.738421 -400.09093) (xy 421.753865 -400.138462) (xy 421.761684 -400.187825)
			(xy 421.762174 -400.212814) (xy 421.762174 -400.213068) (xy 421.761667 -400.238576) (xy 421.753491 -400.288934)
			(xy 421.737393 -400.337345) (xy 421.713783 -400.382571) (xy 421.698928 -400.403314) (xy 421.69334 -400.41068)
			(xy 421.68826 -400.42846) (xy 421.695118 -400.513804) (xy 421.702992 -400.530568) (xy 421.709596 -400.536918)
			(xy 421.727638 -400.554969) (xy 421.759266 -400.595023) (xy 421.785275 -400.638934) (xy 421.805202 -400.685919)
			(xy 421.818689 -400.735141) (xy 421.825498 -400.78572) (xy 421.825928 -400.811238) (xy 421.825928 -401.476718)
			(xy 421.826304 -401.485827) (xy 421.832651 -401.502902) (xy 421.844546 -401.516701) (xy 421.852344 -401.521422)
			(xy 421.942768 -401.570952) (xy 421.9702 -401.569936) (xy 421.981884 -401.56257) (xy 421.982392 -401.56257)
			(xy 422.004723 -401.548857) (xy 422.052418 -401.52715) (xy 422.102702 -401.512401) (xy 422.154566 -401.504906)
			(xy 422.180766 -401.504404) (xy 422.20837 -401.504868) (xy 422.262962 -401.513092) (xy 422.315719 -401.529361)
			(xy 422.365462 -401.553311) (xy 422.411079 -401.584409) (xy 422.451551 -401.621958) (xy 422.485974 -401.66512)
			(xy 422.51358 -401.712931) (xy 422.533751 -401.764322) (xy 422.546037 -401.818146) (xy 422.550163 -401.8732)
			(xy 422.546037 -401.928254) (xy 422.533751 -401.982078) (xy 422.51358 -402.033469) (xy 422.485974 -402.08128)
			(xy 422.451551 -402.124442) (xy 422.411079 -402.161991) (xy 422.365462 -402.193089) (xy 422.315719 -402.217039)
			(xy 422.262962 -402.233308) (xy 422.20837 -402.241532) (xy 422.180766 -402.24202) (xy 422.152795 -402.24146)
			(xy 422.097497 -402.232993) (xy 422.044111 -402.216273) (xy 421.993862 -402.191684) (xy 421.947902 -402.15979)
			(xy 421.907285 -402.121321) (xy 421.872942 -402.077161) (xy 421.845661 -402.028321) (xy 421.826067 -401.975922)
			(xy 421.819832 -401.94865) (xy 421.817067 -401.938442) (xy 421.80473 -401.921297) (xy 421.786548 -401.91055)
			(xy 421.76558 -401.908008) (xy 421.755316 -401.91055) (xy 421.748458 -401.912943) (xy 421.736339 -401.920936)
			(xy 421.73144 -401.926298) (xy 421.728646 -401.929346) (xy 421.722804 -401.93595) (xy 421.715946 -401.952714)
			(xy 421.713914 -402.027136) (xy 421.714029 -402.036041) (xy 421.719624 -402.052934) (xy 421.724836 -402.060156)
			(xy 421.72509 -402.06041) (xy 421.739863 -402.079582) (xy 421.764689 -402.121131) (xy 421.783724 -402.165631)
			(xy 421.796625 -402.212281) (xy 421.803159 -402.260238) (xy 421.803576 -402.284438) (xy 421.803074 -402.311334)
			(xy 421.795056 -402.364526) (xy 421.7792 -402.415929) (xy 421.755861 -402.464395) (xy 421.725558 -402.508841)
			(xy 421.68897 -402.548274) (xy 421.646913 -402.581813) (xy 421.600327 -402.608709) (xy 421.550253 -402.628362)
			(xy 421.497808 -402.640332) (xy 421.444166 -402.644352) (xy 421.390524 -402.640332) (xy 421.338079 -402.628362)
			(xy 421.288005 -402.608709) (xy 421.241419 -402.581813) (xy 421.199362 -402.548274) (xy 421.162774 -402.508841)
			(xy 421.132471 -402.464395) (xy 421.109132 -402.415929) (xy 421.093276 -402.364526) (xy 421.085258 -402.311334)
			(xy 421.084756 -402.284438) (xy 421.085167 -402.260235) (xy 421.091668 -402.212269) (xy 421.104556 -402.165611)
			(xy 421.123598 -402.121108) (xy 421.148448 -402.079569) (xy 421.163242 -402.06041) (xy 421.163496 -402.060156)
			(xy 421.168764 -402.052966) (xy 421.174351 -402.03605) (xy 421.174418 -402.027136) (xy 421.172386 -401.952714)
			(xy 421.165528 -401.93595) (xy 421.159686 -401.929346) (xy 421.141484 -401.90823) (xy 421.110739 -401.861728)
			(xy 421.087086 -401.811248) (xy 421.071031 -401.757864) (xy 421.062914 -401.702711) (xy 421.062404 -401.674838)
			(xy 420.626032 -401.674838) (xy 420.625477 -401.704002) (xy 420.616556 -401.761644) (xy 420.598971 -401.817259)
			(xy 420.573134 -401.869553) (xy 420.539643 -401.917309) (xy 420.51986 -401.938744) (xy 420.513699 -401.945825)
			(xy 420.506544 -401.963162) (xy 420.50589 -401.972526) (xy 420.504112 -402.041106) (xy 420.504253 -402.050363)
			(xy 420.510388 -402.067816) (xy 420.51605 -402.075142) (xy 420.516558 -402.07565) (xy 420.532916 -402.09526)
			(xy 420.560447 -402.13827) (xy 420.581603 -402.184749) (xy 420.595957 -402.233757) (xy 420.603219 -402.284305)
			(xy 420.60368 -402.309838) (xy 420.603178 -402.336734) (xy 420.59516 -402.389926) (xy 420.579304 -402.441329)
			(xy 420.555965 -402.489795) (xy 420.525662 -402.534241) (xy 420.489074 -402.573674) (xy 420.447017 -402.607213)
			(xy 420.400431 -402.634109) (xy 420.350357 -402.653762) (xy 420.297912 -402.665732) (xy 420.24427 -402.669752)
			(xy 420.190628 -402.665732) (xy 420.138183 -402.653762) (xy 420.088109 -402.634109) (xy 420.041523 -402.607213)
			(xy 419.999466 -402.573674) (xy 419.962878 -402.534241) (xy 419.932575 -402.489795) (xy 419.909236 -402.441329)
			(xy 419.89338 -402.389926) (xy 419.885362 -402.336734) (xy 419.88486 -402.309838) (xy 419.885334 -402.28427)
			(xy 419.892611 -402.233655) (xy 419.907007 -402.184587) (xy 419.928231 -402.138064) (xy 419.955851 -402.095029)
			(xy 419.972236 -402.075396) (xy 419.97249 -402.075142) (xy 419.978156 -402.067822) (xy 419.984265 -402.050362)
			(xy 419.984428 -402.041106) (xy 419.982396 -401.962874) (xy 419.975284 -401.945856) (xy 419.96868 -401.938744)
			(xy 419.948891 -401.917314) (xy 419.915401 -401.869558) (xy 419.889566 -401.817263) (xy 419.871989 -401.761646)
			(xy 419.863079 -401.704002) (xy 419.862508 -401.674838) (xy 419.425628 -401.674838) (xy 419.425074 -401.703991)
			(xy 419.416204 -401.761619) (xy 419.398675 -401.817228) (xy 419.372896 -401.869526) (xy 419.339465 -401.917297)
			(xy 419.31971 -401.938744) (xy 419.313556 -401.94583) (xy 419.306395 -401.963163) (xy 419.30574 -401.972526)
			(xy 419.303962 -402.041106) (xy 419.304114 -402.050362) (xy 419.310243 -402.067814) (xy 419.3159 -402.075142)
			(xy 419.316408 -402.07565) (xy 419.332725 -402.095281) (xy 419.360197 -402.138304) (xy 419.381299 -402.184783)
			(xy 419.395606 -402.233783) (xy 419.40283 -402.284315) (xy 419.403276 -402.309838) (xy 419.402774 -402.336715)
			(xy 419.394762 -402.38987) (xy 419.378918 -402.441236) (xy 419.355594 -402.489668) (xy 419.325313 -402.534082)
			(xy 419.288751 -402.573487) (xy 419.246723 -402.607003) (xy 419.20017 -402.63388) (xy 419.150131 -402.653519)
			(xy 419.097724 -402.66548) (xy 419.04412 -402.669498) (xy 418.990516 -402.66548) (xy 418.938109 -402.653519)
			(xy 418.88807 -402.63388) (xy 418.841517 -402.607003) (xy 418.799489 -402.573487) (xy 418.762927 -402.534082)
			(xy 418.732646 -402.489668) (xy 418.709322 -402.441236) (xy 418.693478 -402.38987) (xy 418.685466 -402.336715)
			(xy 418.684964 -402.309838) (xy 418.685433 -402.284281) (xy 418.692669 -402.233681) (xy 418.707015 -402.184621)
			(xy 418.72818 -402.138094) (xy 418.755735 -402.095043) (xy 418.772086 -402.075396) (xy 418.77234 -402.075142)
			(xy 418.778001 -402.067819) (xy 418.784114 -402.050361) (xy 418.784278 -402.041106) (xy 418.782246 -401.962874)
			(xy 418.775134 -401.945856) (xy 418.76853 -401.938744) (xy 418.7488 -401.917275) (xy 418.71536 -401.869513)
			(xy 418.689573 -401.817221) (xy 418.67204 -401.761616) (xy 418.663167 -401.70399) (xy 418.662612 -401.674838)
			(xy 418.225732 -401.674838) (xy 418.225732 -401.675346) (xy 418.225235 -401.703743) (xy 418.216824 -401.75991)
			(xy 418.200165 -401.814205) (xy 418.175628 -401.865424) (xy 418.143757 -401.912432) (xy 418.124894 -401.933664)
			(xy 418.119032 -401.940598) (xy 418.112126 -401.957377) (xy 418.111432 -401.96643) (xy 418.110416 -401.997418)
			(xy 418.110467 -402.00657) (xy 418.116337 -402.023891) (xy 418.121846 -402.0312) (xy 418.137187 -402.050549)
			(xy 418.162962 -402.092669) (xy 418.182741 -402.137915) (xy 418.196154 -402.185438) (xy 418.202949 -402.234348)
			(xy 418.20338 -402.259038) (xy 418.202878 -402.285915) (xy 418.194866 -402.33907) (xy 418.179022 -402.390436)
			(xy 418.155698 -402.438868) (xy 418.125417 -402.483282) (xy 418.088855 -402.522687) (xy 418.046827 -402.556203)
			(xy 418.000274 -402.58308) (xy 417.950235 -402.602719) (xy 417.897828 -402.61468) (xy 417.844224 -402.618698)
			(xy 417.79062 -402.61468) (xy 417.738213 -402.602719) (xy 417.688174 -402.58308) (xy 417.641621 -402.556203)
			(xy 417.599593 -402.522687) (xy 417.563031 -402.483282) (xy 417.53275 -402.438868) (xy 417.509426 -402.390436)
			(xy 417.493582 -402.33907) (xy 417.48557 -402.285915) (xy 417.485068 -402.259038) (xy 417.485474 -402.234345)
			(xy 417.49223 -402.185422) (xy 417.505633 -402.137889) (xy 417.52543 -402.092644) (xy 417.551246 -402.050543)
			(xy 417.566602 -402.0312) (xy 417.572089 -402.023884) (xy 417.57793 -402.006564) (xy 417.578032 -401.997418)
			(xy 417.577016 -401.96643) (xy 417.576381 -401.957365) (xy 417.56946 -401.940573) (xy 417.563554 -401.933664)
			(xy 417.544733 -401.912403) (xy 417.512915 -401.865375) (xy 417.4884 -401.814159) (xy 417.471729 -401.759882)
			(xy 417.463267 -401.703736) (xy 417.462716 -401.675346) (xy 417.025826 -401.675346) (xy 417.02528 -401.703991)
			(xy 417.01641 -401.761619) (xy 416.998882 -401.817228) (xy 416.973103 -401.869526) (xy 416.939672 -401.917297)
			(xy 416.919918 -401.938744) (xy 416.913751 -401.94582) (xy 416.9066 -401.963161) (xy 416.905948 -401.972526)
			(xy 416.90417 -402.041106) (xy 416.904321 -402.050362) (xy 416.91045 -402.067814) (xy 416.916108 -402.075142)
			(xy 416.916616 -402.07565) (xy 416.932934 -402.09528) (xy 416.960406 -402.138303) (xy 416.981508 -402.184783)
			(xy 416.995815 -402.233783) (xy 417.003038 -402.284315) (xy 417.003484 -402.309838) (xy 417.002982 -402.336715)
			(xy 416.99497 -402.38987) (xy 416.979126 -402.441236) (xy 416.955802 -402.489668) (xy 416.925521 -402.534082)
			(xy 416.888959 -402.573487) (xy 416.846931 -402.607003) (xy 416.800378 -402.63388) (xy 416.750339 -402.653519)
			(xy 416.697932 -402.66548) (xy 416.644328 -402.669498) (xy 416.590724 -402.66548) (xy 416.538317 -402.653519)
			(xy 416.488278 -402.63388) (xy 416.441725 -402.607003) (xy 416.399697 -402.573487) (xy 416.363135 -402.534082)
			(xy 416.332854 -402.489668) (xy 416.30953 -402.441236) (xy 416.293686 -402.38987) (xy 416.285674 -402.336715)
			(xy 416.285172 -402.309838) (xy 416.285639 -402.284281) (xy 416.292876 -402.233681) (xy 416.307222 -402.184621)
			(xy 416.328387 -402.138094) (xy 416.355943 -402.095043) (xy 416.372294 -402.075396) (xy 416.372548 -402.075142)
			(xy 416.37821 -402.067819) (xy 416.384322 -402.050362) (xy 416.384486 -402.041106) (xy 416.382454 -401.962874)
			(xy 416.375342 -401.945856) (xy 416.368738 -401.938744) (xy 416.349009 -401.917274) (xy 416.315569 -401.869512)
			(xy 416.289782 -401.817221) (xy 416.272248 -401.761615) (xy 416.263375 -401.70399) (xy 416.26282 -401.674838)
			(xy 415.96818 -401.674838) (xy 415.96818 -402.810218) (xy 415.967769 -402.820289) (xy 415.960039 -402.838887)
			(xy 415.953194 -402.846286) (xy 415.667444 -403.132036) (xy 415.660027 -403.138854) (xy 415.641441 -403.146586)
			(xy 415.631376 -403.147022) (xy 408.814524 -403.147022) (xy 408.804453 -403.146605) (xy 408.785854 -403.138881)
			(xy 408.778456 -403.132036) (xy 408.7495 -403.10308) (xy 408.735276 -403.095968) (xy 408.727656 -403.094698)
			(xy 408.704136 -403.090421) (xy 408.658699 -403.075572) (xy 408.616137 -403.053814) (xy 408.577491 -403.025681)
			(xy 408.56027 -403.0091) (xy 408.355292 -402.804122) (xy 408.336945 -402.7849) (xy 408.306472 -402.741376)
			(xy 408.284001 -402.69323) (xy 408.276552 -402.667724) (xy 408.244294 -402.669248) (xy 408.218623 -402.668758)
			(xy 408.167803 -402.661451) (xy 408.11854 -402.646986) (xy 408.071837 -402.625659) (xy 408.028645 -402.597902)
			(xy 407.989841 -402.564281) (xy 407.956217 -402.525481) (xy 407.928457 -402.482291) (xy 407.907125 -402.43559)
			(xy 407.892656 -402.386328) (xy 407.885344 -402.335509) (xy 407.884884 -402.309838) (xy 407.885352 -402.28427)
			(xy 407.892629 -402.233654) (xy 407.907027 -402.184586) (xy 407.928252 -402.138063) (xy 407.955874 -402.095029)
			(xy 407.97226 -402.075396) (xy 407.972514 -402.075142) (xy 407.978183 -402.067825) (xy 407.98429 -402.050363)
			(xy 407.984452 -402.041106) (xy 407.98242 -401.962874) (xy 407.975308 -401.945856) (xy 407.968704 -401.938744)
			(xy 407.948919 -401.917311) (xy 407.915427 -401.869556) (xy 407.889592 -401.817262) (xy 407.872014 -401.761645)
			(xy 407.863103 -401.704002) (xy 407.862532 -401.674838) (xy 407.862532 -400.811238) (xy 407.86296 -400.785718)
			(xy 407.869749 -400.735132) (xy 407.883226 -400.685904) (xy 407.903149 -400.638913) (xy 407.929161 -400.594999)
			(xy 407.960799 -400.554948) (xy 407.978864 -400.536918) (xy 407.985468 -400.530568) (xy 407.993342 -400.513804)
			(xy 408.0002 -400.42846) (xy 407.99512 -400.41068) (xy 407.989532 -400.403314) (xy 407.974682 -400.382566)
			(xy 407.951046 -400.337352) (xy 407.934945 -400.288941) (xy 407.926792 -400.238577) (xy 407.926286 -400.213068)
			(xy 407.926286 -400.212814) (xy 407.926708 -400.189139) (xy 407.933734 -400.142314) (xy 407.947619 -400.097045)
			(xy 407.968056 -400.054333) (xy 407.994595 -400.015119) (xy 408.026649 -399.980269) (xy 408.063511 -399.950551)
			(xy 408.104369 -399.926622) (xy 408.126184 -399.917412) (xy 408.140662 -399.91157) (xy 408.158188 -399.885916)
			(xy 408.158188 -399.197576) (xy 408.157778 -399.187505) (xy 408.150047 -399.168907) (xy 408.143202 -399.161508)
			(xy 407.928318 -398.946878) (xy 407.920909 -398.94005) (xy 407.902316 -398.932324) (xy 407.89225 -398.931892)
			(xy 407.565352 -398.931892) (xy 407.55534 -398.931451) (xy 407.536846 -398.923774) (xy 407.522694 -398.909607)
			(xy 407.515038 -398.891104) (xy 407.514552 -398.881092) (xy 407.514552 -398.666716) (xy 407.505408 -398.666716)
			(xy 407.495403 -398.666206) (xy 407.476914 -398.658552) (xy 407.462762 -398.644406) (xy 407.455099 -398.625921)
			(xy 407.454608 -398.615916) (xy 407.454608 -398.411954) (xy 407.455197 -398.389839) (xy 407.464281 -398.346552)
			(xy 407.482072 -398.306058) (xy 407.494486 -398.287748) (xy 407.499058 -398.281144) (xy 407.503884 -398.266412)
			(xy 407.503884 -398.236694) (xy 407.503543 -398.225994) (xy 407.494972 -398.206392) (xy 407.487374 -398.198848)
			(xy 407.464006 -398.177766) (xy 407.456469 -398.171602) (xy 407.438183 -398.164953) (xy 407.428446 -398.164812)
			(xy 407.419048 -398.164812) (xy 407.393655 -398.164269) (xy 407.343523 -398.156146) (xy 407.295339 -398.140102)
			(xy 407.250345 -398.11655) (xy 407.209701 -398.086098) (xy 407.174458 -398.049532) (xy 407.145523 -398.007796)
			(xy 407.123643 -397.961965) (xy 407.116026 -397.937736) (xy 407.114502 -397.931894) (xy 406.794208 -397.378174)
			(xy 406.790144 -397.373856) (xy 406.773931 -397.356156) (xy 406.746511 -397.316762) (xy 406.72537 -397.27367)
			(xy 406.710999 -397.227875) (xy 406.703726 -397.180431) (xy 406.703276 -397.156432) (xy 406.703455 -397.142384)
			(xy 406.705998 -397.114402) (xy 406.708356 -397.100552) (xy 406.709652 -397.091296) (xy 406.706251 -397.072931)
			(xy 406.701752 -397.064738) (xy 406.684988 -397.037814) (xy 406.679796 -397.030102) (xy 406.665064 -397.018783)
			(xy 406.656286 -397.015716) (xy 406.634664 -397.008902) (xy 406.593449 -396.990024) (xy 406.555328 -396.965493)
			(xy 406.521071 -396.935804) (xy 406.505918 -396.918942) (xy 406.503456 -396.916169) (xy 406.497843 -396.911323)
			(xy 406.494742 -396.90929) (xy 406.482728 -396.90119) (xy 406.462832 -396.880139) (xy 406.448819 -396.854789)
			(xy 406.441576 -396.826744) (xy 406.441148 -396.812262) (xy 406.441148 -396.800324) (xy 406.43937 -396.79372)
			(xy 406.434164 -396.773351) (xy 406.428563 -396.731683) (xy 406.428194 -396.710662) (xy 405.864314 -396.710662)
			(xy 405.864314 -396.71117) (xy 405.864143 -396.725795) (xy 405.861477 -396.754924) (xy 405.85898 -396.769336)
			(xy 405.857619 -396.77851) (xy 405.860891 -396.796752) (xy 405.86533 -396.804896) (xy 405.88184 -396.83182)
			(xy 405.887011 -396.839597) (xy 405.901736 -396.85106) (xy 405.910542 -396.854172) (xy 405.935469 -396.862297)
			(xy 405.982435 -396.885593) (xy 406.024914 -396.916317) (xy 406.061742 -396.953627) (xy 406.091912 -396.996502)
			(xy 406.114595 -397.043766) (xy 406.122378 -397.068802) (xy 406.123902 -397.074644) (xy 406.443688 -397.627602)
			(xy 406.447752 -397.63192) (xy 406.463952 -397.649631) (xy 406.491375 -397.689022) (xy 406.512518 -397.732111)
			(xy 406.526892 -397.777904) (xy 406.534168 -397.825346) (xy 406.53462 -397.849344) (xy 406.534132 -397.874806)
			(xy 406.525934 -397.925067) (xy 406.509772 -397.97336) (xy 406.486067 -398.018431) (xy 406.455433 -398.059113)
			(xy 406.418666 -398.094348) (xy 406.397968 -398.109186) (xy 406.389477 -398.115672) (xy 406.378295 -398.133849)
			(xy 406.375461 -398.155002) (xy 406.381465 -398.175481) (xy 406.395271 -398.191755) (xy 406.414497 -398.201017)
			(xy 406.425146 -398.201896) (xy 406.434798 -398.201388) (xy 406.443312 -398.200096) (xy 406.460477 -398.198696)
			(xy 406.469088 -398.198594) (xy 406.469342 -398.198848) (xy 406.768554 -398.198848) (xy 406.768808 -398.198594)
			(xy 406.789871 -398.198955) (xy 406.831232 -398.206918) (xy 406.870231 -398.222831) (xy 406.905356 -398.246075)
			(xy 406.935247 -398.275751) (xy 406.958744 -398.310709) (xy 406.974937 -398.349592) (xy 406.983198 -398.390894)
			(xy 406.983692 -398.411954) (xy 406.983692 -398.666716) (xy 406.974548 -398.666716) (xy 406.964528 -398.667159)
			(xy 406.946009 -398.674816) (xy 406.931834 -398.688982) (xy 406.924165 -398.707496) (xy 406.923748 -398.717516)
			(xy 406.923748 -398.881092) (xy 406.923207 -398.891093) (xy 406.915559 -398.909576) (xy 406.901423 -398.923727)
			(xy 406.882949 -398.931396) (xy 406.872948 -398.931892) (xy 406.364948 -398.931892) (xy 406.354929 -398.931441)
			(xy 406.336411 -398.923785) (xy 406.322237 -398.909622) (xy 406.314567 -398.891111) (xy 406.314148 -398.881092)
			(xy 406.314148 -398.666716) (xy 406.305004 -398.666716) (xy 406.294999 -398.666209) (xy 406.27651 -398.658554)
			(xy 406.262357 -398.644407) (xy 406.254695 -398.625921) (xy 406.254204 -398.615916) (xy 406.254204 -398.411954)
			(xy 406.25455 -398.394721) (xy 406.260121 -398.360709) (xy 406.271092 -398.328036) (xy 406.278842 -398.31264)
			(xy 406.284684 -398.30121) (xy 406.28443 -398.27581) (xy 406.230836 -398.178782) (xy 406.209246 -398.165066)
			(xy 406.196292 -398.16405) (xy 406.172393 -398.161958) (xy 406.125605 -398.151352) (xy 406.080964 -398.133781)
			(xy 406.0395 -398.109649) (xy 406.00217 -398.079515) (xy 405.969837 -398.044072) (xy 405.943246 -398.004141)
			(xy 405.923012 -397.960642) (xy 405.915876 -397.937736) (xy 405.914352 -397.931894) (xy 405.593804 -397.377412)
			(xy 405.58974 -397.373094) (xy 405.573635 -397.355426) (xy 405.546387 -397.316147) (xy 405.525377 -397.273206)
			(xy 405.511085 -397.227587) (xy 405.503838 -397.180334) (xy 405.50338 -397.156432) (xy 405.503559 -397.142384)
			(xy 405.506102 -397.114402) (xy 405.50846 -397.100552) (xy 405.509755 -397.091296) (xy 405.506355 -397.072931)
			(xy 405.501856 -397.064738) (xy 405.485092 -397.037814) (xy 405.479899 -397.030104) (xy 405.465167 -397.018784)
			(xy 405.45639 -397.015716) (xy 405.434769 -397.0089) (xy 405.393554 -396.990023) (xy 405.355432 -396.965493)
			(xy 405.321175 -396.935803) (xy 405.306022 -396.918942) (xy 405.30356 -396.916169) (xy 405.297947 -396.911323)
			(xy 405.294846 -396.90929) (xy 405.282833 -396.901189) (xy 405.262937 -396.880138) (xy 405.248923 -396.854789)
			(xy 405.24168 -396.826744) (xy 405.241252 -396.812262) (xy 405.241252 -396.800324) (xy 405.239474 -396.79372)
			(xy 405.234268 -396.773351) (xy 405.228667 -396.731683) (xy 405.228298 -396.710662) (xy 404.664164 -396.710662)
			(xy 404.664164 -396.71117) (xy 404.663994 -396.725795) (xy 404.661327 -396.754924) (xy 404.65883 -396.769336)
			(xy 404.657463 -396.77851) (xy 404.660737 -396.796753) (xy 404.66518 -396.804896) (xy 404.68169 -396.83182)
			(xy 404.686843 -396.839611) (xy 404.701581 -396.851067) (xy 404.710392 -396.854172) (xy 404.735271 -396.862244)
			(xy 404.78215 -396.885431) (xy 404.824563 -396.916033) (xy 404.861347 -396.953212) (xy 404.891494 -396.995949)
			(xy 404.91418 -397.043073) (xy 404.921974 -397.06804) (xy 404.923498 -397.073882) (xy 405.243792 -397.627602)
			(xy 405.247856 -397.63192) (xy 405.264057 -397.64963) (xy 405.29148 -397.689021) (xy 405.312622 -397.732111)
			(xy 405.326997 -397.777904) (xy 405.334272 -397.825346) (xy 405.334724 -397.849344) (xy 405.334235 -397.874806)
			(xy 405.326036 -397.925067) (xy 405.309875 -397.973359) (xy 405.28617 -398.018431) (xy 405.255537 -398.059112)
			(xy 405.21877 -398.094348) (xy 405.198072 -398.109186) (xy 405.189579 -398.11567) (xy 405.178395 -398.133848)
			(xy 405.175561 -398.155001) (xy 405.181565 -398.175482) (xy 405.195372 -398.191756) (xy 405.214601 -398.201018)
			(xy 405.22525 -398.201896) (xy 405.234902 -398.201388) (xy 405.243416 -398.200096) (xy 405.260581 -398.198696)
			(xy 405.269192 -398.198594) (xy 405.269446 -398.198848) (xy 405.568658 -398.198848) (xy 405.568912 -398.198594)
			(xy 405.589975 -398.198951) (xy 405.631336 -398.206915) (xy 405.670335 -398.222828) (xy 405.705461 -398.246073)
			(xy 405.735352 -398.27575) (xy 405.758849 -398.310708) (xy 405.775042 -398.349591) (xy 405.783303 -398.390894)
			(xy 405.783796 -398.411954) (xy 405.783796 -398.666716) (xy 405.774652 -398.666716) (xy 405.764639 -398.667149)
			(xy 405.746143 -398.674828) (xy 405.731992 -398.688997) (xy 405.724337 -398.707503) (xy 405.723852 -398.717516)
			(xy 405.723852 -398.881092) (xy 405.723473 -398.891119) (xy 405.715797 -398.909645) (xy 405.701611 -398.923819)
			(xy 405.683079 -398.931481) (xy 405.673052 -398.931892) (xy 405.165052 -398.931892) (xy 405.15504 -398.931451)
			(xy 405.136546 -398.923774) (xy 405.122394 -398.909607) (xy 405.114738 -398.891104) (xy 405.114252 -398.881092)
			(xy 405.114252 -398.666716) (xy 405.105108 -398.666716) (xy 405.095103 -398.666206) (xy 405.076614 -398.658552)
			(xy 405.062462 -398.644406) (xy 405.054799 -398.625921) (xy 405.054308 -398.615916) (xy 405.054308 -398.411954)
			(xy 405.054654 -398.394721) (xy 405.060224 -398.360708) (xy 405.071196 -398.328035) (xy 405.078946 -398.31264)
			(xy 405.084788 -398.30121) (xy 405.084534 -398.27581) (xy 405.03094 -398.178782) (xy 405.00935 -398.165066)
			(xy 404.996396 -398.16405) (xy 404.972497 -398.161955) (xy 404.925709 -398.15135) (xy 404.881068 -398.133779)
			(xy 404.839604 -398.109648) (xy 404.802275 -398.079513) (xy 404.769941 -398.044072) (xy 404.74335 -398.00414)
			(xy 404.723116 -397.960642) (xy 404.71598 -397.937736) (xy 404.714456 -397.931894) (xy 404.394162 -397.378174)
			(xy 404.390098 -397.373856) (xy 404.373946 -397.356115) (xy 404.346575 -397.316716) (xy 404.325482 -397.273628)
			(xy 404.311153 -397.227844) (xy 404.303918 -397.180419) (xy 404.303484 -397.156432) (xy 404.303665 -397.142384)
			(xy 404.306206 -397.114402) (xy 404.308564 -397.100552) (xy 404.309891 -397.091273) (xy 404.306361 -397.072875)
			(xy 404.301706 -397.064738) (xy 404.284942 -397.037814) (xy 404.279731 -397.030117) (xy 404.265012 -397.01879)
			(xy 404.25624 -397.015716) (xy 404.234612 -397.00892) (xy 404.193398 -396.990037) (xy 404.155279 -396.9655)
			(xy 404.121023 -396.935806) (xy 404.105872 -396.918942) (xy 404.103404 -396.916175) (xy 404.097796 -396.911325)
			(xy 404.094696 -396.90929) (xy 404.082644 -396.901215) (xy 404.062683 -396.880179) (xy 404.048605 -396.854826)
			(xy 404.041302 -396.826761) (xy 404.040848 -396.812262) (xy 404.040848 -396.800324) (xy 404.039324 -396.79372)
			(xy 404.034117 -396.773351) (xy 404.028517 -396.731683) (xy 404.028148 -396.710662) (xy 403.464268 -396.710662)
			(xy 403.464268 -396.71117) (xy 403.464098 -396.725795) (xy 403.461431 -396.754924) (xy 403.458934 -396.769336)
			(xy 403.457566 -396.77851) (xy 403.460841 -396.796753) (xy 403.465284 -396.804896) (xy 403.481794 -396.83182)
			(xy 403.486945 -396.839612) (xy 403.501684 -396.851067) (xy 403.510496 -396.854172) (xy 403.535376 -396.862242)
			(xy 403.582255 -396.885429) (xy 403.624667 -396.916032) (xy 403.661451 -396.953211) (xy 403.691599 -396.995948)
			(xy 403.714284 -397.043073) (xy 403.722078 -397.06804) (xy 403.723602 -397.073882) (xy 404.043896 -397.627602)
			(xy 404.04796 -397.63192) (xy 404.064162 -397.64963) (xy 404.091584 -397.689021) (xy 404.112726 -397.73211)
			(xy 404.127101 -397.777904) (xy 404.134376 -397.825346) (xy 404.134828 -397.849344) (xy 404.134337 -397.874806)
			(xy 404.126138 -397.925067) (xy 404.109977 -397.973359) (xy 404.086273 -398.018431) (xy 404.05564 -398.059112)
			(xy 404.018874 -398.094348) (xy 403.998176 -398.109186) (xy 403.98969 -398.115647) (xy 403.978509 -398.133783)
			(xy 403.975644 -398.154895) (xy 403.981587 -398.175355) (xy 403.995317 -398.191647) (xy 404.014473 -398.200971)
			(xy 404.0251 -398.201896) (xy 404.035006 -398.201388) (xy 404.043457 -398.200103) (xy 404.060495 -398.198703)
			(xy 404.069042 -398.198594) (xy 404.069296 -398.198848) (xy 404.368508 -398.198848) (xy 404.368762 -398.198594)
			(xy 404.389809 -398.198977) (xy 404.43113 -398.206977) (xy 404.470086 -398.222913) (xy 404.505167 -398.246166)
			(xy 404.535018 -398.275837) (xy 404.558482 -398.310779) (xy 404.574651 -398.349637) (xy 404.5829 -398.39091)
			(xy 404.583392 -398.411954) (xy 404.583392 -398.666716) (xy 404.574248 -398.666716) (xy 404.564228 -398.667159)
			(xy 404.545709 -398.674816) (xy 404.531534 -398.688982) (xy 404.523865 -398.707496) (xy 404.523448 -398.717516)
			(xy 404.523448 -398.881092) (xy 404.522907 -398.891093) (xy 404.515259 -398.909576) (xy 404.501123 -398.923727)
			(xy 404.482649 -398.931396) (xy 404.472648 -398.931892) (xy 403.965156 -398.931892) (xy 403.955145 -398.931448)
			(xy 403.93665 -398.923772) (xy 403.922499 -398.909606) (xy 403.914842 -398.891104) (xy 403.914356 -398.881092)
			(xy 403.914356 -398.717516) (xy 403.913966 -398.70749) (xy 403.906294 -398.688965) (xy 403.892111 -398.674791)
			(xy 403.873582 -398.667128) (xy 403.863556 -398.666716) (xy 403.854412 -398.666716) (xy 403.854412 -398.411446)
			(xy 403.855197 -398.385724) (xy 403.86753 -398.335777) (xy 403.878796 -398.31264) (xy 403.884638 -398.30121)
			(xy 403.884384 -398.27581) (xy 403.836886 -398.190212) (xy 403.830154 -398.179441) (xy 403.808838 -398.165699)
			(xy 403.796246 -398.16405) (xy 403.772375 -398.161846) (xy 403.725631 -398.15122) (xy 403.681035 -398.133641)
			(xy 403.639613 -398.109514) (xy 403.602321 -398.079396) (xy 403.570017 -398.043979) (xy 403.543446 -398.004081)
			(xy 403.52322 -397.960621) (xy 403.516084 -397.937736) (xy 403.51456 -397.931894) (xy 403.194266 -397.378174)
			(xy 403.190202 -397.373856) (xy 403.174051 -397.356115) (xy 403.14668 -397.316716) (xy 403.125587 -397.273628)
			(xy 403.111257 -397.227844) (xy 403.104022 -397.180419) (xy 403.103588 -397.156432) (xy 403.103769 -397.142384)
			(xy 403.10631 -397.114402) (xy 403.108668 -397.100552) (xy 403.109995 -397.091273) (xy 403.106465 -397.072875)
			(xy 403.10181 -397.064738) (xy 403.085046 -397.037814) (xy 403.079834 -397.030118) (xy 403.065116 -397.018791)
			(xy 403.056344 -397.015716) (xy 403.034717 -397.008918) (xy 402.993503 -396.990036) (xy 402.955383 -396.9655)
			(xy 402.921127 -396.935806) (xy 402.905976 -396.918942) (xy 402.903507 -396.916175) (xy 402.897899 -396.911325)
			(xy 402.8948 -396.90929) (xy 402.882749 -396.901214) (xy 402.862788 -396.880178) (xy 402.848709 -396.854825)
			(xy 402.841406 -396.826761) (xy 402.840952 -396.812262) (xy 402.840952 -396.800324) (xy 402.839428 -396.79372)
			(xy 402.834221 -396.773351) (xy 402.828621 -396.731683) (xy 402.828252 -396.710662) (xy 401.061908 -396.710662)
			(xy 401.055216 -396.753845) (xy 401.047966 -396.778226) (xy 401.04568 -396.785846) (xy 401.04568 -396.876778)
			(xy 401.045094 -396.893436) (xy 401.036488 -396.92562) (xy 401.019855 -396.954485) (xy 400.996326 -396.97807)
			(xy 400.9675 -396.994772) (xy 400.935336 -397.003454) (xy 400.91868 -397.004032) (xy 400.788378 -397.004032)
			(xy 400.784568 -397.004794) (xy 400.771763 -397.006699) (xy 400.745952 -397.008735) (xy 400.733006 -397.008858)
			(xy 400.732498 -397.008858) (xy 400.719553 -397.008721) (xy 400.693743 -397.006685) (xy 400.680936 -397.004794)
			(xy 400.677126 -397.004032) (xy 400.537172 -397.004032) (xy 400.520479 -397.003491) (xy 400.488228 -396.994855)
			(xy 400.459305 -396.978179) (xy 400.435674 -396.954594) (xy 400.418941 -396.925704) (xy 400.410242 -396.89347)
			(xy 400.409664 -396.876778) (xy 400.409664 -396.749524) (xy 400.408648 -396.744444) (xy 400.40554 -396.728047)
			(xy 400.402229 -396.694838) (xy 400.402044 -396.67815) (xy 400.200086 -396.67815) (xy 400.200114 -396.679674)
			(xy 400.199605 -396.70756) (xy 400.191485 -396.762736) (xy 400.175417 -396.816143) (xy 400.151745 -396.86664)
			(xy 400.120972 -396.913153) (xy 400.083755 -396.95469) (xy 400.040887 -396.990365) (xy 399.993281 -397.019419)
			(xy 399.941952 -397.041231) (xy 399.887995 -397.055337) (xy 399.832558 -397.061437) (xy 399.776824 -397.0594)
			(xy 399.721981 -397.04927) (xy 399.669197 -397.031263) (xy 399.619597 -397.005762) (xy 399.574239 -396.973311)
			(xy 399.53409 -396.934602) (xy 399.500004 -396.890459) (xy 399.472708 -396.841824) (xy 399.452785 -396.789733)
			(xy 399.440659 -396.735296) (xy 399.436588 -396.679674) (xy 398.361408 -396.679674) (xy 398.361408 -396.735554)
			(xy 398.361894 -396.746299) (xy 398.370721 -396.765892) (xy 398.378426 -396.7734) (xy 398.40277 -396.795729)
			(xy 398.44606 -396.845627) (xy 398.482519 -396.900713) (xy 398.511535 -396.960058) (xy 398.532618 -397.022662)
			(xy 398.545411 -397.08747) (xy 398.549701 -397.153389) (xy 398.545414 -397.219309) (xy 398.532623 -397.284117)
			(xy 398.511543 -397.346723) (xy 398.48253 -397.406069) (xy 398.446072 -397.461156) (xy 398.402785 -397.511056)
			(xy 398.378426 -397.533368) (xy 398.370796 -397.540929) (xy 398.361977 -397.560489) (xy 398.361408 -397.571214)
			(xy 398.361408 -399.008092) (xy 400.39036 -399.008092) (xy 400.39078 -398.984859) (xy 400.397273 -398.938849)
			(xy 400.410145 -398.894202) (xy 400.429141 -398.851797) (xy 400.453888 -398.81247) (xy 400.468592 -398.794478)
			(xy 400.474434 -398.78762) (xy 400.480784 -398.770602) (xy 400.480784 -398.686782) (xy 400.474434 -398.669764)
			(xy 400.468592 -398.662906) (xy 400.453871 -398.644927) (xy 400.429127 -398.605594) (xy 400.41013 -398.563187)
			(xy 400.397254 -398.518538) (xy 400.390753 -398.472526) (xy 400.39036 -398.449292) (xy 400.39087 -398.423305)
			(xy 400.399 -398.37197) (xy 400.415061 -398.32254) (xy 400.438657 -398.27623) (xy 400.469207 -398.234182)
			(xy 400.505958 -398.197431) (xy 400.548006 -398.166881) (xy 400.594316 -398.143285) (xy 400.643746 -398.127224)
			(xy 400.695081 -398.119094) (xy 400.747055 -398.119094) (xy 400.79839 -398.127224) (xy 400.84782 -398.143285)
			(xy 400.89413 -398.166881) (xy 400.936178 -398.197431) (xy 400.972929 -398.234182) (xy 401.003479 -398.27623)
			(xy 401.027075 -398.32254) (xy 401.043136 -398.37197) (xy 401.051266 -398.423305) (xy 401.051776 -398.449292)
			(xy 401.051396 -398.472526) (xy 401.044892 -398.518537) (xy 401.032011 -398.563185) (xy 401.013006 -398.605589)
			(xy 401.006505 -398.615916) (xy 402.654008 -398.615916) (xy 402.654008 -398.411954) (xy 402.654573 -398.390895)
			(xy 402.662816 -398.349593) (xy 402.678994 -398.310707) (xy 402.70248 -398.275746) (xy 402.732361 -398.246065)
			(xy 402.76748 -398.222817) (xy 402.806474 -398.206901) (xy 402.847831 -398.198936) (xy 402.868892 -398.198594)
			(xy 402.869146 -398.198848) (xy 403.168358 -398.198848) (xy 403.168612 -398.198594) (xy 403.189675 -398.198951)
			(xy 403.231036 -398.206915) (xy 403.270035 -398.222828) (xy 403.305161 -398.246073) (xy 403.335052 -398.27575)
			(xy 403.358549 -398.310708) (xy 403.374742 -398.349591) (xy 403.383003 -398.390894) (xy 403.383496 -398.411954)
			(xy 403.383496 -398.666716) (xy 403.374352 -398.666716) (xy 403.364339 -398.667149) (xy 403.345843 -398.674828)
			(xy 403.331692 -398.688997) (xy 403.324037 -398.707503) (xy 403.323552 -398.717516) (xy 403.323552 -398.881092)
			(xy 403.323173 -398.891119) (xy 403.315497 -398.909645) (xy 403.301311 -398.923819) (xy 403.282779 -398.931481)
			(xy 403.272752 -398.931892) (xy 402.764752 -398.931892) (xy 402.75474 -398.931451) (xy 402.736246 -398.923774)
			(xy 402.722094 -398.909607) (xy 402.714438 -398.891104) (xy 402.713952 -398.881092) (xy 402.713952 -398.666716)
			(xy 402.704808 -398.666716) (xy 402.694803 -398.666206) (xy 402.676314 -398.658552) (xy 402.662162 -398.644406)
			(xy 402.654499 -398.625921) (xy 402.654008 -398.615916) (xy 401.006505 -398.615916) (xy 400.988251 -398.644915)
			(xy 400.973544 -398.662906) (xy 400.967702 -398.669764) (xy 400.961352 -398.686782) (xy 400.961352 -398.770602)
			(xy 400.967702 -398.78762) (xy 400.973544 -398.794478) (xy 400.988248 -398.812471) (xy 401.012997 -398.851798)
			(xy 401.031998 -398.894203) (xy 401.044878 -398.938849) (xy 401.051382 -398.984859) (xy 401.051776 -399.008092)
			(xy 401.051776 -399.008346) (xy 401.051349 -399.032396) (xy 401.044358 -399.079986) (xy 401.030558 -399.126065)
			(xy 401.020788 -399.148046) (xy 401.015454 -399.159476) (xy 401.016724 -399.184622) (xy 401.066508 -399.26768)
			(xy 401.073439 -399.278049) (xy 401.09475 -399.290956) (xy 401.107148 -399.292318) (xy 401.132143 -399.294174)
			(xy 401.181187 -399.304504) (xy 401.228111 -399.322116) (xy 401.27184 -399.346607) (xy 401.311373 -399.377416)
			(xy 401.345804 -399.413838) (xy 401.374345 -399.455038) (xy 401.396342 -399.500073) (xy 401.411292 -399.547911)
			(xy 401.418852 -399.597458) (xy 401.419314 -399.622518) (xy 401.418804 -399.648505) (xy 401.410674 -399.69984)
			(xy 401.394613 -399.74927) (xy 401.371017 -399.79558) (xy 401.340467 -399.837628) (xy 401.303716 -399.874379)
			(xy 401.261668 -399.904929) (xy 401.215358 -399.928525) (xy 401.165928 -399.944586) (xy 401.114593 -399.952716)
			(xy 401.062619 -399.952716) (xy 401.011284 -399.944586) (xy 400.961854 -399.928525) (xy 400.915544 -399.904929)
			(xy 400.873496 -399.874379) (xy 400.836745 -399.837628) (xy 400.806195 -399.79558) (xy 400.782599 -399.74927)
			(xy 400.766538 -399.69984) (xy 400.758408 -399.648505) (xy 400.757898 -399.622518) (xy 400.757898 -399.622264)
			(xy 400.758331 -399.598214) (xy 400.76532 -399.550624) (xy 400.779118 -399.504545) (xy 400.788886 -399.482564)
			(xy 400.79422 -399.471134) (xy 400.79295 -399.445988) (xy 400.743166 -399.36293) (xy 400.736196 -399.352594)
			(xy 400.714914 -399.33967) (xy 400.702526 -399.338292) (xy 400.67753 -399.336448) (xy 400.628486 -399.326115)
			(xy 400.581563 -399.3085) (xy 400.537835 -399.284007) (xy 400.498303 -399.253197) (xy 400.463872 -399.216774)
			(xy 400.435331 -399.175573) (xy 400.413334 -399.130538) (xy 400.398383 -399.082699) (xy 400.390822 -399.033152)
			(xy 400.39036 -399.008092) (xy 398.361408 -399.008092) (xy 398.361408 -399.528284) (xy 398.36097 -399.538348)
			(xy 398.353235 -399.556931) (xy 398.346422 -399.564352) (xy 398.145254 -399.76552) (xy 398.137857 -399.772368)
			(xy 398.119258 -399.780098) (xy 398.109186 -399.780506) (xy 397.800322 -399.780506) (xy 397.790258 -399.780944)
			(xy 397.771675 -399.788679) (xy 397.764254 -399.795492) (xy 397.705834 -399.854166) (xy 397.698434 -399.861006)
			(xy 397.679835 -399.868721) (xy 397.669766 -399.869152) (xy 396.839948 -399.869152) (xy 396.829917 -399.869591)
			(xy 396.811346 -399.877171) (xy 396.80388 -399.883884) (xy 396.788132 -399.899632) (xy 396.781287 -399.907031)
			(xy 396.773559 -399.925629) (xy 396.773146 -399.9357) (xy 396.773146 -400.567652) (xy 399.583656 -400.567652)
			(xy 399.584146 -400.537684) (xy 399.591969 -400.478262) (xy 399.607482 -400.420369) (xy 399.630418 -400.364996)
			(xy 399.660385 -400.31309) (xy 399.696872 -400.26554) (xy 399.739252 -400.22316) (xy 399.786802 -400.186673)
			(xy 399.838708 -400.156706) (xy 399.894081 -400.13377) (xy 399.951974 -400.118257) (xy 400.011396 -400.110434)
			(xy 400.071332 -400.110434) (xy 400.130754 -400.118257) (xy 400.188647 -400.13377) (xy 400.24402 -400.156706)
			(xy 400.295926 -400.186673) (xy 400.343476 -400.22316) (xy 400.373262 -400.252946) (xy 401.750276 -400.252946)
			(xy 401.750276 -399.998184) (xy 401.75942 -399.998184) (xy 401.769431 -399.997728) (xy 401.787926 -399.990059)
			(xy 401.802079 -399.975896) (xy 401.809735 -399.957395) (xy 401.81022 -399.947384) (xy 401.81022 -399.783808)
			(xy 401.810626 -399.773785) (xy 401.818298 -399.755264) (xy 401.832474 -399.741091) (xy 401.850997 -399.733424)
			(xy 401.86102 -399.733008) (xy 402.36902 -399.733008) (xy 402.37903 -399.733472) (xy 402.397524 -399.741139)
			(xy 402.411676 -399.7553) (xy 402.419334 -399.773798) (xy 402.41982 -399.783808) (xy 402.41982 -399.998184)
			(xy 402.428964 -399.998184) (xy 402.438981 -399.998649) (xy 402.457494 -400.006304) (xy 402.471667 -400.020462)
			(xy 402.479341 -400.038967) (xy 402.479764 -400.048984) (xy 402.479764 -400.252946) (xy 402.479198 -400.275553)
			(xy 402.469676 -400.319753) (xy 402.451068 -400.360961) (xy 402.424206 -400.397331) (xy 402.407628 -400.412712)
			(xy 402.40077 -400.418808) (xy 402.392134 -400.43481) (xy 402.381974 -400.50974) (xy 402.381107 -400.518623)
			(xy 402.384863 -400.536056) (xy 402.38934 -400.543776) (xy 402.389594 -400.543776) (xy 402.389594 -400.544284)
			(xy 402.40164 -400.563652) (xy 402.420709 -400.605082) (xy 402.433661 -400.648813) (xy 402.44023 -400.693946)
			(xy 402.440648 -400.71675) (xy 402.440158 -400.741739) (xy 402.432339 -400.791102) (xy 402.416895 -400.838634)
			(xy 402.394205 -400.883166) (xy 402.364829 -400.923599) (xy 402.329489 -400.958939) (xy 402.289056 -400.988315)
			(xy 402.244524 -401.011005) (xy 402.196992 -401.026449) (xy 402.147629 -401.034268) (xy 402.097651 -401.034268)
			(xy 402.048288 -401.026449) (xy 402.000756 -401.011005) (xy 401.956224 -400.988315) (xy 401.915791 -400.958939)
			(xy 401.880451 -400.923599) (xy 401.851075 -400.883166) (xy 401.828385 -400.838634) (xy 401.812941 -400.791102)
			(xy 401.805122 -400.741739) (xy 401.804632 -400.71675) (xy 401.805307 -400.687549) (xy 401.815957 -400.630126)
			(xy 401.836909 -400.575612) (xy 401.851622 -400.55038) (xy 401.856092 -400.542383) (xy 401.859609 -400.524419)
			(xy 401.85848 -400.515328) (xy 401.845526 -400.43989) (xy 401.836636 -400.424396) (xy 401.829524 -400.418554)
			(xy 401.829016 -400.418046) (xy 401.814599 -400.405793) (xy 401.789927 -400.377113) (xy 401.770689 -400.344538)
			(xy 401.757486 -400.309085) (xy 401.75073 -400.271861) (xy 401.750276 -400.252946) (xy 400.373262 -400.252946)
			(xy 400.385856 -400.26554) (xy 400.422343 -400.31309) (xy 400.45231 -400.364996) (xy 400.475246 -400.420369)
			(xy 400.490759 -400.478262) (xy 400.498582 -400.537684) (xy 400.499072 -400.567652) (xy 400.499072 -400.568668)
			(xy 400.498743 -400.592079) (xy 400.493911 -400.638653) (xy 400.48942 -400.661632) (xy 400.487388 -400.67103)
			(xy 400.49069 -400.690588) (xy 400.533362 -400.758406) (xy 400.538817 -400.766391) (xy 400.554356 -400.777878)
			(xy 400.563588 -400.780758) (xy 400.563842 -400.780758) (xy 400.590897 -400.78812) (xy 400.642626 -400.809752)
			(xy 400.690633 -400.83872) (xy 400.733886 -400.8744) (xy 400.771453 -400.916024) (xy 400.802525 -400.962696)
			(xy 400.826435 -401.013412) (xy 400.842668 -401.067081) (xy 400.850874 -401.122547) (xy 400.85137 -401.150582)
			(xy 400.850884 -401.177833) (xy 400.843128 -401.231781) (xy 400.827773 -401.284076) (xy 400.805131 -401.333653)
			(xy 400.775665 -401.379503) (xy 400.739974 -401.420694) (xy 400.698783 -401.456385) (xy 400.652933 -401.485851)
			(xy 400.603356 -401.508493) (xy 400.551061 -401.523848) (xy 400.497113 -401.531604) (xy 400.442611 -401.531604)
			(xy 400.388663 -401.523848) (xy 400.336368 -401.508493) (xy 400.286791 -401.485851) (xy 400.240941 -401.456385)
			(xy 400.19975 -401.420694) (xy 400.164059 -401.379503) (xy 400.134593 -401.333653) (xy 400.111951 -401.284076)
			(xy 400.096596 -401.231781) (xy 400.08884 -401.177833) (xy 400.088354 -401.150582) (xy 400.088862 -401.129754)
			(xy 400.08937 -401.120102) (xy 400.083274 -401.101306) (xy 400.024346 -401.033234) (xy 400.00682 -401.02409)
			(xy 399.997168 -401.023328) (xy 399.966671 -401.019915) (xy 399.906934 -401.005856) (xy 399.849609 -400.983944)
			(xy 399.795725 -400.954574) (xy 399.746246 -400.918269) (xy 399.702059 -400.875682) (xy 399.663955 -400.827575)
			(xy 399.632617 -400.77481) (xy 399.608607 -400.718333) (xy 399.592355 -400.659155) (xy 399.584152 -400.598337)
			(xy 399.583656 -400.567652) (xy 396.773146 -400.567652) (xy 396.773146 -401.043648) (xy 396.773579 -401.053713)
			(xy 396.781311 -401.072301) (xy 396.788132 -401.079716) (xy 396.926562 -401.217892) (xy 396.933414 -401.225288)
			(xy 396.941157 -401.243887) (xy 396.941548 -401.25396) (xy 396.941548 -401.674838) (xy 403.06244 -401.674838)
			(xy 403.06244 -400.811238) (xy 403.062865 -400.785718) (xy 403.069655 -400.735132) (xy 403.083132 -400.685903)
			(xy 403.103055 -400.638912) (xy 403.129068 -400.594999) (xy 403.160707 -400.554948) (xy 403.178772 -400.536918)
			(xy 403.185376 -400.530568) (xy 403.19325 -400.513804) (xy 403.200108 -400.42846) (xy 403.195028 -400.41068)
			(xy 403.18944 -400.403314) (xy 403.174591 -400.382565) (xy 403.150955 -400.337352) (xy 403.134853 -400.28894)
			(xy 403.1267 -400.238577) (xy 403.126194 -400.213068) (xy 403.126194 -400.212814) (xy 403.126684 -400.187825)
			(xy 403.134503 -400.138462) (xy 403.149947 -400.09093) (xy 403.172637 -400.046398) (xy 403.202013 -400.005965)
			(xy 403.237353 -399.970625) (xy 403.277786 -399.941249) (xy 403.322318 -399.918559) (xy 403.36985 -399.903115)
			(xy 403.419213 -399.895296) (xy 403.469191 -399.895296) (xy 403.518554 -399.903115) (xy 403.566086 -399.918559)
			(xy 403.610618 -399.941249) (xy 403.651051 -399.970625) (xy 403.686391 -400.005965) (xy 403.715767 -400.046398)
			(xy 403.738457 -400.09093) (xy 403.753901 -400.138462) (xy 403.76172 -400.187825) (xy 403.76221 -400.212814)
			(xy 403.76221 -400.213068) (xy 403.761715 -400.238577) (xy 403.753538 -400.288936) (xy 403.737436 -400.337347)
			(xy 403.713822 -400.382572) (xy 403.698964 -400.403314) (xy 403.693376 -400.41068) (xy 403.688296 -400.42846)
			(xy 403.695154 -400.513804) (xy 403.703028 -400.530568) (xy 403.709632 -400.536918) (xy 403.727662 -400.554981)
			(xy 403.759294 -400.595031) (xy 403.785306 -400.638939) (xy 403.805235 -400.685922) (xy 403.818724 -400.735142)
			(xy 403.825534 -400.785721) (xy 403.825964 -400.811238) (xy 403.825964 -401.674838) (xy 404.262336 -401.674838)
			(xy 404.262336 -400.811238) (xy 404.262762 -400.785718) (xy 404.269552 -400.735132) (xy 404.283029 -400.685903)
			(xy 404.302952 -400.638913) (xy 404.328965 -400.594999) (xy 404.360603 -400.554948) (xy 404.378668 -400.536918)
			(xy 404.385526 -400.530568) (xy 404.3934 -400.513804) (xy 404.399496 -400.43735) (xy 404.399843 -400.428285)
			(xy 404.394901 -400.410845) (xy 404.389844 -400.403314) (xy 404.38959 -400.40306) (xy 404.374729 -400.38232)
			(xy 404.351103 -400.3371) (xy 404.335006 -400.288687) (xy 404.326852 -400.238324) (xy 404.326344 -400.212814)
			(xy 404.326834 -400.187825) (xy 404.334653 -400.138462) (xy 404.350097 -400.09093) (xy 404.372787 -400.046398)
			(xy 404.402163 -400.005965) (xy 404.437503 -399.970625) (xy 404.477936 -399.941249) (xy 404.522468 -399.918559)
			(xy 404.57 -399.903115) (xy 404.619363 -399.895296) (xy 404.669341 -399.895296) (xy 404.718704 -399.903115)
			(xy 404.766236 -399.918559) (xy 404.810768 -399.941249) (xy 404.851201 -399.970625) (xy 404.886541 -400.005965)
			(xy 404.915917 -400.046398) (xy 404.938607 -400.09093) (xy 404.954051 -400.138462) (xy 404.96187 -400.187825)
			(xy 404.96236 -400.212814) (xy 404.961844 -400.238367) (xy 404.953657 -400.288812) (xy 404.937497 -400.337295)
			(xy 404.913781 -400.382564) (xy 404.89886 -400.403314) (xy 404.893272 -400.41068) (xy 404.888192 -400.42846)
			(xy 404.894288 -400.504914) (xy 404.895392 -400.513912) (xy 404.90306 -400.53032) (xy 404.909274 -400.536918)
			(xy 404.909528 -400.537172) (xy 404.927581 -400.555185) (xy 404.959195 -400.595201) (xy 404.985195 -400.639073)
			(xy 405.005117 -400.686018) (xy 405.018607 -400.735199) (xy 405.025424 -400.785739) (xy 405.02586 -400.811238)
			(xy 405.02586 -401.674838) (xy 405.46274 -401.674838) (xy 405.46274 -400.81073) (xy 405.463168 -400.785262)
			(xy 405.469971 -400.734781) (xy 405.483434 -400.685655) (xy 405.503316 -400.638759) (xy 405.529264 -400.594926)
			(xy 405.560815 -400.554938) (xy 405.578818 -400.536918) (xy 405.585422 -400.530568) (xy 405.593296 -400.513804)
			(xy 405.600154 -400.42846) (xy 405.595074 -400.41068) (xy 405.589486 -400.403314) (xy 405.57463 -400.38257)
			(xy 405.550997 -400.337354) (xy 405.534898 -400.288942) (xy 405.526746 -400.238578) (xy 405.52624 -400.213068)
			(xy 405.52624 -400.212814) (xy 405.52673 -400.187825) (xy 405.534549 -400.138462) (xy 405.549993 -400.09093)
			(xy 405.572683 -400.046398) (xy 405.602059 -400.005965) (xy 405.637399 -399.970625) (xy 405.677832 -399.941249)
			(xy 405.722364 -399.918559) (xy 405.769896 -399.903115) (xy 405.819259 -399.895296) (xy 405.869237 -399.895296)
			(xy 405.9186 -399.903115) (xy 405.966132 -399.918559) (xy 406.010664 -399.941249) (xy 406.051097 -399.970625)
			(xy 406.086437 -400.005965) (xy 406.115813 -400.046398) (xy 406.138503 -400.09093) (xy 406.153947 -400.138462)
			(xy 406.161766 -400.187825) (xy 406.162256 -400.212814) (xy 406.162256 -400.213068) (xy 406.161752 -400.238576)
			(xy 406.153576 -400.288935) (xy 406.137477 -400.337346) (xy 406.113866 -400.382571) (xy 406.09901 -400.403314)
			(xy 406.093422 -400.41068) (xy 406.088342 -400.42846) (xy 406.0952 -400.513804) (xy 406.103074 -400.530568)
			(xy 406.109678 -400.536918) (xy 406.127682 -400.554936) (xy 406.159222 -400.594931) (xy 406.185161 -400.638766)
			(xy 406.20504 -400.685662) (xy 406.218505 -400.734785) (xy 406.225315 -400.785263) (xy 406.225756 -400.81073)
			(xy 406.225756 -401.674838) (xy 406.225746 -401.675346) (xy 406.662636 -401.675346) (xy 406.662636 -400.81073)
			(xy 406.663065 -400.785262) (xy 406.669868 -400.734781) (xy 406.68333 -400.685656) (xy 406.703212 -400.638759)
			(xy 406.72916 -400.594927) (xy 406.760712 -400.554938) (xy 406.778714 -400.536918) (xy 406.785318 -400.530568)
			(xy 406.793192 -400.513804) (xy 406.80005 -400.42846) (xy 406.79497 -400.41068) (xy 406.789382 -400.403314)
			(xy 406.774525 -400.38257) (xy 406.750893 -400.337354) (xy 406.734793 -400.288942) (xy 406.726642 -400.238578)
			(xy 406.726136 -400.213068) (xy 406.726136 -400.212814) (xy 406.726626 -400.187825) (xy 406.734445 -400.138462)
			(xy 406.749889 -400.09093) (xy 406.772579 -400.046398) (xy 406.801955 -400.005965) (xy 406.837295 -399.970625)
			(xy 406.877728 -399.941249) (xy 406.92226 -399.918559) (xy 406.969792 -399.903115) (xy 407.019155 -399.895296)
			(xy 407.069133 -399.895296) (xy 407.118496 -399.903115) (xy 407.166028 -399.918559) (xy 407.21056 -399.941249)
			(xy 407.250993 -399.970625) (xy 407.286333 -400.005965) (xy 407.315709 -400.046398) (xy 407.338399 -400.09093)
			(xy 407.353843 -400.138462) (xy 407.361662 -400.187825) (xy 407.362152 -400.212814) (xy 407.362152 -400.213068)
			(xy 407.361649 -400.238577) (xy 407.353473 -400.288935) (xy 407.337374 -400.337346) (xy 407.313762 -400.382571)
			(xy 407.298906 -400.403314) (xy 407.293318 -400.41068) (xy 407.288238 -400.42846) (xy 407.295096 -400.513804)
			(xy 407.30297 -400.530568) (xy 407.309574 -400.536918) (xy 407.327577 -400.554936) (xy 407.359117 -400.594931)
			(xy 407.385057 -400.638766) (xy 407.404936 -400.685662) (xy 407.4184 -400.734785) (xy 407.425211 -400.785263)
			(xy 407.425652 -400.81073) (xy 407.425652 -401.675346) (xy 407.425176 -401.703744) (xy 407.416763 -401.759913)
			(xy 407.4001 -401.814209) (xy 407.375558 -401.865428) (xy 407.343681 -401.912433) (xy 407.324814 -401.933664)
			(xy 407.318954 -401.9406) (xy 407.312046 -401.957378) (xy 407.311352 -401.96643) (xy 407.310336 -401.997418)
			(xy 407.310382 -402.00657) (xy 407.316255 -402.023892) (xy 407.321766 -402.0312) (xy 407.33711 -402.050547)
			(xy 407.362884 -402.092668) (xy 407.382662 -402.137914) (xy 407.396074 -402.185438) (xy 407.402869 -402.234348)
			(xy 407.4033 -402.259038) (xy 407.402798 -402.285915) (xy 407.394786 -402.33907) (xy 407.378942 -402.390436)
			(xy 407.355618 -402.438868) (xy 407.325337 -402.483282) (xy 407.288775 -402.522687) (xy 407.246747 -402.556203)
			(xy 407.200194 -402.58308) (xy 407.150155 -402.602719) (xy 407.097748 -402.61468) (xy 407.044144 -402.618698)
			(xy 406.99054 -402.61468) (xy 406.938133 -402.602719) (xy 406.888094 -402.58308) (xy 406.841541 -402.556203)
			(xy 406.799513 -402.522687) (xy 406.762951 -402.483282) (xy 406.73267 -402.438868) (xy 406.709346 -402.390436)
			(xy 406.693502 -402.33907) (xy 406.68549 -402.285915) (xy 406.684988 -402.259038) (xy 406.68539 -402.234344)
			(xy 406.692146 -402.185422) (xy 406.70555 -402.137888) (xy 406.725348 -402.092643) (xy 406.751166 -402.050542)
			(xy 406.766522 -402.0312) (xy 406.772001 -402.023878) (xy 406.777849 -402.006563) (xy 406.777952 -401.997418)
			(xy 406.776936 -401.96643) (xy 406.776296 -401.957366) (xy 406.769378 -401.940573) (xy 406.763474 -401.933664)
			(xy 406.744656 -401.9124) (xy 406.712837 -401.865373) (xy 406.688321 -401.814158) (xy 406.671649 -401.759881)
			(xy 406.663187 -401.703735) (xy 406.662636 -401.675346) (xy 406.225746 -401.675346) (xy 406.225195 -401.703991)
			(xy 406.216325 -401.761618) (xy 406.198798 -401.817227) (xy 406.17302 -401.869525) (xy 406.139591 -401.917296)
			(xy 406.119838 -401.938744) (xy 406.113674 -401.945823) (xy 406.106521 -401.963161) (xy 406.105868 -401.972526)
			(xy 406.10409 -402.041106) (xy 406.104236 -402.050362) (xy 406.110368 -402.067815) (xy 406.116028 -402.075142)
			(xy 406.116536 -402.07565) (xy 406.132857 -402.095277) (xy 406.160328 -402.138301) (xy 406.181429 -402.184782)
			(xy 406.195735 -402.233782) (xy 406.202958 -402.284315) (xy 406.203404 -402.309838) (xy 406.202902 -402.336715)
			(xy 406.19489 -402.38987) (xy 406.179046 -402.441236) (xy 406.155722 -402.489668) (xy 406.125441 -402.534082)
			(xy 406.088879 -402.573487) (xy 406.046851 -402.607003) (xy 406.000298 -402.63388) (xy 405.950259 -402.653519)
			(xy 405.897852 -402.66548) (xy 405.844248 -402.669498) (xy 405.790644 -402.66548) (xy 405.738237 -402.653519)
			(xy 405.688198 -402.63388) (xy 405.641645 -402.607003) (xy 405.599617 -402.573487) (xy 405.563055 -402.534082)
			(xy 405.532774 -402.489668) (xy 405.50945 -402.441236) (xy 405.493606 -402.38987) (xy 405.485594 -402.336715)
			(xy 405.485092 -402.309838) (xy 405.485554 -402.28428) (xy 405.492791 -402.23368) (xy 405.507138 -402.18462)
			(xy 405.528305 -402.138093) (xy 405.555862 -402.095043) (xy 405.572214 -402.075396) (xy 405.572468 -402.075142)
			(xy 405.578132 -402.067821) (xy 405.584243 -402.050362) (xy 405.584406 -402.041106) (xy 405.582374 -401.962874)
			(xy 405.575262 -401.945856) (xy 405.568658 -401.938744) (xy 405.548932 -401.917271) (xy 405.515491 -401.869511)
			(xy 405.489703 -401.81722) (xy 405.472168 -401.761615) (xy 405.463295 -401.70399) (xy 405.46274 -401.674838)
			(xy 405.02586 -401.674838) (xy 405.025341 -401.702712) (xy 405.017235 -401.757867) (xy 405.001187 -401.811255)
			(xy 404.977538 -401.861738) (xy 404.946793 -401.908241) (xy 404.928578 -401.929346) (xy 404.922736 -401.93595)
			(xy 404.915878 -401.952714) (xy 404.913846 -402.027136) (xy 404.913955 -402.036041) (xy 404.919553 -402.052935)
			(xy 404.924768 -402.060156) (xy 404.925022 -402.06041) (xy 404.939799 -402.079579) (xy 404.964624 -402.121129)
			(xy 404.983658 -402.16563) (xy 404.996558 -402.21228) (xy 405.003091 -402.260238) (xy 405.003508 -402.284438)
			(xy 405.003006 -402.311334) (xy 404.994988 -402.364526) (xy 404.979132 -402.415929) (xy 404.955793 -402.464395)
			(xy 404.92549 -402.508841) (xy 404.888902 -402.548274) (xy 404.846845 -402.581813) (xy 404.800259 -402.608709)
			(xy 404.750185 -402.628362) (xy 404.69774 -402.640332) (xy 404.644098 -402.644352) (xy 404.590456 -402.640332)
			(xy 404.538011 -402.628362) (xy 404.487937 -402.608709) (xy 404.441351 -402.581813) (xy 404.399294 -402.548274)
			(xy 404.362706 -402.508841) (xy 404.332403 -402.464395) (xy 404.309064 -402.415929) (xy 404.293208 -402.364526)
			(xy 404.28519 -402.311334) (xy 404.284688 -402.284438) (xy 404.285093 -402.260235) (xy 404.291594 -402.212268)
			(xy 404.304483 -402.16561) (xy 404.323527 -402.121107) (xy 404.348379 -402.079568) (xy 404.363174 -402.06041)
			(xy 404.363428 -402.060156) (xy 404.368699 -402.052968) (xy 404.374283 -402.03605) (xy 404.37435 -402.027136)
			(xy 404.372318 -401.952714) (xy 404.36546 -401.93595) (xy 404.359618 -401.929346) (xy 404.341421 -401.908226)
			(xy 404.310674 -401.861726) (xy 404.28702 -401.811247) (xy 404.270964 -401.757863) (xy 404.262846 -401.702711)
			(xy 404.262336 -401.674838) (xy 403.825964 -401.674838) (xy 403.825469 -401.702713) (xy 403.817361 -401.75787)
			(xy 403.801308 -401.811259) (xy 403.777654 -401.861742) (xy 403.746901 -401.908243) (xy 403.728682 -401.929346)
			(xy 403.72284 -401.93595) (xy 403.715982 -401.952714) (xy 403.71395 -402.027136) (xy 403.714058 -402.036042)
			(xy 403.719657 -402.052935) (xy 403.724872 -402.060156) (xy 403.725126 -402.06041) (xy 403.73989 -402.079589)
			(xy 403.764719 -402.121135) (xy 403.783757 -402.165633) (xy 403.79666 -402.212282) (xy 403.803195 -402.260238)
			(xy 403.803612 -402.284438) (xy 403.80311 -402.311334) (xy 403.795092 -402.364526) (xy 403.779236 -402.415929)
			(xy 403.755897 -402.464395) (xy 403.725594 -402.508841) (xy 403.689006 -402.548274) (xy 403.646949 -402.581813)
			(xy 403.600363 -402.608709) (xy 403.550289 -402.628362) (xy 403.497844 -402.640332) (xy 403.444202 -402.644352)
			(xy 403.39056 -402.640332) (xy 403.338115 -402.628362) (xy 403.288041 -402.608709) (xy 403.241455 -402.581813)
			(xy 403.199398 -402.548274) (xy 403.16281 -402.508841) (xy 403.132507 -402.464395) (xy 403.109168 -402.415929)
			(xy 403.093312 -402.364526) (xy 403.085294 -402.311334) (xy 403.084792 -402.284438) (xy 403.085196 -402.260235)
			(xy 403.091697 -402.212268) (xy 403.104586 -402.165609) (xy 403.12363 -402.121107) (xy 403.148483 -402.079568)
			(xy 403.163278 -402.06041) (xy 403.163532 -402.060156) (xy 403.168804 -402.052968) (xy 403.174388 -402.03605)
			(xy 403.174454 -402.027136) (xy 403.172422 -401.952714) (xy 403.165564 -401.93595) (xy 403.159722 -401.929346)
			(xy 403.141526 -401.908225) (xy 403.110778 -401.861726) (xy 403.087124 -401.811247) (xy 403.071068 -401.757863)
			(xy 403.06295 -401.702711) (xy 403.06244 -401.674838) (xy 396.941548 -401.674838) (xy 396.941548 -401.866608)
			(xy 396.942056 -401.867116) (xy 396.942056 -401.89531) (xy 396.942482 -401.905378) (xy 396.950206 -401.923975)
			(xy 396.957042 -401.931378) (xy 397.378682 -402.353272) (xy 397.385519 -402.360674) (xy 397.39323 -402.379272)
			(xy 397.393668 -402.38934) (xy 397.393668 -402.44522) (xy 397.394094 -402.455289) (xy 397.40181 -402.473891)
			(xy 397.408654 -402.481288) (xy 397.466566 -402.5392) (xy 397.473416 -402.546597) (xy 397.481156 -402.565195)
			(xy 397.481552 -402.575268) (xy 397.481552 -402.763986) (xy 401.757624 -402.763986) (xy 401.757624 -402.70405)
			(xy 401.765447 -402.644628) (xy 401.78096 -402.586735) (xy 401.803896 -402.531362) (xy 401.833863 -402.479456)
			(xy 401.87035 -402.431906) (xy 401.91273 -402.389526) (xy 401.96028 -402.353039) (xy 402.012186 -402.323072)
			(xy 402.067559 -402.300136) (xy 402.125452 -402.284623) (xy 402.184874 -402.2768) (xy 402.24481 -402.2768)
			(xy 402.304232 -402.284623) (xy 402.362125 -402.300136) (xy 402.417498 -402.323072) (xy 402.469404 -402.353039)
			(xy 402.516954 -402.389526) (xy 402.559334 -402.431906) (xy 402.595821 -402.479456) (xy 402.625788 -402.531362)
			(xy 402.648724 -402.586735) (xy 402.664237 -402.644628) (xy 402.67206 -402.70405) (xy 402.67255 -402.734018)
			(xy 402.67206 -402.763986) (xy 402.664237 -402.823408) (xy 402.648724 -402.881301) (xy 402.625788 -402.936674)
			(xy 402.595821 -402.98858) (xy 402.559334 -403.03613) (xy 402.516954 -403.07851) (xy 402.469404 -403.114997)
			(xy 402.417498 -403.144964) (xy 402.362125 -403.1679) (xy 402.304232 -403.183413) (xy 402.24481 -403.191236)
			(xy 402.184874 -403.191236) (xy 402.125452 -403.183413) (xy 402.067559 -403.1679) (xy 402.012186 -403.144964)
			(xy 401.96028 -403.114997) (xy 401.91273 -403.07851) (xy 401.87035 -403.03613) (xy 401.833863 -402.98858)
			(xy 401.803896 -402.936674) (xy 401.78096 -402.881301) (xy 401.765447 -402.823408) (xy 401.757624 -402.763986)
			(xy 397.481552 -402.763986) (xy 397.481552 -403.502368) (xy 397.481989 -403.512432) (xy 397.489727 -403.531013)
			(xy 397.496538 -403.538436) (xy 398.594029 -404.635927) (xy 421.125644 -404.635927) (xy 421.125644 -404.572005)
			(xy 421.133655 -404.508587) (xy 421.149552 -404.446673) (xy 421.173084 -404.38724) (xy 421.203878 -404.331225)
			(xy 421.241451 -404.27951) (xy 421.285208 -404.232913) (xy 421.334461 -404.192168) (xy 421.388432 -404.157917)
			(xy 421.446271 -404.1307) (xy 421.507064 -404.110947) (xy 421.569854 -404.098969) (xy 421.63365 -404.094956)
			(xy 421.697446 -404.098969) (xy 421.760236 -404.110947) (xy 421.821029 -404.1307) (xy 421.878868 -404.157917)
			(xy 421.932839 -404.192168) (xy 421.982092 -404.232913) (xy 422.025849 -404.27951) (xy 422.063422 -404.331225)
			(xy 422.094216 -404.38724) (xy 422.117748 -404.446673) (xy 422.133645 -404.508587) (xy 422.141656 -404.572005)
			(xy 422.142158 -404.603966) (xy 422.141656 -404.635927) (xy 422.133645 -404.699345) (xy 422.117748 -404.761259)
			(xy 422.094216 -404.820692) (xy 422.063422 -404.876707) (xy 422.025849 -404.928422) (xy 421.982092 -404.975019)
			(xy 421.932839 -405.015764) (xy 421.878868 -405.050015) (xy 421.821029 -405.077232) (xy 421.760236 -405.096985)
			(xy 421.697446 -405.108963) (xy 421.63365 -405.112977) (xy 421.569854 -405.108963) (xy 421.507064 -405.096985)
			(xy 421.446271 -405.077232) (xy 421.388432 -405.050015) (xy 421.334461 -405.015764) (xy 421.285208 -404.975019)
			(xy 421.241451 -404.928422) (xy 421.203878 -404.876707) (xy 421.173084 -404.820692) (xy 421.149552 -404.761259)
			(xy 421.133655 -404.699345) (xy 421.125644 -404.635927) (xy 398.594029 -404.635927) (xy 400.483578 -406.525476)
			(xy 400.49098 -406.532313) (xy 400.509578 -406.540023) (xy 400.519646 -406.540462)
		)
		(stroke
			(width 0)
			(type solid)
		)
		(fill yes)
		(layer "B.Cu")
		(net "P0V9_CPU0_RT2_2A")
	)
	(gr_poly
		(pts
			(xy 165.147244 -398.158462) (xy 165.158575 -398.157855) (xy 165.179028 -398.1481) (xy 165.193269 -398.130473)
			(xy 165.19652 -398.1196) (xy 165.20365 -398.092219) (xy 165.224889 -398.039779) (xy 165.253642 -397.991051)
			(xy 165.289276 -397.947104) (xy 165.33101 -397.908903) (xy 165.377929 -397.877285) (xy 165.429004 -397.852943)
			(xy 165.483113 -397.836413) (xy 165.539071 -397.828056) (xy 165.595649 -397.828056) (xy 165.651607 -397.836413)
			(xy 165.705716 -397.852943) (xy 165.756791 -397.877285) (xy 165.80371 -397.908903) (xy 165.845444 -397.947104)
			(xy 165.881078 -397.991051) (xy 165.909831 -398.039779) (xy 165.93107 -398.092219) (xy 165.9382 -398.1196)
			(xy 165.942264 -398.136618) (xy 165.96995 -398.158462) (xy 168.735248 -398.158462) (xy 168.745314 -398.158029)
			(xy 168.763902 -398.150298) (xy 168.771316 -398.143476) (xy 168.901872 -398.01292) (xy 168.908709 -398.005519)
			(xy 168.916419 -397.98692) (xy 168.916858 -397.976852) (xy 168.916858 -396.969488) (xy 168.916255 -396.958158)
			(xy 168.906495 -396.937709) (xy 168.898062 -396.930118) (xy 168.837102 -396.880588) (xy 168.827981 -396.873943)
			(xy 168.806101 -396.868529) (xy 168.794938 -396.870174) (xy 168.77603 -396.87377) (xy 168.73773 -396.877589)
			(xy 168.718484 -396.877794) (xy 168.692017 -396.877341) (xy 168.639593 -396.870021) (xy 168.588683 -396.855523)
			(xy 168.540267 -396.834126) (xy 168.495274 -396.806241) (xy 168.474644 -396.789656) (xy 168.467278 -396.78356)
			(xy 168.45026 -396.777718) (xy 168.364154 -396.780258) (xy 168.347136 -396.78737) (xy 168.340278 -396.79372)
			(xy 168.31896 -396.812948) (xy 168.27163 -396.845435) (xy 168.219967 -396.870464) (xy 168.165137 -396.88747)
			(xy 168.108377 -396.896068) (xy 168.079674 -396.89659) (xy 168.052425 -396.896102) (xy 167.998483 -396.888343)
			(xy 167.946194 -396.872986) (xy 167.896622 -396.850345) (xy 167.850777 -396.820879) (xy 167.809592 -396.785189)
			(xy 167.773905 -396.744002) (xy 167.744443 -396.698155) (xy 167.721805 -396.648582) (xy 167.706452 -396.596292)
			(xy 167.698696 -396.542349) (xy 167.698696 -396.487851) (xy 167.706452 -396.433908) (xy 167.721805 -396.381618)
			(xy 167.744443 -396.332045) (xy 167.773905 -396.286198) (xy 167.809592 -396.245011) (xy 167.850777 -396.209321)
			(xy 167.896622 -396.179855) (xy 167.946194 -396.157214) (xy 167.998483 -396.141857) (xy 168.052425 -396.134098)
			(xy 168.079674 -396.133574) (xy 168.106139 -396.134032) (xy 168.158559 -396.14136) (xy 168.209462 -396.155866)
			(xy 168.257871 -396.177271) (xy 168.302855 -396.205164) (xy 168.323514 -396.221712) (xy 168.33088 -396.227808)
			(xy 168.347898 -396.23365) (xy 168.434004 -396.23111) (xy 168.451022 -396.223998) (xy 168.45788 -396.217648)
			(xy 168.479195 -396.198415) (xy 168.526522 -396.165916) (xy 168.578185 -396.140877) (xy 168.633017 -396.123862)
			(xy 168.689779 -396.115257) (xy 168.718484 -396.114778) (xy 168.737729 -396.114995) (xy 168.776029 -396.118813)
			(xy 168.794938 -396.122398) (xy 168.806105 -396.124071) (xy 168.827997 -396.118662) (xy 168.837102 -396.111984)
			(xy 168.898062 -396.062454) (xy 168.906456 -396.054836) (xy 168.916204 -396.034402) (xy 168.916858 -396.023084)
			(xy 168.916858 -395.021308) (xy 168.916259 -395.009976) (xy 168.906504 -394.98952) (xy 168.898062 -394.981938)
			(xy 168.874194 -394.961777) (xy 168.831605 -394.916064) (xy 168.795627 -394.864986) (xy 168.766926 -394.80949)
			(xy 168.746036 -394.750608) (xy 168.733345 -394.689433) (xy 168.729089 -394.6271) (xy 168.733345 -394.564767)
			(xy 168.746036 -394.503592) (xy 168.766926 -394.44471) (xy 168.795627 -394.389214) (xy 168.831605 -394.338136)
			(xy 168.874194 -394.292423) (xy 168.898062 -394.272262) (xy 168.906457 -394.264644) (xy 168.916208 -394.24421)
			(xy 168.916858 -394.232892) (xy 168.916858 -392.936476) (xy 168.913302 -392.927332) (xy 168.902993 -392.89989)
			(xy 168.891869 -392.84234) (xy 168.891204 -392.813032) (xy 168.891204 -391.002266) (xy 168.890775 -390.992198)
			(xy 168.883052 -390.973603) (xy 168.876218 -390.966198) (xy 168.613836 -390.70407) (xy 168.606438 -390.697226)
			(xy 168.587838 -390.689504) (xy 168.577768 -390.689084) (xy 167.759634 -390.689084) (xy 167.74928 -390.689636)
			(xy 167.730287 -390.697906) (xy 167.722804 -390.705086) (xy 167.664638 -390.766808) (xy 167.657526 -390.78662)
			(xy 167.658288 -390.797288) (xy 167.65905 -390.819132) (xy 167.65854 -390.845119) (xy 167.65041 -390.896454)
			(xy 167.634349 -390.945884) (xy 167.610753 -390.992194) (xy 167.580203 -391.034242) (xy 167.543452 -391.070993)
			(xy 167.501404 -391.101543) (xy 167.455094 -391.125139) (xy 167.405664 -391.1412) (xy 167.354329 -391.14933)
			(xy 167.302355 -391.14933) (xy 167.25102 -391.1412) (xy 167.20159 -391.125139) (xy 167.15528 -391.101543)
			(xy 167.113232 -391.070993) (xy 167.076481 -391.034242) (xy 167.045931 -390.992194) (xy 167.022335 -390.945884)
			(xy 167.006274 -390.896454) (xy 166.998144 -390.845119) (xy 166.997634 -390.819132) (xy 166.998187 -390.791526)
			(xy 167.007357 -390.737082) (xy 167.025448 -390.684918) (xy 167.051956 -390.636487) (xy 167.086144 -390.593134)
			(xy 167.127062 -390.556066) (xy 167.150034 -390.540748) (xy 167.157532 -390.535463) (xy 167.168462 -390.520747)
			(xy 167.17137 -390.512046) (xy 167.180006 -390.482074) (xy 167.182141 -390.473183) (xy 167.180696 -390.454969)
			(xy 167.177212 -390.446514) (xy 167.167429 -390.424493) (xy 167.153621 -390.378329) (xy 167.146647 -390.330652)
			(xy 167.146224 -390.30656) (xy 167.146639 -390.282787) (xy 167.153454 -390.235732) (xy 167.166938 -390.190139)
			(xy 167.186813 -390.146947) (xy 167.21267 -390.107046) (xy 167.228012 -390.088882) (xy 167.233694 -390.081761)
			(xy 167.240076 -390.06471) (xy 167.240458 -390.055608) (xy 167.240458 -390.024112) (xy 167.240079 -390.01501)
			(xy 167.233689 -389.997964) (xy 167.228012 -389.990838) (xy 167.212664 -389.972678) (xy 167.186799 -389.932782)
			(xy 167.166923 -389.889589) (xy 167.153447 -389.843992) (xy 167.146648 -389.796934) (xy 167.146224 -389.77316)
			(xy 167.146759 -389.74572) (xy 167.15581 -389.691592) (xy 167.173672 -389.639701) (xy 167.199856 -389.591471)
			(xy 167.233643 -389.548226) (xy 167.274106 -389.511152) (xy 167.320134 -389.481266) (xy 167.345106 -389.469884)
			(xy 167.356055 -389.464304) (xy 167.371445 -389.445194) (xy 167.37457 -389.433308) (xy 167.386508 -389.374888)
			(xy 167.374824 -389.363966) (xy 167.345614 -389.334502) (xy 167.337486 -389.330692) (xy 167.313403 -389.318887)
			(xy 167.269092 -389.288675) (xy 167.230235 -389.251711) (xy 167.19785 -389.208962) (xy 167.172785 -389.161549)
			(xy 167.155697 -389.110714) (xy 167.147034 -389.057787) (xy 167.146478 -389.030972) (xy 167.146938 -389.005981)
			(xy 167.154469 -388.956568) (xy 167.169353 -388.908853) (xy 167.191252 -388.863922) (xy 167.219667 -388.822802)
			(xy 167.25395 -388.786428) (xy 167.293318 -388.755632) (xy 167.336875 -388.731114) (xy 167.360092 -388.721854)
			(xy 167.370252 -388.71779) (xy 167.377872 -388.71017) (xy 167.384599 -388.702738) (xy 167.392253 -388.684233)
			(xy 167.392261 -388.664208) (xy 167.384622 -388.645697) (xy 167.377872 -388.638288) (xy 167.338756 -388.599172)
			(xy 167.329358 -388.595362) (xy 167.306896 -388.585694) (xy 167.264858 -388.560712) (xy 167.226958 -388.529811)
			(xy 167.194021 -388.493665) (xy 167.166767 -388.453063) (xy 167.145789 -388.408891) (xy 167.131544 -388.36211)
			(xy 167.124344 -388.313742) (xy 167.123872 -388.289292) (xy 167.124363 -388.262827) (xy 167.132741 -388.210567)
			(xy 167.149345 -388.16031) (xy 167.17375 -388.113345) (xy 167.205331 -388.070871) (xy 167.223948 -388.052056)
			(xy 167.230963 -388.044657) (xy 167.238955 -388.025918) (xy 167.239442 -388.015734) (xy 167.239442 -385.474718)
			(xy 167.239052 -385.466062) (xy 167.233205 -385.449764) (xy 167.222272 -385.436337) (xy 167.215058 -385.431538)
			(xy 167.194701 -385.418545) (xy 167.157633 -385.387591) (xy 167.125459 -385.351578) (xy 167.09886 -385.311271)
			(xy 167.078403 -385.267525) (xy 167.064521 -385.221271) (xy 167.05751 -385.17349) (xy 167.05707 -385.149344)
			(xy 167.05707 -385.14909) (xy 167.057514 -385.124217) (xy 167.064959 -385.075032) (xy 167.079696 -385.02752)
			(xy 167.10139 -384.982754) (xy 167.129552 -384.941747) (xy 167.146224 -384.923284) (xy 167.152574 -384.916426)
			(xy 167.159686 -384.899408) (xy 167.161972 -384.813048) (xy 167.155876 -384.795522) (xy 167.14978 -384.78841)
			(xy 167.135036 -384.770406) (xy 167.110215 -384.731043) (xy 167.091156 -384.68859) (xy 167.078235 -384.643884)
			(xy 167.071707 -384.59781) (xy 167.071294 -384.574542) (xy 167.071822 -384.547576) (xy 167.080558 -384.494358)
			(xy 167.097806 -384.443259) (xy 167.12311 -384.395633) (xy 167.1558 -384.352738) (xy 167.195011 -384.315711)
			(xy 167.21709 -384.300222) (xy 167.227083 -384.29275) (xy 167.238836 -384.270772) (xy 167.239442 -384.258312)
			(xy 167.239442 -384.067304) (xy 167.239018 -384.057235) (xy 167.231298 -384.038635) (xy 167.224456 -384.031236)
			(xy 166.999666 -383.806446) (xy 166.992268 -383.7996) (xy 166.973669 -383.791871) (xy 166.963598 -383.79146)
			(xy 166.616888 -383.79146) (xy 166.58717 -383.761742) (xy 166.58717 -383.757424) (xy 166.479474 -383.757424)
			(xy 166.469405 -383.756997) (xy 166.450805 -383.749278) (xy 166.443406 -383.742438) (xy 166.110666 -383.409698)
			(xy 166.103813 -383.402303) (xy 166.096068 -383.383704) (xy 166.09568 -383.37363) (xy 166.09568 -382.619504)
			(xy 166.096102 -382.609433) (xy 166.103813 -382.590826) (xy 166.110666 -382.583436) (xy 166.224204 -382.469898)
			(xy 166.23105 -382.462499) (xy 166.238783 -382.443901) (xy 166.23919 -382.43383) (xy 166.23919 -379.624082)
			(xy 166.238763 -379.614013) (xy 166.231043 -379.595415) (xy 166.224204 -379.588014) (xy 166.010336 -379.374146)
			(xy 166.002936 -379.367305) (xy 165.984338 -379.359586) (xy 165.974268 -379.35916) (xy 160.293812 -379.35916)
			(xy 160.283742 -379.359583) (xy 160.26514 -379.367301) (xy 160.257744 -379.374146) (xy 160.145476 -379.486414)
			(xy 160.138624 -379.49381) (xy 160.130882 -379.512409) (xy 160.13049 -379.522482) (xy 160.13049 -382.619758)
			(xy 160.130056 -382.629823) (xy 160.122326 -382.648411) (xy 160.115504 -382.655826) (xy 159.892413 -382.878917)
			(xy 160.314134 -382.878917) (xy 160.314134 -382.826943) (xy 160.322264 -382.775608) (xy 160.338325 -382.726178)
			(xy 160.361921 -382.679868) (xy 160.392471 -382.63782) (xy 160.429222 -382.601069) (xy 160.47127 -382.570519)
			(xy 160.51758 -382.546923) (xy 160.56701 -382.530862) (xy 160.618345 -382.522732) (xy 160.670319 -382.522732)
			(xy 160.721654 -382.530862) (xy 160.771084 -382.546923) (xy 160.817394 -382.570519) (xy 160.859442 -382.601069)
			(xy 160.896193 -382.63782) (xy 160.926743 -382.679868) (xy 160.950339 -382.726178) (xy 160.9664 -382.775608)
			(xy 160.97453 -382.826943) (xy 160.97504 -382.85293) (xy 160.97453 -382.878917) (xy 161.51403 -382.878917)
			(xy 161.51403 -382.826943) (xy 161.52216 -382.775608) (xy 161.538221 -382.726178) (xy 161.561817 -382.679868)
			(xy 161.592367 -382.63782) (xy 161.629118 -382.601069) (xy 161.671166 -382.570519) (xy 161.717476 -382.546923)
			(xy 161.766906 -382.530862) (xy 161.818241 -382.522732) (xy 161.870215 -382.522732) (xy 161.92155 -382.530862)
			(xy 161.97098 -382.546923) (xy 162.01729 -382.570519) (xy 162.059338 -382.601069) (xy 162.096089 -382.63782)
			(xy 162.126639 -382.679868) (xy 162.150235 -382.726178) (xy 162.166296 -382.775608) (xy 162.174426 -382.826943)
			(xy 162.174936 -382.85293) (xy 162.174426 -382.878917) (xy 162.713926 -382.878917) (xy 162.713926 -382.826943)
			(xy 162.722056 -382.775608) (xy 162.738117 -382.726178) (xy 162.761713 -382.679868) (xy 162.792263 -382.63782)
			(xy 162.829014 -382.601069) (xy 162.871062 -382.570519) (xy 162.917372 -382.546923) (xy 162.966802 -382.530862)
			(xy 163.018137 -382.522732) (xy 163.070111 -382.522732) (xy 163.121446 -382.530862) (xy 163.170876 -382.546923)
			(xy 163.217186 -382.570519) (xy 163.259234 -382.601069) (xy 163.295985 -382.63782) (xy 163.326535 -382.679868)
			(xy 163.350131 -382.726178) (xy 163.366192 -382.775608) (xy 163.374322 -382.826943) (xy 163.374832 -382.85293)
			(xy 163.374322 -382.878917) (xy 163.914076 -382.878917) (xy 163.914076 -382.826943) (xy 163.922206 -382.775608)
			(xy 163.938267 -382.726178) (xy 163.961863 -382.679868) (xy 163.992413 -382.63782) (xy 164.029164 -382.601069)
			(xy 164.071212 -382.570519) (xy 164.117522 -382.546923) (xy 164.166952 -382.530862) (xy 164.218287 -382.522732)
			(xy 164.270261 -382.522732) (xy 164.321596 -382.530862) (xy 164.371026 -382.546923) (xy 164.417336 -382.570519)
			(xy 164.459384 -382.601069) (xy 164.496135 -382.63782) (xy 164.526685 -382.679868) (xy 164.550281 -382.726178)
			(xy 164.566342 -382.775608) (xy 164.574472 -382.826943) (xy 164.574982 -382.85293) (xy 164.574472 -382.878917)
			(xy 165.113972 -382.878917) (xy 165.113972 -382.826943) (xy 165.122102 -382.775608) (xy 165.138163 -382.726178)
			(xy 165.161759 -382.679868) (xy 165.192309 -382.63782) (xy 165.22906 -382.601069) (xy 165.271108 -382.570519)
			(xy 165.317418 -382.546923) (xy 165.366848 -382.530862) (xy 165.418183 -382.522732) (xy 165.470157 -382.522732)
			(xy 165.521492 -382.530862) (xy 165.570922 -382.546923) (xy 165.617232 -382.570519) (xy 165.65928 -382.601069)
			(xy 165.696031 -382.63782) (xy 165.726581 -382.679868) (xy 165.750177 -382.726178) (xy 165.766238 -382.775608)
			(xy 165.774368 -382.826943) (xy 165.774878 -382.85293) (xy 165.774368 -382.878917) (xy 165.766238 -382.930252)
			(xy 165.750177 -382.979682) (xy 165.726581 -383.025992) (xy 165.696031 -383.06804) (xy 165.65928 -383.104791)
			(xy 165.617232 -383.135341) (xy 165.570922 -383.158937) (xy 165.521492 -383.174998) (xy 165.470157 -383.183128)
			(xy 165.418183 -383.183128) (xy 165.366848 -383.174998) (xy 165.317418 -383.158937) (xy 165.271108 -383.135341)
			(xy 165.22906 -383.104791) (xy 165.192309 -383.06804) (xy 165.161759 -383.025992) (xy 165.138163 -382.979682)
			(xy 165.122102 -382.930252) (xy 165.113972 -382.878917) (xy 164.574472 -382.878917) (xy 164.566342 -382.930252)
			(xy 164.550281 -382.979682) (xy 164.526685 -383.025992) (xy 164.496135 -383.06804) (xy 164.459384 -383.104791)
			(xy 164.417336 -383.135341) (xy 164.371026 -383.158937) (xy 164.321596 -383.174998) (xy 164.270261 -383.183128)
			(xy 164.218287 -383.183128) (xy 164.166952 -383.174998) (xy 164.117522 -383.158937) (xy 164.071212 -383.135341)
			(xy 164.029164 -383.104791) (xy 163.992413 -383.06804) (xy 163.961863 -383.025992) (xy 163.938267 -382.979682)
			(xy 163.922206 -382.930252) (xy 163.914076 -382.878917) (xy 163.374322 -382.878917) (xy 163.366192 -382.930252)
			(xy 163.350131 -382.979682) (xy 163.326535 -383.025992) (xy 163.295985 -383.06804) (xy 163.259234 -383.104791)
			(xy 163.217186 -383.135341) (xy 163.170876 -383.158937) (xy 163.121446 -383.174998) (xy 163.070111 -383.183128)
			(xy 163.018137 -383.183128) (xy 162.966802 -383.174998) (xy 162.917372 -383.158937) (xy 162.871062 -383.135341)
			(xy 162.829014 -383.104791) (xy 162.792263 -383.06804) (xy 162.761713 -383.025992) (xy 162.738117 -382.979682)
			(xy 162.722056 -382.930252) (xy 162.713926 -382.878917) (xy 162.174426 -382.878917) (xy 162.166296 -382.930252)
			(xy 162.150235 -382.979682) (xy 162.126639 -383.025992) (xy 162.096089 -383.06804) (xy 162.059338 -383.104791)
			(xy 162.01729 -383.135341) (xy 161.97098 -383.158937) (xy 161.92155 -383.174998) (xy 161.870215 -383.183128)
			(xy 161.818241 -383.183128) (xy 161.766906 -383.174998) (xy 161.717476 -383.158937) (xy 161.671166 -383.135341)
			(xy 161.629118 -383.104791) (xy 161.592367 -383.06804) (xy 161.561817 -383.025992) (xy 161.538221 -382.979682)
			(xy 161.52216 -382.930252) (xy 161.51403 -382.878917) (xy 160.97453 -382.878917) (xy 160.9664 -382.930252)
			(xy 160.950339 -382.979682) (xy 160.926743 -383.025992) (xy 160.896193 -383.06804) (xy 160.859442 -383.104791)
			(xy 160.817394 -383.135341) (xy 160.771084 -383.158937) (xy 160.721654 -383.174998) (xy 160.670319 -383.183128)
			(xy 160.618345 -383.183128) (xy 160.56701 -383.174998) (xy 160.51758 -383.158937) (xy 160.47127 -383.135341)
			(xy 160.429222 -383.104791) (xy 160.392471 -383.06804) (xy 160.361921 -383.025992) (xy 160.338325 -382.979682)
			(xy 160.322264 -382.930252) (xy 160.314134 -382.878917) (xy 159.892413 -382.878917) (xy 159.571436 -383.199894)
			(xy 159.564034 -383.206731) (xy 159.545436 -383.214443) (xy 159.535368 -383.21488) (xy 153.285952 -383.21488)
			(xy 153.275886 -383.214448) (xy 153.257296 -383.206719) (xy 153.249884 -383.199894) (xy 153.23947 -383.18948)
			(xy 153.23947 -383.18694) (xy 153.099516 -383.046986) (xy 153.09267 -383.039587) (xy 153.084938 -383.020989)
			(xy 153.08453 -383.010918) (xy 153.08453 -379.479302) (xy 153.084108 -379.469231) (xy 153.076398 -379.450623)
			(xy 153.069544 -379.443234) (xy 152.964896 -379.338586) (xy 152.957501 -379.331731) (xy 152.938902 -379.323984)
			(xy 152.928828 -379.3236) (xy 152.442672 -379.3236) (xy 152.42413 -379.31598) (xy 152.42159 -379.31344)
			(xy 146.032982 -379.31344) (xy 146.022914 -379.313868) (xy 146.004318 -379.321591) (xy 145.996914 -379.328426)
			(xy 145.537936 -379.787404) (xy 145.531086 -379.794801) (xy 145.523348 -379.813399) (xy 145.52295 -379.823472)
			(xy 145.52295 -382.493266) (xy 145.523427 -382.50299) (xy 145.53073 -382.521021) (xy 145.537174 -382.528318)
			(xy 145.558002 -382.550162) (xy 145.564559 -382.556502) (xy 145.580967 -382.564434) (xy 145.590006 -382.565656)
			(xy 145.615983 -382.568622) (xy 145.666604 -382.581694) (xy 145.714539 -382.602565) (xy 145.758594 -382.630716)
			(xy 145.778474 -382.647698) (xy 145.785078 -382.65354) (xy 145.80108 -382.660144) (xy 145.874232 -382.663192)
			(xy 145.882865 -382.663205) (xy 145.899362 -382.658154) (xy 145.90649 -382.653286) (xy 145.927199 -382.63853)
			(xy 145.972325 -382.615096) (xy 146.020603 -382.599136) (xy 146.070804 -382.591055) (xy 146.096228 -382.590548)
			(xy 146.121219 -382.591041) (xy 146.170586 -382.598863) (xy 146.218121 -382.614312) (xy 146.262654 -382.637007)
			(xy 146.303089 -382.666388) (xy 146.338431 -382.701732) (xy 146.367808 -382.74217) (xy 146.390499 -382.786705)
			(xy 146.405943 -382.834242) (xy 146.412861 -382.877919) (xy 147.126688 -382.877919) (xy 147.126688 -382.827941)
			(xy 147.134507 -382.778578) (xy 147.149951 -382.731046) (xy 147.172641 -382.686514) (xy 147.202017 -382.646081)
			(xy 147.237357 -382.610741) (xy 147.27779 -382.581365) (xy 147.322322 -382.558675) (xy 147.369854 -382.543231)
			(xy 147.419217 -382.535412) (xy 147.469195 -382.535412) (xy 147.518558 -382.543231) (xy 147.56609 -382.558675)
			(xy 147.610622 -382.581365) (xy 147.651055 -382.610741) (xy 147.686395 -382.646081) (xy 147.715771 -382.686514)
			(xy 147.738461 -382.731046) (xy 147.753905 -382.778578) (xy 147.761724 -382.827941) (xy 147.762214 -382.85293)
			(xy 147.761724 -382.877919) (xy 147.761566 -382.878917) (xy 148.314158 -382.878917) (xy 148.314158 -382.826943)
			(xy 148.322288 -382.775608) (xy 148.338349 -382.726178) (xy 148.361945 -382.679868) (xy 148.392495 -382.63782)
			(xy 148.429246 -382.601069) (xy 148.471294 -382.570519) (xy 148.517604 -382.546923) (xy 148.567034 -382.530862)
			(xy 148.618369 -382.522732) (xy 148.670343 -382.522732) (xy 148.721678 -382.530862) (xy 148.771108 -382.546923)
			(xy 148.817418 -382.570519) (xy 148.859466 -382.601069) (xy 148.896217 -382.63782) (xy 148.926767 -382.679868)
			(xy 148.950363 -382.726178) (xy 148.966424 -382.775608) (xy 148.974554 -382.826943) (xy 148.975064 -382.85293)
			(xy 148.974554 -382.878917) (xy 149.514054 -382.878917) (xy 149.514054 -382.826943) (xy 149.522184 -382.775608)
			(xy 149.538245 -382.726178) (xy 149.561841 -382.679868) (xy 149.592391 -382.63782) (xy 149.629142 -382.601069)
			(xy 149.67119 -382.570519) (xy 149.7175 -382.546923) (xy 149.76693 -382.530862) (xy 149.818265 -382.522732)
			(xy 149.870239 -382.522732) (xy 149.921574 -382.530862) (xy 149.971004 -382.546923) (xy 150.017314 -382.570519)
			(xy 150.059362 -382.601069) (xy 150.096113 -382.63782) (xy 150.126663 -382.679868) (xy 150.150259 -382.726178)
			(xy 150.16632 -382.775608) (xy 150.17445 -382.826943) (xy 150.17496 -382.85293) (xy 150.17445 -382.878917)
			(xy 150.71395 -382.878917) (xy 150.71395 -382.826943) (xy 150.72208 -382.775608) (xy 150.738141 -382.726178)
			(xy 150.761737 -382.679868) (xy 150.792287 -382.63782) (xy 150.829038 -382.601069) (xy 150.871086 -382.570519)
			(xy 150.917396 -382.546923) (xy 150.966826 -382.530862) (xy 151.018161 -382.522732) (xy 151.070135 -382.522732)
			(xy 151.12147 -382.530862) (xy 151.1709 -382.546923) (xy 151.21721 -382.570519) (xy 151.259258 -382.601069)
			(xy 151.296009 -382.63782) (xy 151.326559 -382.679868) (xy 151.350155 -382.726178) (xy 151.366216 -382.775608)
			(xy 151.374346 -382.826943) (xy 151.374856 -382.85293) (xy 151.374346 -382.878917) (xy 151.9141 -382.878917)
			(xy 151.9141 -382.826943) (xy 151.92223 -382.775608) (xy 151.938291 -382.726178) (xy 151.961887 -382.679868)
			(xy 151.992437 -382.63782) (xy 152.029188 -382.601069) (xy 152.071236 -382.570519) (xy 152.117546 -382.546923)
			(xy 152.166976 -382.530862) (xy 152.218311 -382.522732) (xy 152.270285 -382.522732) (xy 152.32162 -382.530862)
			(xy 152.37105 -382.546923) (xy 152.41736 -382.570519) (xy 152.459408 -382.601069) (xy 152.496159 -382.63782)
			(xy 152.526709 -382.679868) (xy 152.550305 -382.726178) (xy 152.566366 -382.775608) (xy 152.574496 -382.826943)
			(xy 152.575006 -382.85293) (xy 152.574496 -382.878917) (xy 152.566366 -382.930252) (xy 152.550305 -382.979682)
			(xy 152.526709 -383.025992) (xy 152.496159 -383.06804) (xy 152.459408 -383.104791) (xy 152.41736 -383.135341)
			(xy 152.37105 -383.158937) (xy 152.32162 -383.174998) (xy 152.270285 -383.183128) (xy 152.218311 -383.183128)
			(xy 152.166976 -383.174998) (xy 152.117546 -383.158937) (xy 152.071236 -383.135341) (xy 152.029188 -383.104791)
			(xy 151.992437 -383.06804) (xy 151.961887 -383.025992) (xy 151.938291 -382.979682) (xy 151.92223 -382.930252)
			(xy 151.9141 -382.878917) (xy 151.374346 -382.878917) (xy 151.366216 -382.930252) (xy 151.350155 -382.979682)
			(xy 151.326559 -383.025992) (xy 151.296009 -383.06804) (xy 151.259258 -383.104791) (xy 151.21721 -383.135341)
			(xy 151.1709 -383.158937) (xy 151.12147 -383.174998) (xy 151.070135 -383.183128) (xy 151.018161 -383.183128)
			(xy 150.966826 -383.174998) (xy 150.917396 -383.158937) (xy 150.871086 -383.135341) (xy 150.829038 -383.104791)
			(xy 150.792287 -383.06804) (xy 150.761737 -383.025992) (xy 150.738141 -382.979682) (xy 150.72208 -382.930252)
			(xy 150.71395 -382.878917) (xy 150.17445 -382.878917) (xy 150.16632 -382.930252) (xy 150.150259 -382.979682)
			(xy 150.126663 -383.025992) (xy 150.096113 -383.06804) (xy 150.059362 -383.104791) (xy 150.017314 -383.135341)
			(xy 149.971004 -383.158937) (xy 149.921574 -383.174998) (xy 149.870239 -383.183128) (xy 149.818265 -383.183128)
			(xy 149.76693 -383.174998) (xy 149.7175 -383.158937) (xy 149.67119 -383.135341) (xy 149.629142 -383.104791)
			(xy 149.592391 -383.06804) (xy 149.561841 -383.025992) (xy 149.538245 -382.979682) (xy 149.522184 -382.930252)
			(xy 149.514054 -382.878917) (xy 148.974554 -382.878917) (xy 148.966424 -382.930252) (xy 148.950363 -382.979682)
			(xy 148.926767 -383.025992) (xy 148.896217 -383.06804) (xy 148.859466 -383.104791) (xy 148.817418 -383.135341)
			(xy 148.771108 -383.158937) (xy 148.721678 -383.174998) (xy 148.670343 -383.183128) (xy 148.618369 -383.183128)
			(xy 148.567034 -383.174998) (xy 148.517604 -383.158937) (xy 148.471294 -383.135341) (xy 148.429246 -383.104791)
			(xy 148.392495 -383.06804) (xy 148.361945 -383.025992) (xy 148.338349 -382.979682) (xy 148.322288 -382.930252)
			(xy 148.314158 -382.878917) (xy 147.761566 -382.878917) (xy 147.753905 -382.927282) (xy 147.738461 -382.974814)
			(xy 147.715771 -383.019346) (xy 147.686395 -383.059779) (xy 147.651055 -383.095119) (xy 147.610622 -383.124495)
			(xy 147.56609 -383.147185) (xy 147.518558 -383.162629) (xy 147.469195 -383.170448) (xy 147.419217 -383.170448)
			(xy 147.369854 -383.162629) (xy 147.322322 -383.147185) (xy 147.27779 -383.124495) (xy 147.237357 -383.095119)
			(xy 147.202017 -383.059779) (xy 147.172641 -383.019346) (xy 147.149951 -382.974814) (xy 147.134507 -382.927282)
			(xy 147.126688 -382.877919) (xy 146.412861 -382.877919) (xy 146.413762 -382.883609) (xy 146.413762 -382.933591)
			(xy 146.405943 -382.982958) (xy 146.390499 -383.030495) (xy 146.367808 -383.07503) (xy 146.338431 -383.115468)
			(xy 146.303089 -383.150812) (xy 146.262654 -383.180193) (xy 146.218121 -383.202888) (xy 146.170586 -383.218337)
			(xy 146.121219 -383.226159) (xy 146.096228 -383.226564) (xy 146.095974 -383.226564) (xy 146.068566 -383.225958)
			(xy 146.014569 -383.216512) (xy 145.962983 -383.197971) (xy 145.915328 -383.170882) (xy 145.89379 -383.15392)
			(xy 145.886932 -383.148332) (xy 145.870422 -383.142236) (xy 145.797524 -383.141728) (xy 145.788943 -383.142019)
			(xy 145.772717 -383.147599) (xy 145.765774 -383.15265) (xy 145.76552 -383.152904) (xy 145.74336 -383.169929)
			(xy 145.694508 -383.197056) (xy 145.641788 -383.215575) (xy 145.586703 -383.224956) (xy 145.558764 -383.225548)
			(xy 145.55851 -383.225548) (xy 145.534122 -383.225112) (xy 145.485875 -383.217941) (xy 145.439207 -383.203753)
			(xy 145.395133 -383.182858) (xy 145.374614 -383.169668) (xy 145.359628 -383.159508) (xy 145.323306 -383.163064)
			(xy 145.158206 -383.328164) (xy 145.151369 -383.335566) (xy 145.143657 -383.354164) (xy 145.14322 -383.364232)
			(xy 145.14322 -383.629154) (xy 145.143653 -383.639219) (xy 145.151384 -383.657808) (xy 145.158206 -383.665222)
			(xy 145.246598 -383.75336) (xy 145.26337 -383.7708) (xy 145.291814 -383.80994) (xy 145.313786 -383.853047)
			(xy 145.328744 -383.89906) (xy 145.336322 -383.946846) (xy 145.336768 -383.971038) (xy 145.336768 -384.23596)
			(xy 145.339816 -384.244342) (xy 145.34903 -384.271557) (xy 145.358986 -384.328139) (xy 145.359628 -384.356864)
			(xy 145.359628 -384.357372) (xy 145.359102 -384.383931) (xy 145.350617 -384.436366) (xy 145.33386 -384.486771)
			(xy 145.309262 -384.533849) (xy 145.277456 -384.576391) (xy 145.239259 -384.613303) (xy 145.196982 -384.642711)
			(xy 146.772612 -384.642711) (xy 146.772612 -384.592733) (xy 146.780431 -384.54337) (xy 146.795875 -384.495838)
			(xy 146.818565 -384.451306) (xy 146.847941 -384.410873) (xy 146.883281 -384.375533) (xy 146.923714 -384.346157)
			(xy 146.968246 -384.323467) (xy 147.015778 -384.308023) (xy 147.065141 -384.300204) (xy 147.115119 -384.300204)
			(xy 147.164482 -384.308023) (xy 147.212014 -384.323467) (xy 147.256546 -384.346157) (xy 147.296979 -384.375533)
			(xy 147.332319 -384.410873) (xy 147.361695 -384.451306) (xy 147.384385 -384.495838) (xy 147.399829 -384.54337)
			(xy 147.407648 -384.592733) (xy 147.408138 -384.617722) (xy 147.407648 -384.642711) (xy 147.40749 -384.643709)
			(xy 147.959828 -384.643709) (xy 147.959828 -384.591735) (xy 147.967958 -384.5404) (xy 147.984019 -384.49097)
			(xy 148.007615 -384.44466) (xy 148.038165 -384.402612) (xy 148.074916 -384.365861) (xy 148.116964 -384.335311)
			(xy 148.163274 -384.311715) (xy 148.212704 -384.295654) (xy 148.264039 -384.287524) (xy 148.316013 -384.287524)
			(xy 148.367348 -384.295654) (xy 148.416778 -384.311715) (xy 148.463088 -384.335311) (xy 148.505136 -384.365861)
			(xy 148.541887 -384.402612) (xy 148.572437 -384.44466) (xy 148.596033 -384.49097) (xy 148.612094 -384.5404)
			(xy 148.620224 -384.591735) (xy 148.620734 -384.617722) (xy 148.620224 -384.643709) (xy 149.159978 -384.643709)
			(xy 149.159978 -384.591735) (xy 149.168108 -384.5404) (xy 149.184169 -384.49097) (xy 149.207765 -384.44466)
			(xy 149.238315 -384.402612) (xy 149.275066 -384.365861) (xy 149.317114 -384.335311) (xy 149.363424 -384.311715)
			(xy 149.412854 -384.295654) (xy 149.464189 -384.287524) (xy 149.516163 -384.287524) (xy 149.567498 -384.295654)
			(xy 149.616928 -384.311715) (xy 149.663238 -384.335311) (xy 149.705286 -384.365861) (xy 149.742037 -384.402612)
			(xy 149.772587 -384.44466) (xy 149.796183 -384.49097) (xy 149.812244 -384.5404) (xy 149.820374 -384.591735)
			(xy 149.820884 -384.617722) (xy 149.820374 -384.643709) (xy 150.359874 -384.643709) (xy 150.359874 -384.591735)
			(xy 150.368004 -384.5404) (xy 150.384065 -384.49097) (xy 150.407661 -384.44466) (xy 150.438211 -384.402612)
			(xy 150.474962 -384.365861) (xy 150.51701 -384.335311) (xy 150.56332 -384.311715) (xy 150.61275 -384.295654)
			(xy 150.664085 -384.287524) (xy 150.716059 -384.287524) (xy 150.767394 -384.295654) (xy 150.816824 -384.311715)
			(xy 150.863134 -384.335311) (xy 150.905182 -384.365861) (xy 150.941933 -384.402612) (xy 150.972483 -384.44466)
			(xy 150.996079 -384.49097) (xy 151.01214 -384.5404) (xy 151.02027 -384.591735) (xy 151.02078 -384.617722)
			(xy 151.02027 -384.643709) (xy 151.560024 -384.643709) (xy 151.560024 -384.591735) (xy 151.568154 -384.5404)
			(xy 151.584215 -384.49097) (xy 151.607811 -384.44466) (xy 151.638361 -384.402612) (xy 151.675112 -384.365861)
			(xy 151.71716 -384.335311) (xy 151.76347 -384.311715) (xy 151.8129 -384.295654) (xy 151.864235 -384.287524)
			(xy 151.916209 -384.287524) (xy 151.967544 -384.295654) (xy 152.016974 -384.311715) (xy 152.063284 -384.335311)
			(xy 152.105332 -384.365861) (xy 152.142083 -384.402612) (xy 152.172633 -384.44466) (xy 152.196229 -384.49097)
			(xy 152.21229 -384.5404) (xy 152.22042 -384.591735) (xy 152.22093 -384.617722) (xy 152.22042 -384.643709)
			(xy 152.75992 -384.643709) (xy 152.75992 -384.591735) (xy 152.76805 -384.5404) (xy 152.784111 -384.49097)
			(xy 152.807707 -384.44466) (xy 152.838257 -384.402612) (xy 152.875008 -384.365861) (xy 152.917056 -384.335311)
			(xy 152.963366 -384.311715) (xy 153.012796 -384.295654) (xy 153.064131 -384.287524) (xy 153.116105 -384.287524)
			(xy 153.16744 -384.295654) (xy 153.21687 -384.311715) (xy 153.26318 -384.335311) (xy 153.305228 -384.365861)
			(xy 153.341979 -384.402612) (xy 153.372529 -384.44466) (xy 153.396125 -384.49097) (xy 153.412186 -384.5404)
			(xy 153.420316 -384.591735) (xy 153.420826 -384.617722) (xy 153.420316 -384.643709) (xy 153.959816 -384.643709)
			(xy 153.959816 -384.591735) (xy 153.967946 -384.5404) (xy 153.984007 -384.49097) (xy 154.007603 -384.44466)
			(xy 154.038153 -384.402612) (xy 154.074904 -384.365861) (xy 154.116952 -384.335311) (xy 154.163262 -384.311715)
			(xy 154.212692 -384.295654) (xy 154.264027 -384.287524) (xy 154.316001 -384.287524) (xy 154.367336 -384.295654)
			(xy 154.416766 -384.311715) (xy 154.463076 -384.335311) (xy 154.505124 -384.365861) (xy 154.541875 -384.402612)
			(xy 154.572425 -384.44466) (xy 154.596021 -384.49097) (xy 154.612082 -384.5404) (xy 154.620212 -384.591735)
			(xy 154.620722 -384.617722) (xy 154.620212 -384.643709) (xy 155.159966 -384.643709) (xy 155.159966 -384.591735)
			(xy 155.168096 -384.5404) (xy 155.184157 -384.49097) (xy 155.207753 -384.44466) (xy 155.238303 -384.402612)
			(xy 155.275054 -384.365861) (xy 155.317102 -384.335311) (xy 155.363412 -384.311715) (xy 155.412842 -384.295654)
			(xy 155.464177 -384.287524) (xy 155.516151 -384.287524) (xy 155.567486 -384.295654) (xy 155.616916 -384.311715)
			(xy 155.663226 -384.335311) (xy 155.705274 -384.365861) (xy 155.742025 -384.402612) (xy 155.772575 -384.44466)
			(xy 155.796171 -384.49097) (xy 155.812232 -384.5404) (xy 155.820362 -384.591735) (xy 155.820872 -384.617722)
			(xy 155.820362 -384.643709) (xy 156.359862 -384.643709) (xy 156.359862 -384.591735) (xy 156.367992 -384.5404)
			(xy 156.384053 -384.49097) (xy 156.407649 -384.44466) (xy 156.438199 -384.402612) (xy 156.47495 -384.365861)
			(xy 156.516998 -384.335311) (xy 156.563308 -384.311715) (xy 156.612738 -384.295654) (xy 156.664073 -384.287524)
			(xy 156.716047 -384.287524) (xy 156.767382 -384.295654) (xy 156.816812 -384.311715) (xy 156.863122 -384.335311)
			(xy 156.90517 -384.365861) (xy 156.941921 -384.402612) (xy 156.972471 -384.44466) (xy 156.996067 -384.49097)
			(xy 157.012128 -384.5404) (xy 157.020258 -384.591735) (xy 157.020768 -384.617722) (xy 157.020258 -384.643709)
			(xy 157.560012 -384.643709) (xy 157.560012 -384.591735) (xy 157.568142 -384.5404) (xy 157.584203 -384.49097)
			(xy 157.607799 -384.44466) (xy 157.638349 -384.402612) (xy 157.6751 -384.365861) (xy 157.717148 -384.335311)
			(xy 157.763458 -384.311715) (xy 157.812888 -384.295654) (xy 157.864223 -384.287524) (xy 157.916197 -384.287524)
			(xy 157.967532 -384.295654) (xy 158.016962 -384.311715) (xy 158.063272 -384.335311) (xy 158.10532 -384.365861)
			(xy 158.142071 -384.402612) (xy 158.172621 -384.44466) (xy 158.196217 -384.49097) (xy 158.212278 -384.5404)
			(xy 158.220408 -384.591735) (xy 158.220918 -384.617722) (xy 158.220408 -384.643709) (xy 158.759908 -384.643709)
			(xy 158.759908 -384.591735) (xy 158.768038 -384.5404) (xy 158.784099 -384.49097) (xy 158.807695 -384.44466)
			(xy 158.838245 -384.402612) (xy 158.874996 -384.365861) (xy 158.917044 -384.335311) (xy 158.963354 -384.311715)
			(xy 159.012784 -384.295654) (xy 159.064119 -384.287524) (xy 159.116093 -384.287524) (xy 159.167428 -384.295654)
			(xy 159.216858 -384.311715) (xy 159.263168 -384.335311) (xy 159.305216 -384.365861) (xy 159.341967 -384.402612)
			(xy 159.372517 -384.44466) (xy 159.396113 -384.49097) (xy 159.412174 -384.5404) (xy 159.420304 -384.591735)
			(xy 159.420814 -384.617722) (xy 159.420304 -384.643709) (xy 159.959804 -384.643709) (xy 159.959804 -384.591735)
			(xy 159.967934 -384.5404) (xy 159.983995 -384.49097) (xy 160.007591 -384.44466) (xy 160.038141 -384.402612)
			(xy 160.074892 -384.365861) (xy 160.11694 -384.335311) (xy 160.16325 -384.311715) (xy 160.21268 -384.295654)
			(xy 160.264015 -384.287524) (xy 160.315989 -384.287524) (xy 160.367324 -384.295654) (xy 160.416754 -384.311715)
			(xy 160.463064 -384.335311) (xy 160.505112 -384.365861) (xy 160.541863 -384.402612) (xy 160.572413 -384.44466)
			(xy 160.596009 -384.49097) (xy 160.61207 -384.5404) (xy 160.6202 -384.591735) (xy 160.62071 -384.617722)
			(xy 160.6202 -384.643709) (xy 161.159954 -384.643709) (xy 161.159954 -384.591735) (xy 161.168084 -384.5404)
			(xy 161.184145 -384.49097) (xy 161.207741 -384.44466) (xy 161.238291 -384.402612) (xy 161.275042 -384.365861)
			(xy 161.31709 -384.335311) (xy 161.3634 -384.311715) (xy 161.41283 -384.295654) (xy 161.464165 -384.287524)
			(xy 161.516139 -384.287524) (xy 161.567474 -384.295654) (xy 161.616904 -384.311715) (xy 161.663214 -384.335311)
			(xy 161.705262 -384.365861) (xy 161.742013 -384.402612) (xy 161.772563 -384.44466) (xy 161.796159 -384.49097)
			(xy 161.81222 -384.5404) (xy 161.82035 -384.591735) (xy 161.82086 -384.617722) (xy 161.82035 -384.643709)
			(xy 162.35985 -384.643709) (xy 162.35985 -384.591735) (xy 162.36798 -384.5404) (xy 162.384041 -384.49097)
			(xy 162.407637 -384.44466) (xy 162.438187 -384.402612) (xy 162.474938 -384.365861) (xy 162.516986 -384.335311)
			(xy 162.563296 -384.311715) (xy 162.612726 -384.295654) (xy 162.664061 -384.287524) (xy 162.716035 -384.287524)
			(xy 162.76737 -384.295654) (xy 162.8168 -384.311715) (xy 162.86311 -384.335311) (xy 162.905158 -384.365861)
			(xy 162.941909 -384.402612) (xy 162.972459 -384.44466) (xy 162.996055 -384.49097) (xy 163.012116 -384.5404)
			(xy 163.020246 -384.591735) (xy 163.020756 -384.617722) (xy 163.020246 -384.643709) (xy 163.56 -384.643709)
			(xy 163.56 -384.591735) (xy 163.56813 -384.5404) (xy 163.584191 -384.49097) (xy 163.607787 -384.44466)
			(xy 163.638337 -384.402612) (xy 163.675088 -384.365861) (xy 163.717136 -384.335311) (xy 163.763446 -384.311715)
			(xy 163.812876 -384.295654) (xy 163.864211 -384.287524) (xy 163.916185 -384.287524) (xy 163.96752 -384.295654)
			(xy 164.01695 -384.311715) (xy 164.06326 -384.335311) (xy 164.105308 -384.365861) (xy 164.142059 -384.402612)
			(xy 164.172609 -384.44466) (xy 164.196205 -384.49097) (xy 164.212266 -384.5404) (xy 164.220396 -384.591735)
			(xy 164.220906 -384.617721) (xy 164.75876 -384.617721) (xy 164.763634 -384.561048) (xy 164.770308 -384.533394)
			(xy 164.771832 -384.527044) (xy 164.771832 -384.41376) (xy 164.772303 -384.39704) (xy 164.780968 -384.364742)
			(xy 164.797697 -384.335787) (xy 164.82135 -384.312148) (xy 164.850316 -384.295437) (xy 164.88262 -384.286792)
			(xy 164.89934 -384.286252) (xy 165.28034 -384.286252) (xy 165.297053 -384.286802) (xy 165.32934 -384.29546)
			(xy 165.358287 -384.312177) (xy 165.381923 -384.335813) (xy 165.39864 -384.36476) (xy 165.407298 -384.397047)
			(xy 165.407848 -384.41376) (xy 165.407848 -384.525266) (xy 165.409372 -384.53187) (xy 165.414707 -384.552931)
			(xy 165.420442 -384.595998) (xy 165.420802 -384.617722) (xy 165.420412 -384.639443) (xy 165.41468 -384.682508)
			(xy 165.409372 -384.703574) (xy 165.407848 -384.710178) (xy 165.407848 -384.71856) (xy 165.407358 -384.734282)
			(xy 165.399668 -384.764772) (xy 165.384768 -384.792462) (xy 165.363559 -384.815677) (xy 165.350698 -384.824732)
			(xy 165.340284 -384.833876) (xy 165.324529 -384.851535) (xy 165.288811 -384.882582) (xy 165.249029 -384.908217)
			(xy 165.205999 -384.927916) (xy 165.160598 -384.941277) (xy 165.113757 -384.948025) (xy 165.090094 -384.94843)
			(xy 165.066504 -384.948046) (xy 165.0198 -384.941351) (xy 164.974524 -384.928084) (xy 164.931594 -384.908513)
			(xy 164.891882 -384.883038) (xy 164.856196 -384.852175) (xy 164.840412 -384.834638) (xy 164.829744 -384.82524)
			(xy 164.816714 -384.81622) (xy 164.795211 -384.792953) (xy 164.780099 -384.765109) (xy 164.772308 -384.734401)
			(xy 164.771832 -384.71856) (xy 164.771832 -384.7084) (xy 164.770308 -384.70205) (xy 164.763642 -384.674394)
			(xy 164.75876 -384.617721) (xy 164.220906 -384.617721) (xy 164.220906 -384.617722) (xy 164.220396 -384.643709)
			(xy 164.212266 -384.695044) (xy 164.196205 -384.744474) (xy 164.172609 -384.790784) (xy 164.142059 -384.832832)
			(xy 164.105308 -384.869583) (xy 164.06326 -384.900133) (xy 164.01695 -384.923729) (xy 163.96752 -384.93979)
			(xy 163.916185 -384.94792) (xy 163.864211 -384.94792) (xy 163.812876 -384.93979) (xy 163.763446 -384.923729)
			(xy 163.717136 -384.900133) (xy 163.675088 -384.869583) (xy 163.638337 -384.832832) (xy 163.607787 -384.790784)
			(xy 163.584191 -384.744474) (xy 163.56813 -384.695044) (xy 163.56 -384.643709) (xy 163.020246 -384.643709)
			(xy 163.012116 -384.695044) (xy 162.996055 -384.744474) (xy 162.972459 -384.790784) (xy 162.941909 -384.832832)
			(xy 162.905158 -384.869583) (xy 162.86311 -384.900133) (xy 162.8168 -384.923729) (xy 162.76737 -384.93979)
			(xy 162.716035 -384.94792) (xy 162.664061 -384.94792) (xy 162.612726 -384.93979) (xy 162.563296 -384.923729)
			(xy 162.516986 -384.900133) (xy 162.474938 -384.869583) (xy 162.438187 -384.832832) (xy 162.407637 -384.790784)
			(xy 162.384041 -384.744474) (xy 162.36798 -384.695044) (xy 162.35985 -384.643709) (xy 161.82035 -384.643709)
			(xy 161.81222 -384.695044) (xy 161.796159 -384.744474) (xy 161.772563 -384.790784) (xy 161.742013 -384.832832)
			(xy 161.705262 -384.869583) (xy 161.663214 -384.900133) (xy 161.616904 -384.923729) (xy 161.567474 -384.93979)
			(xy 161.516139 -384.94792) (xy 161.464165 -384.94792) (xy 161.41283 -384.93979) (xy 161.3634 -384.923729)
			(xy 161.31709 -384.900133) (xy 161.275042 -384.869583) (xy 161.238291 -384.832832) (xy 161.207741 -384.790784)
			(xy 161.184145 -384.744474) (xy 161.168084 -384.695044) (xy 161.159954 -384.643709) (xy 160.6202 -384.643709)
			(xy 160.61207 -384.695044) (xy 160.596009 -384.744474) (xy 160.572413 -384.790784) (xy 160.541863 -384.832832)
			(xy 160.505112 -384.869583) (xy 160.463064 -384.900133) (xy 160.416754 -384.923729) (xy 160.367324 -384.93979)
			(xy 160.315989 -384.94792) (xy 160.264015 -384.94792) (xy 160.21268 -384.93979) (xy 160.16325 -384.923729)
			(xy 160.11694 -384.900133) (xy 160.074892 -384.869583) (xy 160.038141 -384.832832) (xy 160.007591 -384.790784)
			(xy 159.983995 -384.744474) (xy 159.967934 -384.695044) (xy 159.959804 -384.643709) (xy 159.420304 -384.643709)
			(xy 159.412174 -384.695044) (xy 159.396113 -384.744474) (xy 159.372517 -384.790784) (xy 159.341967 -384.832832)
			(xy 159.305216 -384.869583) (xy 159.263168 -384.900133) (xy 159.216858 -384.923729) (xy 159.167428 -384.93979)
			(xy 159.116093 -384.94792) (xy 159.064119 -384.94792) (xy 159.012784 -384.93979) (xy 158.963354 -384.923729)
			(xy 158.917044 -384.900133) (xy 158.874996 -384.869583) (xy 158.838245 -384.832832) (xy 158.807695 -384.790784)
			(xy 158.784099 -384.744474) (xy 158.768038 -384.695044) (xy 158.759908 -384.643709) (xy 158.220408 -384.643709)
			(xy 158.212278 -384.695044) (xy 158.196217 -384.744474) (xy 158.172621 -384.790784) (xy 158.142071 -384.832832)
			(xy 158.10532 -384.869583) (xy 158.063272 -384.900133) (xy 158.016962 -384.923729) (xy 157.967532 -384.93979)
			(xy 157.916197 -384.94792) (xy 157.864223 -384.94792) (xy 157.812888 -384.93979) (xy 157.763458 -384.923729)
			(xy 157.717148 -384.900133) (xy 157.6751 -384.869583) (xy 157.638349 -384.832832) (xy 157.607799 -384.790784)
			(xy 157.584203 -384.744474) (xy 157.568142 -384.695044) (xy 157.560012 -384.643709) (xy 157.020258 -384.643709)
			(xy 157.012128 -384.695044) (xy 156.996067 -384.744474) (xy 156.972471 -384.790784) (xy 156.941921 -384.832832)
			(xy 156.90517 -384.869583) (xy 156.863122 -384.900133) (xy 156.816812 -384.923729) (xy 156.767382 -384.93979)
			(xy 156.716047 -384.94792) (xy 156.664073 -384.94792) (xy 156.612738 -384.93979) (xy 156.563308 -384.923729)
			(xy 156.516998 -384.900133) (xy 156.47495 -384.869583) (xy 156.438199 -384.832832) (xy 156.407649 -384.790784)
			(xy 156.384053 -384.744474) (xy 156.367992 -384.695044) (xy 156.359862 -384.643709) (xy 155.820362 -384.643709)
			(xy 155.812232 -384.695044) (xy 155.796171 -384.744474) (xy 155.772575 -384.790784) (xy 155.742025 -384.832832)
			(xy 155.705274 -384.869583) (xy 155.663226 -384.900133) (xy 155.616916 -384.923729) (xy 155.567486 -384.93979)
			(xy 155.516151 -384.94792) (xy 155.464177 -384.94792) (xy 155.412842 -384.93979) (xy 155.363412 -384.923729)
			(xy 155.317102 -384.900133) (xy 155.275054 -384.869583) (xy 155.238303 -384.832832) (xy 155.207753 -384.790784)
			(xy 155.184157 -384.744474) (xy 155.168096 -384.695044) (xy 155.159966 -384.643709) (xy 154.620212 -384.643709)
			(xy 154.612082 -384.695044) (xy 154.596021 -384.744474) (xy 154.572425 -384.790784) (xy 154.541875 -384.832832)
			(xy 154.505124 -384.869583) (xy 154.463076 -384.900133) (xy 154.416766 -384.923729) (xy 154.367336 -384.93979)
			(xy 154.316001 -384.94792) (xy 154.264027 -384.94792) (xy 154.212692 -384.93979) (xy 154.163262 -384.923729)
			(xy 154.116952 -384.900133) (xy 154.074904 -384.869583) (xy 154.038153 -384.832832) (xy 154.007603 -384.790784)
			(xy 153.984007 -384.744474) (xy 153.967946 -384.695044) (xy 153.959816 -384.643709) (xy 153.420316 -384.643709)
			(xy 153.412186 -384.695044) (xy 153.396125 -384.744474) (xy 153.372529 -384.790784) (xy 153.341979 -384.832832)
			(xy 153.305228 -384.869583) (xy 153.26318 -384.900133) (xy 153.21687 -384.923729) (xy 153.16744 -384.93979)
			(xy 153.116105 -384.94792) (xy 153.064131 -384.94792) (xy 153.012796 -384.93979) (xy 152.963366 -384.923729)
			(xy 152.917056 -384.900133) (xy 152.875008 -384.869583) (xy 152.838257 -384.832832) (xy 152.807707 -384.790784)
			(xy 152.784111 -384.744474) (xy 152.76805 -384.695044) (xy 152.75992 -384.643709) (xy 152.22042 -384.643709)
			(xy 152.21229 -384.695044) (xy 152.196229 -384.744474) (xy 152.172633 -384.790784) (xy 152.142083 -384.832832)
			(xy 152.105332 -384.869583) (xy 152.063284 -384.900133) (xy 152.016974 -384.923729) (xy 151.967544 -384.93979)
			(xy 151.916209 -384.94792) (xy 151.864235 -384.94792) (xy 151.8129 -384.93979) (xy 151.76347 -384.923729)
			(xy 151.71716 -384.900133) (xy 151.675112 -384.869583) (xy 151.638361 -384.832832) (xy 151.607811 -384.790784)
			(xy 151.584215 -384.744474) (xy 151.568154 -384.695044) (xy 151.560024 -384.643709) (xy 151.02027 -384.643709)
			(xy 151.01214 -384.695044) (xy 150.996079 -384.744474) (xy 150.972483 -384.790784) (xy 150.941933 -384.832832)
			(xy 150.905182 -384.869583) (xy 150.863134 -384.900133) (xy 150.816824 -384.923729) (xy 150.767394 -384.93979)
			(xy 150.716059 -384.94792) (xy 150.664085 -384.94792) (xy 150.61275 -384.93979) (xy 150.56332 -384.923729)
			(xy 150.51701 -384.900133) (xy 150.474962 -384.869583) (xy 150.438211 -384.832832) (xy 150.407661 -384.790784)
			(xy 150.384065 -384.744474) (xy 150.368004 -384.695044) (xy 150.359874 -384.643709) (xy 149.820374 -384.643709)
			(xy 149.812244 -384.695044) (xy 149.796183 -384.744474) (xy 149.772587 -384.790784) (xy 149.742037 -384.832832)
			(xy 149.705286 -384.869583) (xy 149.663238 -384.900133) (xy 149.616928 -384.923729) (xy 149.567498 -384.93979)
			(xy 149.516163 -384.94792) (xy 149.464189 -384.94792) (xy 149.412854 -384.93979) (xy 149.363424 -384.923729)
			(xy 149.317114 -384.900133) (xy 149.275066 -384.869583) (xy 149.238315 -384.832832) (xy 149.207765 -384.790784)
			(xy 149.184169 -384.744474) (xy 149.168108 -384.695044) (xy 149.159978 -384.643709) (xy 148.620224 -384.643709)
			(xy 148.612094 -384.695044) (xy 148.596033 -384.744474) (xy 148.572437 -384.790784) (xy 148.541887 -384.832832)
			(xy 148.505136 -384.869583) (xy 148.463088 -384.900133) (xy 148.416778 -384.923729) (xy 148.367348 -384.93979)
			(xy 148.316013 -384.94792) (xy 148.264039 -384.94792) (xy 148.212704 -384.93979) (xy 148.163274 -384.923729)
			(xy 148.116964 -384.900133) (xy 148.074916 -384.869583) (xy 148.038165 -384.832832) (xy 148.007615 -384.790784)
			(xy 147.984019 -384.744474) (xy 147.967958 -384.695044) (xy 147.959828 -384.643709) (xy 147.40749 -384.643709)
			(xy 147.399829 -384.692074) (xy 147.384385 -384.739606) (xy 147.361695 -384.784138) (xy 147.332319 -384.824571)
			(xy 147.296979 -384.859911) (xy 147.256546 -384.889287) (xy 147.212014 -384.911977) (xy 147.164482 -384.927421)
			(xy 147.115119 -384.93524) (xy 147.065141 -384.93524) (xy 147.015778 -384.927421) (xy 146.968246 -384.911977)
			(xy 146.923714 -384.889287) (xy 146.883281 -384.859911) (xy 146.847941 -384.824571) (xy 146.818565 -384.784138)
			(xy 146.795875 -384.739606) (xy 146.780431 -384.692074) (xy 146.772612 -384.642711) (xy 145.196982 -384.642711)
			(xy 145.195654 -384.643635) (xy 145.171922 -384.655568) (xy 145.158714 -384.661918) (xy 145.14322 -384.686556)
			(xy 145.14322 -385.87553) (xy 146.461734 -385.87553) (xy 146.462294 -385.84795) (xy 146.471494 -385.793561)
			(xy 146.480022 -385.767326) (xy 146.482816 -385.759452) (xy 146.482816 -385.61518) (xy 146.483317 -385.598483)
			(xy 146.491955 -385.566226) (xy 146.508637 -385.537298) (xy 146.532231 -385.513666) (xy 146.561131 -385.496936)
			(xy 146.593374 -385.488245) (xy 146.61007 -385.487672) (xy 146.99107 -385.487672) (xy 147.000976 -385.48818)
			(xy 147.012752 -385.488527) (xy 147.0346 -385.479791) (xy 147.042886 -385.471416) (xy 147.104608 -385.402836)
			(xy 147.110958 -385.379976) (xy 147.110196 -385.376166) (xy 147.110196 -385.375404) (xy 147.10707 -385.359331)
			(xy 147.103761 -385.326753) (xy 147.103592 -385.31038) (xy 147.104099 -385.285592) (xy 147.111857 -385.236626)
			(xy 147.127178 -385.189477) (xy 147.149686 -385.145304) (xy 147.178825 -385.105195) (xy 147.21388 -385.070138)
			(xy 147.253987 -385.040996) (xy 147.298158 -385.018486) (xy 147.345307 -385.003162) (xy 147.394272 -384.995401)
			(xy 147.41906 -384.994912) (xy 147.442672 -384.995378) (xy 147.489368 -385.002419) (xy 147.534495 -385.016337)
			(xy 147.577046 -385.03682) (xy 147.616071 -385.063412) (xy 147.650702 -385.095519) (xy 147.680164 -385.132425)
			(xy 147.692364 -385.152646) (xy 147.701587 -385.169158) (xy 147.716489 -385.203921) (xy 147.722082 -385.221988)
			(xy 147.72259 -385.22402) (xy 147.723606 -385.228084) (xy 147.771525 -385.310888) (xy 148.303488 -385.310888)
			(xy 148.303488 -385.31038) (xy 148.303999 -385.285592) (xy 148.311757 -385.236627) (xy 148.327078 -385.189478)
			(xy 148.349585 -385.145305) (xy 148.378724 -385.105197) (xy 148.413778 -385.07014) (xy 148.453885 -385.040997)
			(xy 148.498055 -385.018487) (xy 148.545203 -385.003162) (xy 148.594168 -384.995401) (xy 148.618956 -384.994912)
			(xy 148.64435 -384.995434) (xy 148.694483 -385.003559) (xy 148.74267 -385.019605) (xy 148.787665 -385.04316)
			(xy 148.828308 -385.073614) (xy 148.863551 -385.110183) (xy 148.892485 -385.151924) (xy 148.914362 -385.197758)
			(xy 148.921978 -385.221988) (xy 148.923502 -385.22783) (xy 148.971252 -385.31038) (xy 149.503384 -385.31038)
			(xy 149.503898 -385.285605) (xy 149.511648 -385.236664) (xy 149.526953 -385.189537) (xy 149.549438 -385.145382)
			(xy 149.578549 -385.105285) (xy 149.61357 -385.070232) (xy 149.653641 -385.041085) (xy 149.697776 -385.018561)
			(xy 149.74489 -385.003214) (xy 149.793823 -384.99542) (xy 149.818598 -384.994912) (xy 149.819106 -384.994912)
			(xy 149.844553 -384.995424) (xy 149.89479 -385.003574) (xy 149.943069 -385.019679) (xy 149.988139 -385.04332)
			(xy 150.028832 -385.073886) (xy 150.064093 -385.110585) (xy 150.093011 -385.152466) (xy 150.114834 -385.198443)
			(xy 150.122382 -385.22275) (xy 150.123906 -385.228592) (xy 150.443692 -385.78155) (xy 150.447756 -385.785868)
			(xy 150.463964 -385.803538) (xy 150.491361 -385.842889) (xy 150.51249 -385.885931) (xy 150.526866 -385.931673)
			(xy 150.534158 -385.979064) (xy 150.534624 -386.003038) (xy 150.534624 -386.003546) (xy 150.533862 -386.023866)
			(xy 150.5331 -386.033772) (xy 150.53945 -386.052822) (xy 150.600156 -386.122164) (xy 150.617936 -386.131054)
			(xy 150.628096 -386.131816) (xy 150.653074 -386.133997) (xy 150.701933 -386.145254) (xy 150.748419 -386.164037)
			(xy 150.791384 -386.189881) (xy 150.829761 -386.222147) (xy 150.846536 -386.240782) (xy 150.849001 -386.243552)
			(xy 150.854611 -386.2484) (xy 150.857712 -386.250434) (xy 150.869776 -386.258491) (xy 150.889736 -386.279533)
			(xy 150.903811 -386.304892) (xy 150.911109 -386.332962) (xy 150.91156 -386.347462) (xy 150.91156 -386.3594)
			(xy 150.913084 -386.366004) (xy 150.918277 -386.386376) (xy 150.923886 -386.428042) (xy 150.92426 -386.449062)
			(xy 150.923877 -386.470082) (xy 150.918277 -386.511748) (xy 150.913084 -386.53212) (xy 150.91156 -386.538724)
			(xy 150.91156 -386.652262) (xy 150.911034 -386.667256) (xy 150.903292 -386.696226) (xy 150.888324 -386.72221)
			(xy 150.867147 -386.743441) (xy 150.841202 -386.758477) (xy 150.812252 -386.766294) (xy 150.79726 -386.766816)
			(xy 150.615142 -386.766816) (xy 150.614634 -386.76707) (xy 150.59787 -386.76707) (xy 150.597362 -386.766816)
			(xy 150.415752 -386.766816) (xy 150.400721 -386.766362) (xy 150.371684 -386.758582) (xy 150.345643 -386.743564)
			(xy 150.324367 -386.722328) (xy 150.3093 -386.696314) (xy 150.301466 -386.667292) (xy 150.300944 -386.652262)
			(xy 150.300944 -386.538724) (xy 150.29942 -386.53212) (xy 150.294213 -386.511751) (xy 150.288613 -386.470083)
			(xy 150.288244 -386.449062) (xy 150.289006 -386.426456) (xy 150.289768 -386.41655) (xy 150.283418 -386.397246)
			(xy 150.22322 -386.327904) (xy 150.205186 -386.31876) (xy 150.19528 -386.317998) (xy 150.171451 -386.31582)
			(xy 150.124821 -386.305088) (xy 150.080346 -386.287439) (xy 150.039045 -386.263277) (xy 150.001866 -386.233156)
			(xy 149.969662 -386.197766) (xy 149.94317 -386.157919) (xy 149.922999 -386.114529) (xy 149.91588 -386.091684)
			(xy 149.914356 -386.085842) (xy 149.593808 -385.53136) (xy 149.589744 -385.527042) (xy 149.573614 -385.509395)
			(xy 149.54637 -385.47011) (xy 149.525364 -385.427164) (xy 149.511078 -385.38154) (xy 149.503839 -385.334284)
			(xy 149.503384 -385.31038) (xy 148.971252 -385.31038) (xy 149.243796 -385.78155) (xy 149.24786 -385.785868)
			(xy 149.264069 -385.803538) (xy 149.291465 -385.842889) (xy 149.312594 -385.885931) (xy 149.32697 -385.931673)
			(xy 149.334262 -385.979064) (xy 149.334728 -386.003038) (xy 149.334728 -386.003546) (xy 149.333966 -386.023866)
			(xy 149.333204 -386.033772) (xy 149.339554 -386.052822) (xy 149.40026 -386.122164) (xy 149.41804 -386.131054)
			(xy 149.4282 -386.131816) (xy 149.453179 -386.133994) (xy 149.502037 -386.145252) (xy 149.548524 -386.164036)
			(xy 149.591488 -386.189881) (xy 149.629865 -386.222146) (xy 149.64664 -386.240782) (xy 149.649104 -386.243553)
			(xy 149.654715 -386.2484) (xy 149.657816 -386.250434) (xy 149.669881 -386.25849) (xy 149.68984 -386.279533)
			(xy 149.703915 -386.304892) (xy 149.711213 -386.332961) (xy 149.711664 -386.347462) (xy 149.711664 -386.3594)
			(xy 149.713188 -386.366004) (xy 149.718379 -386.386377) (xy 149.72399 -386.428042) (xy 149.724364 -386.449062)
			(xy 149.723984 -386.470082) (xy 149.718383 -386.511749) (xy 149.713188 -386.53212) (xy 149.711664 -386.538724)
			(xy 149.711664 -386.652262) (xy 149.711134 -386.667255) (xy 149.703392 -386.696225) (xy 149.688425 -386.722208)
			(xy 149.667249 -386.74344) (xy 149.641305 -386.758476) (xy 149.612356 -386.766294) (xy 149.597364 -386.766816)
			(xy 149.415246 -386.766816) (xy 149.414738 -386.76707) (xy 149.397974 -386.76707) (xy 149.397466 -386.766816)
			(xy 149.215856 -386.766816) (xy 149.200826 -386.766359) (xy 149.171788 -386.75858) (xy 149.145747 -386.743563)
			(xy 149.124471 -386.722326) (xy 149.109404 -386.696314) (xy 149.10157 -386.667291) (xy 149.101048 -386.652262)
			(xy 149.101048 -386.538724) (xy 149.099524 -386.53212) (xy 149.094317 -386.511751) (xy 149.088717 -386.470083)
			(xy 149.088348 -386.449062) (xy 149.08911 -386.426456) (xy 149.089872 -386.41655) (xy 149.083522 -386.397246)
			(xy 149.023324 -386.327904) (xy 149.00529 -386.31876) (xy 148.995384 -386.317998) (xy 148.971556 -386.315816)
			(xy 148.924925 -386.305086) (xy 148.88045 -386.287437) (xy 148.839149 -386.263275) (xy 148.80197 -386.233154)
			(xy 148.769766 -386.197765) (xy 148.743274 -386.157919) (xy 148.723103 -386.114529) (xy 148.715984 -386.091684)
			(xy 148.71446 -386.085842) (xy 148.394166 -385.532122) (xy 148.390102 -385.527804) (xy 148.373958 -385.510124)
			(xy 148.346636 -385.470811) (xy 148.325564 -385.427822) (xy 148.311227 -385.382144) (xy 148.303953 -385.334825)
			(xy 148.303488 -385.310888) (xy 147.771525 -385.310888) (xy 148.0439 -385.78155) (xy 148.047964 -385.785868)
			(xy 148.064173 -385.803537) (xy 148.09157 -385.842888) (xy 148.112699 -385.88593) (xy 148.127074 -385.931673)
			(xy 148.134366 -385.979064) (xy 148.134832 -386.003038) (xy 148.134832 -386.003546) (xy 148.13407 -386.023866)
			(xy 148.133308 -386.033772) (xy 148.139658 -386.052822) (xy 148.200364 -386.122164) (xy 148.218144 -386.131054)
			(xy 148.228304 -386.131816) (xy 148.253254 -386.134031) (xy 148.302054 -386.145312) (xy 148.348484 -386.1641)
			(xy 148.391396 -386.189931) (xy 148.429731 -386.222167) (xy 148.44649 -386.240782) (xy 148.448948 -386.243559)
			(xy 148.454563 -386.248402) (xy 148.457666 -386.250434) (xy 148.469693 -386.258517) (xy 148.489587 -386.279574)
			(xy 148.503597 -386.304929) (xy 148.510835 -386.332978) (xy 148.51126 -386.347462) (xy 148.51126 -386.3594)
			(xy 148.513038 -386.366004) (xy 148.51823 -386.386376) (xy 148.52384 -386.428042) (xy 148.524214 -386.449062)
			(xy 148.523832 -386.470082) (xy 148.518232 -386.511748) (xy 148.513038 -386.53212) (xy 148.51126 -386.538724)
			(xy 148.51126 -386.652262) (xy 148.510775 -386.667282) (xy 148.503008 -386.696302) (xy 148.487994 -386.722321)
			(xy 148.466756 -386.743567) (xy 148.440742 -386.758591) (xy 148.411726 -386.766369) (xy 148.396706 -386.766816)
			(xy 148.215096 -386.766816) (xy 148.214588 -386.76707) (xy 148.197824 -386.76707) (xy 148.197316 -386.766816)
			(xy 148.015706 -386.766816) (xy 148.000681 -386.766402) (xy 147.971654 -386.758624) (xy 147.94563 -386.743597)
			(xy 147.924384 -386.722345) (xy 147.909364 -386.696317) (xy 147.901594 -386.667288) (xy 147.901152 -386.652262)
			(xy 147.901152 -386.538724) (xy 147.899374 -386.53212) (xy 147.894168 -386.511751) (xy 147.888567 -386.470083)
			(xy 147.888198 -386.449062) (xy 147.88896 -386.426456) (xy 147.889722 -386.416296) (xy 147.883626 -386.3975)
			(xy 147.830032 -386.335524) (xy 147.823093 -386.328274) (xy 147.80519 -386.319254) (xy 147.795234 -386.317998)
			(xy 147.771425 -386.315777) (xy 147.724833 -386.305022) (xy 147.680398 -386.287359) (xy 147.639136 -386.263193)
			(xy 147.601994 -386.233077) (xy 147.569822 -386.197702) (xy 147.543355 -386.157877) (xy 147.523202 -386.114514)
			(xy 147.516088 -386.091684) (xy 147.514564 -386.085842) (xy 147.197064 -385.537202) (xy 147.190206 -385.527804)
			(xy 147.181824 -385.51866) (xy 147.141438 -385.542028) (xy 147.132776 -385.547617) (xy 147.120441 -385.564107)
			(xy 147.115576 -385.584117) (xy 147.1168 -385.594352) (xy 147.118324 -385.614926) (xy 147.118324 -385.615434)
			(xy 147.118324 -385.819904) (xy 147.119086 -385.823714) (xy 147.120989 -385.83652) (xy 147.123027 -385.86233)
			(xy 147.12315 -385.875276) (xy 147.12315 -385.87553) (xy 147.122979 -385.891119) (xy 147.120053 -385.92216)
			(xy 147.117308 -385.937506) (xy 147.1168 -385.939538) (xy 147.113244 -385.956048) (xy 147.112736 -385.957572)
			(xy 147.108243 -385.97421) (xy 147.096285 -386.006535) (xy 147.08886 -386.022088) (xy 147.08886 -386.022342)
			(xy 147.08486 -386.031623) (xy 147.083666 -386.05178) (xy 147.086574 -386.061458) (xy 147.114514 -386.140198)
			(xy 147.128484 -386.155184) (xy 147.137882 -386.159502) (xy 147.158458 -386.169346) (xy 147.196846 -386.19398)
			(xy 147.231339 -386.223824) (xy 147.246594 -386.240782) (xy 147.249052 -386.243559) (xy 147.254667 -386.248403)
			(xy 147.25777 -386.250434) (xy 147.269798 -386.258516) (xy 147.289691 -386.279573) (xy 147.303701 -386.304929)
			(xy 147.310939 -386.332978) (xy 147.311364 -386.347462) (xy 147.311364 -386.3594) (xy 147.313142 -386.366004)
			(xy 147.318334 -386.386376) (xy 147.323944 -386.428042) (xy 147.324318 -386.449062) (xy 147.323936 -386.470082)
			(xy 147.318336 -386.511748) (xy 147.313142 -386.53212) (xy 147.311364 -386.538724) (xy 147.311364 -386.652262)
			(xy 147.310875 -386.667282) (xy 147.303108 -386.696301) (xy 147.288095 -386.72232) (xy 147.266858 -386.743566)
			(xy 147.240845 -386.75859) (xy 147.21183 -386.766369) (xy 147.19681 -386.766816) (xy 147.0152 -386.766816)
			(xy 147.014692 -386.76707) (xy 146.997928 -386.76707) (xy 146.99742 -386.766816) (xy 146.81581 -386.766816)
			(xy 146.800785 -386.766399) (xy 146.771758 -386.758622) (xy 146.745734 -386.743595) (xy 146.724488 -386.722343)
			(xy 146.709468 -386.696316) (xy 146.701698 -386.667287) (xy 146.701256 -386.652262) (xy 146.701256 -386.538724)
			(xy 146.699478 -386.53212) (xy 146.694272 -386.511751) (xy 146.688671 -386.470083) (xy 146.688302 -386.449062)
			(xy 146.688668 -386.428041) (xy 146.694279 -386.386375) (xy 146.699478 -386.366004) (xy 146.701256 -386.3594)
			(xy 146.701256 -386.347462) (xy 146.701451 -386.336867) (xy 146.705284 -386.316029) (xy 146.708876 -386.30606)
			(xy 146.712432 -386.296916) (xy 146.712178 -386.277612) (xy 146.678142 -386.194554) (xy 146.665188 -386.180838)
			(xy 146.656044 -386.176774) (xy 146.631572 -386.165168) (xy 146.586533 -386.135087) (xy 146.546997 -386.098069)
			(xy 146.514023 -386.055103) (xy 146.488492 -386.007337) (xy 146.471086 -385.956049) (xy 146.462271 -385.902611)
			(xy 146.461734 -385.87553) (xy 145.14322 -385.87553) (xy 145.14322 -386.618988) (xy 145.1428 -386.62906)
			(xy 145.135091 -386.647669) (xy 145.128234 -386.655056) (xy 145.037302 -386.745988) (xy 145.032984 -386.780278)
			(xy 145.04162 -386.795264) (xy 145.049817 -386.810121) (xy 145.058836 -386.842821) (xy 145.0594 -386.85978)
			(xy 145.0594 -386.995162) (xy 145.059908 -386.998972) (xy 145.061579 -387.011094) (xy 145.063356 -387.035503)
			(xy 145.063464 -387.04774) (xy 145.063375 -387.059977) (xy 145.061598 -387.084387) (xy 145.059908 -387.096508)
			(xy 145.0594 -387.100318) (xy 145.0594 -387.24078) (xy 145.058906 -387.257503) (xy 145.050254 -387.289809)
			(xy 145.033533 -387.318775) (xy 145.009885 -387.342426) (xy 144.980921 -387.359149) (xy 144.948615 -387.367804)
			(xy 144.931892 -387.368288) (xy 144.814798 -387.368288) (xy 144.808956 -387.369558) (xy 144.78389 -387.374993)
			(xy 144.732756 -387.378961) (xy 144.681622 -387.374993) (xy 144.656556 -387.369558) (xy 144.650714 -387.368288)
			(xy 144.627092 -387.368288) (xy 144.609785 -387.367706) (xy 144.576443 -387.358407) (xy 144.546823 -387.340494)
			(xy 144.523104 -387.315284) (xy 144.51457 -387.300216) (xy 144.512577 -387.296577) (xy 144.507599 -387.28994)
			(xy 144.504664 -387.287008) (xy 144.485624 -387.268172) (xy 144.453289 -387.22548) (xy 144.428261 -387.178132)
			(xy 144.411195 -387.127369) (xy 144.402537 -387.074518) (xy 144.402048 -387.04774) (xy 144.402179 -387.035821)
			(xy 144.403959 -387.012048) (xy 144.405604 -387.000242) (xy 144.405604 -386.999988) (xy 144.406614 -386.989112)
			(xy 144.400418 -386.968189) (xy 144.393666 -386.959602) (xy 144.343374 -386.901436) (xy 144.335823 -386.893517)
			(xy 144.315948 -386.884417) (xy 144.30502 -386.88391) (xy 142.989808 -386.88391) (xy 142.979737 -386.884332)
			(xy 142.961132 -386.892045) (xy 142.95374 -386.898896) (xy 142.376652 -387.475984) (xy 142.369813 -387.483384)
			(xy 142.362101 -387.501983) (xy 142.361666 -387.512052) (xy 142.361666 -388.297674) (xy 143.436592 -388.297674)
			(xy 143.440663 -388.242052) (xy 143.452789 -388.187615) (xy 143.472712 -388.135524) (xy 143.500008 -388.086889)
			(xy 143.534094 -388.042746) (xy 143.574243 -388.004037) (xy 143.619601 -387.971586) (xy 143.669201 -387.946085)
			(xy 143.721985 -387.928078) (xy 143.776828 -387.917948) (xy 143.832562 -387.915911) (xy 143.887999 -387.922011)
			(xy 143.941956 -387.936117) (xy 143.993285 -387.957929) (xy 144.040891 -387.986983) (xy 144.083759 -388.022658)
			(xy 144.120976 -388.064195) (xy 144.151749 -388.110708) (xy 144.175421 -388.161205) (xy 144.191489 -388.214612)
			(xy 144.199609 -388.269788) (xy 144.20009 -388.29615) (xy 144.402048 -388.29615) (xy 144.402224 -388.279462)
			(xy 144.405535 -388.246251) (xy 144.408652 -388.229856) (xy 144.409668 -388.224776) (xy 144.409668 -388.189978)
			(xy 144.410257 -388.172049) (xy 144.420216 -388.137602) (xy 144.439346 -388.107273) (xy 144.466142 -388.083446)
			(xy 144.482058 -388.07517) (xy 144.486065 -388.073153) (xy 144.493344 -388.067909) (xy 144.496536 -388.064756)
			(xy 144.515317 -388.046295) (xy 144.557652 -388.014979) (xy 144.604419 -387.990774) (xy 144.654432 -387.974291)
			(xy 144.706426 -387.965949) (xy 144.732756 -387.965442) (xy 144.760577 -387.966047) (xy 144.815433 -387.97536)
			(xy 144.867955 -387.993729) (xy 144.916658 -388.020635) (xy 144.960166 -388.05532) (xy 144.979136 -388.075678)
			(xy 144.988788 -388.08406) (xy 145.000787 -388.092607) (xy 145.020869 -388.114149) (xy 145.035497 -388.139709)
			(xy 145.043897 -388.167936) (xy 145.045176 -388.182612) (xy 145.047462 -388.195058) (xy 145.054907 -388.219666)
			(xy 145.06294 -388.270445) (xy 145.063464 -388.29615) (xy 145.063009 -388.321582) (xy 145.061912 -388.328662)
			(xy 146.828256 -388.328662) (xy 146.828624 -388.307641) (xy 146.834234 -388.265975) (xy 146.839432 -388.245604)
			(xy 146.840956 -388.239) (xy 146.840956 -388.125462) (xy 146.8414 -388.110464) (xy 146.849161 -388.081488)
			(xy 146.864147 -388.055503) (xy 146.885339 -388.034273) (xy 146.911297 -388.019241) (xy 146.940259 -388.011427)
			(xy 146.955256 -388.010908) (xy 147.137374 -388.010908) (xy 147.137882 -388.010654) (xy 147.154646 -388.010654)
			(xy 147.155154 -388.010908) (xy 147.336764 -388.010908) (xy 147.351793 -388.011412) (xy 147.380831 -388.019174)
			(xy 147.406874 -388.034179) (xy 147.428154 -388.055407) (xy 147.443221 -388.081415) (xy 147.451052 -388.110434)
			(xy 147.451572 -388.125462) (xy 147.451572 -388.239) (xy 147.453096 -388.245604) (xy 147.458287 -388.265977)
			(xy 147.463898 -388.307642) (xy 147.464272 -388.328662) (xy 148.028152 -388.328662) (xy 148.02852 -388.307641)
			(xy 148.03413 -388.265975) (xy 148.039328 -388.245604) (xy 148.040852 -388.239) (xy 148.040852 -388.125462)
			(xy 148.0413 -388.110464) (xy 148.049061 -388.081489) (xy 148.064046 -388.055504) (xy 148.085237 -388.034274)
			(xy 148.111194 -388.019242) (xy 148.140155 -388.011427) (xy 148.155152 -388.010908) (xy 148.33727 -388.010908)
			(xy 148.337778 -388.010654) (xy 148.354542 -388.010654) (xy 148.35505 -388.010908) (xy 148.53666 -388.010908)
			(xy 148.551689 -388.011415) (xy 148.580726 -388.019176) (xy 148.60677 -388.034181) (xy 148.628049 -388.055408)
			(xy 148.643117 -388.081416) (xy 148.650948 -388.110435) (xy 148.651468 -388.125462) (xy 148.651468 -388.239)
			(xy 148.652992 -388.245604) (xy 148.658183 -388.265977) (xy 148.663794 -388.307642) (xy 148.664168 -388.328662)
			(xy 149.228302 -388.328662) (xy 149.228668 -388.307641) (xy 149.234279 -388.265975) (xy 149.239478 -388.245604)
			(xy 149.241256 -388.239) (xy 149.241256 -388.125462) (xy 149.241703 -388.110443) (xy 149.249486 -388.08143)
			(xy 149.264512 -388.055419) (xy 149.285757 -388.034182) (xy 149.311774 -388.019167) (xy 149.34079 -388.011396)
			(xy 149.35581 -388.010908) (xy 149.53742 -388.010908) (xy 149.537928 -388.010654) (xy 149.554692 -388.010654)
			(xy 149.5552 -388.010908) (xy 149.73681 -388.010908) (xy 149.751824 -388.011427) (xy 149.780829 -388.019199)
			(xy 149.806835 -388.034212) (xy 149.828071 -388.055442) (xy 149.84309 -388.081445) (xy 149.85087 -388.110448)
			(xy 149.851364 -388.125462) (xy 149.851364 -388.239) (xy 149.853142 -388.245604) (xy 149.858334 -388.265976)
			(xy 149.863944 -388.307642) (xy 149.864318 -388.328662) (xy 150.428198 -388.328662) (xy 150.428565 -388.307641)
			(xy 150.434175 -388.265975) (xy 150.439374 -388.245604) (xy 150.441152 -388.239) (xy 150.441152 -388.125462)
			(xy 150.441603 -388.110443) (xy 150.449385 -388.08143) (xy 150.464411 -388.05542) (xy 150.485655 -388.034184)
			(xy 150.511671 -388.019169) (xy 150.540687 -388.011397) (xy 150.555706 -388.010908) (xy 150.737316 -388.010908)
			(xy 150.737824 -388.010654) (xy 150.754588 -388.010654) (xy 150.755096 -388.010908) (xy 150.936706 -388.010908)
			(xy 150.95172 -388.01143) (xy 150.980725 -388.019202) (xy 151.006731 -388.034214) (xy 151.027967 -388.055444)
			(xy 151.042986 -388.081445) (xy 151.050766 -388.110448) (xy 151.05126 -388.125462) (xy 151.05126 -388.239)
			(xy 151.053038 -388.245604) (xy 151.05823 -388.265976) (xy 151.06384 -388.307642) (xy 151.064214 -388.328662)
			(xy 151.064214 -388.32917) (xy 151.064043 -388.343795) (xy 151.061377 -388.372924) (xy 151.05888 -388.387336)
			(xy 151.057519 -388.39651) (xy 151.060791 -388.414752) (xy 151.06523 -388.422896) (xy 151.08174 -388.44982)
			(xy 151.086911 -388.457597) (xy 151.101636 -388.46906) (xy 151.110442 -388.472172) (xy 151.135331 -388.480215)
			(xy 151.182209 -388.50341) (xy 151.22462 -388.534018) (xy 151.261402 -388.571202) (xy 151.291548 -388.613944)
			(xy 151.314231 -388.661071) (xy 151.322024 -388.68604) (xy 151.323548 -388.691882) (xy 151.418036 -388.855204)
			(xy 151.449786 -388.868412) (xy 151.46655 -388.86384) (xy 151.477136 -388.860385) (xy 151.494171 -388.84609)
			(xy 151.503573 -388.825937) (xy 151.504142 -388.814818) (xy 151.504142 -387.6675) (xy 151.51735 -387.6675)
			(xy 151.51735 -387.495542) (xy 151.517784 -387.485473) (xy 151.525497 -387.466875) (xy 151.532336 -387.459474)
			(xy 151.596598 -387.395212) (xy 151.603321 -387.387841) (xy 151.610955 -387.369425) (xy 151.611017 -387.34949)
			(xy 151.603498 -387.331027) (xy 151.596852 -387.323584) (xy 151.595582 -387.322314) (xy 151.594566 -387.321298)
			(xy 151.586983 -387.314474) (xy 151.572621 -387.299984) (xy 151.565864 -387.292342) (xy 151.563396 -387.289574)
			(xy 151.557788 -387.284725) (xy 151.554688 -387.28269) (xy 151.542634 -387.274618) (xy 151.522674 -387.25358)
			(xy 151.508597 -387.228226) (xy 151.501294 -387.200161) (xy 151.50084 -387.185662) (xy 151.50084 -387.173724)
			(xy 151.499316 -387.16712) (xy 151.494109 -387.146751) (xy 151.488509 -387.105083) (xy 151.48814 -387.084062)
			(xy 151.488508 -387.063041) (xy 151.494118 -387.021375) (xy 151.499316 -387.001004) (xy 151.50084 -386.9944)
			(xy 151.50084 -386.880862) (xy 151.501498 -386.862743) (xy 151.512753 -386.828297) (xy 151.522938 -386.813298)
			(xy 151.527443 -386.806633) (xy 151.532484 -386.791364) (xy 151.532844 -386.783326) (xy 151.532844 -386.749798)
			(xy 151.53254 -386.74175) (xy 151.527493 -386.726467) (xy 151.522938 -386.719826) (xy 151.51285 -386.704777)
			(xy 151.501596 -386.670363) (xy 151.50084 -386.652262) (xy 151.50084 -386.538724) (xy 151.499316 -386.53212)
			(xy 151.494109 -386.511751) (xy 151.488509 -386.470083) (xy 151.48814 -386.449062) (xy 151.488902 -386.426456)
			(xy 151.489664 -386.416296) (xy 151.483568 -386.3975) (xy 151.429974 -386.335524) (xy 151.423056 -386.328251)
			(xy 151.405137 -386.319244) (xy 151.395176 -386.317998) (xy 151.371362 -386.315824) (xy 151.324769 -386.30506)
			(xy 151.280333 -386.287389) (xy 151.239072 -386.263216) (xy 151.201931 -386.233094) (xy 151.16976 -386.197713)
			(xy 151.143295 -386.157883) (xy 151.123143 -386.114516) (xy 151.11603 -386.091684) (xy 151.114506 -386.085842)
			(xy 150.794212 -385.532122) (xy 150.790148 -385.527804) (xy 150.773911 -385.510125) (xy 150.746494 -385.470725)
			(xy 150.725358 -385.427628) (xy 150.710992 -385.381828) (xy 150.703726 -385.33438) (xy 150.70328 -385.31038)
			(xy 150.703699 -385.2856) (xy 150.711451 -385.23665) (xy 150.726762 -385.189515) (xy 150.749255 -385.145353)
			(xy 150.778377 -385.105252) (xy 150.813411 -385.070198) (xy 150.853495 -385.041053) (xy 150.897643 -385.018534)
			(xy 150.944769 -385.003195) (xy 150.993714 -384.995413) (xy 151.018494 -384.994912) (xy 151.019002 -384.994912)
			(xy 151.044397 -384.995394) (xy 151.094533 -385.003525) (xy 151.14272 -385.019578) (xy 151.187715 -385.043139)
			(xy 151.228358 -385.073599) (xy 151.2636 -385.110173) (xy 151.292533 -385.151918) (xy 151.314409 -385.197756)
			(xy 151.322024 -385.221988) (xy 151.323548 -385.22783) (xy 151.643842 -385.78155) (xy 151.647906 -385.785868)
			(xy 151.664054 -385.803578) (xy 151.6914 -385.842935) (xy 151.712482 -385.885973) (xy 151.726816 -385.931704)
			(xy 151.73407 -385.979076) (xy 151.73452 -386.003038) (xy 151.73452 -386.003546) (xy 151.734012 -386.023866)
			(xy 151.73325 -386.033772) (xy 151.7396 -386.052822) (xy 151.800306 -386.122164) (xy 151.818086 -386.131054)
			(xy 151.828246 -386.131816) (xy 151.853199 -386.134006) (xy 151.901999 -386.145293) (xy 151.948429 -386.164087)
			(xy 151.99134 -386.189924) (xy 152.029674 -386.222164) (xy 152.046432 -386.240782) (xy 152.048897 -386.243552)
			(xy 152.054508 -386.2484) (xy 152.057608 -386.250434) (xy 152.069672 -386.258492) (xy 152.089631 -386.279534)
			(xy 152.103706 -386.304892) (xy 152.111005 -386.332962) (xy 152.111456 -386.347462) (xy 152.111456 -386.3594)
			(xy 152.11298 -386.366004) (xy 152.118173 -386.386376) (xy 152.123782 -386.428042) (xy 152.124156 -386.449062)
			(xy 152.123773 -386.470082) (xy 152.118173 -386.511748) (xy 152.11298 -386.53212) (xy 152.111456 -386.538724)
			(xy 152.111456 -386.599176) (xy 152.112006 -386.609177) (xy 152.11965 -386.62766) (xy 152.133783 -386.641812)
			(xy 152.152256 -386.64948) (xy 152.162256 -386.649976) (xy 152.166066 -386.649976) (xy 152.17013 -386.649214)
			(xy 152.181798 -386.647455) (xy 152.205321 -386.645551) (xy 152.21712 -386.645404) (xy 152.650444 -386.645404)
			(xy 152.660454 -386.644948) (xy 152.678946 -386.637275) (xy 152.693097 -386.623112) (xy 152.700756 -386.604614)
			(xy 152.701244 -386.594604) (xy 152.701244 -386.538724) (xy 152.699466 -386.53212) (xy 152.69426 -386.511751)
			(xy 152.688659 -386.470083) (xy 152.68829 -386.449062) (xy 152.689052 -386.426456) (xy 152.689814 -386.41655)
			(xy 152.683464 -386.397246) (xy 152.623266 -386.327904) (xy 152.605232 -386.31876) (xy 152.595326 -386.317998)
			(xy 152.571501 -386.315782) (xy 152.524872 -386.305058) (xy 152.480397 -386.287415) (xy 152.439096 -386.263258)
			(xy 152.401917 -386.233142) (xy 152.369711 -386.197757) (xy 152.343219 -386.157914) (xy 152.323046 -386.114528)
			(xy 152.315926 -386.091684) (xy 152.314402 -386.085842) (xy 151.994108 -385.532122) (xy 151.990044 -385.527804)
			(xy 151.973807 -385.510125) (xy 151.946389 -385.470726) (xy 151.925254 -385.427629) (xy 151.910888 -385.381828)
			(xy 151.903622 -385.33438) (xy 151.903176 -385.31038) (xy 151.903599 -385.2856) (xy 151.911351 -385.236651)
			(xy 151.926662 -385.189516) (xy 151.949154 -385.145355) (xy 151.978276 -385.105254) (xy 152.013309 -385.070199)
			(xy 152.053392 -385.041054) (xy 152.09754 -385.018535) (xy 152.144666 -385.003195) (xy 152.193611 -384.995414)
			(xy 152.21839 -384.994912) (xy 152.218898 -384.994912) (xy 152.244293 -384.995397) (xy 152.294428 -385.003528)
			(xy 152.342615 -385.019581) (xy 152.387611 -385.043141) (xy 152.428254 -385.073601) (xy 152.463496 -385.110174)
			(xy 152.492429 -385.151918) (xy 152.514305 -385.197756) (xy 152.52192 -385.221988) (xy 152.523444 -385.22783)
			(xy 152.843738 -385.78155) (xy 152.847802 -385.785868) (xy 152.863949 -385.803579) (xy 152.891296 -385.842935)
			(xy 152.912378 -385.885973) (xy 152.926711 -385.931704) (xy 152.933966 -385.979076) (xy 152.934416 -386.003038)
			(xy 152.934416 -386.003546) (xy 152.933908 -386.023866) (xy 152.933146 -386.033772) (xy 152.939496 -386.052822)
			(xy 153.000202 -386.122164) (xy 153.017982 -386.131054) (xy 153.028142 -386.131816) (xy 153.053117 -386.134029)
			(xy 153.101974 -386.145278) (xy 153.148461 -386.164054) (xy 153.191427 -386.189891) (xy 153.229806 -386.22215)
			(xy 153.246582 -386.240782) (xy 153.249041 -386.243558) (xy 153.254656 -386.248402) (xy 153.257758 -386.250434)
			(xy 153.269783 -386.258519) (xy 153.289678 -386.279575) (xy 153.303688 -386.304929) (xy 153.310927 -386.332978)
			(xy 153.311352 -386.347462) (xy 153.311352 -386.3594) (xy 153.31313 -386.366004) (xy 153.318322 -386.386376)
			(xy 153.323932 -386.428042) (xy 153.324306 -386.449062) (xy 153.323924 -386.470082) (xy 153.318324 -386.511748)
			(xy 153.31313 -386.53212) (xy 153.311352 -386.538724) (xy 153.311352 -386.594604) (xy 153.311884 -386.604606)
			(xy 153.319536 -386.623089) (xy 153.333674 -386.63724) (xy 153.35215 -386.644908) (xy 153.362152 -386.645404)
			(xy 153.439114 -386.645404) (xy 153.468573 -386.64614) (xy 153.526385 -386.657517) (xy 153.553922 -386.66801)
			(xy 153.56332 -386.67182) (xy 153.864818 -386.67182) (xy 153.871194 -386.671611) (xy 153.883537 -386.668402)
			(xy 153.889202 -386.66547) (xy 153.90114 -386.659374) (xy 153.90114 -386.538724) (xy 153.899362 -386.53212)
			(xy 153.894156 -386.511751) (xy 153.888555 -386.470083) (xy 153.888186 -386.449062) (xy 153.888948 -386.426456)
			(xy 153.88971 -386.416296) (xy 153.883614 -386.3975) (xy 153.83002 -386.335524) (xy 153.823086 -386.32827)
			(xy 153.805179 -386.319252) (xy 153.795222 -386.317998) (xy 153.771412 -386.315787) (xy 153.72482 -386.30503)
			(xy 153.680384 -386.287365) (xy 153.639123 -386.263197) (xy 153.601981 -386.233081) (xy 153.569809 -386.197704)
			(xy 153.543343 -386.157878) (xy 153.523189 -386.114515) (xy 153.516076 -386.091684) (xy 153.514552 -386.085842)
			(xy 153.194258 -385.532122) (xy 153.190194 -385.527804) (xy 153.174049 -385.510125) (xy 153.146727 -385.470812)
			(xy 153.125656 -385.427823) (xy 153.111319 -385.382145) (xy 153.104045 -385.334825) (xy 153.10358 -385.310888)
			(xy 153.10358 -385.31038) (xy 153.103975 -385.285585) (xy 153.111736 -385.236607) (xy 153.127063 -385.189447)
			(xy 153.14958 -385.145264) (xy 153.178732 -385.105149) (xy 153.213801 -385.070088) (xy 153.253923 -385.040945)
			(xy 153.29811 -385.018437) (xy 153.345274 -385.00312) (xy 153.394253 -384.995369) (xy 153.419048 -384.994912)
			(xy 153.444445 -384.995353) (xy 153.494582 -385.003492) (xy 153.54277 -385.019552) (xy 153.587765 -385.043119)
			(xy 153.628408 -385.073584) (xy 153.663649 -385.110164) (xy 153.692581 -385.151912) (xy 153.714455 -385.197754)
			(xy 153.72207 -385.221988) (xy 153.723594 -385.22783) (xy 154.043888 -385.78155) (xy 154.047952 -385.785868)
			(xy 154.064159 -385.803539) (xy 154.091556 -385.842889) (xy 154.112686 -385.885931) (xy 154.127062 -385.931674)
			(xy 154.134354 -385.979064) (xy 154.13482 -386.003038) (xy 154.13482 -386.003546) (xy 154.134058 -386.023866)
			(xy 154.133296 -386.033772) (xy 154.139646 -386.052822) (xy 154.200352 -386.122164) (xy 154.218132 -386.131054)
			(xy 154.228292 -386.131816) (xy 154.253241 -386.134038) (xy 154.302041 -386.145318) (xy 154.348471 -386.164104)
			(xy 154.391383 -386.189933) (xy 154.429719 -386.222167) (xy 154.446478 -386.240782) (xy 154.448938 -386.243557)
			(xy 154.454552 -386.248402) (xy 154.457654 -386.250434) (xy 154.469678 -386.258521) (xy 154.489573 -386.279576)
			(xy 154.503584 -386.30493) (xy 154.510823 -386.332978) (xy 154.511248 -386.347462) (xy 154.511248 -386.3594)
			(xy 154.513026 -386.366004) (xy 154.518217 -386.386377) (xy 154.523828 -386.428042) (xy 154.524202 -386.449062)
			(xy 154.523821 -386.470082) (xy 154.51822 -386.511748) (xy 154.513026 -386.53212) (xy 154.511248 -386.538724)
			(xy 154.511248 -386.576824) (xy 154.511601 -386.586853) (xy 154.519288 -386.605379) (xy 154.533481 -386.619552)
			(xy 154.552019 -386.627213) (xy 154.562048 -386.627624) (xy 155.050236 -386.627624) (xy 155.060243 -386.627142)
			(xy 155.078731 -386.619475) (xy 155.092882 -386.605321) (xy 155.100544 -386.586831) (xy 155.101036 -386.576824)
			(xy 155.101036 -386.538724) (xy 155.099512 -386.53212) (xy 155.094307 -386.511751) (xy 155.088705 -386.470083)
			(xy 155.088336 -386.449062) (xy 155.089098 -386.426456) (xy 155.08986 -386.41655) (xy 155.08351 -386.397246)
			(xy 155.023312 -386.327904) (xy 155.005278 -386.31876) (xy 154.995372 -386.317998) (xy 154.971551 -386.315745)
			(xy 154.924923 -386.305027) (xy 154.880448 -386.287391) (xy 154.839147 -386.26324) (xy 154.801967 -386.233129)
			(xy 154.76976 -386.197748) (xy 154.743266 -386.157909) (xy 154.723093 -386.114526) (xy 154.715972 -386.091684)
			(xy 154.714448 -386.085842) (xy 154.394154 -385.532122) (xy 154.39009 -385.527804) (xy 154.373944 -385.510126)
			(xy 154.346622 -385.470812) (xy 154.325551 -385.427823) (xy 154.311215 -385.382145) (xy 154.303941 -385.334825)
			(xy 154.303476 -385.310888) (xy 154.303476 -385.31038) (xy 154.303875 -385.285586) (xy 154.311636 -385.236608)
			(xy 154.326963 -385.189448) (xy 154.34948 -385.145266) (xy 154.378631 -385.10515) (xy 154.413699 -385.070089)
			(xy 154.45382 -385.040946) (xy 154.498007 -385.018439) (xy 154.54517 -385.003121) (xy 154.59415 -384.99537)
			(xy 154.618944 -384.994912) (xy 154.644341 -384.995357) (xy 154.694478 -385.003495) (xy 154.742665 -385.019554)
			(xy 154.787661 -385.04312) (xy 154.828304 -385.073586) (xy 154.863545 -385.110164) (xy 154.892476 -385.151913)
			(xy 154.914351 -385.197754) (xy 154.921966 -385.221988) (xy 154.92349 -385.22783) (xy 155.243784 -385.78155)
			(xy 155.247848 -385.785868) (xy 155.264055 -385.80354) (xy 155.291452 -385.84289) (xy 155.312582 -385.885931)
			(xy 155.326958 -385.931674) (xy 155.33425 -385.979064) (xy 155.334716 -386.003038) (xy 155.334716 -386.003546)
			(xy 155.333954 -386.023866) (xy 155.333192 -386.033772) (xy 155.339542 -386.052822) (xy 155.400248 -386.122164)
			(xy 155.418028 -386.131054) (xy 155.428188 -386.131816) (xy 155.453166 -386.134002) (xy 155.502024 -386.145257)
			(xy 155.548511 -386.16404) (xy 155.591475 -386.189883) (xy 155.629853 -386.222147) (xy 155.646628 -386.240782)
			(xy 155.649094 -386.243552) (xy 155.654704 -386.2484) (xy 155.657804 -386.250434) (xy 155.669867 -386.258494)
			(xy 155.689827 -386.279535) (xy 155.703902 -386.304893) (xy 155.711201 -386.332962) (xy 155.711652 -386.347462)
			(xy 155.711652 -386.3594) (xy 155.713176 -386.366004) (xy 155.718368 -386.386376) (xy 155.723978 -386.428042)
			(xy 155.724352 -386.449062) (xy 155.723969 -386.470082) (xy 155.718369 -386.511748) (xy 155.713176 -386.53212)
			(xy 155.711652 -386.538724) (xy 155.711652 -386.576824) (xy 155.712167 -386.586827) (xy 155.719826 -386.60531)
			(xy 155.733969 -386.619461) (xy 155.752449 -386.627128) (xy 155.762452 -386.627624) (xy 156.250132 -386.627624)
			(xy 156.260139 -386.627139) (xy 156.278627 -386.619473) (xy 156.292778 -386.60532) (xy 156.30044 -386.586831)
			(xy 156.300932 -386.576824) (xy 156.300932 -386.538724) (xy 156.299408 -386.53212) (xy 156.294203 -386.511751)
			(xy 156.288601 -386.470083) (xy 156.288232 -386.449062) (xy 156.288994 -386.426456) (xy 156.289756 -386.41655)
			(xy 156.283406 -386.397246) (xy 156.223208 -386.327904) (xy 156.205174 -386.31876) (xy 156.195268 -386.317998)
			(xy 156.171447 -386.315748) (xy 156.124819 -386.30503) (xy 156.080344 -386.287393) (xy 156.039043 -386.263241)
			(xy 156.001863 -386.23313) (xy 155.969656 -386.197749) (xy 155.943162 -386.157909) (xy 155.922989 -386.114526)
			(xy 155.915868 -386.091684) (xy 155.914344 -386.085842) (xy 155.593796 -385.53136) (xy 155.589732 -385.527042)
			(xy 155.5736 -385.509397) (xy 155.546357 -385.470111) (xy 155.525352 -385.427164) (xy 155.511066 -385.381541)
			(xy 155.503827 -385.334284) (xy 155.503372 -385.31038) (xy 155.503799 -385.285601) (xy 155.511551 -385.236652)
			(xy 155.526861 -385.189517) (xy 155.549354 -385.145356) (xy 155.578474 -385.105255) (xy 155.613507 -385.070201)
			(xy 155.65359 -385.041055) (xy 155.697737 -385.018536) (xy 155.744863 -385.003196) (xy 155.793807 -384.995414)
			(xy 155.818586 -384.994912) (xy 155.819094 -384.994912) (xy 155.844541 -384.995434) (xy 155.894777 -385.003583)
			(xy 155.943056 -385.019686) (xy 155.988126 -385.043326) (xy 156.028819 -385.07389) (xy 156.064081 -385.110588)
			(xy 156.092998 -385.152467) (xy 156.114822 -385.198444) (xy 156.12237 -385.22275) (xy 156.123894 -385.228592)
			(xy 156.44368 -385.78155) (xy 156.447744 -385.785868) (xy 156.46395 -385.80354) (xy 156.491347 -385.84289)
			(xy 156.512478 -385.885932) (xy 156.526854 -385.931674) (xy 156.534146 -385.979064) (xy 156.534612 -386.003038)
			(xy 156.534612 -386.003546) (xy 156.53385 -386.023866) (xy 156.533088 -386.033772) (xy 156.539438 -386.052822)
			(xy 156.600144 -386.122164) (xy 156.617924 -386.131054) (xy 156.628084 -386.131816) (xy 156.653061 -386.134004)
			(xy 156.70192 -386.145259) (xy 156.748407 -386.164041) (xy 156.791371 -386.189884) (xy 156.829749 -386.222147)
			(xy 156.846524 -386.240782) (xy 156.84899 -386.243551) (xy 156.8546 -386.2484) (xy 156.8577 -386.250434)
			(xy 156.869762 -386.258495) (xy 156.889723 -386.279535) (xy 156.903798 -386.304893) (xy 156.911097 -386.332962)
			(xy 156.911548 -386.347462) (xy 156.911548 -386.3594) (xy 156.913072 -386.366004) (xy 156.918264 -386.386376)
			(xy 156.923874 -386.428042) (xy 156.924248 -386.449062) (xy 156.923865 -386.470082) (xy 156.918265 -386.511748)
			(xy 156.913072 -386.53212) (xy 156.911548 -386.538724) (xy 156.911548 -386.576824) (xy 156.911901 -386.586853)
			(xy 156.919588 -386.605379) (xy 156.933781 -386.619552) (xy 156.952319 -386.627213) (xy 156.962348 -386.627624)
			(xy 157.462728 -386.627624) (xy 157.472277 -386.627684) (xy 157.49134 -386.628827) (xy 157.500828 -386.62991)
			(xy 157.500828 -386.538724) (xy 157.499304 -386.53212) (xy 157.494099 -386.511751) (xy 157.488497 -386.470083)
			(xy 157.488128 -386.449062) (xy 157.48889 -386.426456) (xy 157.489652 -386.416296) (xy 157.483556 -386.3975)
			(xy 157.429962 -386.335524) (xy 157.423013 -386.328286) (xy 157.405117 -386.319259) (xy 157.395164 -386.317998)
			(xy 157.371358 -386.315753) (xy 157.324767 -386.305001) (xy 157.280331 -386.287342) (xy 157.23907 -386.26318)
			(xy 157.201927 -386.233068) (xy 157.169754 -386.197696) (xy 157.143287 -386.157873) (xy 157.123132 -386.114513)
			(xy 157.116018 -386.091684) (xy 157.114494 -386.085842) (xy 156.7942 -385.532122) (xy 156.790136 -385.527804)
			(xy 156.773897 -385.510127) (xy 156.74648 -385.470726) (xy 156.725345 -385.427629) (xy 156.71098 -385.381828)
			(xy 156.703714 -385.33438) (xy 156.703268 -385.31038) (xy 156.703699 -385.285601) (xy 156.711451 -385.236652)
			(xy 156.726761 -385.189518) (xy 156.749253 -385.145357) (xy 156.778373 -385.105256) (xy 156.813406 -385.070202)
			(xy 156.853488 -385.041057) (xy 156.897635 -385.018537) (xy 156.944759 -385.003197) (xy 156.993703 -384.995414)
			(xy 157.018482 -384.994912) (xy 157.01899 -384.994912) (xy 157.044385 -384.995404) (xy 157.09452 -385.003534)
			(xy 157.142707 -385.019585) (xy 157.187702 -385.043144) (xy 157.228345 -385.073603) (xy 157.263588 -385.110176)
			(xy 157.29252 -385.151919) (xy 157.314397 -385.197756) (xy 157.322012 -385.221988) (xy 157.323536 -385.22783)
			(xy 157.64383 -385.78155) (xy 157.647894 -385.785868) (xy 157.66404 -385.80358) (xy 157.691387 -385.842936)
			(xy 157.71247 -385.885974) (xy 157.726803 -385.931704) (xy 157.734058 -385.979076) (xy 157.734508 -386.003038)
			(xy 157.734508 -386.003546) (xy 157.734 -386.023866) (xy 157.733238 -386.033772) (xy 157.739588 -386.052822)
			(xy 157.800294 -386.122164) (xy 157.818074 -386.131054) (xy 157.828234 -386.131816) (xy 157.853186 -386.134013)
			(xy 157.901986 -386.145299) (xy 157.948416 -386.164091) (xy 157.991328 -386.189926) (xy 158.029662 -386.222165)
			(xy 158.04642 -386.240782) (xy 158.048887 -386.243551) (xy 158.054496 -386.2484) (xy 158.057596 -386.250434)
			(xy 158.069657 -386.258496) (xy 158.089618 -386.279536) (xy 158.103694 -386.304893) (xy 158.110993 -386.332962)
			(xy 158.111444 -386.347462) (xy 158.111444 -386.3594) (xy 158.112968 -386.366004) (xy 158.11816 -386.386376)
			(xy 158.12377 -386.428042) (xy 158.124144 -386.449062) (xy 158.123761 -386.470082) (xy 158.118162 -386.511748)
			(xy 158.112968 -386.53212) (xy 158.111444 -386.538724) (xy 158.111444 -386.62102) (xy 158.111804 -386.631048)
			(xy 158.119489 -386.649574) (xy 158.13368 -386.663747) (xy 158.152215 -386.671408) (xy 158.162244 -386.67182)
			(xy 158.501588 -386.67182) (xy 158.514034 -386.668518) (xy 158.519622 -386.66547) (xy 158.546627 -386.651332)
			(xy 158.604721 -386.632902) (xy 158.634938 -386.628894) (xy 158.643776 -386.627572) (xy 158.659776 -386.619633)
			(xy 158.66618 -386.6134) (xy 158.687262 -386.591302) (xy 158.693628 -386.583972) (xy 158.700804 -386.565949)
			(xy 158.701232 -386.55625) (xy 158.701232 -386.538724) (xy 158.699454 -386.53212) (xy 158.694248 -386.511751)
			(xy 158.688647 -386.470083) (xy 158.688278 -386.449062) (xy 158.68904 -386.426456) (xy 158.689802 -386.41655)
			(xy 158.683452 -386.397246) (xy 158.623254 -386.327904) (xy 158.60522 -386.31876) (xy 158.595314 -386.317998)
			(xy 158.571488 -386.315792) (xy 158.524859 -386.305065) (xy 158.480384 -386.287421) (xy 158.439083 -386.263263)
			(xy 158.401904 -386.233145) (xy 158.369698 -386.197759) (xy 158.343206 -386.157915) (xy 158.323034 -386.114528)
			(xy 158.315914 -386.091684) (xy 158.31439 -386.085842) (xy 157.994096 -385.532122) (xy 157.990032 -385.527804)
			(xy 157.973793 -385.510127) (xy 157.946376 -385.470727) (xy 157.925241 -385.427629) (xy 157.910875 -385.381828)
			(xy 157.90361 -385.33438) (xy 157.903164 -385.31038) (xy 157.903599 -385.285601) (xy 157.911351 -385.236653)
			(xy 157.926661 -385.189519) (xy 157.949152 -385.145358) (xy 157.978272 -385.105258) (xy 158.013304 -385.070203)
			(xy 158.053386 -385.041058) (xy 158.097532 -385.018538) (xy 158.144656 -385.003198) (xy 158.193599 -384.995415)
			(xy 158.218378 -384.994912) (xy 158.218886 -384.994912) (xy 158.244281 -384.995408) (xy 158.294416 -385.003537)
			(xy 158.342602 -385.019588) (xy 158.387598 -385.043146) (xy 158.428241 -385.073605) (xy 158.463483 -385.110177)
			(xy 158.492416 -385.15192) (xy 158.514293 -385.197757) (xy 158.521908 -385.221988) (xy 158.523432 -385.22783)
			(xy 158.571476 -385.310888) (xy 159.103568 -385.310888) (xy 159.103568 -385.31038) (xy 159.103975 -385.285586)
			(xy 159.111735 -385.236609) (xy 159.127062 -385.189449) (xy 159.149578 -385.145268) (xy 159.178729 -385.105153)
			(xy 159.213796 -385.070092) (xy 159.253916 -385.040949) (xy 159.298101 -385.018441) (xy 159.345264 -385.003122)
			(xy 159.394242 -384.99537) (xy 159.419036 -384.994912) (xy 159.444432 -384.995364) (xy 159.494569 -385.003501)
			(xy 159.542757 -385.019559) (xy 159.587752 -385.043124) (xy 159.628395 -385.073588) (xy 159.663637 -385.110166)
			(xy 159.692568 -385.151914) (xy 159.714443 -385.197755) (xy 159.722058 -385.221988) (xy 159.723582 -385.22783)
			(xy 159.771626 -385.310888) (xy 160.303464 -385.310888) (xy 160.303464 -385.31038) (xy 160.303875 -385.285586)
			(xy 160.311635 -385.23661) (xy 160.326962 -385.18945) (xy 160.349478 -385.145269) (xy 160.378627 -385.105154)
			(xy 160.413694 -385.070094) (xy 160.453814 -385.04095) (xy 160.497998 -385.018442) (xy 160.54516 -385.003123)
			(xy 160.594138 -384.995371) (xy 160.618932 -384.994912) (xy 160.644328 -384.995367) (xy 160.694465 -385.003503)
			(xy 160.742652 -385.019561) (xy 160.787648 -385.043126) (xy 160.828291 -385.07359) (xy 160.863532 -385.110167)
			(xy 160.892464 -385.151914) (xy 160.914339 -385.197755) (xy 160.921954 -385.221988) (xy 160.923478 -385.22783)
			(xy 160.971228 -385.31038) (xy 161.50336 -385.31038) (xy 161.503799 -385.285601) (xy 161.51155 -385.236653)
			(xy 161.52686 -385.18952) (xy 161.549352 -385.145359) (xy 161.578471 -385.105259) (xy 161.613502 -385.070205)
			(xy 161.653583 -385.041059) (xy 161.697729 -385.018539) (xy 161.744853 -385.003199) (xy 161.793795 -384.995415)
			(xy 161.818574 -384.994912) (xy 161.819082 -384.994912) (xy 161.844531 -384.995357) (xy 161.894772 -385.003519)
			(xy 161.943052 -385.019635) (xy 161.988122 -385.043286) (xy 162.028814 -385.073862) (xy 162.064074 -385.110569)
			(xy 162.09299 -385.152457) (xy 162.114811 -385.19844) (xy 162.122358 -385.22275) (xy 162.123882 -385.228592)
			(xy 162.171182 -385.31038) (xy 162.703256 -385.31038) (xy 162.703699 -385.285601) (xy 162.71145 -385.236654)
			(xy 162.72676 -385.189521) (xy 162.749251 -385.145361) (xy 162.77837 -385.10526) (xy 162.8134 -385.070206)
			(xy 162.853481 -385.041061) (xy 162.897626 -385.01854) (xy 162.944749 -385.003199) (xy 162.993692 -384.995415)
			(xy 163.01847 -384.994912) (xy 163.018978 -384.994912) (xy 163.044373 -384.995415) (xy 163.094507 -385.003543)
			(xy 163.142694 -385.019592) (xy 163.187689 -385.04315) (xy 163.228332 -385.073607) (xy 163.263575 -385.110179)
			(xy 163.292508 -385.151921) (xy 163.314385 -385.197757) (xy 163.322 -385.221988) (xy 163.323524 -385.22783)
			(xy 163.371274 -385.31038) (xy 163.90366 -385.31038) (xy 163.904075 -385.285586) (xy 163.911835 -385.23661)
			(xy 163.927162 -385.189451) (xy 163.949677 -385.14527) (xy 163.978826 -385.105156) (xy 164.013892 -385.070095)
			(xy 164.054011 -385.040952) (xy 164.098196 -385.018443) (xy 164.145357 -385.003124) (xy 164.194334 -384.995371)
			(xy 164.219128 -384.994912) (xy 164.244576 -384.995404) (xy 164.294814 -385.003558) (xy 164.343093 -385.019666)
			(xy 164.388163 -385.04331) (xy 164.428855 -385.073879) (xy 164.464117 -385.11058) (xy 164.493034 -385.152463)
			(xy 164.514857 -385.198442) (xy 164.522404 -385.22275) (xy 164.523928 -385.228592) (xy 164.571521 -385.310888)
			(xy 165.103556 -385.310888) (xy 165.103556 -385.31038) (xy 165.103975 -385.285587) (xy 165.111735 -385.236611)
			(xy 165.127061 -385.189452) (xy 165.149576 -385.145272) (xy 165.178725 -385.105157) (xy 165.213791 -385.070097)
			(xy 165.253909 -385.040953) (xy 165.298093 -385.018444) (xy 165.345254 -385.003125) (xy 165.394231 -384.995371)
			(xy 165.419024 -384.994912) (xy 165.44442 -384.995374) (xy 165.494556 -385.003509) (xy 165.542744 -385.019566)
			(xy 165.587739 -385.043129) (xy 165.628382 -385.073592) (xy 165.663624 -385.110169) (xy 165.692556 -385.151915)
			(xy 165.714431 -385.197755) (xy 165.722046 -385.221988) (xy 165.72357 -385.22783) (xy 166.043864 -385.78155)
			(xy 166.047928 -385.785868) (xy 166.064131 -385.803543) (xy 166.09153 -385.842892) (xy 166.112661 -385.885932)
			(xy 166.127038 -385.931674) (xy 166.13433 -385.979064) (xy 166.134796 -386.003038) (xy 166.134796 -386.003546)
			(xy 166.134034 -386.023612) (xy 166.133868 -386.03366) (xy 166.140395 -386.052647) (xy 166.146734 -386.060442)
			(xy 166.201344 -386.122164) (xy 166.219378 -386.131054) (xy 166.229538 -386.131562) (xy 166.254918 -386.13351)
			(xy 166.304625 -386.144466) (xy 166.351954 -386.163195) (xy 166.395697 -386.189222) (xy 166.434738 -386.221881)
			(xy 166.451788 -386.240782) (xy 166.454246 -386.243558) (xy 166.459862 -386.248402) (xy 166.462964 -386.250434)
			(xy 166.47504 -386.258475) (xy 166.494995 -386.279525) (xy 166.509065 -386.304888) (xy 166.516362 -386.33296)
			(xy 166.516812 -386.347462) (xy 166.516812 -386.3594) (xy 166.518336 -386.366004) (xy 166.523528 -386.386376)
			(xy 166.529138 -386.428042) (xy 166.529512 -386.449062) (xy 166.52913 -386.470082) (xy 166.52353 -386.511748)
			(xy 166.518336 -386.53212) (xy 166.516812 -386.538724) (xy 166.516812 -386.652262) (xy 166.516333 -386.66726)
			(xy 166.508587 -386.696237) (xy 166.493611 -386.722226) (xy 166.472425 -386.743458) (xy 166.446469 -386.758491)
			(xy 166.417508 -386.7663) (xy 166.402512 -386.766816) (xy 166.220394 -386.766816) (xy 166.219886 -386.76707)
			(xy 166.203122 -386.76707) (xy 166.202614 -386.766816) (xy 166.021004 -386.766816) (xy 166.005976 -386.766317)
			(xy 165.97694 -386.758549) (xy 165.950899 -386.743542) (xy 165.929621 -386.722313) (xy 165.914553 -386.696307)
			(xy 165.906718 -386.667289) (xy 165.906196 -386.652262) (xy 165.906196 -386.538724) (xy 165.904672 -386.53212)
			(xy 165.899466 -386.511751) (xy 165.893865 -386.470083) (xy 165.893496 -386.449062) (xy 165.894258 -386.42671)
			(xy 165.89502 -386.41655) (xy 165.88867 -386.3975) (xy 165.827456 -386.32765) (xy 165.809422 -386.31876)
			(xy 165.799262 -386.318252) (xy 165.775177 -386.316277) (xy 165.727972 -386.305949) (xy 165.682894 -386.288543)
			(xy 165.640998 -386.264465) (xy 165.603265 -386.234279) (xy 165.570576 -386.198692) (xy 165.543697 -386.158536)
			(xy 165.523257 -386.11475) (xy 165.516052 -386.091684) (xy 165.514528 -386.085842) (xy 165.194234 -385.532122)
			(xy 165.19017 -385.527804) (xy 165.174021 -385.510129) (xy 165.1467 -385.470814) (xy 165.12563 -385.427824)
			(xy 165.111294 -385.382145) (xy 165.104021 -385.334825) (xy 165.103556 -385.310888) (xy 164.571521 -385.310888)
			(xy 164.843714 -385.78155) (xy 164.847778 -385.785868) (xy 164.863938 -385.803567) (xy 164.89128 -385.842928)
			(xy 164.912359 -385.885969) (xy 164.926689 -385.931702) (xy 164.933942 -385.979075) (xy 164.934392 -386.003038)
			(xy 164.934392 -386.003546) (xy 164.933884 -386.023866) (xy 164.933122 -386.033772) (xy 164.939472 -386.052822)
			(xy 165.000178 -386.122164) (xy 165.017958 -386.131054) (xy 165.028118 -386.131816) (xy 165.053098 -386.133983)
			(xy 165.101956 -386.145244) (xy 165.148443 -386.16403) (xy 165.191407 -386.189878) (xy 165.229783 -386.222145)
			(xy 165.246558 -386.240782) (xy 165.24902 -386.243555) (xy 165.254633 -386.248401) (xy 165.257734 -386.250434)
			(xy 165.269775 -386.258496) (xy 165.289664 -386.279562) (xy 165.303668 -386.304924) (xy 165.310904 -386.332977)
			(xy 165.311328 -386.347462) (xy 165.311328 -386.3594) (xy 165.313106 -386.366004) (xy 165.318297 -386.386377)
			(xy 165.323908 -386.428042) (xy 165.324282 -386.449062) (xy 165.323901 -386.470082) (xy 165.3183 -386.511749)
			(xy 165.313106 -386.53212) (xy 165.311328 -386.538724) (xy 165.311328 -386.652262) (xy 165.310874 -386.667285)
			(xy 165.303105 -386.696309) (xy 165.288086 -386.722332) (xy 165.266841 -386.743578) (xy 165.24082 -386.7586)
			(xy 165.211797 -386.766373) (xy 165.196774 -386.766816) (xy 165.015164 -386.766816) (xy 165.014656 -386.76707)
			(xy 164.997892 -386.76707) (xy 164.997384 -386.766816) (xy 164.815774 -386.766816) (xy 164.800747 -386.76643)
			(xy 164.771719 -386.758644) (xy 164.745696 -386.743611) (xy 164.72445 -386.722353) (xy 164.709431 -386.696321)
			(xy 164.701662 -386.667289) (xy 164.70122 -386.652262) (xy 164.70122 -386.538724) (xy 164.699442 -386.53212)
			(xy 164.694235 -386.511751) (xy 164.688635 -386.470083) (xy 164.688266 -386.449062) (xy 164.689028 -386.426456)
			(xy 164.68979 -386.41655) (xy 164.68344 -386.397246) (xy 164.623242 -386.327904) (xy 164.605208 -386.31876)
			(xy 164.595302 -386.317998) (xy 164.571475 -386.315801) (xy 164.524846 -386.305073) (xy 164.48037 -386.287427)
			(xy 164.43907 -386.263268) (xy 164.40189 -386.233149) (xy 164.369686 -386.197761) (xy 164.343194 -386.157916)
			(xy 164.323022 -386.114528) (xy 164.315902 -386.091684) (xy 164.314378 -386.085842) (xy 163.99383 -385.53136)
			(xy 163.989766 -385.527042) (xy 163.973692 -385.509359) (xy 163.9465 -385.470067) (xy 163.925543 -385.427123)
			(xy 163.9113 -385.381511) (xy 163.904098 -385.334272) (xy 163.90366 -385.31038) (xy 163.371274 -385.31038)
			(xy 163.643818 -385.78155) (xy 163.647882 -385.785868) (xy 163.664043 -385.803567) (xy 163.691384 -385.842928)
			(xy 163.712463 -385.885969) (xy 163.726793 -385.931702) (xy 163.734046 -385.979075) (xy 163.734496 -386.003038)
			(xy 163.734496 -386.003546) (xy 163.733988 -386.023866) (xy 163.733226 -386.033772) (xy 163.739576 -386.052822)
			(xy 163.800282 -386.122164) (xy 163.818062 -386.131054) (xy 163.828222 -386.131816) (xy 163.853202 -386.133981)
			(xy 163.902061 -386.145242) (xy 163.948548 -386.164029) (xy 163.991511 -386.189877) (xy 164.029887 -386.222145)
			(xy 164.046662 -386.240782) (xy 164.049123 -386.243556) (xy 164.054736 -386.248401) (xy 164.057838 -386.250434)
			(xy 164.06988 -386.258495) (xy 164.089768 -386.279562) (xy 164.103772 -386.304923) (xy 164.111008 -386.332977)
			(xy 164.111432 -386.347462) (xy 164.111432 -386.3594) (xy 164.11321 -386.366004) (xy 164.118401 -386.386377)
			(xy 164.124012 -386.428042) (xy 164.124386 -386.449062) (xy 164.124005 -386.470082) (xy 164.118404 -386.511749)
			(xy 164.11321 -386.53212) (xy 164.111432 -386.538724) (xy 164.111432 -386.652262) (xy 164.110975 -386.667285)
			(xy 164.103205 -386.696308) (xy 164.088187 -386.72233) (xy 164.066943 -386.743577) (xy 164.040923 -386.758599)
			(xy 164.011901 -386.766372) (xy 163.996878 -386.766816) (xy 163.815268 -386.766816) (xy 163.81476 -386.76707)
			(xy 163.797996 -386.76707) (xy 163.797488 -386.766816) (xy 163.615878 -386.766816) (xy 163.600851 -386.766427)
			(xy 163.571823 -386.758642) (xy 163.5458 -386.743609) (xy 163.524554 -386.722352) (xy 163.509535 -386.696321)
			(xy 163.501766 -386.667289) (xy 163.501324 -386.652262) (xy 163.501324 -386.538724) (xy 163.499546 -386.53212)
			(xy 163.494339 -386.511751) (xy 163.488739 -386.470083) (xy 163.48837 -386.449062) (xy 163.489132 -386.426456)
			(xy 163.489894 -386.41655) (xy 163.483544 -386.397246) (xy 163.423346 -386.327904) (xy 163.405312 -386.31876)
			(xy 163.395406 -386.317998) (xy 163.37158 -386.315798) (xy 163.32495 -386.305071) (xy 163.280475 -386.287425)
			(xy 163.239174 -386.263266) (xy 163.201995 -386.233148) (xy 163.16979 -386.19776) (xy 163.143298 -386.157916)
			(xy 163.123126 -386.114528) (xy 163.116006 -386.091684) (xy 163.114482 -386.085842) (xy 162.794188 -385.532122)
			(xy 162.790124 -385.527804) (xy 162.7739 -385.510113) (xy 162.746478 -385.470718) (xy 162.725338 -385.427624)
			(xy 162.710969 -385.381826) (xy 162.703703 -385.33438) (xy 162.703256 -385.31038) (xy 162.171182 -385.31038)
			(xy 162.443668 -385.78155) (xy 162.447732 -385.785868) (xy 162.463936 -385.803542) (xy 162.491334 -385.842891)
			(xy 162.512465 -385.885932) (xy 162.526842 -385.931674) (xy 162.534134 -385.979064) (xy 162.5346 -386.003038)
			(xy 162.5346 -386.003546) (xy 162.533838 -386.023866) (xy 162.533076 -386.033772) (xy 162.539426 -386.052822)
			(xy 162.600132 -386.122164) (xy 162.617912 -386.131054) (xy 162.628072 -386.131816) (xy 162.653049 -386.134011)
			(xy 162.701907 -386.145265) (xy 162.748394 -386.164044) (xy 162.791358 -386.189886) (xy 162.829736 -386.222148)
			(xy 162.846512 -386.240782) (xy 162.84898 -386.24355) (xy 162.854588 -386.248399) (xy 162.857688 -386.250434)
			(xy 162.869769 -386.258468) (xy 162.889722 -386.279521) (xy 162.903791 -386.304886) (xy 162.911086 -386.33296)
			(xy 162.911536 -386.347462) (xy 162.911536 -386.3594) (xy 162.91306 -386.366004) (xy 162.918252 -386.386376)
			(xy 162.923862 -386.428042) (xy 162.924236 -386.449062) (xy 162.923853 -386.470082) (xy 162.918254 -386.511748)
			(xy 162.91306 -386.53212) (xy 162.911536 -386.538724) (xy 162.911536 -386.652262) (xy 162.911033 -386.667258)
			(xy 162.903289 -386.696231) (xy 162.888317 -386.722218) (xy 162.867136 -386.74345) (xy 162.841186 -386.758484)
			(xy 162.81223 -386.766297) (xy 162.797236 -386.766816) (xy 162.615118 -386.766816) (xy 162.61461 -386.76707)
			(xy 162.597846 -386.76707) (xy 162.597338 -386.766816) (xy 162.415728 -386.766816) (xy 162.400701 -386.766295)
			(xy 162.371666 -386.758534) (xy 162.345625 -386.743531) (xy 162.324347 -386.722306) (xy 162.309278 -386.696303)
			(xy 162.301443 -386.667288) (xy 162.30092 -386.652262) (xy 162.30092 -386.538724) (xy 162.299396 -386.53212)
			(xy 162.29419 -386.511751) (xy 162.288589 -386.470083) (xy 162.28822 -386.449062) (xy 162.288982 -386.426456)
			(xy 162.289744 -386.41655) (xy 162.283394 -386.397246) (xy 162.223196 -386.327904) (xy 162.205162 -386.31876)
			(xy 162.195256 -386.317998) (xy 162.171434 -386.315758) (xy 162.124806 -386.305038) (xy 162.080331 -386.287399)
			(xy 162.039029 -386.263246) (xy 162.001849 -386.233133) (xy 161.969643 -386.197751) (xy 161.94315 -386.157911)
			(xy 161.922976 -386.114527) (xy 161.915856 -386.091684) (xy 161.914332 -386.085842) (xy 161.593784 -385.53136)
			(xy 161.58972 -385.527042) (xy 161.573604 -385.509384) (xy 161.546355 -385.470103) (xy 161.525345 -385.42716)
			(xy 161.511056 -385.381538) (xy 161.503815 -385.334283) (xy 161.50336 -385.31038) (xy 160.971228 -385.31038)
			(xy 161.243772 -385.78155) (xy 161.247836 -385.785868) (xy 161.264041 -385.803542) (xy 161.291439 -385.842891)
			(xy 161.312569 -385.885932) (xy 161.326946 -385.931674) (xy 161.334238 -385.979064) (xy 161.334704 -386.003038)
			(xy 161.334704 -386.003546) (xy 161.333942 -386.023866) (xy 161.33318 -386.033772) (xy 161.33953 -386.052822)
			(xy 161.400236 -386.122164) (xy 161.418016 -386.131054) (xy 161.428176 -386.131816) (xy 161.453153 -386.134009)
			(xy 161.502011 -386.145263) (xy 161.548498 -386.164043) (xy 161.591463 -386.189885) (xy 161.62984 -386.222148)
			(xy 161.646616 -386.240782) (xy 161.649083 -386.24355) (xy 161.654692 -386.248399) (xy 161.657792 -386.250434)
			(xy 161.669874 -386.258467) (xy 161.689826 -386.27952) (xy 161.703895 -386.304886) (xy 161.71119 -386.33296)
			(xy 161.71164 -386.347462) (xy 161.71164 -386.3594) (xy 161.713164 -386.366004) (xy 161.718356 -386.386376)
			(xy 161.723966 -386.428042) (xy 161.72434 -386.449062) (xy 161.723957 -386.470082) (xy 161.718358 -386.511748)
			(xy 161.713164 -386.53212) (xy 161.71164 -386.538724) (xy 161.71164 -386.652262) (xy 161.711133 -386.667257)
			(xy 161.70339 -386.69623) (xy 161.688418 -386.722216) (xy 161.667238 -386.743448) (xy 161.641288 -386.758483)
			(xy 161.612334 -386.766297) (xy 161.59734 -386.766816) (xy 161.415222 -386.766816) (xy 161.414714 -386.76707)
			(xy 161.39795 -386.76707) (xy 161.397442 -386.766816) (xy 161.215832 -386.766816) (xy 161.200805 -386.766292)
			(xy 161.171771 -386.758531) (xy 161.145729 -386.743529) (xy 161.124451 -386.722305) (xy 161.109382 -386.696302)
			(xy 161.101547 -386.667288) (xy 161.101024 -386.652262) (xy 161.101024 -386.538724) (xy 161.0995 -386.53212)
			(xy 161.094294 -386.511751) (xy 161.088693 -386.470083) (xy 161.088324 -386.449062) (xy 161.089086 -386.426456)
			(xy 161.089848 -386.41655) (xy 161.083498 -386.397246) (xy 161.0233 -386.327904) (xy 161.005266 -386.31876)
			(xy 160.99536 -386.317998) (xy 160.971538 -386.315755) (xy 160.92491 -386.305035) (xy 160.880435 -386.287397)
			(xy 160.839134 -386.263245) (xy 160.801954 -386.233132) (xy 160.769748 -386.19775) (xy 160.743254 -386.15791)
			(xy 160.723081 -386.114526) (xy 160.71596 -386.091684) (xy 160.714436 -386.085842) (xy 160.394142 -385.532122)
			(xy 160.390078 -385.527804) (xy 160.37393 -385.510128) (xy 160.346609 -385.470813) (xy 160.325539 -385.427824)
			(xy 160.311202 -385.382145) (xy 160.303929 -385.334825) (xy 160.303464 -385.310888) (xy 159.771626 -385.310888)
			(xy 160.043876 -385.78155) (xy 160.04794 -385.785868) (xy 160.064145 -385.803541) (xy 160.091543 -385.842891)
			(xy 160.112673 -385.885932) (xy 160.12705 -385.931674) (xy 160.134342 -385.979064) (xy 160.134808 -386.003038)
			(xy 160.134808 -386.003546) (xy 160.134046 -386.023866) (xy 160.133284 -386.033772) (xy 160.139634 -386.052822)
			(xy 160.20034 -386.122164) (xy 160.21812 -386.131054) (xy 160.22828 -386.131816) (xy 160.253228 -386.134046)
			(xy 160.302028 -386.145323) (xy 160.348458 -386.164108) (xy 160.391371 -386.189935) (xy 160.429706 -386.222168)
			(xy 160.446466 -386.240782) (xy 160.448927 -386.243556) (xy 160.45454 -386.248402) (xy 160.457642 -386.250434)
			(xy 160.469685 -386.258494) (xy 160.489573 -386.279561) (xy 160.503577 -386.304923) (xy 160.510812 -386.332976)
			(xy 160.511236 -386.347462) (xy 160.511236 -386.3594) (xy 160.513014 -386.366004) (xy 160.518205 -386.386377)
			(xy 160.523816 -386.428042) (xy 160.52419 -386.449062) (xy 160.523809 -386.470082) (xy 160.518208 -386.511748)
			(xy 160.513014 -386.53212) (xy 160.511236 -386.538724) (xy 160.511236 -386.652262) (xy 160.510593 -386.670383)
			(xy 160.499328 -386.704828) (xy 160.489138 -386.719826) (xy 160.484652 -386.726489) (xy 160.479729 -386.741769)
			(xy 160.479486 -386.749798) (xy 160.479486 -386.783326) (xy 160.479799 -386.791344) (xy 160.484707 -386.806609)
			(xy 160.489138 -386.813298) (xy 160.499233 -386.828343) (xy 160.510483 -386.86276) (xy 160.511236 -386.880862)
			(xy 160.511236 -386.9944) (xy 160.513014 -387.001004) (xy 160.518205 -387.021377) (xy 160.523816 -387.063042)
			(xy 160.52419 -387.084062) (xy 160.523809 -387.105082) (xy 160.518208 -387.146748) (xy 160.513014 -387.16712)
			(xy 160.511236 -387.173724) (xy 160.511236 -387.185662) (xy 160.510745 -387.201032) (xy 160.502616 -387.230678)
			(xy 160.486929 -387.257114) (xy 160.464803 -387.278453) (xy 160.451546 -387.286246) (xy 160.447736 -387.290818)
			(xy 160.440428 -387.300286) (xy 160.434742 -387.323487) (xy 160.436814 -387.335268) (xy 160.443926 -387.367018)
			(xy 160.447231 -387.378519) (xy 160.462452 -387.396938) (xy 160.473136 -387.402324) (xy 160.494559 -387.41207)
			(xy 160.534512 -387.436943) (xy 160.570363 -387.467433) (xy 160.586166 -387.484874) (xy 160.588628 -387.487647)
			(xy 160.594241 -387.492493) (xy 160.597342 -387.494526) (xy 160.609486 -387.502608) (xy 160.629576 -387.523746)
			(xy 160.643723 -387.549247) (xy 160.651022 -387.577481) (xy 160.651444 -387.592062) (xy 160.651444 -387.604508)
			(xy 160.653222 -387.610858) (xy 160.658355 -387.631172) (xy 160.66383 -387.672712) (xy 160.664144 -387.693662)
			(xy 160.66381 -387.714611) (xy 160.658334 -387.756148) (xy 160.653222 -387.776466) (xy 160.651444 -387.782816)
			(xy 160.651444 -388.239508) (xy 160.653222 -388.245858) (xy 160.658355 -388.266172) (xy 160.66383 -388.307712)
			(xy 160.664144 -388.328662) (xy 161.228278 -388.328662) (xy 161.228645 -388.307641) (xy 161.234255 -388.265975)
			(xy 161.239454 -388.245604) (xy 161.241232 -388.239) (xy 161.241232 -388.125462) (xy 161.241702 -388.110445)
			(xy 161.249484 -388.081435) (xy 161.264506 -388.055427) (xy 161.285746 -388.034191) (xy 161.311757 -388.019174)
			(xy 161.340769 -388.011399) (xy 161.355786 -388.010908) (xy 161.537396 -388.010908) (xy 161.537904 -388.010654)
			(xy 161.554668 -388.010654) (xy 161.555176 -388.010908) (xy 161.736786 -388.010908) (xy 161.751799 -388.011448)
			(xy 161.780803 -388.019215) (xy 161.806809 -388.034223) (xy 161.828045 -388.055449) (xy 161.843065 -388.081449)
			(xy 161.850845 -388.110449) (xy 161.85134 -388.125462) (xy 161.85134 -388.239) (xy 161.853118 -388.245604)
			(xy 161.858309 -388.265977) (xy 161.86392 -388.307642) (xy 161.864294 -388.328662) (xy 162.428174 -388.328662)
			(xy 162.428541 -388.307641) (xy 162.434151 -388.265975) (xy 162.43935 -388.245604) (xy 162.441128 -388.239)
			(xy 162.441128 -388.125462) (xy 162.441602 -388.110445) (xy 162.449383 -388.081436) (xy 162.464405 -388.055428)
			(xy 162.485644 -388.034192) (xy 162.511655 -388.019175) (xy 162.540665 -388.0114) (xy 162.555682 -388.010908)
			(xy 162.737292 -388.010908) (xy 162.7378 -388.010654) (xy 162.754564 -388.010654) (xy 162.755072 -388.010908)
			(xy 162.936682 -388.010908) (xy 162.951695 -388.011452) (xy 162.980699 -388.019217) (xy 163.006705 -388.034224)
			(xy 163.027941 -388.055451) (xy 163.042961 -388.081449) (xy 163.050741 -388.110449) (xy 163.051236 -388.125462)
			(xy 163.051236 -388.239) (xy 163.053014 -388.245604) (xy 163.058205 -388.265977) (xy 163.063816 -388.307642)
			(xy 163.06419 -388.328662) (xy 163.628324 -388.328662) (xy 163.62869 -388.307641) (xy 163.634301 -388.265975)
			(xy 163.6395 -388.245604) (xy 163.641024 -388.239) (xy 163.641024 -388.125462) (xy 163.641499 -388.110466)
			(xy 163.649258 -388.081496) (xy 163.664239 -388.055514) (xy 163.685424 -388.034284) (xy 163.711375 -388.01925)
			(xy 163.740329 -388.011431) (xy 163.755324 -388.010908) (xy 163.937442 -388.010908) (xy 163.93795 -388.010654)
			(xy 163.954714 -388.010654) (xy 163.955222 -388.010908) (xy 164.136832 -388.010908) (xy 164.151864 -388.011352)
			(xy 164.180904 -388.01913) (xy 164.206948 -388.034149) (xy 164.228225 -388.055388) (xy 164.243291 -388.081405)
			(xy 164.251121 -388.110431) (xy 164.25164 -388.125462) (xy 164.25164 -388.239) (xy 164.253164 -388.245604)
			(xy 164.258356 -388.265976) (xy 164.263966 -388.307642) (xy 164.26434 -388.328662) (xy 164.82822 -388.328662)
			(xy 164.828586 -388.307641) (xy 164.834197 -388.265975) (xy 164.839396 -388.245604) (xy 164.84092 -388.239)
			(xy 164.84092 -388.125462) (xy 164.841399 -388.110467) (xy 164.849158 -388.081497) (xy 164.864138 -388.055515)
			(xy 164.885322 -388.034286) (xy 164.911272 -388.019251) (xy 164.940226 -388.011431) (xy 164.95522 -388.010908)
			(xy 165.137338 -388.010908) (xy 165.137846 -388.010654) (xy 165.15461 -388.010654) (xy 165.155118 -388.010908)
			(xy 165.336728 -388.010908) (xy 165.35176 -388.011356) (xy 165.3808 -388.019133) (xy 165.406844 -388.034151)
			(xy 165.428121 -388.055389) (xy 165.443187 -388.081405) (xy 165.451017 -388.110431) (xy 165.451536 -388.125462)
			(xy 165.451536 -388.239) (xy 165.45306 -388.245604) (xy 165.458252 -388.265976) (xy 165.463862 -388.307642)
			(xy 165.464236 -388.328662) (xy 165.464236 -388.32917) (xy 165.464067 -388.343795) (xy 165.461399 -388.372924)
			(xy 165.458902 -388.387336) (xy 165.457539 -388.39651) (xy 165.460811 -388.414752) (xy 165.465252 -388.422896)
			(xy 165.481762 -388.44982) (xy 165.486925 -388.457603) (xy 165.501656 -388.469063) (xy 165.510464 -388.472172)
			(xy 165.535337 -388.48026) (xy 165.582217 -388.503443) (xy 165.624631 -388.534041) (xy 165.661416 -388.571217)
			(xy 165.691565 -388.613952) (xy 165.714251 -388.661074) (xy 165.722046 -388.68604) (xy 165.72357 -388.691882)
			(xy 166.043864 -389.245602) (xy 166.047928 -389.24992) (xy 166.064124 -389.267634) (xy 166.091549 -389.307024)
			(xy 166.112692 -389.350112) (xy 166.127068 -389.395905) (xy 166.134344 -389.443346) (xy 166.134796 -389.467344)
			(xy 166.134324 -389.492121) (xy 166.12657 -389.541064) (xy 166.11126 -389.588193) (xy 166.088771 -389.63235)
			(xy 166.059655 -389.672447) (xy 166.024629 -389.7075) (xy 165.984553 -389.736646) (xy 165.940414 -389.759169)
			(xy 165.893296 -389.774514) (xy 165.844358 -389.782305) (xy 165.819582 -389.782812) (xy 165.819074 -389.782812)
			(xy 165.793679 -389.782334) (xy 165.743544 -389.7742) (xy 165.695358 -389.758145) (xy 165.650364 -389.734583)
			(xy 165.609721 -389.704122) (xy 165.574479 -389.667548) (xy 165.545546 -389.625805) (xy 165.523668 -389.579967)
			(xy 165.516052 -389.555736) (xy 165.514528 -389.549894) (xy 165.194234 -388.996174) (xy 165.19017 -388.991856)
			(xy 165.174013 -388.97412) (xy 165.146644 -388.934719) (xy 165.125553 -388.891629) (xy 165.111225 -388.845845)
			(xy 165.10399 -388.798419) (xy 165.103556 -388.774432) (xy 165.103737 -388.760384) (xy 165.106278 -388.732402)
			(xy 165.108636 -388.718552) (xy 165.109953 -388.709272) (xy 165.106428 -388.690876) (xy 165.101778 -388.682738)
			(xy 165.085014 -388.655814) (xy 165.079813 -388.64811) (xy 165.065087 -388.636787) (xy 165.056312 -388.633716)
			(xy 165.034681 -388.626931) (xy 164.993467 -388.608044) (xy 164.955349 -388.583504) (xy 164.921094 -388.553807)
			(xy 164.905944 -388.536942) (xy 164.903479 -388.534172) (xy 164.897868 -388.529324) (xy 164.894768 -388.52729)
			(xy 164.88271 -388.519224) (xy 164.862752 -388.498184) (xy 164.848676 -388.472828) (xy 164.841374 -388.444761)
			(xy 164.84092 -388.430262) (xy 164.84092 -388.418324) (xy 164.839396 -388.41172) (xy 164.83419 -388.391351)
			(xy 164.828589 -388.349683) (xy 164.82822 -388.328662) (xy 164.26434 -388.328662) (xy 164.26434 -388.32917)
			(xy 164.26417 -388.343795) (xy 164.261503 -388.372924) (xy 164.259006 -388.387336) (xy 164.257642 -388.39651)
			(xy 164.260915 -388.414752) (xy 164.265356 -388.422896) (xy 164.281866 -388.44982) (xy 164.287028 -388.457604)
			(xy 164.301759 -388.469063) (xy 164.310568 -388.472172) (xy 164.3355 -388.480283) (xy 164.382465 -388.503582)
			(xy 164.424943 -388.534309) (xy 164.461771 -388.571623) (xy 164.491939 -388.614499) (xy 164.514622 -388.661765)
			(xy 164.522404 -388.686802) (xy 164.523928 -388.692644) (xy 164.843714 -389.245602) (xy 164.847778 -389.24992)
			(xy 164.863947 -389.267578) (xy 164.891263 -389.306899) (xy 164.912328 -389.349893) (xy 164.92666 -389.395575)
			(xy 164.933929 -389.442898) (xy 164.934392 -389.466836) (xy 164.934392 -389.467344) (xy 164.933874 -389.492792)
			(xy 164.925704 -389.543027) (xy 164.909583 -389.591301) (xy 164.885928 -389.636365) (xy 164.855352 -389.677052)
			(xy 164.818646 -389.712308) (xy 164.797994 -389.727186) (xy 164.78949 -389.73366) (xy 164.778299 -389.75184)
			(xy 164.775462 -389.773) (xy 164.781469 -389.793486) (xy 164.795282 -389.809763) (xy 164.814519 -389.819022)
			(xy 164.825172 -389.819896) (xy 164.834824 -389.819388) (xy 164.843338 -389.818093) (xy 164.860503 -389.816695)
			(xy 164.869114 -389.816594) (xy 164.869368 -389.816848) (xy 165.16858 -389.816848) (xy 165.168834 -389.816594)
			(xy 165.18988 -389.817002) (xy 165.2312 -389.824998) (xy 165.270155 -389.840928) (xy 165.305237 -389.864178)
			(xy 165.335088 -389.893846) (xy 165.358553 -389.928784) (xy 165.374723 -389.967641) (xy 165.382972 -390.008911)
			(xy 165.383464 -390.029954) (xy 165.383464 -390.233916) (xy 166.008304 -390.233916) (xy 166.008304 -390.029954)
			(xy 166.008873 -390.008896) (xy 166.017116 -389.967594) (xy 166.033294 -389.928708) (xy 166.056779 -389.893747)
			(xy 166.086659 -389.864067) (xy 166.121777 -389.840818) (xy 166.160771 -389.824902) (xy 166.202127 -389.816936)
			(xy 166.223188 -389.816594) (xy 166.223442 -389.816848) (xy 166.522654 -389.816848) (xy 166.522908 -389.816594)
			(xy 166.543971 -389.816955) (xy 166.585332 -389.824918) (xy 166.624331 -389.840831) (xy 166.659456 -389.864075)
			(xy 166.689347 -389.893751) (xy 166.712844 -389.928709) (xy 166.729037 -389.967592) (xy 166.737298 -390.008894)
			(xy 166.737792 -390.029954) (xy 166.737792 -390.284716) (xy 166.728648 -390.284716) (xy 166.718628 -390.285159)
			(xy 166.700109 -390.292816) (xy 166.685934 -390.306982) (xy 166.678265 -390.325496) (xy 166.677848 -390.335516)
			(xy 166.677848 -390.499092) (xy 166.677307 -390.509093) (xy 166.669659 -390.527576) (xy 166.655523 -390.541727)
			(xy 166.637049 -390.549396) (xy 166.627048 -390.549892) (xy 166.119048 -390.549892) (xy 166.109029 -390.549441)
			(xy 166.090511 -390.541785) (xy 166.076337 -390.527622) (xy 166.068667 -390.509111) (xy 166.068248 -390.499092)
			(xy 166.068248 -390.284716) (xy 166.059104 -390.284716) (xy 166.049099 -390.284209) (xy 166.03061 -390.276554)
			(xy 166.016457 -390.262407) (xy 166.008795 -390.243921) (xy 166.008304 -390.233916) (xy 165.383464 -390.233916)
			(xy 165.383464 -390.284716) (xy 165.37432 -390.284716) (xy 165.364298 -390.285137) (xy 165.345779 -390.292803)
			(xy 165.331605 -390.306975) (xy 165.323937 -390.325494) (xy 165.32352 -390.335516) (xy 165.32352 -390.499092)
			(xy 165.323006 -390.509097) (xy 165.315353 -390.527584) (xy 165.301208 -390.541737) (xy 165.282724 -390.5494)
			(xy 165.27272 -390.549892) (xy 164.765228 -390.549892) (xy 164.755208 -390.549457) (xy 164.73669 -390.541795)
			(xy 164.722516 -390.527627) (xy 164.714847 -390.509112) (xy 164.714428 -390.499092) (xy 164.714428 -390.335516)
			(xy 164.7139 -390.325513) (xy 164.706251 -390.307027) (xy 164.69211 -390.292874) (xy 164.673631 -390.285209)
			(xy 164.663628 -390.284716) (xy 164.654484 -390.284716) (xy 164.654484 -390.029446) (xy 164.655272 -390.003724)
			(xy 164.667603 -389.953778) (xy 164.678868 -389.93064) (xy 164.68471 -389.91921) (xy 164.684456 -389.89381)
			(xy 164.630862 -389.796782) (xy 164.609272 -389.783066) (xy 164.596318 -389.78205) (xy 164.572421 -389.779937)
			(xy 164.525634 -389.769335) (xy 164.480993 -389.751767) (xy 164.439528 -389.727639) (xy 164.402199 -389.697507)
			(xy 164.369865 -389.662067) (xy 164.343273 -389.622138) (xy 164.323038 -389.578641) (xy 164.315902 -389.555736)
			(xy 164.314378 -389.549894) (xy 163.99383 -388.995412) (xy 163.989766 -388.991094) (xy 163.973669 -388.973431)
			(xy 163.94648 -388.934133) (xy 163.925527 -388.891185) (xy 163.911291 -388.845568) (xy 163.904095 -388.798326)
			(xy 163.90366 -388.774432) (xy 163.903841 -388.760384) (xy 163.906382 -388.732402) (xy 163.90874 -388.718552)
			(xy 163.910071 -388.709273) (xy 163.906539 -388.690874) (xy 163.901882 -388.682738) (xy 163.885118 -388.655814)
			(xy 163.879915 -388.648111) (xy 163.86519 -388.636787) (xy 163.856416 -388.633716) (xy 163.834785 -388.626929)
			(xy 163.793572 -388.608043) (xy 163.755453 -388.583504) (xy 163.721199 -388.553807) (xy 163.706048 -388.536942)
			(xy 163.703583 -388.534172) (xy 163.697972 -388.529324) (xy 163.694872 -388.52729) (xy 163.682815 -388.519223)
			(xy 163.662856 -388.498183) (xy 163.64878 -388.472827) (xy 163.641478 -388.444761) (xy 163.641024 -388.430262)
			(xy 163.641024 -388.418324) (xy 163.6395 -388.41172) (xy 163.634294 -388.391351) (xy 163.628693 -388.349683)
			(xy 163.628324 -388.328662) (xy 163.06419 -388.328662) (xy 163.06419 -388.32917) (xy 163.06402 -388.343795)
			(xy 163.061353 -388.372924) (xy 163.058856 -388.387336) (xy 163.057485 -388.39651) (xy 163.060761 -388.414753)
			(xy 163.065206 -388.422896) (xy 163.081716 -388.44982) (xy 163.086896 -388.45759) (xy 163.101615 -388.469057)
			(xy 163.110418 -388.472172) (xy 163.135302 -388.480229) (xy 163.182181 -388.50342) (xy 163.224592 -388.534026)
			(xy 163.261375 -388.571207) (xy 163.291522 -388.613946) (xy 163.314206 -388.661072) (xy 163.322 -388.68604)
			(xy 163.323524 -388.691882) (xy 163.643818 -389.245602) (xy 163.647882 -389.24992) (xy 163.664051 -389.267577)
			(xy 163.691367 -389.306898) (xy 163.712432 -389.349893) (xy 163.726764 -389.395575) (xy 163.734033 -389.442898)
			(xy 163.734496 -389.466836) (xy 163.734496 -389.467344) (xy 163.733976 -389.492791) (xy 163.725807 -389.543027)
			(xy 163.709686 -389.591301) (xy 163.686031 -389.636365) (xy 163.655455 -389.677052) (xy 163.61875 -389.712308)
			(xy 163.598098 -389.727186) (xy 163.589592 -389.733658) (xy 163.578399 -389.751839) (xy 163.575562 -389.773)
			(xy 163.581569 -389.793487) (xy 163.595384 -389.809765) (xy 163.614622 -389.819023) (xy 163.625276 -389.819896)
			(xy 163.634928 -389.819388) (xy 163.643442 -389.818093) (xy 163.660607 -389.816695) (xy 163.669218 -389.816594)
			(xy 163.669472 -389.816848) (xy 163.968684 -389.816848) (xy 163.968938 -389.816594) (xy 163.989984 -389.816999)
			(xy 164.031305 -389.824995) (xy 164.07026 -389.840926) (xy 164.105342 -389.864176) (xy 164.135193 -389.893844)
			(xy 164.158657 -389.928783) (xy 164.174827 -389.96764) (xy 164.183076 -390.008911) (xy 164.183568 -390.029954)
			(xy 164.183568 -390.284716) (xy 164.174424 -390.284716) (xy 164.164402 -390.28514) (xy 164.145883 -390.292805)
			(xy 164.131709 -390.306976) (xy 164.124041 -390.325494) (xy 164.123624 -390.335516) (xy 164.123624 -390.499092)
			(xy 164.123106 -390.509096) (xy 164.115454 -390.527583) (xy 164.10131 -390.541736) (xy 164.082828 -390.5494)
			(xy 164.072824 -390.549892) (xy 163.565332 -390.549892) (xy 163.555312 -390.549454) (xy 163.536794 -390.541793)
			(xy 163.52262 -390.527626) (xy 163.514951 -390.509112) (xy 163.514532 -390.499092) (xy 163.514532 -390.335516)
			(xy 163.514 -390.325513) (xy 163.506351 -390.307028) (xy 163.492212 -390.292876) (xy 163.473734 -390.28521)
			(xy 163.463732 -390.284716) (xy 163.454588 -390.284716) (xy 163.454588 -390.029446) (xy 163.455375 -390.003724)
			(xy 163.467707 -389.953778) (xy 163.478972 -389.93064) (xy 163.484814 -389.91921) (xy 163.48456 -389.89381)
			(xy 163.430966 -389.796782) (xy 163.409376 -389.783066) (xy 163.396422 -389.78205) (xy 163.372525 -389.779934)
			(xy 163.325738 -389.769332) (xy 163.281097 -389.751765) (xy 163.239633 -389.727637) (xy 163.202303 -389.697506)
			(xy 163.169969 -389.662067) (xy 163.143377 -389.622138) (xy 163.123142 -389.578641) (xy 163.116006 -389.555736)
			(xy 163.114482 -389.549894) (xy 162.794188 -388.996174) (xy 162.790124 -388.991856) (xy 162.773925 -388.974144)
			(xy 162.746499 -388.934755) (xy 162.725355 -388.891666) (xy 162.71098 -388.845873) (xy 162.703706 -388.79843)
			(xy 162.703256 -388.774432) (xy 162.703434 -388.760384) (xy 162.705978 -388.732402) (xy 162.708336 -388.718552)
			(xy 162.709621 -388.709296) (xy 162.706226 -388.690933) (xy 162.701732 -388.682738) (xy 162.684968 -388.655814)
			(xy 162.679748 -388.648125) (xy 162.665035 -388.636794) (xy 162.656266 -388.633716) (xy 162.634642 -388.62691)
			(xy 162.593427 -388.60803) (xy 162.555307 -388.583496) (xy 162.52105 -388.553804) (xy 162.505898 -388.536942)
			(xy 162.503439 -388.534166) (xy 162.497824 -388.529322) (xy 162.494722 -388.52729) (xy 162.482703 -388.519196)
			(xy 162.462809 -388.498142) (xy 162.448798 -388.472791) (xy 162.441555 -388.444745) (xy 162.441128 -388.430262)
			(xy 162.441128 -388.418324) (xy 162.43935 -388.41172) (xy 162.434143 -388.391351) (xy 162.428543 -388.349683)
			(xy 162.428174 -388.328662) (xy 161.864294 -388.328662) (xy 161.864294 -388.32917) (xy 161.864124 -388.343795)
			(xy 161.861457 -388.372924) (xy 161.85896 -388.387336) (xy 161.857602 -388.39651) (xy 161.860872 -388.414751)
			(xy 161.86531 -388.422896) (xy 161.88182 -388.44982) (xy 161.886998 -388.457592) (xy 161.901718 -388.469057)
			(xy 161.910522 -388.472172) (xy 161.935445 -388.480308) (xy 161.982411 -388.503601) (xy 162.024891 -388.534323)
			(xy 162.06172 -388.571631) (xy 162.091891 -388.614504) (xy 162.114575 -388.661767) (xy 162.122358 -388.686802)
			(xy 162.123882 -388.692644) (xy 162.443668 -389.245602) (xy 162.447732 -389.24992) (xy 162.463929 -389.267634)
			(xy 162.491353 -389.307024) (xy 162.512497 -389.350112) (xy 162.526872 -389.395905) (xy 162.534148 -389.443346)
			(xy 162.5346 -389.467344) (xy 162.534121 -389.492807) (xy 162.525922 -389.543069) (xy 162.509759 -389.591362)
			(xy 162.486052 -389.636433) (xy 162.455417 -389.677114) (xy 162.418647 -389.712349) (xy 162.397948 -389.727186)
			(xy 162.389417 -389.733635) (xy 162.378207 -389.751822) (xy 162.375363 -389.772996) (xy 162.381376 -389.793497)
			(xy 162.395207 -389.80978) (xy 162.414464 -389.819031) (xy 162.425126 -389.819896) (xy 162.434778 -389.819388)
			(xy 162.443292 -389.818099) (xy 162.460457 -389.816697) (xy 162.469068 -389.816594) (xy 162.469322 -389.816848)
			(xy 162.768534 -389.816848) (xy 162.768788 -389.816594) (xy 162.789851 -389.816973) (xy 162.831211 -389.824933)
			(xy 162.870209 -389.840842) (xy 162.905335 -389.864084) (xy 162.935226 -389.893757) (xy 162.958724 -389.928712)
			(xy 162.974917 -389.967594) (xy 162.983178 -390.008895) (xy 162.983672 -390.029954) (xy 162.983672 -390.284716)
			(xy 162.974528 -390.284716) (xy 162.964507 -390.285143) (xy 162.945987 -390.292807) (xy 162.931813 -390.306977)
			(xy 162.924145 -390.325495) (xy 162.923728 -390.335516) (xy 162.923728 -390.499092) (xy 162.923206 -390.509096)
			(xy 162.915554 -390.527582) (xy 162.901412 -390.541734) (xy 162.882931 -390.549399) (xy 162.872928 -390.549892)
			(xy 162.364928 -390.549892) (xy 162.354908 -390.549457) (xy 162.33639 -390.541795) (xy 162.322216 -390.527627)
			(xy 162.314547 -390.509112) (xy 162.314128 -390.499092) (xy 162.314128 -390.284716) (xy 162.304984 -390.284716)
			(xy 162.294977 -390.284226) (xy 162.276488 -390.276564) (xy 162.262336 -390.262412) (xy 162.254674 -390.243923)
			(xy 162.254184 -390.233916) (xy 162.254184 -390.029954) (xy 162.254533 -390.012721) (xy 162.260102 -389.978709)
			(xy 162.271073 -389.946036) (xy 162.278822 -389.93064) (xy 162.284664 -389.91921) (xy 162.28441 -389.89381)
			(xy 162.230816 -389.796782) (xy 162.209226 -389.783066) (xy 162.196272 -389.78205) (xy 162.172371 -389.779974)
			(xy 162.125583 -389.769366) (xy 162.080941 -389.751791) (xy 162.039477 -389.727657) (xy 162.002148 -389.69752)
			(xy 161.969816 -389.662076) (xy 161.943225 -389.622143) (xy 161.922992 -389.578642) (xy 161.915856 -389.555736)
			(xy 161.914332 -389.549894) (xy 161.593784 -388.995412) (xy 161.58972 -388.991094) (xy 161.573628 -388.973414)
			(xy 161.546376 -388.934139) (xy 161.525362 -388.891202) (xy 161.511067 -388.845585) (xy 161.503819 -388.798334)
			(xy 161.50336 -388.774432) (xy 161.503538 -388.760384) (xy 161.506082 -388.732402) (xy 161.50844 -388.718552)
			(xy 161.509724 -388.709296) (xy 161.506329 -388.690933) (xy 161.501836 -388.682738) (xy 161.485072 -388.655814)
			(xy 161.479886 -388.648098) (xy 161.465149 -388.636781) (xy 161.45637 -388.633716) (xy 161.434746 -388.626908)
			(xy 161.393532 -388.608029) (xy 161.355411 -388.583495) (xy 161.321154 -388.553804) (xy 161.306002 -388.536942)
			(xy 161.303542 -388.534167) (xy 161.297928 -388.529322) (xy 161.294826 -388.52729) (xy 161.282808 -388.519195)
			(xy 161.262914 -388.498141) (xy 161.248902 -388.47279) (xy 161.24166 -388.444745) (xy 161.241232 -388.430262)
			(xy 161.241232 -388.418324) (xy 161.239454 -388.41172) (xy 161.234248 -388.391351) (xy 161.228647 -388.349683)
			(xy 161.228278 -388.328662) (xy 160.664144 -388.328662) (xy 160.664004 -388.343415) (xy 160.661328 -388.372799)
			(xy 160.65881 -388.387336) (xy 160.657445 -388.39651) (xy 160.660719 -388.414752) (xy 160.66516 -388.422896)
			(xy 160.68167 -388.44982) (xy 160.68683 -388.457606) (xy 160.701563 -388.469064) (xy 160.710372 -388.472172)
			(xy 160.735247 -388.480255) (xy 160.782127 -388.503439) (xy 160.82454 -388.534039) (xy 160.861325 -388.571216)
			(xy 160.891473 -388.613951) (xy 160.914159 -388.661074) (xy 160.921954 -388.68604) (xy 160.923478 -388.691882)
			(xy 161.243772 -389.245602) (xy 161.247836 -389.24992) (xy 161.264034 -389.267633) (xy 161.291458 -389.307023)
			(xy 161.312601 -389.350112) (xy 161.326976 -389.395904) (xy 161.334252 -389.443346) (xy 161.334704 -389.467344)
			(xy 161.334223 -389.492807) (xy 161.326024 -389.543068) (xy 161.309862 -389.591361) (xy 161.286155 -389.636433)
			(xy 161.25552 -389.677114) (xy 161.218751 -389.712349) (xy 161.198052 -389.727186) (xy 161.189519 -389.733633)
			(xy 161.178308 -389.751821) (xy 161.175463 -389.772996) (xy 161.181477 -389.793498) (xy 161.195309 -389.809781)
			(xy 161.214568 -389.819032) (xy 161.22523 -389.819896) (xy 161.234882 -389.819388) (xy 161.243396 -389.818098)
			(xy 161.260561 -389.816697) (xy 161.269172 -389.816594) (xy 161.269426 -389.816848) (xy 161.568638 -389.816848)
			(xy 161.568892 -389.816594) (xy 161.589955 -389.81697) (xy 161.631315 -389.82493) (xy 161.670314 -389.84084)
			(xy 161.705439 -389.864082) (xy 161.73533 -389.893756) (xy 161.758828 -389.928712) (xy 161.775021 -389.967594)
			(xy 161.783282 -390.008895) (xy 161.783776 -390.029954) (xy 161.783776 -390.284716) (xy 161.774632 -390.284716)
			(xy 161.764611 -390.285146) (xy 161.746092 -390.292809) (xy 161.731918 -390.306978) (xy 161.724249 -390.325495)
			(xy 161.723832 -390.335516) (xy 161.723832 -390.499092) (xy 161.723306 -390.509095) (xy 161.715655 -390.527581)
			(xy 161.701514 -390.541733) (xy 161.683035 -390.549398) (xy 161.673032 -390.549892) (xy 161.165032 -390.549892)
			(xy 161.155012 -390.549454) (xy 161.136494 -390.541793) (xy 161.12232 -390.527626) (xy 161.114651 -390.509112)
			(xy 161.114232 -390.499092) (xy 161.114232 -390.284716) (xy 161.105088 -390.284716) (xy 161.095082 -390.284222)
			(xy 161.076593 -390.276561) (xy 161.062441 -390.262411) (xy 161.054779 -390.243922) (xy 161.054288 -390.233916)
			(xy 161.054288 -390.029954) (xy 161.054636 -390.012721) (xy 161.060206 -389.978709) (xy 161.071177 -389.946036)
			(xy 161.078926 -389.93064) (xy 161.084768 -389.91921) (xy 161.084514 -389.89381) (xy 161.03092 -389.796782)
			(xy 161.00933 -389.783066) (xy 160.996376 -389.78205) (xy 160.972475 -389.779971) (xy 160.925687 -389.769363)
			(xy 160.881046 -389.751789) (xy 160.839582 -389.727656) (xy 160.802253 -389.697519) (xy 160.76992 -389.662075)
			(xy 160.74333 -389.622143) (xy 160.723096 -389.578642) (xy 160.71596 -389.555736) (xy 160.714436 -389.549894)
			(xy 160.394142 -388.996174) (xy 160.390078 -388.991856) (xy 160.373923 -388.974118) (xy 160.346553 -388.934718)
			(xy 160.325461 -388.891629) (xy 160.311133 -388.845845) (xy 160.303898 -388.798419) (xy 160.303464 -388.774432)
			(xy 160.303645 -388.760384) (xy 160.306186 -388.732402) (xy 160.308544 -388.718552) (xy 160.309875 -388.709273)
			(xy 160.306343 -388.690874) (xy 160.301686 -388.682738) (xy 160.284922 -388.655814) (xy 160.279718 -388.648112)
			(xy 160.264994 -388.636788) (xy 160.25622 -388.633716) (xy 160.234651 -388.626945) (xy 160.193524 -388.608177)
			(xy 160.155469 -388.583776) (xy 160.121251 -388.554234) (xy 160.106106 -388.53745) (xy 160.103645 -388.534676)
			(xy 160.098032 -388.52983) (xy 160.09493 -388.527798) (xy 160.082791 -388.519709) (xy 160.062702 -388.498572)
			(xy 160.048555 -388.473074) (xy 160.041253 -388.444842) (xy 160.040828 -388.430262) (xy 160.040828 -388.417816)
			(xy 160.03905 -388.411466) (xy 160.033921 -388.391151) (xy 160.028444 -388.349612) (xy 160.028128 -388.328662)
			(xy 160.028465 -388.307714) (xy 160.033938 -388.266176) (xy 160.03905 -388.245858) (xy 160.040828 -388.239508)
			(xy 160.040828 -387.782816) (xy 160.03905 -387.776466) (xy 160.033921 -387.756151) (xy 160.028444 -387.714612)
			(xy 160.028128 -387.693662) (xy 160.028465 -387.672714) (xy 160.033938 -387.631176) (xy 160.03905 -387.610858)
			(xy 160.040828 -387.604508) (xy 160.040828 -387.592062) (xy 160.041321 -387.576599) (xy 160.049547 -387.546786)
			(xy 160.065375 -387.520216) (xy 160.087674 -387.498786) (xy 160.101026 -387.49097) (xy 160.104582 -387.486906)
			(xy 160.111935 -387.477383) (xy 160.117633 -387.454044) (xy 160.115504 -387.442202) (xy 160.108392 -387.410706)
			(xy 160.105113 -387.399196) (xy 160.089872 -387.380783) (xy 160.079182 -387.3754) (xy 160.057696 -387.365584)
			(xy 160.017632 -387.340564) (xy 159.981714 -387.309887) (xy 159.965898 -387.292342) (xy 159.963439 -387.289566)
			(xy 159.957824 -387.284722) (xy 159.954722 -387.28269) (xy 159.942703 -387.274596) (xy 159.922809 -387.253542)
			(xy 159.908798 -387.228191) (xy 159.901555 -387.200145) (xy 159.901128 -387.185662) (xy 159.901128 -387.173724)
			(xy 159.89935 -387.16712) (xy 159.894143 -387.146751) (xy 159.888543 -387.105083) (xy 159.888174 -387.084062)
			(xy 159.888541 -387.063041) (xy 159.894151 -387.021375) (xy 159.89935 -387.001004) (xy 159.901128 -386.9944)
			(xy 159.901128 -386.880862) (xy 159.901788 -386.862743) (xy 159.913042 -386.828297) (xy 159.923226 -386.813298)
			(xy 159.927699 -386.806627) (xy 159.932631 -386.791353) (xy 159.932878 -386.783326) (xy 159.932878 -386.749798)
			(xy 159.932561 -386.74178) (xy 159.927657 -386.726515) (xy 159.923226 -386.719826) (xy 159.913147 -386.704772)
			(xy 159.901886 -386.670362) (xy 159.901128 -386.652262) (xy 159.901128 -386.538724) (xy 159.89935 -386.53212)
			(xy 159.894143 -386.511751) (xy 159.888543 -386.470083) (xy 159.888174 -386.449062) (xy 159.888936 -386.426456)
			(xy 159.889698 -386.416296) (xy 159.883602 -386.3975) (xy 159.830008 -386.335524) (xy 159.823078 -386.328265)
			(xy 159.805168 -386.31925) (xy 159.79521 -386.317998) (xy 159.771399 -386.315797) (xy 159.724806 -386.305038)
			(xy 159.680371 -386.287371) (xy 159.63911 -386.263202) (xy 159.601968 -386.233084) (xy 159.569796 -386.197706)
			(xy 159.54333 -386.157879) (xy 159.523177 -386.114515) (xy 159.516064 -386.091684) (xy 159.51454 -386.085842)
			(xy 159.194246 -385.532122) (xy 159.190182 -385.527804) (xy 159.174035 -385.510127) (xy 159.146713 -385.470813)
			(xy 159.125643 -385.427823) (xy 159.111307 -385.382145) (xy 159.104033 -385.334825) (xy 159.103568 -385.310888)
			(xy 158.571476 -385.310888) (xy 158.843726 -385.78155) (xy 158.84779 -385.785868) (xy 158.863952 -385.803566)
			(xy 158.891293 -385.842927) (xy 158.912371 -385.885969) (xy 158.926701 -385.931702) (xy 158.933954 -385.979075)
			(xy 158.934404 -386.003038) (xy 158.934404 -386.003546) (xy 158.933896 -386.023866) (xy 158.933134 -386.033772)
			(xy 158.939484 -386.052822) (xy 159.00019 -386.122164) (xy 159.01797 -386.131054) (xy 159.02813 -386.131816)
			(xy 159.053104 -386.134037) (xy 159.101961 -386.145284) (xy 159.148448 -386.164057) (xy 159.191414 -386.189893)
			(xy 159.229793 -386.22215) (xy 159.24657 -386.240782) (xy 159.24903 -386.243557) (xy 159.254644 -386.248402)
			(xy 159.257746 -386.250434) (xy 159.26979 -386.258493) (xy 159.289677 -386.27956) (xy 159.303681 -386.304923)
			(xy 159.310916 -386.332976) (xy 159.31134 -386.347462) (xy 159.31134 -386.3594) (xy 159.313118 -386.366004)
			(xy 159.318309 -386.386377) (xy 159.32392 -386.428042) (xy 159.324294 -386.449062) (xy 159.323913 -386.470082)
			(xy 159.318312 -386.511748) (xy 159.313118 -386.53212) (xy 159.31134 -386.538724) (xy 159.31134 -386.576316)
			(xy 159.311708 -386.586343) (xy 159.31939 -386.604868) (xy 159.333579 -386.619041) (xy 159.352112 -386.626703)
			(xy 159.36214 -386.627116) (xy 159.395668 -386.627116) (xy 159.405736 -386.627554) (xy 159.424334 -386.635265)
			(xy 159.431736 -386.642102) (xy 159.446468 -386.656834) (xy 159.453881 -386.663657) (xy 159.472471 -386.671386)
			(xy 159.482536 -386.67182) (xy 159.51454 -386.67182) (xy 159.524553 -386.672256) (xy 159.543049 -386.679932)
			(xy 159.557201 -386.694101) (xy 159.564856 -386.712607) (xy 159.56534 -386.72262) (xy 159.56534 -386.754624)
			(xy 159.565742 -386.764696) (xy 159.573478 -386.783294) (xy 159.580326 -386.790692) (xy 159.621982 -386.832094)
			(xy 159.62881 -386.839504) (xy 159.636537 -386.858096) (xy 159.636968 -386.868162) (xy 159.636968 -388.501128)
			(xy 159.637361 -388.511201) (xy 159.645102 -388.5298) (xy 159.651954 -388.537196) (xy 159.992822 -388.878064)
			(xy 159.999642 -388.88548) (xy 160.007373 -388.904067) (xy 160.007808 -388.914132) (xy 160.007808 -389.169402)
			(xy 160.008031 -389.176064) (xy 160.011517 -389.188926) (xy 160.014666 -389.194802) (xy 160.043876 -389.245602)
			(xy 160.04794 -389.24992) (xy 160.064138 -389.267633) (xy 160.091562 -389.307023) (xy 160.112705 -389.350111)
			(xy 160.12708 -389.395904) (xy 160.134356 -389.443346) (xy 160.134808 -389.467344) (xy 160.134371 -389.491271)
			(xy 160.127132 -389.538575) (xy 160.112841 -389.584246) (xy 160.091826 -389.627239) (xy 160.064567 -389.666571)
			(xy 160.048448 -389.68426) (xy 160.042463 -389.691124) (xy 160.035329 -389.707863) (xy 160.034548 -389.726042)
			(xy 160.037018 -389.734806) (xy 160.040096 -389.744681) (xy 160.045053 -389.764765) (xy 160.046924 -389.774938)
			(xy 160.046924 -389.775192) (xy 160.04967 -389.786729) (xy 160.063924 -389.805648) (xy 160.085118 -389.816227)
			(xy 160.096962 -389.816848) (xy 160.368488 -389.816848) (xy 160.368742 -389.816594) (xy 160.389788 -389.816995)
			(xy 160.431109 -389.824992) (xy 160.470064 -389.840924) (xy 160.505146 -389.864174) (xy 160.534997 -389.893843)
			(xy 160.558461 -389.928783) (xy 160.574631 -389.96764) (xy 160.58288 -390.008911) (xy 160.583372 -390.029954)
			(xy 160.583372 -390.284716) (xy 160.574228 -390.284716) (xy 160.564207 -390.285143) (xy 160.545687 -390.292807)
			(xy 160.531513 -390.306977) (xy 160.523845 -390.325495) (xy 160.523428 -390.335516) (xy 160.523428 -390.499092)
			(xy 160.522906 -390.509096) (xy 160.515254 -390.527582) (xy 160.501112 -390.541734) (xy 160.482631 -390.549399)
			(xy 160.472628 -390.549892) (xy 160.066736 -390.549892) (xy 160.056718 -390.550349) (xy 160.038203 -390.558006)
			(xy 160.02403 -390.572166) (xy 160.016358 -390.590674) (xy 160.015936 -390.600692) (xy 160.015936 -391.47115)
			(xy 160.015317 -391.497669) (xy 160.006104 -391.549904) (xy 159.988015 -391.599764) (xy 159.975296 -391.623042)
			(xy 159.971994 -391.628884) (xy 159.968438 -391.641584) (xy 159.968438 -392.647932) (xy 159.971994 -392.660632)
			(xy 159.975296 -392.666474) (xy 159.988037 -392.68979) (xy 160.006163 -392.739731) (xy 160.015363 -392.792056)
			(xy 160.015936 -392.81862) (xy 160.015936 -392.903456) (xy 160.015361 -392.930019) (xy 160.006152 -392.982343)
			(xy 159.988038 -393.032287) (xy 159.975296 -393.055602) (xy 159.971994 -393.061444) (xy 159.968438 -393.074144)
			(xy 159.968438 -393.292838) (xy 160.262824 -393.292838) (xy 160.262824 -392.42873) (xy 160.263257 -392.403262)
			(xy 160.27006 -392.352782) (xy 160.283521 -392.303656) (xy 160.303403 -392.25676) (xy 160.32935 -392.212927)
			(xy 160.3609 -392.172939) (xy 160.378902 -392.154918) (xy 160.385506 -392.148568) (xy 160.39338 -392.131804)
			(xy 160.400238 -392.04646) (xy 160.395158 -392.02868) (xy 160.38957 -392.021314) (xy 160.374724 -392.000563)
			(xy 160.351087 -391.95535) (xy 160.334984 -391.90694) (xy 160.32683 -391.856577) (xy 160.326324 -391.831068)
			(xy 160.326324 -391.830814) (xy 160.326814 -391.805825) (xy 160.334633 -391.756462) (xy 160.350077 -391.70893)
			(xy 160.372767 -391.664398) (xy 160.402143 -391.623965) (xy 160.437483 -391.588625) (xy 160.477916 -391.559249)
			(xy 160.522448 -391.536559) (xy 160.56998 -391.521115) (xy 160.619343 -391.513296) (xy 160.669321 -391.513296)
			(xy 160.718684 -391.521115) (xy 160.766216 -391.536559) (xy 160.810748 -391.559249) (xy 160.851181 -391.588625)
			(xy 160.886521 -391.623965) (xy 160.915897 -391.664398) (xy 160.938587 -391.70893) (xy 160.954031 -391.756462)
			(xy 160.96185 -391.805825) (xy 160.96234 -391.830814) (xy 160.96234 -391.831068) (xy 160.961839 -391.856577)
			(xy 160.953663 -391.906935) (xy 160.937563 -391.955347) (xy 160.913951 -392.000572) (xy 160.899094 -392.021314)
			(xy 160.893506 -392.02868) (xy 160.888426 -392.04646) (xy 160.895284 -392.131804) (xy 160.903158 -392.148568)
			(xy 160.909762 -392.154918) (xy 160.927763 -392.172939) (xy 160.959304 -392.212933) (xy 160.985244 -392.256767)
			(xy 161.005123 -392.303662) (xy 161.018588 -392.352785) (xy 161.025399 -392.403263) (xy 161.02584 -392.42873)
			(xy 161.02584 -393.292838) (xy 161.02583 -393.293346) (xy 161.46272 -393.293346) (xy 161.46272 -392.42873)
			(xy 161.463154 -392.403262) (xy 161.469957 -392.352782) (xy 161.483418 -392.303656) (xy 161.503299 -392.25676)
			(xy 161.529246 -392.212928) (xy 161.560796 -392.172939) (xy 161.578798 -392.154918) (xy 161.585402 -392.148568)
			(xy 161.593276 -392.131804) (xy 161.600134 -392.04646) (xy 161.595054 -392.02868) (xy 161.589466 -392.021314)
			(xy 161.57462 -392.000563) (xy 161.550982 -391.955351) (xy 161.53488 -391.90694) (xy 161.526726 -391.856577)
			(xy 161.52622 -391.831068) (xy 161.52622 -391.830814) (xy 161.52671 -391.805825) (xy 161.534529 -391.756462)
			(xy 161.549973 -391.70893) (xy 161.572663 -391.664398) (xy 161.602039 -391.623965) (xy 161.637379 -391.588625)
			(xy 161.677812 -391.559249) (xy 161.722344 -391.536559) (xy 161.769876 -391.521115) (xy 161.819239 -391.513296)
			(xy 161.869217 -391.513296) (xy 161.91858 -391.521115) (xy 161.966112 -391.536559) (xy 162.010644 -391.559249)
			(xy 162.051077 -391.588625) (xy 162.086417 -391.623965) (xy 162.115793 -391.664398) (xy 162.138483 -391.70893)
			(xy 162.153927 -391.756462) (xy 162.161746 -391.805825) (xy 162.162236 -391.830814) (xy 162.162236 -391.831068)
			(xy 162.161736 -391.856577) (xy 162.15356 -391.906936) (xy 162.137459 -391.955347) (xy 162.113847 -392.000572)
			(xy 162.09899 -392.021314) (xy 162.093402 -392.02868) (xy 162.088322 -392.04646) (xy 162.09518 -392.131804)
			(xy 162.103054 -392.148568) (xy 162.109658 -392.154918) (xy 162.127658 -392.172939) (xy 162.159199 -392.212933)
			(xy 162.18514 -392.256767) (xy 162.205019 -392.303663) (xy 162.218484 -392.352785) (xy 162.225295 -392.403263)
			(xy 162.225736 -392.42873) (xy 162.225736 -393.292838) (xy 162.662616 -393.292838) (xy 162.662616 -392.42873)
			(xy 162.663051 -392.403262) (xy 162.669854 -392.352782) (xy 162.683315 -392.303657) (xy 162.703196 -392.25676)
			(xy 162.729142 -392.212928) (xy 162.760692 -392.172939) (xy 162.778694 -392.154918) (xy 162.785298 -392.148568)
			(xy 162.793172 -392.131804) (xy 162.80003 -392.04646) (xy 162.79495 -392.02868) (xy 162.789362 -392.021314)
			(xy 162.774515 -392.000563) (xy 162.750878 -391.955351) (xy 162.734775 -391.90694) (xy 162.726622 -391.856577)
			(xy 162.726116 -391.831068) (xy 162.726116 -391.830814) (xy 162.726606 -391.805825) (xy 162.734425 -391.756462)
			(xy 162.749869 -391.70893) (xy 162.772559 -391.664398) (xy 162.801935 -391.623965) (xy 162.837275 -391.588625)
			(xy 162.877708 -391.559249) (xy 162.92224 -391.536559) (xy 162.969772 -391.521115) (xy 163.019135 -391.513296)
			(xy 163.069113 -391.513296) (xy 163.118476 -391.521115) (xy 163.166008 -391.536559) (xy 163.21054 -391.559249)
			(xy 163.250973 -391.588625) (xy 163.286313 -391.623965) (xy 163.315689 -391.664398) (xy 163.338379 -391.70893)
			(xy 163.353823 -391.756462) (xy 163.361642 -391.805825) (xy 163.362132 -391.830814) (xy 163.362132 -391.831068)
			(xy 163.361633 -391.856577) (xy 163.353456 -391.906936) (xy 163.337356 -391.955347) (xy 163.313743 -392.000572)
			(xy 163.298886 -392.021314) (xy 163.293298 -392.02868) (xy 163.288218 -392.04646) (xy 163.295076 -392.131804)
			(xy 163.30295 -392.148568) (xy 163.309554 -392.154918) (xy 163.327553 -392.17294) (xy 163.359094 -392.212934)
			(xy 163.385035 -392.256768) (xy 163.404915 -392.303663) (xy 163.41838 -392.352786) (xy 163.425191 -392.403263)
			(xy 163.425632 -392.42873) (xy 163.425632 -393.292838) (xy 163.862512 -393.292838) (xy 163.862512 -392.429238)
			(xy 163.862946 -392.403718) (xy 163.869735 -392.353133) (xy 163.883211 -392.303905) (xy 163.903133 -392.256914)
			(xy 163.929144 -392.213) (xy 163.96078 -392.172949) (xy 163.978844 -392.154918) (xy 163.985448 -392.148568)
			(xy 163.993322 -392.131804) (xy 164.00018 -392.04646) (xy 163.9951 -392.02868) (xy 163.989512 -392.021314)
			(xy 163.974659 -392.000568) (xy 163.951025 -391.955353) (xy 163.934924 -391.906941) (xy 163.926772 -391.856578)
			(xy 163.926266 -391.831068) (xy 163.926266 -391.830814) (xy 163.926756 -391.805825) (xy 163.934575 -391.756462)
			(xy 163.950019 -391.70893) (xy 163.972709 -391.664398) (xy 164.002085 -391.623965) (xy 164.037425 -391.588625)
			(xy 164.077858 -391.559249) (xy 164.12239 -391.536559) (xy 164.169922 -391.521115) (xy 164.219285 -391.513296)
			(xy 164.269263 -391.513296) (xy 164.318626 -391.521115) (xy 164.366158 -391.536559) (xy 164.41069 -391.559249)
			(xy 164.451123 -391.588625) (xy 164.486463 -391.623965) (xy 164.515839 -391.664398) (xy 164.538529 -391.70893)
			(xy 164.553973 -391.756462) (xy 164.561792 -391.805825) (xy 164.562282 -391.830814) (xy 164.562282 -391.831068)
			(xy 164.561773 -391.856576) (xy 164.553598 -391.906934) (xy 164.5375 -391.955345) (xy 164.513891 -392.000571)
			(xy 164.499036 -392.021314) (xy 164.493448 -392.02868) (xy 164.488368 -392.04646) (xy 164.495226 -392.131804)
			(xy 164.5031 -392.148568) (xy 164.509704 -392.154918) (xy 164.527729 -392.172986) (xy 164.559362 -392.213034)
			(xy 164.585376 -392.256941) (xy 164.605306 -392.303923) (xy 164.618796 -392.353143) (xy 164.625606 -392.403721)
			(xy 164.626036 -392.429238) (xy 164.626036 -393.292838) (xy 165.062408 -393.292838) (xy 165.062408 -392.429238)
			(xy 165.062843 -392.403718) (xy 165.069632 -392.353133) (xy 165.083108 -392.303905) (xy 165.103029 -392.256914)
			(xy 165.12904 -392.213001) (xy 165.160676 -392.172949) (xy 165.17874 -392.154918) (xy 165.185344 -392.148568)
			(xy 165.193218 -392.131804) (xy 165.200076 -392.04646) (xy 165.194996 -392.02868) (xy 165.189408 -392.021314)
			(xy 165.174555 -392.000568) (xy 165.150921 -391.955353) (xy 165.13482 -391.906941) (xy 165.126668 -391.856578)
			(xy 165.126162 -391.831068) (xy 165.126162 -391.830814) (xy 165.126652 -391.805825) (xy 165.134471 -391.756462)
			(xy 165.149915 -391.70893) (xy 165.172605 -391.664398) (xy 165.201981 -391.623965) (xy 165.237321 -391.588625)
			(xy 165.277754 -391.559249) (xy 165.322286 -391.536559) (xy 165.369818 -391.521115) (xy 165.419181 -391.513296)
			(xy 165.469159 -391.513296) (xy 165.518522 -391.521115) (xy 165.566054 -391.536559) (xy 165.610586 -391.559249)
			(xy 165.651019 -391.588625) (xy 165.686359 -391.623965) (xy 165.715735 -391.664398) (xy 165.738425 -391.70893)
			(xy 165.753869 -391.756462) (xy 165.761688 -391.805825) (xy 165.762178 -391.830814) (xy 165.762178 -391.831068)
			(xy 165.76167 -391.856576) (xy 165.753495 -391.906934) (xy 165.737397 -391.955345) (xy 165.713787 -392.000571)
			(xy 165.698932 -392.021314) (xy 165.693344 -392.02868) (xy 165.688264 -392.04646) (xy 165.695122 -392.131804)
			(xy 165.702996 -392.148568) (xy 165.7096 -392.154918) (xy 165.727642 -392.172968) (xy 165.759271 -392.213022)
			(xy 165.78528 -392.256934) (xy 165.805206 -392.303919) (xy 165.818693 -392.35314) (xy 165.825502 -392.40372)
			(xy 165.825932 -392.429238) (xy 165.825932 -392.815826) (xy 167.13911 -392.815826) (xy 167.143181 -392.760204)
			(xy 167.155307 -392.705767) (xy 167.17523 -392.653676) (xy 167.202526 -392.605041) (xy 167.236612 -392.560898)
			(xy 167.276761 -392.522189) (xy 167.322119 -392.489738) (xy 167.371719 -392.464237) (xy 167.424503 -392.44623)
			(xy 167.479346 -392.4361) (xy 167.53508 -392.434063) (xy 167.590517 -392.440163) (xy 167.644474 -392.454269)
			(xy 167.695803 -392.476081) (xy 167.743409 -392.505135) (xy 167.786277 -392.54081) (xy 167.823494 -392.582347)
			(xy 167.854267 -392.62886) (xy 167.877939 -392.679357) (xy 167.894007 -392.732764) (xy 167.902127 -392.78794)
			(xy 167.902636 -392.815826) (xy 167.902127 -392.843712) (xy 167.894007 -392.898888) (xy 167.877939 -392.952295)
			(xy 167.854267 -393.002792) (xy 167.823494 -393.049305) (xy 167.786277 -393.090842) (xy 167.743409 -393.126517)
			(xy 167.695803 -393.155571) (xy 167.644474 -393.177383) (xy 167.590517 -393.191489) (xy 167.53508 -393.197589)
			(xy 167.479346 -393.195552) (xy 167.424503 -393.185422) (xy 167.371719 -393.167415) (xy 167.322119 -393.141914)
			(xy 167.276761 -393.109463) (xy 167.236612 -393.070754) (xy 167.202526 -393.026611) (xy 167.17523 -392.977976)
			(xy 167.155307 -392.925885) (xy 167.143181 -392.871448) (xy 167.13911 -392.815826) (xy 165.825932 -392.815826)
			(xy 165.825932 -393.01547) (xy 165.826626 -393.028152) (xy 165.838771 -393.050421) (xy 165.849046 -393.057888)
			(xy 165.931088 -393.111482) (xy 165.956488 -393.113514) (xy 165.968172 -393.108434) (xy 165.96868 -393.108434)
			(xy 165.992179 -393.098499) (xy 166.041239 -393.084498) (xy 166.091761 -393.077401) (xy 166.11727 -393.076938)
			(xy 166.144876 -393.077334) (xy 166.199473 -393.085559) (xy 166.252234 -393.10183) (xy 166.301981 -393.125783)
			(xy 166.347602 -393.156883) (xy 166.388077 -393.194436) (xy 166.422503 -393.237602) (xy 166.450111 -393.285417)
			(xy 166.469573 -393.335002) (xy 167.860978 -393.335002) (xy 167.865049 -393.27938) (xy 167.877175 -393.224943)
			(xy 167.897098 -393.172852) (xy 167.924394 -393.124217) (xy 167.95848 -393.080074) (xy 167.998629 -393.041365)
			(xy 168.043987 -393.008914) (xy 168.093587 -392.983413) (xy 168.146371 -392.965406) (xy 168.201214 -392.955276)
			(xy 168.256948 -392.953239) (xy 168.312385 -392.959339) (xy 168.366342 -392.973445) (xy 168.417671 -392.995257)
			(xy 168.465277 -393.024311) (xy 168.508145 -393.059986) (xy 168.545362 -393.101523) (xy 168.576135 -393.148036)
			(xy 168.599807 -393.198533) (xy 168.615875 -393.25194) (xy 168.623995 -393.307116) (xy 168.624504 -393.335002)
			(xy 168.623995 -393.362888) (xy 168.615875 -393.418064) (xy 168.599807 -393.471471) (xy 168.576135 -393.521968)
			(xy 168.545362 -393.568481) (xy 168.508145 -393.610018) (xy 168.465277 -393.645693) (xy 168.417671 -393.674747)
			(xy 168.366342 -393.696559) (xy 168.312385 -393.710665) (xy 168.256948 -393.716765) (xy 168.201214 -393.714728)
			(xy 168.146371 -393.704598) (xy 168.093587 -393.686591) (xy 168.043987 -393.66109) (xy 167.998629 -393.628639)
			(xy 167.95848 -393.58993) (xy 167.924394 -393.545787) (xy 167.897098 -393.497152) (xy 167.877175 -393.445061)
			(xy 167.865049 -393.390624) (xy 167.860978 -393.335002) (xy 166.469573 -393.335002) (xy 166.470284 -393.336813)
			(xy 166.48257 -393.390641) (xy 166.486697 -393.4457) (xy 166.48257 -393.500759) (xy 166.470284 -393.554587)
			(xy 166.450111 -393.605983) (xy 166.422503 -393.653798) (xy 166.388077 -393.696964) (xy 166.347602 -393.734517)
			(xy 166.301981 -393.765617) (xy 166.252234 -393.78957) (xy 166.199473 -393.805841) (xy 166.144877 -393.814066)
			(xy 166.11727 -393.814554) (xy 166.088244 -393.814017) (xy 166.030911 -393.804902) (xy 165.97572 -393.786902)
			(xy 165.94963 -393.774168) (xy 165.937184 -393.767818) (xy 165.910006 -393.769342) (xy 165.812978 -393.834366)
			(xy 165.80104 -393.859258) (xy 165.80231 -393.872974) (xy 165.80358 -393.902438) (xy 165.803078 -393.929334)
			(xy 165.79506 -393.982526) (xy 165.779204 -394.033929) (xy 165.755865 -394.082395) (xy 165.725562 -394.126841)
			(xy 165.688974 -394.166274) (xy 165.646917 -394.199813) (xy 165.600331 -394.226709) (xy 165.550257 -394.246362)
			(xy 165.497812 -394.258332) (xy 165.44417 -394.262352) (xy 165.390528 -394.258332) (xy 165.338083 -394.246362)
			(xy 165.288009 -394.226709) (xy 165.241423 -394.199813) (xy 165.199366 -394.166274) (xy 165.162778 -394.126841)
			(xy 165.132475 -394.082395) (xy 165.109136 -394.033929) (xy 165.09328 -393.982526) (xy 165.085262 -393.929334)
			(xy 165.08476 -393.902438) (xy 165.085171 -393.878235) (xy 165.091671 -393.830269) (xy 165.104559 -393.783611)
			(xy 165.123601 -393.739108) (xy 165.148452 -393.697569) (xy 165.163246 -393.67841) (xy 165.1635 -393.678156)
			(xy 165.168768 -393.670966) (xy 165.174355 -393.65405) (xy 165.174422 -393.645136) (xy 165.17239 -393.570714)
			(xy 165.165532 -393.55395) (xy 165.15969 -393.547346) (xy 165.141489 -393.526229) (xy 165.110743 -393.479728)
			(xy 165.087091 -393.429248) (xy 165.071035 -393.375864) (xy 165.062918 -393.320711) (xy 165.062408 -393.292838)
			(xy 164.626036 -393.292838) (xy 164.62548 -393.322002) (xy 164.616559 -393.379644) (xy 164.598975 -393.435259)
			(xy 164.573137 -393.487552) (xy 164.539647 -393.535309) (xy 164.519864 -393.556744) (xy 164.513703 -393.563825)
			(xy 164.506548 -393.581162) (xy 164.505894 -393.590526) (xy 164.504116 -393.659106) (xy 164.504256 -393.668363)
			(xy 164.510392 -393.685816) (xy 164.516054 -393.693142) (xy 164.516562 -393.69365) (xy 164.532921 -393.713259)
			(xy 164.560451 -393.75627) (xy 164.581607 -393.802748) (xy 164.595961 -393.851757) (xy 164.603223 -393.902305)
			(xy 164.603684 -393.927838) (xy 164.603182 -393.954734) (xy 164.595164 -394.007926) (xy 164.579308 -394.059329)
			(xy 164.555969 -394.107795) (xy 164.525666 -394.152241) (xy 164.489078 -394.191674) (xy 164.447021 -394.225213)
			(xy 164.400435 -394.252109) (xy 164.350361 -394.271762) (xy 164.297916 -394.283732) (xy 164.244274 -394.287752)
			(xy 164.190632 -394.283732) (xy 164.138187 -394.271762) (xy 164.088113 -394.252109) (xy 164.041527 -394.225213)
			(xy 163.99947 -394.191674) (xy 163.962882 -394.152241) (xy 163.932579 -394.107795) (xy 163.90924 -394.059329)
			(xy 163.893384 -394.007926) (xy 163.885366 -393.954734) (xy 163.884864 -393.927838) (xy 163.885337 -393.90227)
			(xy 163.892614 -393.851655) (xy 163.90701 -393.802587) (xy 163.928234 -393.756064) (xy 163.955855 -393.713029)
			(xy 163.97224 -393.693396) (xy 163.972494 -393.693142) (xy 163.978161 -393.685823) (xy 163.984269 -393.668362)
			(xy 163.984432 -393.659106) (xy 163.9824 -393.580874) (xy 163.975288 -393.563856) (xy 163.968684 -393.556744)
			(xy 163.948895 -393.535314) (xy 163.915405 -393.487558) (xy 163.889571 -393.435263) (xy 163.871993 -393.379646)
			(xy 163.863083 -393.322002) (xy 163.862512 -393.292838) (xy 163.425632 -393.292838) (xy 163.425077 -393.321991)
			(xy 163.416207 -393.379619) (xy 163.398678 -393.435228) (xy 163.372899 -393.487526) (xy 163.339468 -393.535297)
			(xy 163.319714 -393.556744) (xy 163.313547 -393.56382) (xy 163.306396 -393.581161) (xy 163.305744 -393.590526)
			(xy 163.303966 -393.659106) (xy 163.304117 -393.668362) (xy 163.310247 -393.685814) (xy 163.315904 -393.693142)
			(xy 163.316412 -393.69365) (xy 163.332729 -393.71328) (xy 163.360201 -393.756303) (xy 163.381303 -393.802783)
			(xy 163.39561 -393.851783) (xy 163.402834 -393.902315) (xy 163.40328 -393.927838) (xy 163.402778 -393.954715)
			(xy 163.394766 -394.00787) (xy 163.378922 -394.059236) (xy 163.355598 -394.107668) (xy 163.325317 -394.152082)
			(xy 163.288755 -394.191487) (xy 163.246727 -394.225003) (xy 163.200174 -394.25188) (xy 163.150135 -394.271519)
			(xy 163.097728 -394.28348) (xy 163.044124 -394.287498) (xy 162.99052 -394.28348) (xy 162.938113 -394.271519)
			(xy 162.888074 -394.25188) (xy 162.841521 -394.225003) (xy 162.799493 -394.191487) (xy 162.762931 -394.152082)
			(xy 162.73265 -394.107668) (xy 162.709326 -394.059236) (xy 162.693482 -394.00787) (xy 162.68547 -393.954715)
			(xy 162.684968 -393.927838) (xy 162.685436 -393.902281) (xy 162.692673 -393.851681) (xy 162.707019 -393.802621)
			(xy 162.728184 -393.756094) (xy 162.755739 -393.713043) (xy 162.77209 -393.693396) (xy 162.772344 -393.693142)
			(xy 162.778005 -393.685819) (xy 162.784118 -393.668362) (xy 162.784282 -393.659106) (xy 162.78225 -393.580874)
			(xy 162.775138 -393.563856) (xy 162.768534 -393.556744) (xy 162.748804 -393.535275) (xy 162.715364 -393.487513)
			(xy 162.689578 -393.435221) (xy 162.672044 -393.379615) (xy 162.663171 -393.32199) (xy 162.662616 -393.292838)
			(xy 162.225736 -393.292838) (xy 162.225736 -393.293346) (xy 162.225238 -393.321743) (xy 162.216827 -393.37791)
			(xy 162.200168 -393.432205) (xy 162.175632 -393.483424) (xy 162.143761 -393.530432) (xy 162.124898 -393.551664)
			(xy 162.119036 -393.558599) (xy 162.11213 -393.575377) (xy 162.111436 -393.58443) (xy 162.11042 -393.615418)
			(xy 162.11047 -393.62457) (xy 162.116341 -393.641891) (xy 162.12185 -393.6492) (xy 162.137192 -393.668549)
			(xy 162.162966 -393.710669) (xy 162.182745 -393.755914) (xy 162.196158 -393.803438) (xy 162.202953 -393.852348)
			(xy 162.203384 -393.877038) (xy 162.202882 -393.903915) (xy 162.19487 -393.95707) (xy 162.179026 -394.008436)
			(xy 162.155702 -394.056868) (xy 162.125421 -394.101282) (xy 162.088859 -394.140687) (xy 162.046831 -394.174203)
			(xy 162.000278 -394.20108) (xy 161.950239 -394.220719) (xy 161.897832 -394.23268) (xy 161.844228 -394.236698)
			(xy 161.790624 -394.23268) (xy 161.738217 -394.220719) (xy 161.688178 -394.20108) (xy 161.641625 -394.174203)
			(xy 161.599597 -394.140687) (xy 161.563035 -394.101282) (xy 161.532754 -394.056868) (xy 161.50943 -394.008436)
			(xy 161.493586 -393.95707) (xy 161.485574 -393.903915) (xy 161.485072 -393.877038) (xy 161.485477 -393.852345)
			(xy 161.492233 -393.803422) (xy 161.505636 -393.755889) (xy 161.525434 -393.710644) (xy 161.55125 -393.668542)
			(xy 161.566606 -393.6492) (xy 161.572094 -393.641884) (xy 161.577934 -393.624564) (xy 161.578036 -393.615418)
			(xy 161.57702 -393.58443) (xy 161.576384 -393.575365) (xy 161.569464 -393.558573) (xy 161.563558 -393.551664)
			(xy 161.544738 -393.530402) (xy 161.512919 -393.483375) (xy 161.488404 -393.432159) (xy 161.471733 -393.377882)
			(xy 161.463271 -393.321735) (xy 161.46272 -393.293346) (xy 161.02583 -393.293346) (xy 161.025283 -393.321991)
			(xy 161.016413 -393.379619) (xy 160.998885 -393.435228) (xy 160.973106 -393.487526) (xy 160.939676 -393.535297)
			(xy 160.919922 -393.556744) (xy 160.913756 -393.563821) (xy 160.906604 -393.581161) (xy 160.905952 -393.590526)
			(xy 160.904174 -393.659106) (xy 160.904324 -393.668362) (xy 160.910454 -393.685815) (xy 160.916112 -393.693142)
			(xy 160.91662 -393.69365) (xy 160.932939 -393.713279) (xy 160.96041 -393.756303) (xy 160.981512 -393.802783)
			(xy 160.995819 -393.851783) (xy 161.003042 -393.902315) (xy 161.003488 -393.927838) (xy 161.002986 -393.954715)
			(xy 160.994974 -394.00787) (xy 160.97913 -394.059236) (xy 160.955806 -394.107668) (xy 160.925525 -394.152082)
			(xy 160.888963 -394.191487) (xy 160.846935 -394.225003) (xy 160.800382 -394.25188) (xy 160.750343 -394.271519)
			(xy 160.697936 -394.28348) (xy 160.644332 -394.287498) (xy 160.590728 -394.28348) (xy 160.538321 -394.271519)
			(xy 160.488282 -394.25188) (xy 160.441729 -394.225003) (xy 160.399701 -394.191487) (xy 160.363139 -394.152082)
			(xy 160.332858 -394.107668) (xy 160.309534 -394.059236) (xy 160.29369 -394.00787) (xy 160.285678 -393.954715)
			(xy 160.285176 -393.927838) (xy 160.285642 -393.902281) (xy 160.292879 -393.851681) (xy 160.307225 -393.802621)
			(xy 160.328391 -393.756094) (xy 160.355947 -393.713043) (xy 160.372298 -393.693396) (xy 160.372552 -393.693142)
			(xy 160.378214 -393.68582) (xy 160.384326 -393.668362) (xy 160.38449 -393.659106) (xy 160.382458 -393.580874)
			(xy 160.375346 -393.563856) (xy 160.368742 -393.556744) (xy 160.349014 -393.535273) (xy 160.315573 -393.487512)
			(xy 160.289786 -393.43522) (xy 160.272252 -393.379615) (xy 160.263379 -393.32199) (xy 160.262824 -393.292838)
			(xy 159.968438 -393.292838) (xy 159.968438 -394.428218) (xy 159.968039 -394.438291) (xy 159.960302 -394.456889)
			(xy 159.953452 -394.464286) (xy 159.667702 -394.750036) (xy 159.6603 -394.756873) (xy 159.641702 -394.764593)
			(xy 159.631634 -394.765022) (xy 152.814782 -394.765022) (xy 152.804709 -394.764626) (xy 152.78611 -394.756887)
			(xy 152.778714 -394.750036) (xy 152.749758 -394.72108) (xy 152.735534 -394.713968) (xy 152.727914 -394.712698)
			(xy 152.70439 -394.708441) (xy 152.658954 -394.693585) (xy 152.616392 -394.671821) (xy 152.577747 -394.643683)
			(xy 152.560528 -394.6271) (xy 152.35555 -394.422122) (xy 152.337196 -394.402906) (xy 152.306726 -394.359379)
			(xy 152.284258 -394.311231) (xy 152.27681 -394.285724) (xy 152.244298 -394.287248) (xy 152.218627 -394.286754)
			(xy 152.167807 -394.279448) (xy 152.118545 -394.264984) (xy 152.071842 -394.243656) (xy 152.028649 -394.2159)
			(xy 151.989846 -394.18228) (xy 151.956221 -394.14348) (xy 151.928461 -394.10029) (xy 151.907129 -394.053589)
			(xy 151.89266 -394.004328) (xy 151.885348 -393.953509) (xy 151.884888 -393.927838) (xy 151.885356 -393.90227)
			(xy 151.892633 -393.851654) (xy 151.90703 -393.802586) (xy 151.928256 -393.756063) (xy 151.955878 -393.713029)
			(xy 151.972264 -393.693396) (xy 151.972518 -393.693142) (xy 151.978187 -393.685825) (xy 151.984294 -393.668363)
			(xy 151.984456 -393.659106) (xy 151.982424 -393.580874) (xy 151.975312 -393.563856) (xy 151.968708 -393.556744)
			(xy 151.948923 -393.53531) (xy 151.915432 -393.487556) (xy 151.889596 -393.435262) (xy 151.872018 -393.379645)
			(xy 151.863107 -393.322002) (xy 151.862536 -393.292838) (xy 151.862536 -392.429238) (xy 151.862962 -392.403718)
			(xy 151.869752 -392.353132) (xy 151.883229 -392.303903) (xy 151.903152 -392.256913) (xy 151.929165 -392.212999)
			(xy 151.960803 -392.172948) (xy 151.978868 -392.154918) (xy 151.985472 -392.148568) (xy 151.993346 -392.131804)
			(xy 152.000204 -392.04646) (xy 151.995124 -392.02868) (xy 151.989536 -392.021314) (xy 151.974686 -392.000566)
			(xy 151.95105 -391.955352) (xy 151.934949 -391.906941) (xy 151.926796 -391.856577) (xy 151.92629 -391.831068)
			(xy 151.92629 -391.830814) (xy 151.926726 -391.807125) (xy 151.933741 -391.760269) (xy 151.947632 -391.714974)
			(xy 151.968091 -391.672241) (xy 151.994666 -391.633018) (xy 152.026767 -391.598174) (xy 152.063685 -391.568479)
			(xy 152.1046 -391.544593) (xy 152.126442 -391.535412) (xy 152.14092 -391.52957) (xy 152.158446 -391.503916)
			(xy 152.158446 -390.815576) (xy 152.158047 -390.805503) (xy 152.15031 -390.786905) (xy 152.14346 -390.779508)
			(xy 151.928576 -390.564878) (xy 151.921181 -390.558032) (xy 151.902578 -390.550316) (xy 151.892508 -390.549892)
			(xy 151.565356 -390.549892) (xy 151.555345 -390.549448) (xy 151.53685 -390.541772) (xy 151.522699 -390.527606)
			(xy 151.515042 -390.509104) (xy 151.514556 -390.499092) (xy 151.514556 -390.284716) (xy 151.505412 -390.284716)
			(xy 151.495407 -390.284203) (xy 151.476919 -390.27655) (xy 151.462766 -390.262405) (xy 151.455103 -390.243921)
			(xy 151.454612 -390.233916) (xy 151.454612 -390.029446) (xy 151.455196 -390.007372) (xy 151.464308 -389.964174)
			(xy 151.482092 -389.923766) (xy 151.49449 -389.905494) (xy 151.499316 -389.899144) (xy 151.504142 -389.883904)
			(xy 151.504142 -389.854694) (xy 151.503783 -389.843996) (xy 151.495223 -389.824396) (xy 151.487632 -389.816848)
			(xy 151.464264 -389.795766) (xy 151.456709 -389.789628) (xy 151.438437 -389.782963) (xy 151.428704 -389.782812)
			(xy 151.419052 -389.782812) (xy 151.393656 -389.782354) (xy 151.343521 -389.774216) (xy 151.295334 -389.758157)
			(xy 151.25034 -389.734593) (xy 151.209697 -389.704129) (xy 151.174456 -389.667553) (xy 151.145523 -389.625807)
			(xy 151.123646 -389.579968) (xy 151.11603 -389.555736) (xy 151.114506 -389.549894) (xy 150.794212 -388.996174)
			(xy 150.790148 -388.991856) (xy 150.773936 -388.974155) (xy 150.746515 -388.934761) (xy 150.725375 -388.89167)
			(xy 150.711003 -388.845874) (xy 150.70373 -388.798431) (xy 150.70328 -388.774432) (xy 150.703459 -388.760384)
			(xy 150.706002 -388.732402) (xy 150.70836 -388.718552) (xy 150.709655 -388.709296) (xy 150.706255 -388.690931)
			(xy 150.701756 -388.682738) (xy 150.684992 -388.655814) (xy 150.679799 -388.648104) (xy 150.665067 -388.636784)
			(xy 150.65629 -388.633716) (xy 150.634669 -388.6269) (xy 150.593454 -388.608023) (xy 150.555332 -388.583493)
			(xy 150.521075 -388.553803) (xy 150.505922 -388.536942) (xy 150.50346 -388.534169) (xy 150.497847 -388.529323)
			(xy 150.494746 -388.52729) (xy 150.482733 -388.519189) (xy 150.462837 -388.498138) (xy 150.448823 -388.472789)
			(xy 150.44158 -388.444744) (xy 150.441152 -388.430262) (xy 150.441152 -388.418324) (xy 150.439374 -388.41172)
			(xy 150.434168 -388.391351) (xy 150.428567 -388.349683) (xy 150.428198 -388.328662) (xy 149.864318 -388.328662)
			(xy 149.864318 -388.32917) (xy 149.864147 -388.343795) (xy 149.86148 -388.372924) (xy 149.858984 -388.387336)
			(xy 149.857623 -388.39651) (xy 149.860894 -388.414752) (xy 149.865334 -388.422896) (xy 149.881844 -388.44982)
			(xy 149.887014 -388.457598) (xy 149.90174 -388.46906) (xy 149.910546 -388.472172) (xy 149.935474 -388.480295)
			(xy 149.982439 -388.503591) (xy 150.024918 -388.534316) (xy 150.061747 -388.571627) (xy 150.091916 -388.614502)
			(xy 150.114599 -388.661766) (xy 150.122382 -388.686802) (xy 150.123906 -388.692644) (xy 150.443692 -389.245602)
			(xy 150.447756 -389.24992) (xy 150.463957 -389.26763) (xy 150.49138 -389.307021) (xy 150.512522 -389.350111)
			(xy 150.526897 -389.395904) (xy 150.534172 -389.443346) (xy 150.534624 -389.467344) (xy 150.534135 -389.492806)
			(xy 150.525936 -389.543067) (xy 150.509775 -389.591359) (xy 150.48607 -389.636431) (xy 150.455437 -389.677112)
			(xy 150.41867 -389.712348) (xy 150.397972 -389.727186) (xy 150.389479 -389.73367) (xy 150.378295 -389.751848)
			(xy 150.375461 -389.773001) (xy 150.381465 -389.793482) (xy 150.395272 -389.809756) (xy 150.414501 -389.819018)
			(xy 150.42515 -389.819896) (xy 150.434802 -389.819388) (xy 150.443316 -389.818096) (xy 150.460481 -389.816696)
			(xy 150.469092 -389.816594) (xy 150.469346 -389.816848) (xy 150.768558 -389.816848) (xy 150.768812 -389.816594)
			(xy 150.789875 -389.816951) (xy 150.831236 -389.824915) (xy 150.870235 -389.840828) (xy 150.905361 -389.864073)
			(xy 150.935252 -389.89375) (xy 150.958749 -389.928708) (xy 150.974942 -389.967591) (xy 150.983203 -390.008894)
			(xy 150.983696 -390.029954) (xy 150.983696 -390.284716) (xy 150.974552 -390.284716) (xy 150.964539 -390.285149)
			(xy 150.946043 -390.292828) (xy 150.931892 -390.306997) (xy 150.924237 -390.325503) (xy 150.923752 -390.335516)
			(xy 150.923752 -390.499092) (xy 150.923373 -390.509119) (xy 150.915697 -390.527645) (xy 150.901511 -390.541819)
			(xy 150.882979 -390.549481) (xy 150.872952 -390.549892) (xy 150.364952 -390.549892) (xy 150.35494 -390.549451)
			(xy 150.336446 -390.541774) (xy 150.322294 -390.527607) (xy 150.314638 -390.509104) (xy 150.314152 -390.499092)
			(xy 150.314152 -390.284716) (xy 150.305008 -390.284716) (xy 150.295003 -390.284206) (xy 150.276514 -390.276552)
			(xy 150.262362 -390.262406) (xy 150.254699 -390.243921) (xy 150.254208 -390.233916) (xy 150.254208 -390.029954)
			(xy 150.254554 -390.012721) (xy 150.260124 -389.978708) (xy 150.271096 -389.946035) (xy 150.278846 -389.93064)
			(xy 150.284688 -389.91921) (xy 150.284434 -389.89381) (xy 150.23084 -389.796782) (xy 150.20925 -389.783066)
			(xy 150.196296 -389.78205) (xy 150.172397 -389.779955) (xy 150.125609 -389.76935) (xy 150.080968 -389.751779)
			(xy 150.039504 -389.727648) (xy 150.002175 -389.697513) (xy 149.969841 -389.662072) (xy 149.94325 -389.62214)
			(xy 149.923016 -389.578642) (xy 149.91588 -389.555736) (xy 149.914356 -389.549894) (xy 149.593808 -388.995412)
			(xy 149.589744 -388.991094) (xy 149.573639 -388.973426) (xy 149.546391 -388.934146) (xy 149.525381 -388.891206)
			(xy 149.511089 -388.845587) (xy 149.503842 -388.798334) (xy 149.503384 -388.774432) (xy 149.503563 -388.760384)
			(xy 149.506106 -388.732402) (xy 149.508464 -388.718552) (xy 149.509759 -388.709296) (xy 149.506359 -388.690931)
			(xy 149.50186 -388.682738) (xy 149.485096 -388.655814) (xy 149.479901 -388.648105) (xy 149.465171 -388.636784)
			(xy 149.456394 -388.633716) (xy 149.434773 -388.626899) (xy 149.393558 -388.608022) (xy 149.355437 -388.583492)
			(xy 149.321179 -388.553803) (xy 149.306026 -388.536942) (xy 149.303563 -388.53417) (xy 149.297951 -388.529323)
			(xy 149.29485 -388.52729) (xy 149.282816 -388.519218) (xy 149.262929 -388.498154) (xy 149.248922 -388.472796)
			(xy 149.241683 -388.444746) (xy 149.241256 -388.430262) (xy 149.241256 -388.418324) (xy 149.239478 -388.41172)
			(xy 149.234272 -388.391351) (xy 149.228671 -388.349683) (xy 149.228302 -388.328662) (xy 148.664168 -388.328662)
			(xy 148.664168 -388.32917) (xy 148.663998 -388.343795) (xy 148.661331 -388.372924) (xy 148.658834 -388.387336)
			(xy 148.657466 -388.39651) (xy 148.660741 -388.414753) (xy 148.665184 -388.422896) (xy 148.681694 -388.44982)
			(xy 148.686845 -388.457612) (xy 148.701584 -388.469067) (xy 148.710396 -388.472172) (xy 148.735276 -388.480242)
			(xy 148.782155 -388.503429) (xy 148.824567 -388.534032) (xy 148.861351 -388.571211) (xy 148.891499 -388.613948)
			(xy 148.914184 -388.661073) (xy 148.921978 -388.68604) (xy 148.923502 -388.691882) (xy 149.243796 -389.245602)
			(xy 149.24786 -389.24992) (xy 149.264062 -389.26763) (xy 149.291484 -389.307021) (xy 149.312626 -389.35011)
			(xy 149.327001 -389.395904) (xy 149.334276 -389.443346) (xy 149.334728 -389.467344) (xy 149.334237 -389.492806)
			(xy 149.326038 -389.543067) (xy 149.309877 -389.591359) (xy 149.286173 -389.636431) (xy 149.25554 -389.677112)
			(xy 149.218774 -389.712348) (xy 149.198076 -389.727186) (xy 149.189581 -389.733669) (xy 149.178396 -389.751847)
			(xy 149.175561 -389.773001) (xy 149.181566 -389.793483) (xy 149.195374 -389.809758) (xy 149.214604 -389.819019)
			(xy 149.225254 -389.819896) (xy 149.234906 -389.819388) (xy 149.24342 -389.818095) (xy 149.260585 -389.816696)
			(xy 149.269196 -389.816594) (xy 149.26945 -389.816848) (xy 149.568662 -389.816848) (xy 149.568916 -389.816594)
			(xy 149.589979 -389.816947) (xy 149.631341 -389.824912) (xy 149.67034 -389.840826) (xy 149.705465 -389.864072)
			(xy 149.735356 -389.893749) (xy 149.758853 -389.928707) (xy 149.775046 -389.967591) (xy 149.783307 -390.008894)
			(xy 149.7838 -390.029954) (xy 149.7838 -390.284716) (xy 149.774656 -390.284716) (xy 149.764644 -390.285153)
			(xy 149.746148 -390.29283) (xy 149.731996 -390.306998) (xy 149.724341 -390.325503) (xy 149.723856 -390.335516)
			(xy 149.723856 -390.499092) (xy 149.723473 -390.509118) (xy 149.715797 -390.527643) (xy 149.701613 -390.541818)
			(xy 149.683083 -390.54948) (xy 149.673056 -390.549892) (xy 149.165056 -390.549892) (xy 149.155045 -390.549448)
			(xy 149.13655 -390.541772) (xy 149.122399 -390.527606) (xy 149.114742 -390.509104) (xy 149.114256 -390.499092)
			(xy 149.114256 -390.284716) (xy 149.105112 -390.284716) (xy 149.095107 -390.284203) (xy 149.076619 -390.27655)
			(xy 149.062466 -390.262405) (xy 149.054803 -390.243921) (xy 149.054312 -390.233916) (xy 149.054312 -390.029954)
			(xy 149.054658 -390.012721) (xy 149.060228 -389.978708) (xy 149.0712 -389.946035) (xy 149.07895 -389.93064)
			(xy 149.084792 -389.91921) (xy 149.084538 -389.89381) (xy 149.030944 -389.796782) (xy 149.009354 -389.783066)
			(xy 148.9964 -389.78205) (xy 148.972501 -389.779951) (xy 148.925714 -389.769347) (xy 148.881072 -389.751777)
			(xy 148.839608 -389.727646) (xy 148.802279 -389.697512) (xy 148.769945 -389.662071) (xy 148.743355 -389.62214)
			(xy 148.72312 -389.578642) (xy 148.715984 -389.555736) (xy 148.71446 -389.549894) (xy 148.394166 -388.996174)
			(xy 148.390102 -388.991856) (xy 148.373951 -388.974115) (xy 148.34658 -388.934716) (xy 148.325487 -388.891628)
			(xy 148.311157 -388.845844) (xy 148.303922 -388.798419) (xy 148.303488 -388.774432) (xy 148.303669 -388.760384)
			(xy 148.30621 -388.732402) (xy 148.308568 -388.718552) (xy 148.309895 -388.709273) (xy 148.306365 -388.690875)
			(xy 148.30171 -388.682738) (xy 148.284946 -388.655814) (xy 148.279734 -388.648118) (xy 148.265016 -388.636791)
			(xy 148.256244 -388.633716) (xy 148.234617 -388.626918) (xy 148.193403 -388.608036) (xy 148.155283 -388.5835)
			(xy 148.121027 -388.553806) (xy 148.105876 -388.536942) (xy 148.103407 -388.534175) (xy 148.097799 -388.529325)
			(xy 148.0947 -388.52729) (xy 148.082649 -388.519214) (xy 148.062688 -388.498178) (xy 148.048609 -388.472825)
			(xy 148.041306 -388.444761) (xy 148.040852 -388.430262) (xy 148.040852 -388.418324) (xy 148.039328 -388.41172)
			(xy 148.034121 -388.391351) (xy 148.028521 -388.349683) (xy 148.028152 -388.328662) (xy 147.464272 -388.328662)
			(xy 147.464272 -388.32917) (xy 147.464102 -388.343795) (xy 147.461435 -388.372924) (xy 147.458938 -388.387336)
			(xy 147.457569 -388.39651) (xy 147.460844 -388.414753) (xy 147.465288 -388.422896) (xy 147.481798 -388.44982)
			(xy 147.486948 -388.457613) (xy 147.501688 -388.469068) (xy 147.5105 -388.472172) (xy 147.53538 -388.480239)
			(xy 147.58226 -388.503428) (xy 147.624672 -388.534031) (xy 147.661456 -388.57121) (xy 147.691603 -388.613948)
			(xy 147.714288 -388.661073) (xy 147.722082 -388.68604) (xy 147.723606 -388.691882) (xy 148.0439 -389.245602)
			(xy 148.047964 -389.24992) (xy 148.064166 -389.267629) (xy 148.091588 -389.307021) (xy 148.11273 -389.35011)
			(xy 148.127105 -389.395904) (xy 148.13438 -389.443346) (xy 148.134832 -389.467344) (xy 148.134339 -389.492806)
			(xy 148.126141 -389.543066) (xy 148.10998 -389.591359) (xy 148.086276 -389.63643) (xy 148.055643 -389.677112)
			(xy 148.018877 -389.712347) (xy 147.99818 -389.727186) (xy 147.989692 -389.733645) (xy 147.97851 -389.751782)
			(xy 147.975645 -389.772895) (xy 147.981588 -389.793356) (xy 147.995319 -389.809648) (xy 148.014477 -389.818972)
			(xy 148.025104 -389.819896) (xy 148.03501 -389.819388) (xy 148.043461 -389.818103) (xy 148.060499 -389.816703)
			(xy 148.069046 -389.816594) (xy 148.0693 -389.816848) (xy 148.368512 -389.816848) (xy 148.368766 -389.816594)
			(xy 148.389813 -389.816973) (xy 148.431135 -389.824974) (xy 148.47009 -389.84091) (xy 148.505172 -389.864164)
			(xy 148.535022 -389.893836) (xy 148.558486 -389.928778) (xy 148.574656 -389.967637) (xy 148.582904 -390.00891)
			(xy 148.583396 -390.029954) (xy 148.583396 -390.284716) (xy 148.574252 -390.284716) (xy 148.564239 -390.285149)
			(xy 148.545743 -390.292828) (xy 148.531592 -390.306997) (xy 148.523937 -390.325503) (xy 148.523452 -390.335516)
			(xy 148.523452 -390.499092) (xy 148.523073 -390.509119) (xy 148.515397 -390.527645) (xy 148.501211 -390.541819)
			(xy 148.482679 -390.549481) (xy 148.472652 -390.549892) (xy 147.96516 -390.549892) (xy 147.955149 -390.549444)
			(xy 147.936655 -390.54177) (xy 147.922503 -390.527605) (xy 147.914846 -390.509104) (xy 147.91436 -390.499092)
			(xy 147.91436 -390.335516) (xy 147.913967 -390.325491) (xy 147.906294 -390.306966) (xy 147.892113 -390.292792)
			(xy 147.873585 -390.285129) (xy 147.86356 -390.284716) (xy 147.854416 -390.284716) (xy 147.854416 -390.029446)
			(xy 147.8552 -390.003724) (xy 147.867533 -389.953777) (xy 147.8788 -389.93064) (xy 147.884642 -389.91921)
			(xy 147.884388 -389.89381) (xy 147.83689 -389.808212) (xy 147.830156 -389.797443) (xy 147.808842 -389.7837)
			(xy 147.79625 -389.78205) (xy 147.772379 -389.779843) (xy 147.725636 -389.769217) (xy 147.681039 -389.751639)
			(xy 147.639617 -389.727513) (xy 147.602325 -389.697395) (xy 147.570021 -389.661979) (xy 147.54345 -389.622081)
			(xy 147.523224 -389.578621) (xy 147.516088 -389.555736) (xy 147.514564 -389.549894) (xy 147.19427 -388.996174)
			(xy 147.190206 -388.991856) (xy 147.174039 -388.974129) (xy 147.146673 -388.934724) (xy 147.125585 -388.891633)
			(xy 147.111259 -388.845846) (xy 147.104026 -388.79842) (xy 147.103592 -388.774432) (xy 147.103773 -388.760384)
			(xy 147.106314 -388.732402) (xy 147.108672 -388.718552) (xy 147.109998 -388.709273) (xy 147.106469 -388.690875)
			(xy 147.101814 -388.682738) (xy 147.08505 -388.655814) (xy 147.079836 -388.648119) (xy 147.065119 -388.636791)
			(xy 147.056348 -388.633716) (xy 147.034721 -388.626917) (xy 146.993507 -388.608035) (xy 146.955387 -388.583499)
			(xy 146.921131 -388.553806) (xy 146.90598 -388.536942) (xy 146.903511 -388.534176) (xy 146.897903 -388.529325)
			(xy 146.894804 -388.52729) (xy 146.882754 -388.519213) (xy 146.862792 -388.498178) (xy 146.848714 -388.472825)
			(xy 146.84141 -388.444761) (xy 146.840956 -388.430262) (xy 146.840956 -388.418324) (xy 146.839432 -388.41172)
			(xy 146.834225 -388.391351) (xy 146.828625 -388.349683) (xy 146.828256 -388.328662) (xy 145.061912 -388.328662)
			(xy 145.05522 -388.371845) (xy 145.04797 -388.396226) (xy 145.045684 -388.403846) (xy 145.045684 -388.494778)
			(xy 145.045094 -388.511435) (xy 145.036488 -388.543619) (xy 145.019856 -388.572484) (xy 144.996328 -388.596069)
			(xy 144.967502 -388.61277) (xy 144.93534 -388.621453) (xy 144.918684 -388.622032) (xy 144.788382 -388.622032)
			(xy 144.784572 -388.622794) (xy 144.771767 -388.624699) (xy 144.745956 -388.626735) (xy 144.73301 -388.626858)
			(xy 144.732502 -388.626858) (xy 144.719557 -388.626721) (xy 144.693747 -388.624685) (xy 144.68094 -388.622794)
			(xy 144.67713 -388.622032) (xy 144.537176 -388.622032) (xy 144.520483 -388.621487) (xy 144.488233 -388.612852)
			(xy 144.45931 -388.596177) (xy 144.435679 -388.572593) (xy 144.418945 -388.543703) (xy 144.410247 -388.51147)
			(xy 144.409668 -388.494778) (xy 144.409668 -388.367524) (xy 144.408652 -388.362444) (xy 144.405544 -388.346047)
			(xy 144.402233 -388.312838) (xy 144.402048 -388.29615) (xy 144.20009 -388.29615) (xy 144.200118 -388.297674)
			(xy 144.199609 -388.32556) (xy 144.191489 -388.380736) (xy 144.175421 -388.434143) (xy 144.151749 -388.48464)
			(xy 144.120976 -388.531153) (xy 144.083759 -388.57269) (xy 144.040891 -388.608365) (xy 143.993285 -388.637419)
			(xy 143.941956 -388.659231) (xy 143.887999 -388.673337) (xy 143.832562 -388.679437) (xy 143.776828 -388.6774)
			(xy 143.721985 -388.66727) (xy 143.669201 -388.649263) (xy 143.619601 -388.623762) (xy 143.574243 -388.591311)
			(xy 143.534094 -388.552602) (xy 143.500008 -388.508459) (xy 143.472712 -388.459824) (xy 143.452789 -388.407733)
			(xy 143.440663 -388.353296) (xy 143.436592 -388.297674) (xy 142.361666 -388.297674) (xy 142.361666 -388.353554)
			(xy 142.362151 -388.3643) (xy 142.370973 -388.383898) (xy 142.378684 -388.3914) (xy 142.402997 -388.413747)
			(xy 142.446225 -388.463669) (xy 142.48263 -388.518765) (xy 142.511601 -388.578108) (xy 142.53265 -388.640701)
			(xy 142.545423 -388.705491) (xy 142.549705 -388.771389) (xy 142.545425 -388.837288) (xy 142.532655 -388.902078)
			(xy 142.511609 -388.964672) (xy 142.482641 -389.024016) (xy 142.446238 -389.079114) (xy 142.403012 -389.129038)
			(xy 142.378684 -389.151368) (xy 142.371059 -389.158932) (xy 142.362247 -389.178491) (xy 142.361666 -389.189214)
			(xy 142.361666 -390.626092) (xy 144.390364 -390.626092) (xy 144.390783 -390.602859) (xy 144.397277 -390.556849)
			(xy 144.410148 -390.512202) (xy 144.429145 -390.469797) (xy 144.453892 -390.43047) (xy 144.468596 -390.412478)
			(xy 144.474438 -390.40562) (xy 144.480788 -390.388602) (xy 144.480788 -390.304782) (xy 144.474438 -390.287764)
			(xy 144.468596 -390.280906) (xy 144.453875 -390.262926) (xy 144.429131 -390.223594) (xy 144.410134 -390.181186)
			(xy 144.397258 -390.136538) (xy 144.390757 -390.090526) (xy 144.390364 -390.067292) (xy 144.390874 -390.041305)
			(xy 144.399004 -389.98997) (xy 144.415065 -389.94054) (xy 144.438661 -389.89423) (xy 144.469211 -389.852182)
			(xy 144.505962 -389.815431) (xy 144.54801 -389.784881) (xy 144.59432 -389.761285) (xy 144.64375 -389.745224)
			(xy 144.695085 -389.737094) (xy 144.747059 -389.737094) (xy 144.798394 -389.745224) (xy 144.847824 -389.761285)
			(xy 144.894134 -389.784881) (xy 144.936182 -389.815431) (xy 144.972933 -389.852182) (xy 145.003483 -389.89423)
			(xy 145.027079 -389.94054) (xy 145.04314 -389.98997) (xy 145.05127 -390.041305) (xy 145.05178 -390.067292)
			(xy 145.051423 -390.090527) (xy 145.044917 -390.13654) (xy 145.032031 -390.181188) (xy 145.013021 -390.223593)
			(xy 145.006521 -390.233916) (xy 146.654012 -390.233916) (xy 146.654012 -390.029954) (xy 146.654573 -390.008895)
			(xy 146.662817 -389.967592) (xy 146.678995 -389.928706) (xy 146.702481 -389.893745) (xy 146.732363 -389.864064)
			(xy 146.767482 -389.840815) (xy 146.806477 -389.8249) (xy 146.847834 -389.816936) (xy 146.868896 -389.816594)
			(xy 146.86915 -389.816848) (xy 147.168362 -389.816848) (xy 147.168616 -389.816594) (xy 147.189679 -389.816947)
			(xy 147.231041 -389.824912) (xy 147.27004 -389.840826) (xy 147.305165 -389.864072) (xy 147.335056 -389.893749)
			(xy 147.358553 -389.928707) (xy 147.374746 -389.967591) (xy 147.383007 -390.008894) (xy 147.3835 -390.029954)
			(xy 147.3835 -390.284716) (xy 147.374356 -390.284716) (xy 147.364344 -390.285153) (xy 147.345848 -390.29283)
			(xy 147.331696 -390.306998) (xy 147.324041 -390.325503) (xy 147.323556 -390.335516) (xy 147.323556 -390.499092)
			(xy 147.323173 -390.509118) (xy 147.315497 -390.527643) (xy 147.301313 -390.541818) (xy 147.282783 -390.54948)
			(xy 147.272756 -390.549892) (xy 146.764756 -390.549892) (xy 146.754745 -390.549448) (xy 146.73625 -390.541772)
			(xy 146.722099 -390.527606) (xy 146.714442 -390.509104) (xy 146.713956 -390.499092) (xy 146.713956 -390.284716)
			(xy 146.704812 -390.284716) (xy 146.694807 -390.284203) (xy 146.676319 -390.27655) (xy 146.662166 -390.262405)
			(xy 146.654503 -390.243921) (xy 146.654012 -390.233916) (xy 145.006521 -390.233916) (xy 144.988259 -390.262917)
			(xy 144.973548 -390.280906) (xy 144.967706 -390.287764) (xy 144.961356 -390.304782) (xy 144.961356 -390.388602)
			(xy 144.967706 -390.40562) (xy 144.973548 -390.412478) (xy 144.988253 -390.43047) (xy 145.013001 -390.469798)
			(xy 145.032002 -390.512203) (xy 145.044882 -390.556849) (xy 145.051386 -390.602859) (xy 145.05178 -390.626092)
			(xy 145.05178 -390.626346) (xy 145.051353 -390.650396) (xy 145.044361 -390.697986) (xy 145.030562 -390.744065)
			(xy 145.020792 -390.766046) (xy 145.015458 -390.777476) (xy 145.016728 -390.802622) (xy 145.066512 -390.88568)
			(xy 145.073441 -390.89605) (xy 145.094753 -390.908957) (xy 145.107152 -390.910318) (xy 145.132148 -390.912171)
			(xy 145.181192 -390.922501) (xy 145.228116 -390.940114) (xy 145.271845 -390.964605) (xy 145.311377 -390.995415)
			(xy 145.345808 -391.031837) (xy 145.374349 -391.073037) (xy 145.396346 -391.118072) (xy 145.411296 -391.165911)
			(xy 145.418856 -391.215458) (xy 145.419318 -391.240518) (xy 145.418808 -391.266505) (xy 145.410678 -391.31784)
			(xy 145.394617 -391.36727) (xy 145.371021 -391.41358) (xy 145.340471 -391.455628) (xy 145.30372 -391.492379)
			(xy 145.261672 -391.522929) (xy 145.215362 -391.546525) (xy 145.165932 -391.562586) (xy 145.114597 -391.570716)
			(xy 145.062623 -391.570716) (xy 145.011288 -391.562586) (xy 144.961858 -391.546525) (xy 144.915548 -391.522929)
			(xy 144.8735 -391.492379) (xy 144.836749 -391.455628) (xy 144.806199 -391.41358) (xy 144.782603 -391.36727)
			(xy 144.766542 -391.31784) (xy 144.758412 -391.266505) (xy 144.757902 -391.240518) (xy 144.757902 -391.240264)
			(xy 144.758334 -391.216214) (xy 144.765324 -391.168624) (xy 144.779122 -391.122545) (xy 144.78889 -391.100564)
			(xy 144.794224 -391.089134) (xy 144.792954 -391.063988) (xy 144.74317 -390.98093) (xy 144.736198 -390.970595)
			(xy 144.714918 -390.95767) (xy 144.70253 -390.956292) (xy 144.677534 -390.954445) (xy 144.62849 -390.944112)
			(xy 144.581567 -390.926498) (xy 144.537839 -390.902005) (xy 144.498307 -390.871195) (xy 144.463876 -390.834773)
			(xy 144.435336 -390.793573) (xy 144.413338 -390.748537) (xy 144.398388 -390.700699) (xy 144.390826 -390.651152)
			(xy 144.390364 -390.626092) (xy 142.361666 -390.626092) (xy 142.361666 -391.146284) (xy 142.361227 -391.156347)
			(xy 142.353487 -391.174926) (xy 142.34668 -391.182352) (xy 142.145512 -391.38352) (xy 142.138118 -391.390377)
			(xy 142.119519 -391.398129) (xy 142.109444 -391.398506) (xy 141.800326 -391.398506) (xy 141.790262 -391.398943)
			(xy 141.771678 -391.406677) (xy 141.764258 -391.413492) (xy 141.705838 -391.472166) (xy 141.698438 -391.479006)
			(xy 141.679839 -391.486724) (xy 141.66977 -391.487152) (xy 140.840206 -391.487152) (xy 140.830178 -391.487599)
			(xy 140.811618 -391.495189) (xy 140.804138 -391.501884) (xy 140.78839 -391.517632) (xy 140.781539 -391.525028)
			(xy 140.773802 -391.543627) (xy 140.773404 -391.5537) (xy 140.773404 -392.251946) (xy 143.690848 -392.251946)
			(xy 143.691334 -392.224695) (xy 143.69909 -392.170747) (xy 143.714445 -392.118452) (xy 143.737087 -392.068875)
			(xy 143.766553 -392.023025) (xy 143.802244 -391.981834) (xy 143.843435 -391.946143) (xy 143.889285 -391.916677)
			(xy 143.938862 -391.894035) (xy 143.991157 -391.87868) (xy 144.045105 -391.870924) (xy 144.099607 -391.870924)
			(xy 144.09976 -391.870946) (xy 145.75028 -391.870946) (xy 145.75028 -391.616184) (xy 145.759424 -391.616184)
			(xy 145.769435 -391.615731) (xy 145.787931 -391.608061) (xy 145.802083 -391.593897) (xy 145.809739 -391.575396)
			(xy 145.810224 -391.565384) (xy 145.810224 -391.401808) (xy 145.810627 -391.391784) (xy 145.818298 -391.373263)
			(xy 145.832476 -391.359089) (xy 145.851 -391.351423) (xy 145.861024 -391.351008) (xy 146.369024 -391.351008)
			(xy 146.379034 -391.351468) (xy 146.397528 -391.359137) (xy 146.411681 -391.373299) (xy 146.419338 -391.391797)
			(xy 146.419824 -391.401808) (xy 146.419824 -391.616184) (xy 146.428968 -391.616184) (xy 146.438985 -391.616645)
			(xy 146.457498 -391.624302) (xy 146.471671 -391.638461) (xy 146.479345 -391.656967) (xy 146.479768 -391.666984)
			(xy 146.479768 -391.870946) (xy 146.479201 -391.893553) (xy 146.469679 -391.937753) (xy 146.451071 -391.978961)
			(xy 146.42421 -392.015331) (xy 146.407632 -392.030712) (xy 146.400774 -392.036808) (xy 146.392138 -392.05281)
			(xy 146.381978 -392.12774) (xy 146.381111 -392.136623) (xy 146.384867 -392.154056) (xy 146.389344 -392.161776)
			(xy 146.389598 -392.161776) (xy 146.389598 -392.162284) (xy 146.401644 -392.181652) (xy 146.420713 -392.223082)
			(xy 146.433665 -392.266813) (xy 146.440234 -392.311946) (xy 146.440652 -392.33475) (xy 146.440162 -392.359739)
			(xy 146.432343 -392.409102) (xy 146.416899 -392.456634) (xy 146.394209 -392.501166) (xy 146.364833 -392.541599)
			(xy 146.329493 -392.576939) (xy 146.28906 -392.606315) (xy 146.244528 -392.629005) (xy 146.196996 -392.644449)
			(xy 146.147633 -392.652268) (xy 146.097655 -392.652268) (xy 146.048292 -392.644449) (xy 146.00076 -392.629005)
			(xy 145.956228 -392.606315) (xy 145.915795 -392.576939) (xy 145.880455 -392.541599) (xy 145.851079 -392.501166)
			(xy 145.828389 -392.456634) (xy 145.812945 -392.409102) (xy 145.805126 -392.359739) (xy 145.804636 -392.33475)
			(xy 145.80531 -392.305549) (xy 145.815961 -392.248126) (xy 145.836913 -392.193612) (xy 145.851626 -392.16838)
			(xy 145.856096 -392.160384) (xy 145.859613 -392.142419) (xy 145.858484 -392.133328) (xy 145.84553 -392.05789)
			(xy 145.83664 -392.042396) (xy 145.829528 -392.036554) (xy 145.82902 -392.036046) (xy 145.814584 -392.023815)
			(xy 145.789918 -391.995127) (xy 145.770685 -391.962546) (xy 145.757487 -391.927089) (xy 145.750733 -391.889862)
			(xy 145.75028 -391.870946) (xy 144.09976 -391.870946) (xy 144.153555 -391.87868) (xy 144.20585 -391.894035)
			(xy 144.255427 -391.916677) (xy 144.301277 -391.946143) (xy 144.342468 -391.981834) (xy 144.378159 -392.023025)
			(xy 144.407625 -392.068875) (xy 144.430267 -392.118452) (xy 144.445622 -392.170747) (xy 144.453378 -392.224695)
			(xy 144.453864 -392.251946) (xy 144.452594 -392.284204) (xy 144.451832 -392.293602) (xy 144.456912 -392.31189)
			(xy 144.504664 -392.373866) (xy 144.510744 -392.381024) (xy 144.526757 -392.390802) (xy 144.535906 -392.392916)
			(xy 144.53616 -392.392916) (xy 144.562314 -392.398009) (xy 144.612988 -392.414476) (xy 144.660877 -392.437834)
			(xy 144.705049 -392.46763) (xy 144.744645 -392.503283) (xy 144.778894 -392.544099) (xy 144.80713 -392.589285)
			(xy 144.828803 -392.63796) (xy 144.843491 -392.689178) (xy 144.850908 -392.741941) (xy 144.851374 -392.768582)
			(xy 144.850888 -392.795833) (xy 144.843132 -392.849781) (xy 144.827777 -392.902076) (xy 144.805135 -392.951653)
			(xy 144.775669 -392.997503) (xy 144.739978 -393.038694) (xy 144.698787 -393.074385) (xy 144.652937 -393.103851)
			(xy 144.60336 -393.126493) (xy 144.551065 -393.141848) (xy 144.497117 -393.149604) (xy 144.442615 -393.149604)
			(xy 144.388667 -393.141848) (xy 144.336372 -393.126493) (xy 144.286795 -393.103851) (xy 144.240945 -393.074385)
			(xy 144.199754 -393.038694) (xy 144.164063 -392.997503) (xy 144.134597 -392.951653) (xy 144.111955 -392.902076)
			(xy 144.0966 -392.849781) (xy 144.088844 -392.795833) (xy 144.088358 -392.768582) (xy 144.089628 -392.736324)
			(xy 144.09039 -392.726926) (xy 144.08531 -392.708638) (xy 144.037558 -392.646662) (xy 144.0315 -392.639482)
			(xy 144.015472 -392.629715) (xy 144.006316 -392.627612) (xy 144.006062 -392.627612) (xy 143.979891 -392.622591)
			(xy 143.92921 -392.606122) (xy 143.881314 -392.582759) (xy 143.837136 -392.552957) (xy 143.797536 -392.517297)
			(xy 143.763285 -392.476471) (xy 143.73505 -392.431276) (xy 143.71338 -392.382591) (xy 143.698697 -392.331364)
			(xy 143.691288 -392.278591) (xy 143.690848 -392.251946) (xy 140.773404 -392.251946) (xy 140.773404 -392.661902)
			(xy 140.773828 -392.671972) (xy 140.781543 -392.690575) (xy 140.78839 -392.69797) (xy 140.926566 -392.835892)
			(xy 140.933417 -392.843289) (xy 140.94116 -392.861887) (xy 140.941552 -392.87196) (xy 140.941552 -393.292838)
			(xy 147.062444 -393.292838) (xy 147.062444 -392.429238) (xy 147.062868 -392.403718) (xy 147.069658 -392.353132)
			(xy 147.083135 -392.303903) (xy 147.103058 -392.256912) (xy 147.129072 -392.212999) (xy 147.160711 -392.172948)
			(xy 147.178776 -392.154918) (xy 147.18538 -392.148568) (xy 147.193254 -392.131804) (xy 147.200112 -392.04646)
			(xy 147.195032 -392.02868) (xy 147.189444 -392.021314) (xy 147.174595 -392.000565) (xy 147.150959 -391.955352)
			(xy 147.134857 -391.90694) (xy 147.126704 -391.856577) (xy 147.126198 -391.831068) (xy 147.126198 -391.830814)
			(xy 147.126688 -391.805825) (xy 147.134507 -391.756462) (xy 147.149951 -391.70893) (xy 147.172641 -391.664398)
			(xy 147.202017 -391.623965) (xy 147.237357 -391.588625) (xy 147.27779 -391.559249) (xy 147.322322 -391.536559)
			(xy 147.369854 -391.521115) (xy 147.419217 -391.513296) (xy 147.469195 -391.513296) (xy 147.518558 -391.521115)
			(xy 147.56609 -391.536559) (xy 147.610622 -391.559249) (xy 147.651055 -391.588625) (xy 147.686395 -391.623965)
			(xy 147.715771 -391.664398) (xy 147.738461 -391.70893) (xy 147.753905 -391.756462) (xy 147.761724 -391.805825)
			(xy 147.762214 -391.830814) (xy 147.762214 -391.831068) (xy 147.761718 -391.856577) (xy 147.753541 -391.906936)
			(xy 147.73744 -391.955347) (xy 147.713826 -392.000572) (xy 147.698968 -392.021314) (xy 147.69338 -392.02868)
			(xy 147.6883 -392.04646) (xy 147.695158 -392.131804) (xy 147.703032 -392.148568) (xy 147.709636 -392.154918)
			(xy 147.727667 -392.17298) (xy 147.759298 -392.21303) (xy 147.78531 -392.256939) (xy 147.805239 -392.303922)
			(xy 147.818728 -392.353142) (xy 147.825538 -392.403721) (xy 147.825968 -392.429238) (xy 147.825968 -393.292838)
			(xy 148.26234 -393.292838) (xy 148.26234 -392.429238) (xy 148.262765 -392.403718) (xy 148.269555 -392.353132)
			(xy 148.283032 -392.303903) (xy 148.302955 -392.256912) (xy 148.328968 -392.212999) (xy 148.360607 -392.172948)
			(xy 148.378672 -392.154918) (xy 148.38553 -392.148568) (xy 148.393404 -392.131804) (xy 148.3995 -392.05535)
			(xy 148.399847 -392.046285) (xy 148.394905 -392.028845) (xy 148.389848 -392.021314) (xy 148.389594 -392.02106)
			(xy 148.374733 -392.000319) (xy 148.351107 -391.9551) (xy 148.33501 -391.906687) (xy 148.326856 -391.856324)
			(xy 148.326348 -391.830814) (xy 148.326838 -391.805825) (xy 148.334657 -391.756462) (xy 148.350101 -391.70893)
			(xy 148.372791 -391.664398) (xy 148.402167 -391.623965) (xy 148.437507 -391.588625) (xy 148.47794 -391.559249)
			(xy 148.522472 -391.536559) (xy 148.570004 -391.521115) (xy 148.619367 -391.513296) (xy 148.669345 -391.513296)
			(xy 148.718708 -391.521115) (xy 148.76624 -391.536559) (xy 148.810772 -391.559249) (xy 148.851205 -391.588625)
			(xy 148.886545 -391.623965) (xy 148.915921 -391.664398) (xy 148.938611 -391.70893) (xy 148.954055 -391.756462)
			(xy 148.961874 -391.805825) (xy 148.962364 -391.830814) (xy 148.961847 -391.856367) (xy 148.95366 -391.906812)
			(xy 148.9375 -391.955295) (xy 148.913785 -392.000564) (xy 148.898864 -392.021314) (xy 148.893276 -392.02868)
			(xy 148.888196 -392.04646) (xy 148.894292 -392.122914) (xy 148.895395 -392.131912) (xy 148.903063 -392.14832)
			(xy 148.909278 -392.154918) (xy 148.909532 -392.155172) (xy 148.927585 -392.173184) (xy 148.959199 -392.213201)
			(xy 148.985199 -392.257073) (xy 149.005122 -392.304018) (xy 149.018611 -392.353199) (xy 149.025428 -392.403739)
			(xy 149.025864 -392.429238) (xy 149.025864 -393.292838) (xy 149.462744 -393.292838) (xy 149.462744 -392.42873)
			(xy 149.463171 -392.403262) (xy 149.469974 -392.352781) (xy 149.483437 -392.303655) (xy 149.503319 -392.256759)
			(xy 149.529267 -392.212926) (xy 149.560819 -392.172938) (xy 149.578822 -392.154918) (xy 149.585426 -392.148568)
			(xy 149.5933 -392.131804) (xy 149.600158 -392.04646) (xy 149.595078 -392.02868) (xy 149.58949 -392.021314)
			(xy 149.574634 -392.00057) (xy 149.551001 -391.955354) (xy 149.534902 -391.906941) (xy 149.52675 -391.856578)
			(xy 149.526244 -391.831068) (xy 149.526244 -391.830814) (xy 149.526734 -391.805825) (xy 149.534553 -391.756462)
			(xy 149.549997 -391.70893) (xy 149.572687 -391.664398) (xy 149.602063 -391.623965) (xy 149.637403 -391.588625)
			(xy 149.677836 -391.559249) (xy 149.722368 -391.536559) (xy 149.7699 -391.521115) (xy 149.819263 -391.513296)
			(xy 149.869241 -391.513296) (xy 149.918604 -391.521115) (xy 149.966136 -391.536559) (xy 150.010668 -391.559249)
			(xy 150.051101 -391.588625) (xy 150.086441 -391.623965) (xy 150.115817 -391.664398) (xy 150.138507 -391.70893)
			(xy 150.153951 -391.756462) (xy 150.16177 -391.805825) (xy 150.16226 -391.830814) (xy 150.16226 -391.831068)
			(xy 150.161755 -391.856576) (xy 150.15358 -391.906935) (xy 150.137481 -391.955346) (xy 150.11387 -392.000571)
			(xy 150.099014 -392.021314) (xy 150.093426 -392.02868) (xy 150.088346 -392.04646) (xy 150.095204 -392.131804)
			(xy 150.103078 -392.148568) (xy 150.109682 -392.154918) (xy 150.127686 -392.172935) (xy 150.159226 -392.21293)
			(xy 150.185166 -392.256766) (xy 150.205044 -392.303662) (xy 150.218509 -392.352785) (xy 150.225319 -392.403263)
			(xy 150.22576 -392.42873) (xy 150.22576 -393.292838) (xy 150.225751 -393.293346) (xy 150.66264 -393.293346)
			(xy 150.66264 -392.42873) (xy 150.663068 -392.403262) (xy 150.669871 -392.352781) (xy 150.683334 -392.303655)
			(xy 150.703216 -392.256759) (xy 150.729164 -392.212926) (xy 150.760715 -392.172938) (xy 150.778718 -392.154918)
			(xy 150.785322 -392.148568) (xy 150.793196 -392.131804) (xy 150.800054 -392.04646) (xy 150.794974 -392.02868)
			(xy 150.789386 -392.021314) (xy 150.77453 -392.00057) (xy 150.750897 -391.955354) (xy 150.734798 -391.906942)
			(xy 150.726646 -391.856578) (xy 150.72614 -391.831068) (xy 150.72614 -391.830814) (xy 150.72663 -391.805825)
			(xy 150.734449 -391.756462) (xy 150.749893 -391.70893) (xy 150.772583 -391.664398) (xy 150.801959 -391.623965)
			(xy 150.837299 -391.588625) (xy 150.877732 -391.559249) (xy 150.922264 -391.536559) (xy 150.969796 -391.521115)
			(xy 151.019159 -391.513296) (xy 151.069137 -391.513296) (xy 151.1185 -391.521115) (xy 151.166032 -391.536559)
			(xy 151.210564 -391.559249) (xy 151.250997 -391.588625) (xy 151.286337 -391.623965) (xy 151.315713 -391.664398)
			(xy 151.338403 -391.70893) (xy 151.353847 -391.756462) (xy 151.361666 -391.805825) (xy 151.362156 -391.830814)
			(xy 151.362156 -391.831068) (xy 151.361652 -391.856576) (xy 151.353476 -391.906935) (xy 151.337377 -391.955346)
			(xy 151.313766 -392.000571) (xy 151.29891 -392.021314) (xy 151.293322 -392.02868) (xy 151.288242 -392.04646)
			(xy 151.2951 -392.131804) (xy 151.302974 -392.148568) (xy 151.309578 -392.154918) (xy 151.327582 -392.172936)
			(xy 151.359122 -392.212931) (xy 151.385061 -392.256766) (xy 151.40494 -392.303662) (xy 151.418405 -392.352785)
			(xy 151.425215 -392.403263) (xy 151.425656 -392.42873) (xy 151.425656 -393.293346) (xy 151.425179 -393.321744)
			(xy 151.416766 -393.377912) (xy 151.400104 -393.432208) (xy 151.375562 -393.483427) (xy 151.343685 -393.530433)
			(xy 151.324818 -393.551664) (xy 151.318959 -393.558601) (xy 151.31205 -393.575378) (xy 151.311356 -393.58443)
			(xy 151.31034 -393.615418) (xy 151.310385 -393.62457) (xy 151.316259 -393.641892) (xy 151.32177 -393.6492)
			(xy 151.337115 -393.668547) (xy 151.362888 -393.710667) (xy 151.382666 -393.755914) (xy 151.396078 -393.803438)
			(xy 151.402873 -393.852348) (xy 151.403304 -393.877038) (xy 151.402802 -393.903915) (xy 151.39479 -393.95707)
			(xy 151.378946 -394.008436) (xy 151.355622 -394.056868) (xy 151.325341 -394.101282) (xy 151.288779 -394.140687)
			(xy 151.246751 -394.174203) (xy 151.200198 -394.20108) (xy 151.150159 -394.220719) (xy 151.097752 -394.23268)
			(xy 151.044148 -394.236698) (xy 150.990544 -394.23268) (xy 150.938137 -394.220719) (xy 150.888098 -394.20108)
			(xy 150.841545 -394.174203) (xy 150.799517 -394.140687) (xy 150.762955 -394.101282) (xy 150.732674 -394.056868)
			(xy 150.70935 -394.008436) (xy 150.693506 -393.95707) (xy 150.685494 -393.903915) (xy 150.684992 -393.877038)
			(xy 150.685393 -393.852344) (xy 150.692149 -393.803422) (xy 150.705553 -393.755888) (xy 150.725351 -393.710643)
			(xy 150.751169 -393.668542) (xy 150.766526 -393.6492) (xy 150.772005 -393.641879) (xy 150.777853 -393.624563)
			(xy 150.777956 -393.615418) (xy 150.77694 -393.58443) (xy 150.776299 -393.575366) (xy 150.769382 -393.558573)
			(xy 150.763478 -393.551664) (xy 150.744661 -393.530399) (xy 150.712841 -393.483373) (xy 150.688326 -393.432158)
			(xy 150.671653 -393.377881) (xy 150.663191 -393.321735) (xy 150.66264 -393.293346) (xy 150.225751 -393.293346)
			(xy 150.225225 -393.321992) (xy 150.216353 -393.379622) (xy 150.198821 -393.435232) (xy 150.173036 -393.48753)
			(xy 150.1396 -393.535299) (xy 150.119842 -393.556744) (xy 150.113679 -393.563823) (xy 150.106525 -393.581161)
			(xy 150.105872 -393.590526) (xy 150.104094 -393.659106) (xy 150.104239 -393.668362) (xy 150.110372 -393.685815)
			(xy 150.116032 -393.693142) (xy 150.11654 -393.69365) (xy 150.132862 -393.713277) (xy 150.160332 -393.756301)
			(xy 150.181433 -393.802782) (xy 150.195739 -393.851782) (xy 150.202962 -393.902315) (xy 150.203408 -393.927838)
			(xy 150.202906 -393.954715) (xy 150.194894 -394.00787) (xy 150.17905 -394.059236) (xy 150.155726 -394.107668)
			(xy 150.125445 -394.152082) (xy 150.088883 -394.191487) (xy 150.046855 -394.225003) (xy 150.000302 -394.25188)
			(xy 149.950263 -394.271519) (xy 149.897856 -394.28348) (xy 149.844252 -394.287498) (xy 149.790648 -394.28348)
			(xy 149.738241 -394.271519) (xy 149.688202 -394.25188) (xy 149.641649 -394.225003) (xy 149.599621 -394.191487)
			(xy 149.563059 -394.152082) (xy 149.532778 -394.107668) (xy 149.509454 -394.059236) (xy 149.49361 -394.00787)
			(xy 149.485598 -393.954715) (xy 149.485096 -393.927838) (xy 149.485557 -393.90228) (xy 149.492794 -393.85168)
			(xy 149.507142 -393.80262) (xy 149.528308 -393.756093) (xy 149.555866 -393.713043) (xy 149.572218 -393.693396)
			(xy 149.572472 -393.693142) (xy 149.578136 -393.685821) (xy 149.584247 -393.668362) (xy 149.58441 -393.659106)
			(xy 149.582378 -393.580874) (xy 149.575266 -393.563856) (xy 149.568662 -393.556744) (xy 149.54892 -393.535286)
			(xy 149.515485 -393.487519) (xy 149.489702 -393.435225) (xy 149.47217 -393.379617) (xy 149.463299 -393.321991)
			(xy 149.462744 -393.292838) (xy 149.025864 -393.292838) (xy 149.025369 -393.320713) (xy 149.017261 -393.37587)
			(xy 149.001208 -393.429259) (xy 148.977554 -393.479742) (xy 148.946801 -393.526243) (xy 148.928582 -393.547346)
			(xy 148.92274 -393.55395) (xy 148.915882 -393.570714) (xy 148.91385 -393.645136) (xy 148.913958 -393.654042)
			(xy 148.919557 -393.670935) (xy 148.924772 -393.678156) (xy 148.925026 -393.67841) (xy 148.93979 -393.697589)
			(xy 148.964619 -393.739135) (xy 148.983657 -393.783633) (xy 148.99656 -393.830282) (xy 149.003095 -393.878238)
			(xy 149.003512 -393.902438) (xy 149.00301 -393.929334) (xy 148.994992 -393.982526) (xy 148.979136 -394.033929)
			(xy 148.955797 -394.082395) (xy 148.925494 -394.126841) (xy 148.888906 -394.166274) (xy 148.846849 -394.199813)
			(xy 148.800263 -394.226709) (xy 148.750189 -394.246362) (xy 148.697744 -394.258332) (xy 148.644102 -394.262352)
			(xy 148.59046 -394.258332) (xy 148.538015 -394.246362) (xy 148.487941 -394.226709) (xy 148.441355 -394.199813)
			(xy 148.399298 -394.166274) (xy 148.36271 -394.126841) (xy 148.332407 -394.082395) (xy 148.309068 -394.033929)
			(xy 148.293212 -393.982526) (xy 148.285194 -393.929334) (xy 148.284692 -393.902438) (xy 148.285096 -393.878235)
			(xy 148.291597 -393.830268) (xy 148.304486 -393.783609) (xy 148.32353 -393.739107) (xy 148.348383 -393.697568)
			(xy 148.363178 -393.67841) (xy 148.363432 -393.678156) (xy 148.368704 -393.670968) (xy 148.374288 -393.65405)
			(xy 148.374354 -393.645136) (xy 148.372322 -393.570714) (xy 148.365464 -393.55395) (xy 148.359622 -393.547346)
			(xy 148.341426 -393.526225) (xy 148.310678 -393.479726) (xy 148.287024 -393.429247) (xy 148.270968 -393.375863)
			(xy 148.26285 -393.320711) (xy 148.26234 -393.292838) (xy 147.825968 -393.292838) (xy 147.825472 -393.320713)
			(xy 147.817364 -393.37587) (xy 147.801312 -393.429259) (xy 147.777657 -393.479742) (xy 147.746905 -393.526243)
			(xy 147.728686 -393.547346) (xy 147.722844 -393.55395) (xy 147.715986 -393.570714) (xy 147.713954 -393.645136)
			(xy 147.714061 -393.654042) (xy 147.71966 -393.670936) (xy 147.724876 -393.678156) (xy 147.72513 -393.67841)
			(xy 147.739894 -393.697589) (xy 147.764724 -393.739135) (xy 147.783761 -393.783633) (xy 147.796664 -393.830282)
			(xy 147.803199 -393.878238) (xy 147.803616 -393.902438) (xy 147.803114 -393.929334) (xy 147.795096 -393.982526)
			(xy 147.77924 -394.033929) (xy 147.755901 -394.082395) (xy 147.725598 -394.126841) (xy 147.68901 -394.166274)
			(xy 147.646953 -394.199813) (xy 147.600367 -394.226709) (xy 147.550293 -394.246362) (xy 147.497848 -394.258332)
			(xy 147.444206 -394.262352) (xy 147.390564 -394.258332) (xy 147.338119 -394.246362) (xy 147.288045 -394.226709)
			(xy 147.241459 -394.199813) (xy 147.199402 -394.166274) (xy 147.162814 -394.126841) (xy 147.132511 -394.082395)
			(xy 147.109172 -394.033929) (xy 147.093316 -393.982526) (xy 147.085298 -393.929334) (xy 147.084796 -393.902438)
			(xy 147.085199 -393.878235) (xy 147.0917 -393.830268) (xy 147.10459 -393.783609) (xy 147.123634 -393.739107)
			(xy 147.148487 -393.697568) (xy 147.163282 -393.67841) (xy 147.163536 -393.678156) (xy 147.168808 -393.670969)
			(xy 147.174392 -393.65405) (xy 147.174458 -393.645136) (xy 147.172426 -393.570714) (xy 147.165568 -393.55395)
			(xy 147.159726 -393.547346) (xy 147.141515 -393.526238) (xy 147.110773 -393.479733) (xy 147.087123 -393.429251)
			(xy 147.07107 -393.375865) (xy 147.062954 -393.320712) (xy 147.062444 -393.292838) (xy 140.941552 -393.292838)
			(xy 140.941552 -393.484608) (xy 140.94206 -393.485116) (xy 140.94206 -393.51331) (xy 140.942487 -393.523378)
			(xy 140.95021 -393.541974) (xy 140.957046 -393.549378) (xy 141.378686 -393.971272) (xy 141.385522 -393.978674)
			(xy 141.393233 -393.997272) (xy 141.393672 -394.00734) (xy 141.393672 -394.062966) (xy 141.394175 -394.073018)
			(xy 141.401893 -394.091582) (xy 141.408658 -394.099034) (xy 141.466824 -394.1572) (xy 141.473678 -394.164595)
			(xy 141.481425 -394.183194) (xy 141.48181 -394.193268) (xy 141.48181 -394.352018) (xy 145.832828 -394.352018)
			(xy 145.836899 -394.296396) (xy 145.849025 -394.241959) (xy 145.868948 -394.189868) (xy 145.896244 -394.141233)
			(xy 145.93033 -394.09709) (xy 145.970479 -394.058381) (xy 146.015837 -394.02593) (xy 146.065437 -394.000429)
			(xy 146.118221 -393.982422) (xy 146.173064 -393.972292) (xy 146.228798 -393.970255) (xy 146.284235 -393.976355)
			(xy 146.338192 -393.990461) (xy 146.389521 -394.012273) (xy 146.437127 -394.041327) (xy 146.479995 -394.077002)
			(xy 146.517212 -394.118539) (xy 146.547985 -394.165052) (xy 146.571657 -394.215549) (xy 146.587725 -394.268956)
			(xy 146.595845 -394.324132) (xy 146.596354 -394.352018) (xy 146.595845 -394.379904) (xy 146.587725 -394.43508)
			(xy 146.571657 -394.488487) (xy 146.547985 -394.538984) (xy 146.517212 -394.585497) (xy 146.479995 -394.627034)
			(xy 146.437127 -394.662709) (xy 146.389521 -394.691763) (xy 146.338192 -394.713575) (xy 146.284235 -394.727681)
			(xy 146.228798 -394.733781) (xy 146.173064 -394.731744) (xy 146.118221 -394.721614) (xy 146.065437 -394.703607)
			(xy 146.015837 -394.678106) (xy 145.970479 -394.645655) (xy 145.93033 -394.606946) (xy 145.896244 -394.562803)
			(xy 145.868948 -394.514168) (xy 145.849025 -394.462077) (xy 145.836899 -394.40764) (xy 145.832828 -394.352018)
			(xy 141.48181 -394.352018) (xy 141.48181 -395.05788) (xy 166.530002 -395.05788) (xy 166.530002 -394.997944)
			(xy 166.537825 -394.938522) (xy 166.553338 -394.880629) (xy 166.576274 -394.825256) (xy 166.606241 -394.77335)
			(xy 166.642728 -394.7258) (xy 166.685108 -394.68342) (xy 166.732658 -394.646933) (xy 166.784564 -394.616966)
			(xy 166.839937 -394.59403) (xy 166.89783 -394.578517) (xy 166.957252 -394.570694) (xy 167.017188 -394.570694)
			(xy 167.07661 -394.578517) (xy 167.134503 -394.59403) (xy 167.189876 -394.616966) (xy 167.241782 -394.646933)
			(xy 167.289332 -394.68342) (xy 167.331712 -394.7258) (xy 167.368199 -394.77335) (xy 167.398166 -394.825256)
			(xy 167.421102 -394.880629) (xy 167.436615 -394.938522) (xy 167.444438 -394.997944) (xy 167.444928 -395.027912)
			(xy 167.444438 -395.05788) (xy 167.436615 -395.117302) (xy 167.421102 -395.175195) (xy 167.398166 -395.230568)
			(xy 167.368199 -395.282474) (xy 167.331712 -395.330024) (xy 167.289332 -395.372404) (xy 167.241782 -395.408891)
			(xy 167.189876 -395.438858) (xy 167.134503 -395.461794) (xy 167.07661 -395.477307) (xy 167.017188 -395.48513)
			(xy 166.957252 -395.48513) (xy 166.89783 -395.477307) (xy 166.839937 -395.461794) (xy 166.784564 -395.438858)
			(xy 166.732658 -395.408891) (xy 166.685108 -395.372404) (xy 166.642728 -395.330024) (xy 166.606241 -395.282474)
			(xy 166.576274 -395.230568) (xy 166.553338 -395.175195) (xy 166.537825 -395.117302) (xy 166.530002 -395.05788)
			(xy 141.48181 -395.05788) (xy 141.48181 -397.739362) (xy 141.482245 -397.749427) (xy 141.489976 -397.768014)
			(xy 141.496796 -397.77543) (xy 141.864842 -398.143476) (xy 141.872242 -398.150319) (xy 141.89084 -398.158042)
			(xy 141.90091 -398.158462)
		)
		(stroke
			(width 0)
			(type solid)
		)
		(fill yes)
		(layer "B.Cu")
		(net "P0V9_CPU1_RT2_2A")
	)
	(gr_poly
		(pts
			(xy 132.791708 -398.158462) (xy 132.801777 -398.158037) (xy 132.820376 -398.150316) (xy 132.827776 -398.143476)
			(xy 136.304782 -394.66647) (xy 136.311626 -394.659071) (xy 136.319352 -394.640472) (xy 136.319768 -394.630402)
			(xy 136.319768 -392.710162) (xy 136.320197 -392.700094) (xy 136.327918 -392.681497) (xy 136.334754 -392.674094)
			(xy 136.427464 -392.581384) (xy 136.429496 -392.57859) (xy 136.450935 -392.551305) (xy 136.500001 -392.502238)
			(xy 136.527286 -392.4808) (xy 136.53008 -392.478768) (xy 136.605518 -392.40333) (xy 136.612916 -392.396483)
			(xy 136.631514 -392.38875) (xy 136.641586 -392.388344) (xy 136.653524 -392.388344) (xy 136.663591 -392.387915)
			(xy 136.682184 -392.380188) (xy 136.689592 -392.373358) (xy 136.702038 -392.360912) (xy 136.708893 -392.353517)
			(xy 136.716642 -392.334919) (xy 136.717024 -392.324844) (xy 136.717024 -389.513572) (xy 136.716596 -389.503504)
			(xy 136.708878 -389.484904) (xy 136.702038 -389.477504) (xy 136.672828 -389.448294) (xy 136.665425 -389.441459)
			(xy 136.646827 -389.433752) (xy 136.63676 -389.433308) (xy 135.660384 -389.433308) (xy 135.650315 -389.432882)
			(xy 135.631714 -389.425165) (xy 135.624316 -389.418322) (xy 135.42645 -389.220456) (xy 135.418365 -389.213148)
			(xy 135.397975 -389.205505) (xy 135.38708 -389.205724) (xy 135.310626 -389.211058) (xy 135.299861 -389.212325)
			(xy 135.280791 -389.222589) (xy 135.273796 -389.23087) (xy 135.260236 -389.248179) (xy 135.229269 -389.279395)
			(xy 135.212074 -389.2931) (xy 135.201152 -389.301482) (xy 135.190992 -389.32612) (xy 135.204454 -389.426958)
			(xy 135.206014 -389.435731) (xy 135.214253 -389.451514) (xy 135.227383 -389.463538) (xy 135.235442 -389.467344)
			(xy 135.257813 -389.47707) (xy 135.299663 -389.502132) (xy 135.337381 -389.533065) (xy 135.37015 -389.569199)
			(xy 135.397262 -389.609751) (xy 135.418128 -389.653842) (xy 135.432297 -389.700519) (xy 135.439462 -389.74877)
			(xy 135.439912 -389.77316) (xy 135.439492 -389.795969) (xy 135.433153 -389.841146) (xy 135.420672 -389.885024)
			(xy 135.402286 -389.926774) (xy 135.390636 -389.946388) (xy 135.386004 -389.9546) (xy 135.382618 -389.973134)
			(xy 135.384032 -389.982456) (xy 135.38962 -390.013698) (xy 135.391751 -390.022788) (xy 135.401526 -390.038675)
			(xy 135.40867 -390.044686) (xy 135.428335 -390.060448) (xy 135.463114 -390.096922) (xy 135.491956 -390.138249)
			(xy 135.514195 -390.183474) (xy 135.529315 -390.231549) (xy 135.536966 -390.281362) (xy 135.537448 -390.30656)
			(xy 135.536965 -390.331836) (xy 135.529266 -390.381798) (xy 135.514056 -390.430007) (xy 135.491689 -390.475341)
			(xy 135.462685 -390.516745) (xy 135.427721 -390.553255) (xy 135.38761 -390.584022) (xy 135.343285 -390.608328)
			(xy 135.295779 -390.625608) (xy 135.246196 -390.635461) (xy 135.220964 -390.637014) (xy 135.209788 -390.637522)
			(xy 135.190484 -390.647428) (xy 135.13562 -390.716262) (xy 135.129179 -390.725183) (xy 135.123896 -390.74652)
			(xy 135.12546 -390.75741) (xy 135.128196 -390.772694) (xy 135.131121 -390.803606) (xy 135.131302 -390.819132)
			(xy 135.130792 -390.845119) (xy 135.122662 -390.896454) (xy 135.106601 -390.945884) (xy 135.083005 -390.992194)
			(xy 135.052455 -391.034242) (xy 135.015704 -391.070993) (xy 134.973656 -391.101543) (xy 134.927346 -391.125139)
			(xy 134.877916 -391.1412) (xy 134.826581 -391.14933) (xy 134.774607 -391.14933) (xy 134.723272 -391.1412)
			(xy 134.673842 -391.125139) (xy 134.627532 -391.101543) (xy 134.585484 -391.070993) (xy 134.548733 -391.034242)
			(xy 134.518183 -390.992194) (xy 134.494587 -390.945884) (xy 134.478526 -390.896454) (xy 134.470396 -390.845119)
			(xy 134.469886 -390.819132) (xy 134.47037 -390.793858) (xy 134.47807 -390.743898) (xy 134.493281 -390.695692)
			(xy 134.515649 -390.650361) (xy 134.544653 -390.608961) (xy 134.579618 -390.572455) (xy 134.61973 -390.541693)
			(xy 134.664054 -390.517392) (xy 134.71156 -390.500116) (xy 134.761141 -390.490269) (xy 134.78637 -390.488678)
			(xy 134.797546 -390.48817) (xy 134.81685 -390.478264) (xy 134.871714 -390.40943) (xy 134.87815 -390.400507)
			(xy 134.883426 -390.379173) (xy 134.881874 -390.368282) (xy 134.879138 -390.352998) (xy 134.876214 -390.322085)
			(xy 134.876032 -390.30656) (xy 134.876451 -390.283751) (xy 134.882788 -390.238574) (xy 134.895268 -390.194694)
			(xy 134.913655 -390.152944) (xy 134.925308 -390.133332) (xy 134.929948 -390.125121) (xy 134.933345 -390.106585)
			(xy 134.931912 -390.097264) (xy 134.926324 -390.066022) (xy 134.924198 -390.056929) (xy 134.914433 -390.04103)
			(xy 134.907274 -390.035034) (xy 134.88761 -390.01927) (xy 134.852836 -389.982795) (xy 134.823996 -389.941467)
			(xy 134.801758 -389.896243) (xy 134.786638 -389.848169) (xy 134.778985 -389.798358) (xy 134.778496 -389.77316)
			(xy 134.778974 -389.747931) (xy 134.786643 -389.698059) (xy 134.801797 -389.64993) (xy 134.824084 -389.604661)
			(xy 134.852987 -389.563302) (xy 134.887836 -389.526811) (xy 134.907528 -389.511032) (xy 134.91845 -389.50265)
			(xy 134.92861 -389.478012) (xy 134.915148 -389.377174) (xy 134.913593 -389.368398) (xy 134.905359 -389.352606)
			(xy 134.89223 -389.340573) (xy 134.88416 -389.336788) (xy 134.861788 -389.327063) (xy 134.819935 -389.302001)
			(xy 134.782214 -389.271069) (xy 134.749441 -389.234936) (xy 134.722325 -389.194385) (xy 134.701455 -389.150293)
			(xy 134.687281 -389.103615) (xy 134.680111 -389.055363) (xy 134.67969 -389.030972) (xy 134.68017 -389.005286)
			(xy 134.688103 -388.95453) (xy 134.703789 -388.905612) (xy 134.72685 -388.859707) (xy 134.756732 -388.81792)
			(xy 134.792717 -388.781257) (xy 134.81304 -388.765542) (xy 134.821676 -388.759192) (xy 134.832344 -388.739634)
			(xy 134.838694 -388.65175) (xy 134.838991 -388.640781) (xy 134.831352 -388.620237) (xy 134.823962 -388.612126)
			(xy 134.811008 -388.599172) (xy 134.80161 -388.595362) (xy 134.777481 -388.584946) (xy 134.7326 -388.557608)
			(xy 134.692608 -388.523515) (xy 134.658511 -388.483525) (xy 134.631168 -388.438647) (xy 134.620762 -388.414514)
			(xy 134.616952 -388.405116) (xy 134.587234 -388.375398) (xy 134.580384 -388.368001) (xy 134.572645 -388.349403)
			(xy 134.572248 -388.33933) (xy 134.572248 -388.143242) (xy 134.571533 -388.130989) (xy 134.560264 -388.109224)
			(xy 134.550658 -388.101586) (xy 134.528079 -388.085216) (xy 134.487195 -388.047283) (xy 134.451881 -388.004118)
			(xy 134.4228 -387.95653) (xy 134.400497 -387.905413) (xy 134.385392 -387.851727) (xy 134.377769 -387.796481)
			(xy 134.377769 -387.74071) (xy 134.385394 -387.685464) (xy 134.4005 -387.631778) (xy 134.422804 -387.580662)
			(xy 134.451887 -387.533074) (xy 134.487202 -387.48991) (xy 134.528086 -387.451978) (xy 134.550658 -387.435598)
			(xy 134.560283 -387.427974) (xy 134.571552 -387.406203) (xy 134.572248 -387.393942) (xy 134.572248 -386.658358)
			(xy 134.571816 -386.648292) (xy 134.564085 -386.629704) (xy 134.557262 -386.62229) (xy 133.843014 -385.908296)
			(xy 133.836167 -385.900898) (xy 133.828432 -385.8823) (xy 133.828028 -385.872228) (xy 133.828028 -383.817114)
			(xy 133.835902 -383.798572) (xy 133.84022 -383.794254) (xy 133.84022 -383.688082) (xy 133.839794 -383.678013)
			(xy 133.832077 -383.659411) (xy 133.825234 -383.652014) (xy 133.582918 -383.409698) (xy 133.57607 -383.4023)
			(xy 133.568334 -383.383702) (xy 133.567932 -383.37363) (xy 133.567932 -382.619504) (xy 133.568355 -382.609434)
			(xy 133.576072 -382.590832) (xy 133.582918 -382.583436) (xy 133.696456 -382.469898) (xy 133.703307 -382.462501)
			(xy 133.711048 -382.443903) (xy 133.711442 -382.43383) (xy 133.711442 -379.624082) (xy 133.711014 -379.614015)
			(xy 133.703289 -379.59542) (xy 133.696456 -379.588014) (xy 133.482588 -379.374146) (xy 133.475191 -379.367296)
			(xy 133.456593 -379.359559) (xy 133.44652 -379.35916) (xy 127.766064 -379.35916) (xy 127.755998 -379.359591)
			(xy 127.737409 -379.367322) (xy 127.729996 -379.374146) (xy 127.617728 -379.486414) (xy 127.610881 -379.493812)
			(xy 127.603147 -379.51241) (xy 127.602742 -379.522482) (xy 127.602742 -382.619758) (xy 127.602307 -382.629822)
			(xy 127.594571 -382.648406) (xy 127.587756 -382.655826) (xy 127.364665 -382.878917) (xy 127.786386 -382.878917)
			(xy 127.786386 -382.826943) (xy 127.794516 -382.775608) (xy 127.810577 -382.726178) (xy 127.834173 -382.679868)
			(xy 127.864723 -382.63782) (xy 127.901474 -382.601069) (xy 127.943522 -382.570519) (xy 127.989832 -382.546923)
			(xy 128.039262 -382.530862) (xy 128.090597 -382.522732) (xy 128.142571 -382.522732) (xy 128.193906 -382.530862)
			(xy 128.243336 -382.546923) (xy 128.289646 -382.570519) (xy 128.331694 -382.601069) (xy 128.368445 -382.63782)
			(xy 128.398995 -382.679868) (xy 128.422591 -382.726178) (xy 128.438652 -382.775608) (xy 128.446782 -382.826943)
			(xy 128.447292 -382.85293) (xy 128.446782 -382.878917) (xy 128.986282 -382.878917) (xy 128.986282 -382.826943)
			(xy 128.994412 -382.775608) (xy 129.010473 -382.726178) (xy 129.034069 -382.679868) (xy 129.064619 -382.63782)
			(xy 129.10137 -382.601069) (xy 129.143418 -382.570519) (xy 129.189728 -382.546923) (xy 129.239158 -382.530862)
			(xy 129.290493 -382.522732) (xy 129.342467 -382.522732) (xy 129.393802 -382.530862) (xy 129.443232 -382.546923)
			(xy 129.489542 -382.570519) (xy 129.53159 -382.601069) (xy 129.568341 -382.63782) (xy 129.598891 -382.679868)
			(xy 129.622487 -382.726178) (xy 129.638548 -382.775608) (xy 129.646678 -382.826943) (xy 129.647188 -382.85293)
			(xy 129.646678 -382.878917) (xy 130.186178 -382.878917) (xy 130.186178 -382.826943) (xy 130.194308 -382.775608)
			(xy 130.210369 -382.726178) (xy 130.233965 -382.679868) (xy 130.264515 -382.63782) (xy 130.301266 -382.601069)
			(xy 130.343314 -382.570519) (xy 130.389624 -382.546923) (xy 130.439054 -382.530862) (xy 130.490389 -382.522732)
			(xy 130.542363 -382.522732) (xy 130.593698 -382.530862) (xy 130.643128 -382.546923) (xy 130.689438 -382.570519)
			(xy 130.731486 -382.601069) (xy 130.768237 -382.63782) (xy 130.798787 -382.679868) (xy 130.822383 -382.726178)
			(xy 130.838444 -382.775608) (xy 130.846574 -382.826943) (xy 130.847084 -382.85293) (xy 130.846574 -382.878917)
			(xy 131.386328 -382.878917) (xy 131.386328 -382.826943) (xy 131.394458 -382.775608) (xy 131.410519 -382.726178)
			(xy 131.434115 -382.679868) (xy 131.464665 -382.63782) (xy 131.501416 -382.601069) (xy 131.543464 -382.570519)
			(xy 131.589774 -382.546923) (xy 131.639204 -382.530862) (xy 131.690539 -382.522732) (xy 131.742513 -382.522732)
			(xy 131.793848 -382.530862) (xy 131.843278 -382.546923) (xy 131.889588 -382.570519) (xy 131.931636 -382.601069)
			(xy 131.968387 -382.63782) (xy 131.998937 -382.679868) (xy 132.022533 -382.726178) (xy 132.038594 -382.775608)
			(xy 132.046724 -382.826943) (xy 132.047234 -382.85293) (xy 132.046724 -382.878917) (xy 132.586224 -382.878917)
			(xy 132.586224 -382.826943) (xy 132.594354 -382.775608) (xy 132.610415 -382.726178) (xy 132.634011 -382.679868)
			(xy 132.664561 -382.63782) (xy 132.701312 -382.601069) (xy 132.74336 -382.570519) (xy 132.78967 -382.546923)
			(xy 132.8391 -382.530862) (xy 132.890435 -382.522732) (xy 132.942409 -382.522732) (xy 132.993744 -382.530862)
			(xy 133.043174 -382.546923) (xy 133.089484 -382.570519) (xy 133.131532 -382.601069) (xy 133.168283 -382.63782)
			(xy 133.198833 -382.679868) (xy 133.222429 -382.726178) (xy 133.23849 -382.775608) (xy 133.24662 -382.826943)
			(xy 133.24713 -382.85293) (xy 133.24662 -382.878917) (xy 133.23849 -382.930252) (xy 133.222429 -382.979682)
			(xy 133.198833 -383.025992) (xy 133.168283 -383.06804) (xy 133.131532 -383.104791) (xy 133.089484 -383.135341)
			(xy 133.043174 -383.158937) (xy 132.993744 -383.174998) (xy 132.942409 -383.183128) (xy 132.890435 -383.183128)
			(xy 132.8391 -383.174998) (xy 132.78967 -383.158937) (xy 132.74336 -383.135341) (xy 132.701312 -383.104791)
			(xy 132.664561 -383.06804) (xy 132.634011 -383.025992) (xy 132.610415 -382.979682) (xy 132.594354 -382.930252)
			(xy 132.586224 -382.878917) (xy 132.046724 -382.878917) (xy 132.038594 -382.930252) (xy 132.022533 -382.979682)
			(xy 131.998937 -383.025992) (xy 131.968387 -383.06804) (xy 131.931636 -383.104791) (xy 131.889588 -383.135341)
			(xy 131.843278 -383.158937) (xy 131.793848 -383.174998) (xy 131.742513 -383.183128) (xy 131.690539 -383.183128)
			(xy 131.639204 -383.174998) (xy 131.589774 -383.158937) (xy 131.543464 -383.135341) (xy 131.501416 -383.104791)
			(xy 131.464665 -383.06804) (xy 131.434115 -383.025992) (xy 131.410519 -382.979682) (xy 131.394458 -382.930252)
			(xy 131.386328 -382.878917) (xy 130.846574 -382.878917) (xy 130.838444 -382.930252) (xy 130.822383 -382.979682)
			(xy 130.798787 -383.025992) (xy 130.768237 -383.06804) (xy 130.731486 -383.104791) (xy 130.689438 -383.135341)
			(xy 130.643128 -383.158937) (xy 130.593698 -383.174998) (xy 130.542363 -383.183128) (xy 130.490389 -383.183128)
			(xy 130.439054 -383.174998) (xy 130.389624 -383.158937) (xy 130.343314 -383.135341) (xy 130.301266 -383.104791)
			(xy 130.264515 -383.06804) (xy 130.233965 -383.025992) (xy 130.210369 -382.979682) (xy 130.194308 -382.930252)
			(xy 130.186178 -382.878917) (xy 129.646678 -382.878917) (xy 129.638548 -382.930252) (xy 129.622487 -382.979682)
			(xy 129.598891 -383.025992) (xy 129.568341 -383.06804) (xy 129.53159 -383.104791) (xy 129.489542 -383.135341)
			(xy 129.443232 -383.158937) (xy 129.393802 -383.174998) (xy 129.342467 -383.183128) (xy 129.290493 -383.183128)
			(xy 129.239158 -383.174998) (xy 129.189728 -383.158937) (xy 129.143418 -383.135341) (xy 129.10137 -383.104791)
			(xy 129.064619 -383.06804) (xy 129.034069 -383.025992) (xy 129.010473 -382.979682) (xy 128.994412 -382.930252)
			(xy 128.986282 -382.878917) (xy 128.446782 -382.878917) (xy 128.438652 -382.930252) (xy 128.422591 -382.979682)
			(xy 128.398995 -383.025992) (xy 128.368445 -383.06804) (xy 128.331694 -383.104791) (xy 128.289646 -383.135341)
			(xy 128.243336 -383.158937) (xy 128.193906 -383.174998) (xy 128.142571 -383.183128) (xy 128.090597 -383.183128)
			(xy 128.039262 -383.174998) (xy 127.989832 -383.158937) (xy 127.943522 -383.135341) (xy 127.901474 -383.104791)
			(xy 127.864723 -383.06804) (xy 127.834173 -383.025992) (xy 127.810577 -382.979682) (xy 127.794516 -382.930252)
			(xy 127.786386 -382.878917) (xy 127.364665 -382.878917) (xy 127.043688 -383.199894) (xy 127.036289 -383.206739)
			(xy 127.017691 -383.21447) (xy 127.00762 -383.21488) (xy 120.758204 -383.21488) (xy 120.748134 -383.214457)
			(xy 120.72953 -383.206742) (xy 120.722136 -383.199894) (xy 120.711722 -383.18948) (xy 120.711722 -383.18694)
			(xy 120.571768 -383.046986) (xy 120.564917 -383.03959) (xy 120.557176 -383.020991) (xy 120.556782 -383.010918)
			(xy 120.556782 -379.479302) (xy 120.556359 -379.469232) (xy 120.548643 -379.450629) (xy 120.541796 -379.443234)
			(xy 120.437148 -379.338586) (xy 120.429751 -379.331739) (xy 120.411152 -379.32401) (xy 120.40108 -379.3236)
			(xy 119.914924 -379.3236) (xy 119.896382 -379.31598) (xy 119.893842 -379.31344) (xy 113.348262 -379.31344)
			(xy 113.338196 -379.313871) (xy 113.319605 -379.3216) (xy 113.312194 -379.328426) (xy 113.010188 -379.630432)
			(xy 113.003337 -379.637828) (xy 112.9956 -379.656427) (xy 112.995202 -379.6665) (xy 112.995202 -382.506728)
			(xy 112.995607 -382.516341) (xy 113.002643 -382.534234) (xy 113.008918 -382.541526) (xy 113.029238 -382.56337)
			(xy 113.035532 -382.569582) (xy 113.051252 -382.577652) (xy 113.059972 -382.579118) (xy 113.084305 -382.582674)
			(xy 113.131625 -382.596051) (xy 113.17644 -382.616293) (xy 113.217761 -382.642953) (xy 113.236502 -382.658874)
			(xy 113.24336 -382.66497) (xy 113.260124 -382.671574) (xy 113.3348 -382.672844) (xy 113.343696 -382.672652)
			(xy 113.360492 -382.66681) (xy 113.367566 -382.661414) (xy 113.36782 -382.661414) (xy 113.389234 -382.644687)
			(xy 113.436582 -382.618037) (xy 113.487772 -382.599826) (xy 113.541314 -382.590585) (xy 113.56848 -382.59004)
			(xy 113.593468 -382.590503) (xy 113.64283 -382.598319) (xy 113.690362 -382.61376) (xy 113.734893 -382.636447)
			(xy 113.775326 -382.665821) (xy 113.810666 -382.701159) (xy 113.840043 -382.74159) (xy 113.862732 -382.786119)
			(xy 113.878177 -382.83365) (xy 113.885188 -382.877919) (xy 114.59894 -382.877919) (xy 114.59894 -382.827941)
			(xy 114.606759 -382.778578) (xy 114.622203 -382.731046) (xy 114.644893 -382.686514) (xy 114.674269 -382.646081)
			(xy 114.709609 -382.610741) (xy 114.750042 -382.581365) (xy 114.794574 -382.558675) (xy 114.842106 -382.543231)
			(xy 114.891469 -382.535412) (xy 114.941447 -382.535412) (xy 114.99081 -382.543231) (xy 115.038342 -382.558675)
			(xy 115.082874 -382.581365) (xy 115.123307 -382.610741) (xy 115.158647 -382.646081) (xy 115.188023 -382.686514)
			(xy 115.210713 -382.731046) (xy 115.226157 -382.778578) (xy 115.233976 -382.827941) (xy 115.234466 -382.85293)
			(xy 115.233976 -382.877919) (xy 115.233818 -382.878917) (xy 115.78641 -382.878917) (xy 115.78641 -382.826943)
			(xy 115.79454 -382.775608) (xy 115.810601 -382.726178) (xy 115.834197 -382.679868) (xy 115.864747 -382.63782)
			(xy 115.901498 -382.601069) (xy 115.943546 -382.570519) (xy 115.989856 -382.546923) (xy 116.039286 -382.530862)
			(xy 116.090621 -382.522732) (xy 116.142595 -382.522732) (xy 116.19393 -382.530862) (xy 116.24336 -382.546923)
			(xy 116.28967 -382.570519) (xy 116.331718 -382.601069) (xy 116.368469 -382.63782) (xy 116.399019 -382.679868)
			(xy 116.422615 -382.726178) (xy 116.438676 -382.775608) (xy 116.446806 -382.826943) (xy 116.447316 -382.85293)
			(xy 116.446806 -382.878917) (xy 116.986306 -382.878917) (xy 116.986306 -382.826943) (xy 116.994436 -382.775608)
			(xy 117.010497 -382.726178) (xy 117.034093 -382.679868) (xy 117.064643 -382.63782) (xy 117.101394 -382.601069)
			(xy 117.143442 -382.570519) (xy 117.189752 -382.546923) (xy 117.239182 -382.530862) (xy 117.290517 -382.522732)
			(xy 117.342491 -382.522732) (xy 117.393826 -382.530862) (xy 117.443256 -382.546923) (xy 117.489566 -382.570519)
			(xy 117.531614 -382.601069) (xy 117.568365 -382.63782) (xy 117.598915 -382.679868) (xy 117.622511 -382.726178)
			(xy 117.638572 -382.775608) (xy 117.646702 -382.826943) (xy 117.647212 -382.85293) (xy 117.646702 -382.878917)
			(xy 118.186202 -382.878917) (xy 118.186202 -382.826943) (xy 118.194332 -382.775608) (xy 118.210393 -382.726178)
			(xy 118.233989 -382.679868) (xy 118.264539 -382.63782) (xy 118.30129 -382.601069) (xy 118.343338 -382.570519)
			(xy 118.389648 -382.546923) (xy 118.439078 -382.530862) (xy 118.490413 -382.522732) (xy 118.542387 -382.522732)
			(xy 118.593722 -382.530862) (xy 118.643152 -382.546923) (xy 118.689462 -382.570519) (xy 118.73151 -382.601069)
			(xy 118.768261 -382.63782) (xy 118.798811 -382.679868) (xy 118.822407 -382.726178) (xy 118.838468 -382.775608)
			(xy 118.846598 -382.826943) (xy 118.847108 -382.85293) (xy 118.846598 -382.878917) (xy 119.386352 -382.878917)
			(xy 119.386352 -382.826943) (xy 119.394482 -382.775608) (xy 119.410543 -382.726178) (xy 119.434139 -382.679868)
			(xy 119.464689 -382.63782) (xy 119.50144 -382.601069) (xy 119.543488 -382.570519) (xy 119.589798 -382.546923)
			(xy 119.639228 -382.530862) (xy 119.690563 -382.522732) (xy 119.742537 -382.522732) (xy 119.793872 -382.530862)
			(xy 119.843302 -382.546923) (xy 119.889612 -382.570519) (xy 119.93166 -382.601069) (xy 119.968411 -382.63782)
			(xy 119.998961 -382.679868) (xy 120.022557 -382.726178) (xy 120.038618 -382.775608) (xy 120.046748 -382.826943)
			(xy 120.047258 -382.85293) (xy 120.046748 -382.878917) (xy 120.038618 -382.930252) (xy 120.022557 -382.979682)
			(xy 119.998961 -383.025992) (xy 119.968411 -383.06804) (xy 119.93166 -383.104791) (xy 119.889612 -383.135341)
			(xy 119.843302 -383.158937) (xy 119.793872 -383.174998) (xy 119.742537 -383.183128) (xy 119.690563 -383.183128)
			(xy 119.639228 -383.174998) (xy 119.589798 -383.158937) (xy 119.543488 -383.135341) (xy 119.50144 -383.104791)
			(xy 119.464689 -383.06804) (xy 119.434139 -383.025992) (xy 119.410543 -382.979682) (xy 119.394482 -382.930252)
			(xy 119.386352 -382.878917) (xy 118.846598 -382.878917) (xy 118.838468 -382.930252) (xy 118.822407 -382.979682)
			(xy 118.798811 -383.025992) (xy 118.768261 -383.06804) (xy 118.73151 -383.104791) (xy 118.689462 -383.135341)
			(xy 118.643152 -383.158937) (xy 118.593722 -383.174998) (xy 118.542387 -383.183128) (xy 118.490413 -383.183128)
			(xy 118.439078 -383.174998) (xy 118.389648 -383.158937) (xy 118.343338 -383.135341) (xy 118.30129 -383.104791)
			(xy 118.264539 -383.06804) (xy 118.233989 -383.025992) (xy 118.210393 -382.979682) (xy 118.194332 -382.930252)
			(xy 118.186202 -382.878917) (xy 117.646702 -382.878917) (xy 117.638572 -382.930252) (xy 117.622511 -382.979682)
			(xy 117.598915 -383.025992) (xy 117.568365 -383.06804) (xy 117.531614 -383.104791) (xy 117.489566 -383.135341)
			(xy 117.443256 -383.158937) (xy 117.393826 -383.174998) (xy 117.342491 -383.183128) (xy 117.290517 -383.183128)
			(xy 117.239182 -383.174998) (xy 117.189752 -383.158937) (xy 117.143442 -383.135341) (xy 117.101394 -383.104791)
			(xy 117.064643 -383.06804) (xy 117.034093 -383.025992) (xy 117.010497 -382.979682) (xy 116.994436 -382.930252)
			(xy 116.986306 -382.878917) (xy 116.446806 -382.878917) (xy 116.438676 -382.930252) (xy 116.422615 -382.979682)
			(xy 116.399019 -383.025992) (xy 116.368469 -383.06804) (xy 116.331718 -383.104791) (xy 116.28967 -383.135341)
			(xy 116.24336 -383.158937) (xy 116.19393 -383.174998) (xy 116.142595 -383.183128) (xy 116.090621 -383.183128)
			(xy 116.039286 -383.174998) (xy 115.989856 -383.158937) (xy 115.943546 -383.135341) (xy 115.901498 -383.104791)
			(xy 115.864747 -383.06804) (xy 115.834197 -383.025992) (xy 115.810601 -382.979682) (xy 115.79454 -382.930252)
			(xy 115.78641 -382.878917) (xy 115.233818 -382.878917) (xy 115.226157 -382.927282) (xy 115.210713 -382.974814)
			(xy 115.188023 -383.019346) (xy 115.158647 -383.059779) (xy 115.123307 -383.095119) (xy 115.082874 -383.124495)
			(xy 115.038342 -383.147185) (xy 114.99081 -383.162629) (xy 114.941447 -383.170448) (xy 114.891469 -383.170448)
			(xy 114.842106 -383.162629) (xy 114.794574 -383.147185) (xy 114.750042 -383.124495) (xy 114.709609 -383.095119)
			(xy 114.674269 -383.059779) (xy 114.644893 -383.019346) (xy 114.622203 -382.974814) (xy 114.606759 -382.927282)
			(xy 114.59894 -382.877919) (xy 113.885188 -382.877919) (xy 113.885995 -382.883012) (xy 113.885995 -382.932988)
			(xy 113.878177 -382.98235) (xy 113.862732 -383.02988) (xy 113.840043 -383.07441) (xy 113.810666 -383.114841)
			(xy 113.775326 -383.150179) (xy 113.734893 -383.179553) (xy 113.690362 -383.20224) (xy 113.64283 -383.217681)
			(xy 113.593468 -383.225497) (xy 113.56848 -383.226056) (xy 113.541196 -383.2255) (xy 113.487425 -383.216204)
			(xy 113.436029 -383.19787) (xy 113.388515 -383.171036) (xy 113.367058 -383.154174) (xy 113.359877 -383.148678)
			(xy 113.342825 -383.1427) (xy 113.333784 -383.14249) (xy 113.259108 -383.14376) (xy 113.242598 -383.15011)
			(xy 113.23574 -383.156206) (xy 113.21758 -383.171553) (xy 113.177683 -383.197417) (xy 113.13449 -383.217292)
			(xy 113.088893 -383.230768) (xy 113.041835 -383.237567) (xy 113.018062 -383.237994) (xy 112.994829 -383.237598)
			(xy 112.948821 -383.23109) (xy 112.904177 -383.218208) (xy 112.861775 -383.199205) (xy 112.822449 -383.174455)
			(xy 112.804448 -383.159762) (xy 112.79759 -383.15392) (xy 112.780572 -383.14757) (xy 112.696752 -383.14757)
			(xy 112.679734 -383.15392) (xy 112.672876 -383.159762) (xy 112.659841 -383.170502) (xy 112.631974 -383.189588)
			(xy 112.61725 -383.197862) (xy 112.609388 -383.202539) (xy 112.59737 -383.216312) (xy 112.590947 -383.233426)
			(xy 112.59058 -383.242566) (xy 112.59058 -383.416556) (xy 112.591013 -383.426622) (xy 112.598739 -383.445214)
			(xy 112.605566 -383.452624) (xy 112.71885 -383.565654) (xy 112.73562 -383.583095) (xy 112.76406 -383.622236)
			(xy 112.786029 -383.665343) (xy 112.800986 -383.711356) (xy 112.808563 -383.759141) (xy 112.80902 -383.783332)
			(xy 112.80902 -384.23596) (xy 112.812068 -384.244342) (xy 112.821283 -384.271557) (xy 112.83124 -384.328139)
			(xy 112.83188 -384.356864) (xy 112.83188 -384.357372) (xy 112.831422 -384.382081) (xy 112.824072 -384.430949)
			(xy 112.809531 -384.47818) (xy 112.788124 -384.52272) (xy 112.760326 -384.563579) (xy 112.726757 -384.599846)
			(xy 112.688165 -384.630713) (xy 112.667463 -384.642711) (xy 114.244864 -384.642711) (xy 114.244864 -384.592733)
			(xy 114.252683 -384.54337) (xy 114.268127 -384.495838) (xy 114.290817 -384.451306) (xy 114.320193 -384.410873)
			(xy 114.355533 -384.375533) (xy 114.395966 -384.346157) (xy 114.440498 -384.323467) (xy 114.48803 -384.308023)
			(xy 114.537393 -384.300204) (xy 114.587371 -384.300204) (xy 114.636734 -384.308023) (xy 114.684266 -384.323467)
			(xy 114.728798 -384.346157) (xy 114.769231 -384.375533) (xy 114.804571 -384.410873) (xy 114.833947 -384.451306)
			(xy 114.856637 -384.495838) (xy 114.872081 -384.54337) (xy 114.8799 -384.592733) (xy 114.88039 -384.617722)
			(xy 114.8799 -384.642711) (xy 114.879742 -384.643709) (xy 115.43208 -384.643709) (xy 115.43208 -384.591735)
			(xy 115.44021 -384.5404) (xy 115.456271 -384.49097) (xy 115.479867 -384.44466) (xy 115.510417 -384.402612)
			(xy 115.547168 -384.365861) (xy 115.589216 -384.335311) (xy 115.635526 -384.311715) (xy 115.684956 -384.295654)
			(xy 115.736291 -384.287524) (xy 115.788265 -384.287524) (xy 115.8396 -384.295654) (xy 115.88903 -384.311715)
			(xy 115.93534 -384.335311) (xy 115.977388 -384.365861) (xy 116.014139 -384.402612) (xy 116.044689 -384.44466)
			(xy 116.068285 -384.49097) (xy 116.084346 -384.5404) (xy 116.092476 -384.591735) (xy 116.092986 -384.617722)
			(xy 116.092476 -384.643709) (xy 116.63223 -384.643709) (xy 116.63223 -384.591735) (xy 116.64036 -384.5404)
			(xy 116.656421 -384.49097) (xy 116.680017 -384.44466) (xy 116.710567 -384.402612) (xy 116.747318 -384.365861)
			(xy 116.789366 -384.335311) (xy 116.835676 -384.311715) (xy 116.885106 -384.295654) (xy 116.936441 -384.287524)
			(xy 116.988415 -384.287524) (xy 117.03975 -384.295654) (xy 117.08918 -384.311715) (xy 117.13549 -384.335311)
			(xy 117.177538 -384.365861) (xy 117.214289 -384.402612) (xy 117.244839 -384.44466) (xy 117.268435 -384.49097)
			(xy 117.284496 -384.5404) (xy 117.292626 -384.591735) (xy 117.293136 -384.617722) (xy 117.292626 -384.643709)
			(xy 117.832126 -384.643709) (xy 117.832126 -384.591735) (xy 117.840256 -384.5404) (xy 117.856317 -384.49097)
			(xy 117.879913 -384.44466) (xy 117.910463 -384.402612) (xy 117.947214 -384.365861) (xy 117.989262 -384.335311)
			(xy 118.035572 -384.311715) (xy 118.085002 -384.295654) (xy 118.136337 -384.287524) (xy 118.188311 -384.287524)
			(xy 118.239646 -384.295654) (xy 118.289076 -384.311715) (xy 118.335386 -384.335311) (xy 118.377434 -384.365861)
			(xy 118.414185 -384.402612) (xy 118.444735 -384.44466) (xy 118.468331 -384.49097) (xy 118.484392 -384.5404)
			(xy 118.492522 -384.591735) (xy 118.493032 -384.617722) (xy 118.492522 -384.643709) (xy 119.032276 -384.643709)
			(xy 119.032276 -384.591735) (xy 119.040406 -384.5404) (xy 119.056467 -384.49097) (xy 119.080063 -384.44466)
			(xy 119.110613 -384.402612) (xy 119.147364 -384.365861) (xy 119.189412 -384.335311) (xy 119.235722 -384.311715)
			(xy 119.285152 -384.295654) (xy 119.336487 -384.287524) (xy 119.388461 -384.287524) (xy 119.439796 -384.295654)
			(xy 119.489226 -384.311715) (xy 119.535536 -384.335311) (xy 119.577584 -384.365861) (xy 119.614335 -384.402612)
			(xy 119.644885 -384.44466) (xy 119.668481 -384.49097) (xy 119.684542 -384.5404) (xy 119.692672 -384.591735)
			(xy 119.693182 -384.617722) (xy 119.692672 -384.643709) (xy 120.232172 -384.643709) (xy 120.232172 -384.591735)
			(xy 120.240302 -384.5404) (xy 120.256363 -384.49097) (xy 120.279959 -384.44466) (xy 120.310509 -384.402612)
			(xy 120.34726 -384.365861) (xy 120.389308 -384.335311) (xy 120.435618 -384.311715) (xy 120.485048 -384.295654)
			(xy 120.536383 -384.287524) (xy 120.588357 -384.287524) (xy 120.639692 -384.295654) (xy 120.689122 -384.311715)
			(xy 120.735432 -384.335311) (xy 120.77748 -384.365861) (xy 120.814231 -384.402612) (xy 120.844781 -384.44466)
			(xy 120.868377 -384.49097) (xy 120.884438 -384.5404) (xy 120.892568 -384.591735) (xy 120.893078 -384.617722)
			(xy 120.892568 -384.643709) (xy 121.432068 -384.643709) (xy 121.432068 -384.591735) (xy 121.440198 -384.5404)
			(xy 121.456259 -384.49097) (xy 121.479855 -384.44466) (xy 121.510405 -384.402612) (xy 121.547156 -384.365861)
			(xy 121.589204 -384.335311) (xy 121.635514 -384.311715) (xy 121.684944 -384.295654) (xy 121.736279 -384.287524)
			(xy 121.788253 -384.287524) (xy 121.839588 -384.295654) (xy 121.889018 -384.311715) (xy 121.935328 -384.335311)
			(xy 121.977376 -384.365861) (xy 122.014127 -384.402612) (xy 122.044677 -384.44466) (xy 122.068273 -384.49097)
			(xy 122.084334 -384.5404) (xy 122.092464 -384.591735) (xy 122.092974 -384.617722) (xy 122.092464 -384.643709)
			(xy 122.632218 -384.643709) (xy 122.632218 -384.591735) (xy 122.640348 -384.5404) (xy 122.656409 -384.49097)
			(xy 122.680005 -384.44466) (xy 122.710555 -384.402612) (xy 122.747306 -384.365861) (xy 122.789354 -384.335311)
			(xy 122.835664 -384.311715) (xy 122.885094 -384.295654) (xy 122.936429 -384.287524) (xy 122.988403 -384.287524)
			(xy 123.039738 -384.295654) (xy 123.089168 -384.311715) (xy 123.135478 -384.335311) (xy 123.177526 -384.365861)
			(xy 123.214277 -384.402612) (xy 123.244827 -384.44466) (xy 123.268423 -384.49097) (xy 123.284484 -384.5404)
			(xy 123.292614 -384.591735) (xy 123.293124 -384.617722) (xy 123.292614 -384.643709) (xy 123.832114 -384.643709)
			(xy 123.832114 -384.591735) (xy 123.840244 -384.5404) (xy 123.856305 -384.49097) (xy 123.879901 -384.44466)
			(xy 123.910451 -384.402612) (xy 123.947202 -384.365861) (xy 123.98925 -384.335311) (xy 124.03556 -384.311715)
			(xy 124.08499 -384.295654) (xy 124.136325 -384.287524) (xy 124.188299 -384.287524) (xy 124.239634 -384.295654)
			(xy 124.289064 -384.311715) (xy 124.335374 -384.335311) (xy 124.377422 -384.365861) (xy 124.414173 -384.402612)
			(xy 124.444723 -384.44466) (xy 124.468319 -384.49097) (xy 124.48438 -384.5404) (xy 124.49251 -384.591735)
			(xy 124.49302 -384.617722) (xy 124.49251 -384.643709) (xy 125.032264 -384.643709) (xy 125.032264 -384.591735)
			(xy 125.040394 -384.5404) (xy 125.056455 -384.49097) (xy 125.080051 -384.44466) (xy 125.110601 -384.402612)
			(xy 125.147352 -384.365861) (xy 125.1894 -384.335311) (xy 125.23571 -384.311715) (xy 125.28514 -384.295654)
			(xy 125.336475 -384.287524) (xy 125.388449 -384.287524) (xy 125.439784 -384.295654) (xy 125.489214 -384.311715)
			(xy 125.535524 -384.335311) (xy 125.577572 -384.365861) (xy 125.614323 -384.402612) (xy 125.644873 -384.44466)
			(xy 125.668469 -384.49097) (xy 125.68453 -384.5404) (xy 125.69266 -384.591735) (xy 125.69317 -384.617722)
			(xy 125.69266 -384.643709) (xy 126.23216 -384.643709) (xy 126.23216 -384.591735) (xy 126.24029 -384.5404)
			(xy 126.256351 -384.49097) (xy 126.279947 -384.44466) (xy 126.310497 -384.402612) (xy 126.347248 -384.365861)
			(xy 126.389296 -384.335311) (xy 126.435606 -384.311715) (xy 126.485036 -384.295654) (xy 126.536371 -384.287524)
			(xy 126.588345 -384.287524) (xy 126.63968 -384.295654) (xy 126.68911 -384.311715) (xy 126.73542 -384.335311)
			(xy 126.777468 -384.365861) (xy 126.814219 -384.402612) (xy 126.844769 -384.44466) (xy 126.868365 -384.49097)
			(xy 126.884426 -384.5404) (xy 126.892556 -384.591735) (xy 126.893066 -384.617722) (xy 126.892556 -384.643709)
			(xy 127.432056 -384.643709) (xy 127.432056 -384.591735) (xy 127.440186 -384.5404) (xy 127.456247 -384.49097)
			(xy 127.479843 -384.44466) (xy 127.510393 -384.402612) (xy 127.547144 -384.365861) (xy 127.589192 -384.335311)
			(xy 127.635502 -384.311715) (xy 127.684932 -384.295654) (xy 127.736267 -384.287524) (xy 127.788241 -384.287524)
			(xy 127.839576 -384.295654) (xy 127.889006 -384.311715) (xy 127.935316 -384.335311) (xy 127.977364 -384.365861)
			(xy 128.014115 -384.402612) (xy 128.044665 -384.44466) (xy 128.068261 -384.49097) (xy 128.084322 -384.5404)
			(xy 128.092452 -384.591735) (xy 128.092962 -384.617722) (xy 128.092452 -384.643709) (xy 128.632206 -384.643709)
			(xy 128.632206 -384.591735) (xy 128.640336 -384.5404) (xy 128.656397 -384.49097) (xy 128.679993 -384.44466)
			(xy 128.710543 -384.402612) (xy 128.747294 -384.365861) (xy 128.789342 -384.335311) (xy 128.835652 -384.311715)
			(xy 128.885082 -384.295654) (xy 128.936417 -384.287524) (xy 128.988391 -384.287524) (xy 129.039726 -384.295654)
			(xy 129.089156 -384.311715) (xy 129.135466 -384.335311) (xy 129.177514 -384.365861) (xy 129.214265 -384.402612)
			(xy 129.244815 -384.44466) (xy 129.268411 -384.49097) (xy 129.284472 -384.5404) (xy 129.292602 -384.591735)
			(xy 129.293112 -384.617722) (xy 129.292602 -384.643709) (xy 129.832102 -384.643709) (xy 129.832102 -384.591735)
			(xy 129.840232 -384.5404) (xy 129.856293 -384.49097) (xy 129.879889 -384.44466) (xy 129.910439 -384.402612)
			(xy 129.94719 -384.365861) (xy 129.989238 -384.335311) (xy 130.035548 -384.311715) (xy 130.084978 -384.295654)
			(xy 130.136313 -384.287524) (xy 130.188287 -384.287524) (xy 130.239622 -384.295654) (xy 130.289052 -384.311715)
			(xy 130.335362 -384.335311) (xy 130.37741 -384.365861) (xy 130.414161 -384.402612) (xy 130.444711 -384.44466)
			(xy 130.468307 -384.49097) (xy 130.484368 -384.5404) (xy 130.492498 -384.591735) (xy 130.493008 -384.617722)
			(xy 130.492498 -384.643709) (xy 131.032252 -384.643709) (xy 131.032252 -384.591735) (xy 131.040382 -384.5404)
			(xy 131.056443 -384.49097) (xy 131.080039 -384.44466) (xy 131.110589 -384.402612) (xy 131.14734 -384.365861)
			(xy 131.189388 -384.335311) (xy 131.235698 -384.311715) (xy 131.285128 -384.295654) (xy 131.336463 -384.287524)
			(xy 131.388437 -384.287524) (xy 131.439772 -384.295654) (xy 131.489202 -384.311715) (xy 131.535512 -384.335311)
			(xy 131.57756 -384.365861) (xy 131.614311 -384.402612) (xy 131.644861 -384.44466) (xy 131.668457 -384.49097)
			(xy 131.684518 -384.5404) (xy 131.692648 -384.591735) (xy 131.693158 -384.617722) (xy 131.692648 -384.643709)
			(xy 132.232148 -384.643709) (xy 132.232148 -384.591735) (xy 132.240278 -384.5404) (xy 132.256339 -384.49097)
			(xy 132.279935 -384.44466) (xy 132.310485 -384.402612) (xy 132.347236 -384.365861) (xy 132.389284 -384.335311)
			(xy 132.435594 -384.311715) (xy 132.485024 -384.295654) (xy 132.536359 -384.287524) (xy 132.588333 -384.287524)
			(xy 132.639668 -384.295654) (xy 132.689098 -384.311715) (xy 132.735408 -384.335311) (xy 132.777456 -384.365861)
			(xy 132.814207 -384.402612) (xy 132.844757 -384.44466) (xy 132.868353 -384.49097) (xy 132.884414 -384.5404)
			(xy 132.892544 -384.591735) (xy 132.893054 -384.617722) (xy 132.892544 -384.643709) (xy 132.884414 -384.695044)
			(xy 132.868353 -384.744474) (xy 132.844757 -384.790784) (xy 132.814207 -384.832832) (xy 132.777456 -384.869583)
			(xy 132.735408 -384.900133) (xy 132.689098 -384.923729) (xy 132.639668 -384.93979) (xy 132.588333 -384.94792)
			(xy 132.536359 -384.94792) (xy 132.485024 -384.93979) (xy 132.435594 -384.923729) (xy 132.389284 -384.900133)
			(xy 132.347236 -384.869583) (xy 132.310485 -384.832832) (xy 132.279935 -384.790784) (xy 132.256339 -384.744474)
			(xy 132.240278 -384.695044) (xy 132.232148 -384.643709) (xy 131.692648 -384.643709) (xy 131.684518 -384.695044)
			(xy 131.668457 -384.744474) (xy 131.644861 -384.790784) (xy 131.614311 -384.832832) (xy 131.57756 -384.869583)
			(xy 131.535512 -384.900133) (xy 131.489202 -384.923729) (xy 131.439772 -384.93979) (xy 131.388437 -384.94792)
			(xy 131.336463 -384.94792) (xy 131.285128 -384.93979) (xy 131.235698 -384.923729) (xy 131.189388 -384.900133)
			(xy 131.14734 -384.869583) (xy 131.110589 -384.832832) (xy 131.080039 -384.790784) (xy 131.056443 -384.744474)
			(xy 131.040382 -384.695044) (xy 131.032252 -384.643709) (xy 130.492498 -384.643709) (xy 130.484368 -384.695044)
			(xy 130.468307 -384.744474) (xy 130.444711 -384.790784) (xy 130.414161 -384.832832) (xy 130.37741 -384.869583)
			(xy 130.335362 -384.900133) (xy 130.289052 -384.923729) (xy 130.239622 -384.93979) (xy 130.188287 -384.94792)
			(xy 130.136313 -384.94792) (xy 130.084978 -384.93979) (xy 130.035548 -384.923729) (xy 129.989238 -384.900133)
			(xy 129.94719 -384.869583) (xy 129.910439 -384.832832) (xy 129.879889 -384.790784) (xy 129.856293 -384.744474)
			(xy 129.840232 -384.695044) (xy 129.832102 -384.643709) (xy 129.292602 -384.643709) (xy 129.284472 -384.695044)
			(xy 129.268411 -384.744474) (xy 129.244815 -384.790784) (xy 129.214265 -384.832832) (xy 129.177514 -384.869583)
			(xy 129.135466 -384.900133) (xy 129.089156 -384.923729) (xy 129.039726 -384.93979) (xy 128.988391 -384.94792)
			(xy 128.936417 -384.94792) (xy 128.885082 -384.93979) (xy 128.835652 -384.923729) (xy 128.789342 -384.900133)
			(xy 128.747294 -384.869583) (xy 128.710543 -384.832832) (xy 128.679993 -384.790784) (xy 128.656397 -384.744474)
			(xy 128.640336 -384.695044) (xy 128.632206 -384.643709) (xy 128.092452 -384.643709) (xy 128.084322 -384.695044)
			(xy 128.068261 -384.744474) (xy 128.044665 -384.790784) (xy 128.014115 -384.832832) (xy 127.977364 -384.869583)
			(xy 127.935316 -384.900133) (xy 127.889006 -384.923729) (xy 127.839576 -384.93979) (xy 127.788241 -384.94792)
			(xy 127.736267 -384.94792) (xy 127.684932 -384.93979) (xy 127.635502 -384.923729) (xy 127.589192 -384.900133)
			(xy 127.547144 -384.869583) (xy 127.510393 -384.832832) (xy 127.479843 -384.790784) (xy 127.456247 -384.744474)
			(xy 127.440186 -384.695044) (xy 127.432056 -384.643709) (xy 126.892556 -384.643709) (xy 126.884426 -384.695044)
			(xy 126.868365 -384.744474) (xy 126.844769 -384.790784) (xy 126.814219 -384.832832) (xy 126.777468 -384.869583)
			(xy 126.73542 -384.900133) (xy 126.68911 -384.923729) (xy 126.63968 -384.93979) (xy 126.588345 -384.94792)
			(xy 126.536371 -384.94792) (xy 126.485036 -384.93979) (xy 126.435606 -384.923729) (xy 126.389296 -384.900133)
			(xy 126.347248 -384.869583) (xy 126.310497 -384.832832) (xy 126.279947 -384.790784) (xy 126.256351 -384.744474)
			(xy 126.24029 -384.695044) (xy 126.23216 -384.643709) (xy 125.69266 -384.643709) (xy 125.68453 -384.695044)
			(xy 125.668469 -384.744474) (xy 125.644873 -384.790784) (xy 125.614323 -384.832832) (xy 125.577572 -384.869583)
			(xy 125.535524 -384.900133) (xy 125.489214 -384.923729) (xy 125.439784 -384.93979) (xy 125.388449 -384.94792)
			(xy 125.336475 -384.94792) (xy 125.28514 -384.93979) (xy 125.23571 -384.923729) (xy 125.1894 -384.900133)
			(xy 125.147352 -384.869583) (xy 125.110601 -384.832832) (xy 125.080051 -384.790784) (xy 125.056455 -384.744474)
			(xy 125.040394 -384.695044) (xy 125.032264 -384.643709) (xy 124.49251 -384.643709) (xy 124.48438 -384.695044)
			(xy 124.468319 -384.744474) (xy 124.444723 -384.790784) (xy 124.414173 -384.832832) (xy 124.377422 -384.869583)
			(xy 124.335374 -384.900133) (xy 124.289064 -384.923729) (xy 124.239634 -384.93979) (xy 124.188299 -384.94792)
			(xy 124.136325 -384.94792) (xy 124.08499 -384.93979) (xy 124.03556 -384.923729) (xy 123.98925 -384.900133)
			(xy 123.947202 -384.869583) (xy 123.910451 -384.832832) (xy 123.879901 -384.790784) (xy 123.856305 -384.744474)
			(xy 123.840244 -384.695044) (xy 123.832114 -384.643709) (xy 123.292614 -384.643709) (xy 123.284484 -384.695044)
			(xy 123.268423 -384.744474) (xy 123.244827 -384.790784) (xy 123.214277 -384.832832) (xy 123.177526 -384.869583)
			(xy 123.135478 -384.900133) (xy 123.089168 -384.923729) (xy 123.039738 -384.93979) (xy 122.988403 -384.94792)
			(xy 122.936429 -384.94792) (xy 122.885094 -384.93979) (xy 122.835664 -384.923729) (xy 122.789354 -384.900133)
			(xy 122.747306 -384.869583) (xy 122.710555 -384.832832) (xy 122.680005 -384.790784) (xy 122.656409 -384.744474)
			(xy 122.640348 -384.695044) (xy 122.632218 -384.643709) (xy 122.092464 -384.643709) (xy 122.084334 -384.695044)
			(xy 122.068273 -384.744474) (xy 122.044677 -384.790784) (xy 122.014127 -384.832832) (xy 121.977376 -384.869583)
			(xy 121.935328 -384.900133) (xy 121.889018 -384.923729) (xy 121.839588 -384.93979) (xy 121.788253 -384.94792)
			(xy 121.736279 -384.94792) (xy 121.684944 -384.93979) (xy 121.635514 -384.923729) (xy 121.589204 -384.900133)
			(xy 121.547156 -384.869583) (xy 121.510405 -384.832832) (xy 121.479855 -384.790784) (xy 121.456259 -384.744474)
			(xy 121.440198 -384.695044) (xy 121.432068 -384.643709) (xy 120.892568 -384.643709) (xy 120.884438 -384.695044)
			(xy 120.868377 -384.744474) (xy 120.844781 -384.790784) (xy 120.814231 -384.832832) (xy 120.77748 -384.869583)
			(xy 120.735432 -384.900133) (xy 120.689122 -384.923729) (xy 120.639692 -384.93979) (xy 120.588357 -384.94792)
			(xy 120.536383 -384.94792) (xy 120.485048 -384.93979) (xy 120.435618 -384.923729) (xy 120.389308 -384.900133)
			(xy 120.34726 -384.869583) (xy 120.310509 -384.832832) (xy 120.279959 -384.790784) (xy 120.256363 -384.744474)
			(xy 120.240302 -384.695044) (xy 120.232172 -384.643709) (xy 119.692672 -384.643709) (xy 119.684542 -384.695044)
			(xy 119.668481 -384.744474) (xy 119.644885 -384.790784) (xy 119.614335 -384.832832) (xy 119.577584 -384.869583)
			(xy 119.535536 -384.900133) (xy 119.489226 -384.923729) (xy 119.439796 -384.93979) (xy 119.388461 -384.94792)
			(xy 119.336487 -384.94792) (xy 119.285152 -384.93979) (xy 119.235722 -384.923729) (xy 119.189412 -384.900133)
			(xy 119.147364 -384.869583) (xy 119.110613 -384.832832) (xy 119.080063 -384.790784) (xy 119.056467 -384.744474)
			(xy 119.040406 -384.695044) (xy 119.032276 -384.643709) (xy 118.492522 -384.643709) (xy 118.484392 -384.695044)
			(xy 118.468331 -384.744474) (xy 118.444735 -384.790784) (xy 118.414185 -384.832832) (xy 118.377434 -384.869583)
			(xy 118.335386 -384.900133) (xy 118.289076 -384.923729) (xy 118.239646 -384.93979) (xy 118.188311 -384.94792)
			(xy 118.136337 -384.94792) (xy 118.085002 -384.93979) (xy 118.035572 -384.923729) (xy 117.989262 -384.900133)
			(xy 117.947214 -384.869583) (xy 117.910463 -384.832832) (xy 117.879913 -384.790784) (xy 117.856317 -384.744474)
			(xy 117.840256 -384.695044) (xy 117.832126 -384.643709) (xy 117.292626 -384.643709) (xy 117.284496 -384.695044)
			(xy 117.268435 -384.744474) (xy 117.244839 -384.790784) (xy 117.214289 -384.832832) (xy 117.177538 -384.869583)
			(xy 117.13549 -384.900133) (xy 117.08918 -384.923729) (xy 117.03975 -384.93979) (xy 116.988415 -384.94792)
			(xy 116.936441 -384.94792) (xy 116.885106 -384.93979) (xy 116.835676 -384.923729) (xy 116.789366 -384.900133)
			(xy 116.747318 -384.869583) (xy 116.710567 -384.832832) (xy 116.680017 -384.790784) (xy 116.656421 -384.744474)
			(xy 116.64036 -384.695044) (xy 116.63223 -384.643709) (xy 116.092476 -384.643709) (xy 116.084346 -384.695044)
			(xy 116.068285 -384.744474) (xy 116.044689 -384.790784) (xy 116.014139 -384.832832) (xy 115.977388 -384.869583)
			(xy 115.93534 -384.900133) (xy 115.88903 -384.923729) (xy 115.8396 -384.93979) (xy 115.788265 -384.94792)
			(xy 115.736291 -384.94792) (xy 115.684956 -384.93979) (xy 115.635526 -384.923729) (xy 115.589216 -384.900133)
			(xy 115.547168 -384.869583) (xy 115.510417 -384.832832) (xy 115.479867 -384.790784) (xy 115.456271 -384.744474)
			(xy 115.44021 -384.695044) (xy 115.43208 -384.643709) (xy 114.879742 -384.643709) (xy 114.872081 -384.692074)
			(xy 114.856637 -384.739606) (xy 114.833947 -384.784138) (xy 114.804571 -384.824571) (xy 114.769231 -384.859911)
			(xy 114.728798 -384.889287) (xy 114.684266 -384.911977) (xy 114.636734 -384.927421) (xy 114.587371 -384.93524)
			(xy 114.537393 -384.93524) (xy 114.48803 -384.927421) (xy 114.440498 -384.911977) (xy 114.395966 -384.889287)
			(xy 114.355533 -384.859911) (xy 114.320193 -384.824571) (xy 114.290817 -384.784138) (xy 114.268127 -384.739606)
			(xy 114.252683 -384.692074) (xy 114.244864 -384.642711) (xy 112.667463 -384.642711) (xy 112.645409 -384.655493)
			(xy 112.622584 -384.664966) (xy 112.608106 -384.670808) (xy 112.59058 -384.696462) (xy 112.59058 -385.87553)
			(xy 113.933986 -385.87553) (xy 113.934549 -385.84795) (xy 113.943747 -385.793561) (xy 113.952274 -385.767326)
			(xy 113.955068 -385.759452) (xy 113.955068 -385.61518) (xy 113.955617 -385.598487) (xy 113.96425 -385.566237)
			(xy 113.980925 -385.537314) (xy 114.004508 -385.513683) (xy 114.033398 -385.496949) (xy 114.06563 -385.488251)
			(xy 114.082322 -385.487672) (xy 114.463322 -385.487672) (xy 114.473228 -385.48818) (xy 114.485003 -385.488497)
			(xy 114.506849 -385.479781) (xy 114.515138 -385.471416) (xy 114.57686 -385.402836) (xy 114.58321 -385.379976)
			(xy 114.582448 -385.376166) (xy 114.582448 -385.375404) (xy 114.579323 -385.359331) (xy 114.576014 -385.326753)
			(xy 114.575844 -385.31038) (xy 114.5763 -385.285589) (xy 114.584059 -385.236619) (xy 114.599383 -385.189465)
			(xy 114.621895 -385.145288) (xy 114.651041 -385.105178) (xy 114.686102 -385.07012) (xy 114.726216 -385.040978)
			(xy 114.770394 -385.018471) (xy 114.81755 -385.003151) (xy 114.866521 -384.995397) (xy 114.891312 -384.994912)
			(xy 114.914925 -384.995336) (xy 114.961624 -385.002385) (xy 115.006751 -385.01631) (xy 115.049302 -385.0368)
			(xy 115.088327 -385.063398) (xy 115.122956 -385.095511) (xy 115.152417 -385.132423) (xy 115.164616 -385.152646)
			(xy 115.173836 -385.169159) (xy 115.18874 -385.203921) (xy 115.194334 -385.221988) (xy 115.194842 -385.22402)
			(xy 115.195858 -385.228084) (xy 115.243777 -385.310888) (xy 115.77574 -385.310888) (xy 115.77574 -385.31038)
			(xy 115.7762 -385.285589) (xy 115.783959 -385.236619) (xy 115.799283 -385.189465) (xy 115.821794 -385.14529)
			(xy 115.850939 -385.105179) (xy 115.886 -385.070121) (xy 115.926113 -385.04098) (xy 115.970291 -385.018472)
			(xy 116.017446 -385.003152) (xy 116.066417 -384.995397) (xy 116.091208 -384.994912) (xy 116.116603 -384.995388)
			(xy 116.166739 -385.003521) (xy 116.214926 -385.019575) (xy 116.259922 -385.043136) (xy 116.300565 -385.073597)
			(xy 116.335807 -385.110172) (xy 116.364739 -385.151917) (xy 116.386615 -385.197756) (xy 116.39423 -385.221988)
			(xy 116.395754 -385.22783) (xy 116.443504 -385.31038) (xy 116.975636 -385.31038) (xy 116.976098 -385.285602)
			(xy 116.98385 -385.236657) (xy 116.999158 -385.189525) (xy 117.021647 -385.145367) (xy 117.050764 -385.105267)
			(xy 117.085792 -385.070213) (xy 117.12587 -385.041067) (xy 117.170012 -385.018546) (xy 117.217133 -385.003203)
			(xy 117.266073 -384.995417) (xy 117.29085 -384.994912) (xy 117.291358 -384.994912) (xy 117.316807 -384.995378)
			(xy 117.367046 -385.003536) (xy 117.415326 -385.019649) (xy 117.460396 -385.043297) (xy 117.501088 -385.073869)
			(xy 117.536349 -385.110574) (xy 117.565265 -385.152459) (xy 117.587087 -385.198441) (xy 117.594634 -385.22275)
			(xy 117.596158 -385.228592) (xy 117.915944 -385.78155) (xy 117.920008 -385.785868) (xy 117.936208 -385.803546)
			(xy 117.963608 -385.842893) (xy 117.984739 -385.885933) (xy 117.999117 -385.931675) (xy 118.00641 -385.979065)
			(xy 118.006876 -386.003038) (xy 118.006876 -386.003546) (xy 118.006114 -386.023866) (xy 118.005352 -386.033772)
			(xy 118.011702 -386.052822) (xy 118.072408 -386.122164) (xy 118.090188 -386.131054) (xy 118.100348 -386.131816)
			(xy 118.125323 -386.134026) (xy 118.174181 -386.145275) (xy 118.220668 -386.164052) (xy 118.263633 -386.18989)
			(xy 118.302012 -386.222149) (xy 118.318788 -386.240782) (xy 118.321246 -386.243558) (xy 118.326862 -386.248402)
			(xy 118.329964 -386.250434) (xy 118.34204 -386.258475) (xy 118.361995 -386.279525) (xy 118.376065 -386.304888)
			(xy 118.383362 -386.33296) (xy 118.383812 -386.347462) (xy 118.383812 -386.3594) (xy 118.385336 -386.366004)
			(xy 118.390528 -386.386376) (xy 118.396138 -386.428042) (xy 118.396512 -386.449062) (xy 118.39613 -386.470082)
			(xy 118.39053 -386.511748) (xy 118.385336 -386.53212) (xy 118.383812 -386.538724) (xy 118.383812 -386.652262)
			(xy 118.383333 -386.66726) (xy 118.375587 -386.696237) (xy 118.360611 -386.722226) (xy 118.339425 -386.743458)
			(xy 118.313469 -386.758491) (xy 118.284508 -386.7663) (xy 118.269512 -386.766816) (xy 118.087394 -386.766816)
			(xy 118.086886 -386.76707) (xy 118.070122 -386.76707) (xy 118.069614 -386.766816) (xy 117.888004 -386.766816)
			(xy 117.872976 -386.766317) (xy 117.84394 -386.758549) (xy 117.817899 -386.743542) (xy 117.796621 -386.722313)
			(xy 117.781553 -386.696307) (xy 117.773718 -386.667289) (xy 117.773196 -386.652262) (xy 117.773196 -386.538724)
			(xy 117.771672 -386.53212) (xy 117.766466 -386.511751) (xy 117.760865 -386.470083) (xy 117.760496 -386.449062)
			(xy 117.761258 -386.426456) (xy 117.76202 -386.41655) (xy 117.75567 -386.397246) (xy 117.695472 -386.327904)
			(xy 117.677438 -386.31876) (xy 117.667532 -386.317998) (xy 117.643708 -386.315777) (xy 117.597079 -386.305054)
			(xy 117.552604 -386.287412) (xy 117.511303 -386.263256) (xy 117.474123 -386.23314) (xy 117.441918 -386.197755)
			(xy 117.415425 -386.157913) (xy 117.395252 -386.114527) (xy 117.388132 -386.091684) (xy 117.386608 -386.085842)
			(xy 117.06606 -385.53136) (xy 117.061996 -385.527042) (xy 117.045876 -385.509387) (xy 117.018628 -385.470105)
			(xy 116.99762 -385.427161) (xy 116.983332 -385.381539) (xy 116.976091 -385.334283) (xy 116.975636 -385.31038)
			(xy 116.443504 -385.31038) (xy 116.716048 -385.78155) (xy 116.720112 -385.785868) (xy 116.736313 -385.803545)
			(xy 116.763712 -385.842893) (xy 116.784844 -385.885933) (xy 116.799221 -385.931675) (xy 116.806514 -385.979064)
			(xy 116.80698 -386.003038) (xy 116.80698 -386.003546) (xy 116.806218 -386.023866) (xy 116.805456 -386.033772)
			(xy 116.811806 -386.052822) (xy 116.872512 -386.122164) (xy 116.890292 -386.131054) (xy 116.900452 -386.131816)
			(xy 116.925427 -386.134023) (xy 116.974285 -386.145274) (xy 117.020772 -386.164051) (xy 117.063737 -386.189889)
			(xy 117.102116 -386.222149) (xy 117.118892 -386.240782) (xy 117.12135 -386.243559) (xy 117.126965 -386.248402)
			(xy 117.130068 -386.250434) (xy 117.142145 -386.258474) (xy 117.162099 -386.279524) (xy 117.17617 -386.304888)
			(xy 117.183466 -386.33296) (xy 117.183916 -386.347462) (xy 117.183916 -386.3594) (xy 117.18544 -386.366004)
			(xy 117.190632 -386.386376) (xy 117.196242 -386.428042) (xy 117.196616 -386.449062) (xy 117.196234 -386.470082)
			(xy 117.190634 -386.511748) (xy 117.18544 -386.53212) (xy 117.183916 -386.538724) (xy 117.183916 -386.652262)
			(xy 117.183433 -386.667259) (xy 117.175687 -386.696236) (xy 117.160712 -386.722224) (xy 117.139527 -386.743457)
			(xy 117.113572 -386.75849) (xy 117.084612 -386.7663) (xy 117.069616 -386.766816) (xy 116.887498 -386.766816)
			(xy 116.88699 -386.76707) (xy 116.870226 -386.76707) (xy 116.869718 -386.766816) (xy 116.688108 -386.766816)
			(xy 116.67308 -386.766313) (xy 116.644045 -386.758547) (xy 116.618003 -386.74354) (xy 116.596725 -386.722312)
			(xy 116.581657 -386.696306) (xy 116.573822 -386.667289) (xy 116.5733 -386.652262) (xy 116.5733 -386.538724)
			(xy 116.571776 -386.53212) (xy 116.56657 -386.511751) (xy 116.560969 -386.470083) (xy 116.5606 -386.449062)
			(xy 116.561362 -386.426456) (xy 116.562124 -386.41655) (xy 116.555774 -386.397246) (xy 116.495576 -386.327904)
			(xy 116.477542 -386.31876) (xy 116.467636 -386.317998) (xy 116.443812 -386.315774) (xy 116.397183 -386.305051)
			(xy 116.352708 -386.287409) (xy 116.311407 -386.263254) (xy 116.274228 -386.233139) (xy 116.242022 -386.197755)
			(xy 116.215529 -386.157913) (xy 116.195356 -386.114527) (xy 116.188236 -386.091684) (xy 116.186712 -386.085842)
			(xy 115.866418 -385.532122) (xy 115.862354 -385.527804) (xy 115.846202 -385.510131) (xy 115.818882 -385.470815)
			(xy 115.797813 -385.427825) (xy 115.783478 -385.382146) (xy 115.776205 -385.334825) (xy 115.77574 -385.310888)
			(xy 115.243777 -385.310888) (xy 115.516152 -385.78155) (xy 115.520216 -385.785868) (xy 115.536417 -385.803545)
			(xy 115.563816 -385.842893) (xy 115.584948 -385.885933) (xy 115.599325 -385.931674) (xy 115.606618 -385.979064)
			(xy 115.607084 -386.003038) (xy 115.607084 -386.003546) (xy 115.606322 -386.023866) (xy 115.60556 -386.033772)
			(xy 115.61191 -386.052822) (xy 115.672616 -386.122164) (xy 115.690396 -386.131054) (xy 115.700556 -386.131816)
			(xy 115.725503 -386.13406) (xy 115.774302 -386.145334) (xy 115.820732 -386.164115) (xy 115.863645 -386.189939)
			(xy 115.901982 -386.222169) (xy 115.918742 -386.240782) (xy 115.921206 -386.243553) (xy 115.926817 -386.248401)
			(xy 115.929918 -386.250434) (xy 115.941956 -386.258501) (xy 115.961846 -386.279565) (xy 115.975851 -386.304925)
			(xy 115.983088 -386.332977) (xy 115.983512 -386.347462) (xy 115.983512 -386.3594) (xy 115.98529 -386.366004)
			(xy 115.990481 -386.386377) (xy 115.996092 -386.428042) (xy 115.996466 -386.449062) (xy 115.996086 -386.470082)
			(xy 115.990485 -386.511749) (xy 115.98529 -386.53212) (xy 115.983512 -386.538724) (xy 115.983512 -386.652262)
			(xy 115.983074 -386.667286) (xy 115.975303 -386.696313) (xy 115.960282 -386.722337) (xy 115.939034 -386.743584)
			(xy 115.913009 -386.758605) (xy 115.883982 -386.766375) (xy 115.868958 -386.766816) (xy 115.687348 -386.766816)
			(xy 115.68684 -386.76707) (xy 115.670076 -386.76707) (xy 115.669568 -386.766816) (xy 115.487958 -386.766816)
			(xy 115.472936 -386.7664) (xy 115.443919 -386.758614) (xy 115.417905 -386.743583) (xy 115.396668 -386.722331)
			(xy 115.381655 -386.696307) (xy 115.373889 -386.667284) (xy 115.373404 -386.652262) (xy 115.373404 -386.538724)
			(xy 115.371626 -386.53212) (xy 115.366419 -386.511751) (xy 115.360819 -386.470083) (xy 115.36045 -386.449062)
			(xy 115.361212 -386.426456) (xy 115.361974 -386.416296) (xy 115.355878 -386.3975) (xy 115.302284 -386.335524)
			(xy 115.295363 -386.328255) (xy 115.277446 -386.319246) (xy 115.267486 -386.317998) (xy 115.243673 -386.315816)
			(xy 115.19708 -386.305053) (xy 115.152644 -386.287384) (xy 115.111383 -386.263212) (xy 115.074242 -386.233091)
			(xy 115.04207 -386.197711) (xy 115.015605 -386.157882) (xy 114.995453 -386.114516) (xy 114.98834 -386.091684)
			(xy 114.986816 -386.085842) (xy 114.669316 -385.537202) (xy 114.662458 -385.527804) (xy 114.654076 -385.51866)
			(xy 114.61369 -385.542028) (xy 114.605038 -385.547631) (xy 114.592696 -385.564113) (xy 114.587827 -385.584119)
			(xy 114.589052 -385.594352) (xy 114.590576 -385.614926) (xy 114.590576 -385.615434) (xy 114.590576 -385.819904)
			(xy 114.591338 -385.823714) (xy 114.593241 -385.83652) (xy 114.595279 -385.86233) (xy 114.595402 -385.875276)
			(xy 114.595402 -385.87553) (xy 114.595232 -385.891119) (xy 114.592306 -385.92216) (xy 114.58956 -385.937506)
			(xy 114.589052 -385.939538) (xy 114.585496 -385.956048) (xy 114.584988 -385.957572) (xy 114.580497 -385.974211)
			(xy 114.568538 -386.006535) (xy 114.561112 -386.022088) (xy 114.561112 -386.022342) (xy 114.557111 -386.031623)
			(xy 114.555916 -386.051781) (xy 114.558826 -386.061458) (xy 114.586766 -386.140198) (xy 114.600736 -386.155184)
			(xy 114.610134 -386.159502) (xy 114.630717 -386.169334) (xy 114.669103 -386.193973) (xy 114.703593 -386.223822)
			(xy 114.718846 -386.240782) (xy 114.721309 -386.243554) (xy 114.726921 -386.248401) (xy 114.730022 -386.250434)
			(xy 114.742061 -386.2585) (xy 114.76195 -386.279564) (xy 114.775956 -386.304925) (xy 114.783192 -386.332977)
			(xy 114.783616 -386.347462) (xy 114.783616 -386.3594) (xy 114.785394 -386.366004) (xy 114.790585 -386.386377)
			(xy 114.796196 -386.428042) (xy 114.79657 -386.449062) (xy 114.79619 -386.470082) (xy 114.790589 -386.511749)
			(xy 114.785394 -386.53212) (xy 114.783616 -386.538724) (xy 114.783616 -386.652262) (xy 114.783174 -386.667286)
			(xy 114.775404 -386.696312) (xy 114.760383 -386.722336) (xy 114.739136 -386.743583) (xy 114.713112 -386.758604)
			(xy 114.684086 -386.766374) (xy 114.669062 -386.766816) (xy 114.487452 -386.766816) (xy 114.486944 -386.76707)
			(xy 114.47018 -386.76707) (xy 114.469672 -386.766816) (xy 114.288062 -386.766816) (xy 114.27304 -386.766397)
			(xy 114.244023 -386.758611) (xy 114.218009 -386.743581) (xy 114.196773 -386.72233) (xy 114.181759 -386.696306)
			(xy 114.173993 -386.667284) (xy 114.173508 -386.652262) (xy 114.173508 -386.538724) (xy 114.17173 -386.53212)
			(xy 114.166523 -386.511751) (xy 114.160923 -386.470083) (xy 114.160554 -386.449062) (xy 114.160922 -386.428041)
			(xy 114.166532 -386.386375) (xy 114.17173 -386.366004) (xy 114.173508 -386.3594) (xy 114.173508 -386.347462)
			(xy 114.173706 -386.336867) (xy 114.177538 -386.316029) (xy 114.181128 -386.30606) (xy 114.184684 -386.296916)
			(xy 114.18443 -386.277612) (xy 114.150394 -386.194554) (xy 114.13744 -386.180838) (xy 114.128296 -386.176774)
			(xy 114.103836 -386.165144) (xy 114.058794 -386.13507) (xy 114.019256 -386.098057) (xy 113.986279 -386.055094)
			(xy 113.960746 -386.007332) (xy 113.943339 -385.956046) (xy 113.934523 -385.90261) (xy 113.933986 -385.87553)
			(xy 112.59058 -385.87553) (xy 112.59058 -386.601208) (xy 112.590155 -386.611277) (xy 112.582436 -386.629878)
			(xy 112.575594 -386.637276) (xy 112.50422 -386.70865) (xy 112.497822 -386.715629) (xy 112.490251 -386.732969)
			(xy 112.489472 -386.751873) (xy 112.49559 -386.769777) (xy 112.501426 -386.77723) (xy 112.501426 -386.777484)
			(xy 112.510749 -386.789155) (xy 112.524222 -386.815807) (xy 112.531184 -386.844849) (xy 112.531652 -386.85978)
			(xy 112.531652 -386.995162) (xy 112.53216 -386.998972) (xy 112.533831 -387.011095) (xy 112.535608 -387.035503)
			(xy 112.535716 -387.04774) (xy 112.535627 -387.059977) (xy 112.533849 -387.084387) (xy 112.53216 -387.096508)
			(xy 112.531652 -387.100318) (xy 112.531652 -387.24078) (xy 112.531109 -387.257499) (xy 112.522461 -387.289799)
			(xy 112.505749 -387.31876) (xy 112.482111 -387.34241) (xy 112.453158 -387.359137) (xy 112.420863 -387.367801)
			(xy 112.404144 -387.368288) (xy 112.28705 -387.368288) (xy 112.281208 -387.369558) (xy 112.256142 -387.374993)
			(xy 112.205008 -387.378961) (xy 112.153874 -387.374993) (xy 112.128808 -387.369558) (xy 112.122966 -387.368288)
			(xy 112.099344 -387.368288) (xy 112.08204 -387.3677) (xy 112.048707 -387.358391) (xy 112.019098 -387.340474)
			(xy 111.995389 -387.315263) (xy 111.986822 -387.300216) (xy 111.984827 -387.296579) (xy 111.979846 -387.289945)
			(xy 111.976916 -387.287008) (xy 111.957878 -387.268171) (xy 111.925548 -387.225477) (xy 111.900523 -387.178129)
			(xy 111.88346 -387.127366) (xy 111.874804 -387.074517) (xy 111.8743 -387.04774) (xy 111.874431 -387.035821)
			(xy 111.876212 -387.012048) (xy 111.877856 -387.000242) (xy 111.877856 -386.999988) (xy 111.878866 -386.989113)
			(xy 111.872665 -386.968193) (xy 111.865918 -386.959602) (xy 111.815626 -386.901436) (xy 111.808072 -386.893525)
			(xy 111.788197 -386.884443) (xy 111.777272 -386.88391) (xy 110.46206 -386.88391) (xy 110.451993 -386.884341)
			(xy 110.4334 -386.892066) (xy 110.425992 -386.898896) (xy 109.848904 -387.475984) (xy 109.84207 -387.483387)
			(xy 109.834366 -387.501985) (xy 109.833918 -387.512052) (xy 109.833918 -388.297674) (xy 110.908844 -388.297674)
			(xy 110.912915 -388.242052) (xy 110.925041 -388.187615) (xy 110.944964 -388.135524) (xy 110.97226 -388.086889)
			(xy 111.006346 -388.042746) (xy 111.046495 -388.004037) (xy 111.091853 -387.971586) (xy 111.141453 -387.946085)
			(xy 111.194237 -387.928078) (xy 111.24908 -387.917948) (xy 111.304814 -387.915911) (xy 111.360251 -387.922011)
			(xy 111.414208 -387.936117) (xy 111.465537 -387.957929) (xy 111.513143 -387.986983) (xy 111.556011 -388.022658)
			(xy 111.593228 -388.064195) (xy 111.624001 -388.110708) (xy 111.647673 -388.161205) (xy 111.663741 -388.214612)
			(xy 111.671861 -388.269788) (xy 111.672342 -388.29615) (xy 111.8743 -388.29615) (xy 111.874852 -388.268181)
			(xy 111.88427 -388.213041) (xy 111.902831 -388.160272) (xy 111.930003 -388.111376) (xy 111.965014 -388.067749)
			(xy 111.985552 -388.048754) (xy 111.994696 -388.038086) (xy 112.003667 -388.024798) (xy 112.027004 -388.002831)
			(xy 112.055076 -387.987365) (xy 112.086113 -387.979372) (xy 112.102138 -387.978904) (xy 112.111028 -387.978904)
			(xy 112.117632 -387.977126) (xy 112.139059 -387.971649) (xy 112.182895 -387.965781) (xy 112.205008 -387.965442)
			(xy 112.227121 -387.965788) (xy 112.270956 -387.971655) (xy 112.292384 -387.977126) (xy 112.298988 -387.978904)
			(xy 112.406938 -387.978904) (xy 112.423597 -387.979454) (xy 112.455781 -387.988073) (xy 112.484644 -388.004715)
			(xy 112.508227 -388.02825) (xy 112.524928 -388.05708) (xy 112.533612 -388.089246) (xy 112.534192 -388.105904)
			(xy 112.534192 -388.26567) (xy 112.534446 -388.267956) (xy 112.535716 -388.295896) (xy 112.535716 -388.296404)
			(xy 112.534446 -388.324344) (xy 112.534192 -388.32663) (xy 112.534192 -388.328662) (xy 114.300508 -388.328662)
			(xy 114.300874 -388.307641) (xy 114.306485 -388.265975) (xy 114.311684 -388.245604) (xy 114.313208 -388.239)
			(xy 114.313208 -388.125462) (xy 114.313699 -388.110468) (xy 114.321456 -388.081499) (xy 114.336435 -388.055519)
			(xy 114.357617 -388.03429) (xy 114.383564 -388.019254) (xy 114.412515 -388.011433) (xy 114.427508 -388.010908)
			(xy 114.609626 -388.010908) (xy 114.610134 -388.010654) (xy 114.626898 -388.010654) (xy 114.627406 -388.010908)
			(xy 114.809016 -388.010908) (xy 114.824047 -388.011366) (xy 114.853087 -388.01914) (xy 114.879131 -388.034156)
			(xy 114.900408 -388.055393) (xy 114.915474 -388.081407) (xy 114.923305 -388.110432) (xy 114.923824 -388.125462)
			(xy 114.923824 -388.239) (xy 114.925348 -388.245604) (xy 114.93054 -388.265976) (xy 114.93615 -388.307642)
			(xy 114.936524 -388.328662) (xy 115.500404 -388.328662) (xy 115.50077 -388.307641) (xy 115.506381 -388.265975)
			(xy 115.51158 -388.245604) (xy 115.513104 -388.239) (xy 115.513104 -388.125462) (xy 115.513599 -388.110468)
			(xy 115.521356 -388.0815) (xy 115.536334 -388.05552) (xy 115.557515 -388.034291) (xy 115.583461 -388.019255)
			(xy 115.612411 -388.011433) (xy 115.627404 -388.010908) (xy 115.809522 -388.010908) (xy 115.81003 -388.010654)
			(xy 115.826794 -388.010654) (xy 115.827302 -388.010908) (xy 116.008912 -388.010908) (xy 116.023943 -388.01137)
			(xy 116.052983 -388.019143) (xy 116.079026 -388.034158) (xy 116.100304 -388.055394) (xy 116.11537 -388.081408)
			(xy 116.123201 -388.110432) (xy 116.12372 -388.125462) (xy 116.12372 -388.239) (xy 116.125244 -388.245604)
			(xy 116.130436 -388.265976) (xy 116.136046 -388.307642) (xy 116.13642 -388.328662) (xy 116.700554 -388.328662)
			(xy 116.700922 -388.307641) (xy 116.706532 -388.265975) (xy 116.71173 -388.245604) (xy 116.713508 -388.239)
			(xy 116.713508 -388.125462) (xy 116.714002 -388.110447) (xy 116.721781 -388.081441) (xy 116.7368 -388.055435)
			(xy 116.758035 -388.0342) (xy 116.784041 -388.019181) (xy 116.813047 -388.011402) (xy 116.828062 -388.010908)
			(xy 117.009672 -388.010908) (xy 117.01018 -388.010654) (xy 117.026944 -388.010654) (xy 117.027452 -388.010908)
			(xy 117.209062 -388.010908) (xy 117.224074 -388.011469) (xy 117.253077 -388.01923) (xy 117.279083 -388.034233)
			(xy 117.30032 -388.055456) (xy 117.315341 -388.081452) (xy 117.323121 -388.11045) (xy 117.323616 -388.125462)
			(xy 117.323616 -388.239) (xy 117.325394 -388.245604) (xy 117.330585 -388.265977) (xy 117.336196 -388.307642)
			(xy 117.33657 -388.328662) (xy 117.90045 -388.328662) (xy 117.900818 -388.307641) (xy 117.906428 -388.265975)
			(xy 117.911626 -388.245604) (xy 117.913404 -388.239) (xy 117.913404 -388.125462) (xy 117.913902 -388.110447)
			(xy 117.921681 -388.081442) (xy 117.936699 -388.055436) (xy 117.957933 -388.034201) (xy 117.983938 -388.019182)
			(xy 118.012943 -388.011403) (xy 118.027958 -388.010908) (xy 118.209568 -388.010908) (xy 118.210076 -388.010654)
			(xy 118.22684 -388.010654) (xy 118.227348 -388.010908) (xy 118.408958 -388.010908) (xy 118.423976 -388.011428)
			(xy 118.45299 -388.019191) (xy 118.479006 -388.0342) (xy 118.500251 -388.05543) (xy 118.515278 -388.081436)
			(xy 118.523061 -388.110445) (xy 118.523512 -388.125462) (xy 118.523512 -388.239) (xy 118.52529 -388.245604)
			(xy 118.530481 -388.265977) (xy 118.536092 -388.307642) (xy 118.536466 -388.328662) (xy 118.536466 -388.32917)
			(xy 118.536296 -388.343795) (xy 118.533629 -388.372924) (xy 118.531132 -388.387336) (xy 118.529764 -388.39651)
			(xy 118.533039 -388.414753) (xy 118.537482 -388.422896) (xy 118.553992 -388.44982) (xy 118.559144 -388.457612)
			(xy 118.573882 -388.469067) (xy 118.582694 -388.472172) (xy 118.607573 -388.480243) (xy 118.654453 -388.50343)
			(xy 118.696865 -388.534032) (xy 118.733649 -388.571211) (xy 118.763797 -388.613949) (xy 118.786482 -388.661073)
			(xy 118.794276 -388.68604) (xy 118.7958 -388.691882) (xy 118.890288 -388.855204) (xy 118.922038 -388.868412)
			(xy 118.938802 -388.86384) (xy 118.949379 -388.86036) (xy 118.966419 -388.84608) (xy 118.975824 -388.825934)
			(xy 118.976394 -388.814818) (xy 118.976394 -387.6675) (xy 118.989602 -387.6675) (xy 118.989602 -387.495542)
			(xy 118.990022 -387.485472) (xy 118.997744 -387.466872) (xy 119.004588 -387.459474) (xy 119.06885 -387.395212)
			(xy 119.075568 -387.387838) (xy 119.083194 -387.369423) (xy 119.083256 -387.349492) (xy 119.075745 -387.33103)
			(xy 119.069104 -387.323584) (xy 119.067834 -387.322314) (xy 119.066818 -387.321298) (xy 119.059233 -387.314477)
			(xy 119.044872 -387.299985) (xy 119.038116 -387.292342) (xy 119.035655 -387.289568) (xy 119.030042 -387.284723)
			(xy 119.02694 -387.28269) (xy 119.014876 -387.274633) (xy 118.99492 -387.253588) (xy 118.980846 -387.22823)
			(xy 118.973545 -387.200162) (xy 118.973092 -387.185662) (xy 118.973092 -387.173724) (xy 118.971568 -387.16712)
			(xy 118.966362 -387.146751) (xy 118.960761 -387.105083) (xy 118.960392 -387.084062) (xy 118.960759 -387.063041)
			(xy 118.966369 -387.021375) (xy 118.971568 -387.001004) (xy 118.973092 -386.9944) (xy 118.973092 -386.880862)
			(xy 118.973759 -386.862744) (xy 118.985009 -386.828299) (xy 118.99519 -386.813298) (xy 118.99969 -386.806629)
			(xy 119.004735 -386.791363) (xy 119.005096 -386.783326) (xy 119.005096 -386.749798) (xy 119.004801 -386.741749)
			(xy 118.999749 -386.726466) (xy 118.99519 -386.719826) (xy 118.985107 -386.704774) (xy 118.973849 -386.670363)
			(xy 118.973092 -386.652262) (xy 118.973092 -386.538724) (xy 118.971568 -386.53212) (xy 118.966362 -386.511751)
			(xy 118.960761 -386.470083) (xy 118.960392 -386.449062) (xy 118.961154 -386.426456) (xy 118.961916 -386.416296)
			(xy 118.95582 -386.3975) (xy 118.902226 -386.335524) (xy 118.89529 -386.328272) (xy 118.877384 -386.319253)
			(xy 118.867428 -386.317998) (xy 118.843618 -386.315782) (xy 118.797026 -386.305026) (xy 118.752591 -386.287362)
			(xy 118.71133 -386.263195) (xy 118.674188 -386.233079) (xy 118.642015 -386.197703) (xy 118.615549 -386.157877)
			(xy 118.595395 -386.114514) (xy 118.588282 -386.091684) (xy 118.586758 -386.085842) (xy 118.266464 -385.532122)
			(xy 118.2624 -385.527804) (xy 118.246172 -385.510117) (xy 118.218751 -385.47072) (xy 118.197613 -385.427626)
			(xy 118.183245 -385.381827) (xy 118.175979 -385.33438) (xy 118.175532 -385.31038) (xy 118.175998 -385.285603)
			(xy 118.183749 -385.236657) (xy 118.199058 -385.189526) (xy 118.221546 -385.145368) (xy 118.250663 -385.105269)
			(xy 118.28569 -385.070215) (xy 118.325768 -385.041069) (xy 118.36991 -385.018547) (xy 118.41703 -385.003204)
			(xy 118.465969 -384.995417) (xy 118.490746 -384.994912) (xy 118.491254 -384.994912) (xy 118.516648 -384.995436)
			(xy 118.566781 -385.00356) (xy 118.614967 -385.019606) (xy 118.659963 -385.04316) (xy 118.700606 -385.073615)
			(xy 118.735849 -385.110184) (xy 118.764783 -385.151924) (xy 118.78666 -385.197758) (xy 118.794276 -385.221988)
			(xy 118.7958 -385.22783) (xy 119.116094 -385.78155) (xy 119.120158 -385.785868) (xy 119.136315 -385.80357)
			(xy 119.163658 -385.84293) (xy 119.184737 -385.88597) (xy 119.199069 -385.931702) (xy 119.206322 -385.979076)
			(xy 119.206772 -386.003038) (xy 119.206772 -386.003546) (xy 119.206264 -386.023866) (xy 119.205502 -386.033772)
			(xy 119.211852 -386.052822) (xy 119.272558 -386.122164) (xy 119.290338 -386.131054) (xy 119.300498 -386.131816)
			(xy 119.325447 -386.134035) (xy 119.374247 -386.145315) (xy 119.420677 -386.164102) (xy 119.46359 -386.189932)
			(xy 119.501925 -386.222167) (xy 119.518684 -386.240782) (xy 119.521143 -386.243558) (xy 119.526758 -386.248402)
			(xy 119.52986 -386.250434) (xy 119.541935 -386.258476) (xy 119.56189 -386.279525) (xy 119.575961 -386.304888)
			(xy 119.583258 -386.33296) (xy 119.583708 -386.347462) (xy 119.583708 -386.3594) (xy 119.585232 -386.366004)
			(xy 119.590424 -386.386376) (xy 119.596034 -386.428042) (xy 119.596408 -386.449062) (xy 119.596026 -386.470082)
			(xy 119.590426 -386.511748) (xy 119.585232 -386.53212) (xy 119.583708 -386.538724) (xy 119.583708 -386.599176)
			(xy 119.58414 -386.609197) (xy 119.591803 -386.627715) (xy 119.605972 -386.641888) (xy 119.624487 -386.649557)
			(xy 119.634508 -386.649976) (xy 119.638318 -386.649976) (xy 119.642382 -386.649214) (xy 119.654051 -386.64746)
			(xy 119.677573 -386.645553) (xy 119.689372 -386.645404) (xy 120.122696 -386.645404) (xy 120.132703 -386.644909)
			(xy 120.151194 -386.637251) (xy 120.165347 -386.623101) (xy 120.173007 -386.604611) (xy 120.173496 -386.594604)
			(xy 120.173496 -386.538724) (xy 120.171718 -386.53212) (xy 120.166511 -386.511751) (xy 120.160911 -386.470083)
			(xy 120.160542 -386.449062) (xy 120.161304 -386.426456) (xy 120.162066 -386.41655) (xy 120.155716 -386.397246)
			(xy 120.095518 -386.327904) (xy 120.077484 -386.31876) (xy 120.067578 -386.317998) (xy 120.043749 -386.315821)
			(xy 119.997119 -386.30509) (xy 119.952643 -386.28744) (xy 119.911343 -386.263278) (xy 119.874164 -386.233156)
			(xy 119.84196 -386.197766) (xy 119.815468 -386.157919) (xy 119.795297 -386.114529) (xy 119.788178 -386.091684)
			(xy 119.786654 -386.085842) (xy 119.46636 -385.532122) (xy 119.462296 -385.527804) (xy 119.446067 -385.510118)
			(xy 119.418647 -385.470721) (xy 119.397509 -385.427626) (xy 119.383141 -385.381827) (xy 119.375875 -385.33438)
			(xy 119.375428 -385.31038) (xy 119.375898 -385.285603) (xy 119.383649 -385.236658) (xy 119.398957 -385.189527)
			(xy 119.421446 -385.145369) (xy 119.450562 -385.10527) (xy 119.485589 -385.070216) (xy 119.525666 -385.04107)
			(xy 119.569807 -385.018548) (xy 119.616926 -385.003205) (xy 119.665865 -384.995417) (xy 119.690642 -384.994912)
			(xy 119.69115 -384.994912) (xy 119.716544 -384.995439) (xy 119.766677 -385.003563) (xy 119.814863 -385.019609)
			(xy 119.859858 -385.043162) (xy 119.900502 -385.073616) (xy 119.935745 -385.110185) (xy 119.964679 -385.151924)
			(xy 119.986556 -385.197758) (xy 119.994172 -385.221988) (xy 119.995696 -385.22783) (xy 120.31599 -385.78155)
			(xy 120.320054 -385.785868) (xy 120.33621 -385.803571) (xy 120.363554 -385.84293) (xy 120.384633 -385.88597)
			(xy 120.398965 -385.931703) (xy 120.406218 -385.979076) (xy 120.406668 -386.003038) (xy 120.406668 -386.003546)
			(xy 120.40616 -386.023866) (xy 120.405398 -386.033772) (xy 120.411748 -386.052822) (xy 120.472454 -386.122164)
			(xy 120.490234 -386.131054) (xy 120.500394 -386.131816) (xy 120.525372 -386.133998) (xy 120.57423 -386.145255)
			(xy 120.620717 -386.164038) (xy 120.663682 -386.189882) (xy 120.702059 -386.222147) (xy 120.718834 -386.240782)
			(xy 120.721299 -386.243552) (xy 120.72691 -386.2484) (xy 120.73001 -386.250434) (xy 120.742046 -386.258503)
			(xy 120.761937 -386.279566) (xy 120.775943 -386.304925) (xy 120.78318 -386.332977) (xy 120.783604 -386.347462)
			(xy 120.783604 -386.3594) (xy 120.785382 -386.366004) (xy 120.790575 -386.386376) (xy 120.796184 -386.428042)
			(xy 120.796558 -386.449062) (xy 120.796175 -386.470082) (xy 120.790575 -386.511748) (xy 120.785382 -386.53212)
			(xy 120.783604 -386.538724) (xy 120.783604 -386.594604) (xy 120.784085 -386.604612) (xy 120.791747 -386.623105)
			(xy 120.805902 -386.637258) (xy 120.824396 -386.644917) (xy 120.834404 -386.645404) (xy 120.911366 -386.645404)
			(xy 120.940826 -386.646125) (xy 120.998638 -386.657513) (xy 121.026174 -386.66801) (xy 121.035572 -386.67182)
			(xy 121.33707 -386.67182) (xy 121.343447 -386.67163) (xy 121.35579 -386.668408) (xy 121.361454 -386.66547)
			(xy 121.373392 -386.659374) (xy 121.373392 -386.538724) (xy 121.371614 -386.53212) (xy 121.366407 -386.511751)
			(xy 121.360807 -386.470083) (xy 121.360438 -386.449062) (xy 121.3612 -386.426456) (xy 121.361962 -386.416296)
			(xy 121.355866 -386.3975) (xy 121.302272 -386.335524) (xy 121.295355 -386.32825) (xy 121.277435 -386.319244)
			(xy 121.267474 -386.317998) (xy 121.24366 -386.315826) (xy 121.197066 -386.305061) (xy 121.152631 -386.28739)
			(xy 121.11137 -386.263217) (xy 121.074229 -386.233094) (xy 121.042057 -386.197713) (xy 121.015593 -386.157883)
			(xy 120.995441 -386.114516) (xy 120.988328 -386.091684) (xy 120.986804 -386.085842) (xy 120.66651 -385.532122)
			(xy 120.662446 -385.527804) (xy 120.646293 -385.510132) (xy 120.618974 -385.470816) (xy 120.597905 -385.427825)
			(xy 120.58357 -385.382146) (xy 120.576297 -385.334826) (xy 120.575832 -385.310888) (xy 120.575832 -385.31038)
			(xy 120.5763 -385.28559) (xy 120.584058 -385.23662) (xy 120.599382 -385.189467) (xy 120.621893 -385.145292)
			(xy 120.651037 -385.105182) (xy 120.686097 -385.070124) (xy 120.726209 -385.040983) (xy 120.770386 -385.018474)
			(xy 120.81754 -385.003154) (xy 120.86651 -384.995398) (xy 120.8913 -384.994912) (xy 120.916695 -384.995395)
			(xy 120.966831 -385.003527) (xy 121.015018 -385.01958) (xy 121.060013 -385.04314) (xy 121.100656 -385.0736)
			(xy 121.135898 -385.110174) (xy 121.164831 -385.151918) (xy 121.186707 -385.197756) (xy 121.194322 -385.221988)
			(xy 121.195846 -385.22783) (xy 121.51614 -385.78155) (xy 121.520204 -385.785868) (xy 121.536403 -385.803546)
			(xy 121.563803 -385.842894) (xy 121.584935 -385.885934) (xy 121.599313 -385.931675) (xy 121.606606 -385.979065)
			(xy 121.607072 -386.003038) (xy 121.607072 -386.003546) (xy 121.60631 -386.023866) (xy 121.605548 -386.033772)
			(xy 121.611898 -386.052822) (xy 121.672604 -386.122164) (xy 121.690384 -386.131054) (xy 121.700544 -386.131816)
			(xy 121.725496 -386.134007) (xy 121.774297 -386.145294) (xy 121.820727 -386.164088) (xy 121.863638 -386.189924)
			(xy 121.901972 -386.222164) (xy 121.91873 -386.240782) (xy 121.921195 -386.243552) (xy 121.926806 -386.2484)
			(xy 121.929906 -386.250434) (xy 121.941942 -386.258505) (xy 121.961832 -386.279567) (xy 121.975839 -386.304926)
			(xy 121.983076 -386.332977) (xy 121.9835 -386.347462) (xy 121.9835 -386.3594) (xy 121.985278 -386.366004)
			(xy 121.99047 -386.386376) (xy 121.99608 -386.428042) (xy 121.996454 -386.449062) (xy 121.996071 -386.470082)
			(xy 121.990471 -386.511748) (xy 121.985278 -386.53212) (xy 121.9835 -386.538724) (xy 121.9835 -386.576824)
			(xy 121.983968 -386.586833) (xy 121.991636 -386.605326) (xy 122.005795 -386.619478) (xy 122.024291 -386.627136)
			(xy 122.0343 -386.627624) (xy 122.522488 -386.627624) (xy 122.532492 -386.627103) (xy 122.550979 -386.619452)
			(xy 122.565131 -386.605309) (xy 122.572796 -386.586828) (xy 122.573288 -386.576824) (xy 122.573288 -386.538724)
			(xy 122.571764 -386.53212) (xy 122.566558 -386.511751) (xy 122.560957 -386.470083) (xy 122.560588 -386.449062)
			(xy 122.56135 -386.426456) (xy 122.562112 -386.41655) (xy 122.555762 -386.397246) (xy 122.495564 -386.327904)
			(xy 122.47753 -386.31876) (xy 122.467624 -386.317998) (xy 122.443799 -386.315784) (xy 122.39717 -386.305059)
			(xy 122.352695 -386.287416) (xy 122.311394 -386.263259) (xy 122.274214 -386.233142) (xy 122.242009 -386.197757)
			(xy 122.215516 -386.157914) (xy 122.195344 -386.114528) (xy 122.188224 -386.091684) (xy 122.1867 -386.085842)
			(xy 121.866406 -385.532122) (xy 121.862342 -385.527804) (xy 121.846188 -385.510133) (xy 121.818869 -385.470816)
			(xy 121.797801 -385.427825) (xy 121.783466 -385.382146) (xy 121.776193 -385.334826) (xy 121.775728 -385.310888)
			(xy 121.775728 -385.31038) (xy 121.7762 -385.28559) (xy 121.783958 -385.236621) (xy 121.799282 -385.189468)
			(xy 121.821792 -385.145293) (xy 121.850936 -385.105183) (xy 121.885995 -385.070126) (xy 121.926107 -385.040984)
			(xy 121.970283 -385.018475) (xy 122.017436 -385.003155) (xy 122.066406 -384.995398) (xy 122.091196 -384.994912)
			(xy 122.116591 -384.995399) (xy 122.166726 -385.00353) (xy 122.214913 -385.019582) (xy 122.259908 -385.043142)
			(xy 122.300552 -385.073601) (xy 122.335794 -385.110175) (xy 122.364727 -385.151919) (xy 122.386603 -385.197756)
			(xy 122.394218 -385.221988) (xy 122.395742 -385.22783) (xy 122.716036 -385.78155) (xy 122.7201 -385.785868)
			(xy 122.736299 -385.803547) (xy 122.763699 -385.842894) (xy 122.784831 -385.885934) (xy 122.799209 -385.931675)
			(xy 122.806502 -385.979065) (xy 122.806968 -386.003038) (xy 122.806968 -386.003546) (xy 122.806206 -386.023866)
			(xy 122.805444 -386.033772) (xy 122.811794 -386.052822) (xy 122.8725 -386.122164) (xy 122.89028 -386.131054)
			(xy 122.90044 -386.131816) (xy 122.925415 -386.134031) (xy 122.974272 -386.145279) (xy 123.020759 -386.164054)
			(xy 123.063724 -386.189891) (xy 123.102104 -386.22215) (xy 123.11888 -386.240782) (xy 123.121339 -386.243557)
			(xy 123.126954 -386.248402) (xy 123.130056 -386.250434) (xy 123.14213 -386.258478) (xy 123.162086 -386.279526)
			(xy 123.176157 -386.304889) (xy 123.183454 -386.332961) (xy 123.183904 -386.347462) (xy 123.183904 -386.3594)
			(xy 123.185428 -386.366004) (xy 123.190619 -386.386376) (xy 123.19623 -386.428042) (xy 123.196604 -386.449062)
			(xy 123.196223 -386.470082) (xy 123.190622 -386.511748) (xy 123.185428 -386.53212) (xy 123.183904 -386.538724)
			(xy 123.183904 -386.576824) (xy 123.184368 -386.586834) (xy 123.192037 -386.605327) (xy 123.206197 -386.619479)
			(xy 123.224694 -386.627137) (xy 123.234704 -386.627624) (xy 123.722384 -386.627624) (xy 123.732388 -386.627099)
			(xy 123.750875 -386.61945) (xy 123.765027 -386.605308) (xy 123.772692 -386.586827) (xy 123.773184 -386.576824)
			(xy 123.773184 -386.538724) (xy 123.77166 -386.53212) (xy 123.766454 -386.511751) (xy 123.760853 -386.470083)
			(xy 123.760484 -386.449062) (xy 123.761246 -386.426456) (xy 123.762008 -386.41655) (xy 123.755658 -386.397246)
			(xy 123.69546 -386.327904) (xy 123.677426 -386.31876) (xy 123.66752 -386.317998) (xy 123.643695 -386.315787)
			(xy 123.597066 -386.305062) (xy 123.55259 -386.287418) (xy 123.51129 -386.263261) (xy 123.47411 -386.233144)
			(xy 123.441905 -386.197758) (xy 123.415412 -386.157915) (xy 123.39524 -386.114528) (xy 123.38812 -386.091684)
			(xy 123.386596 -386.085842) (xy 123.066048 -385.53136) (xy 123.061984 -385.527042) (xy 123.045862 -385.509389)
			(xy 123.018615 -385.470106) (xy 122.997607 -385.427162) (xy 122.98332 -385.381539) (xy 122.976079 -385.334283)
			(xy 122.975624 -385.31038) (xy 122.976098 -385.285603) (xy 122.983849 -385.236659) (xy 122.999157 -385.189528)
			(xy 123.021645 -385.14537) (xy 123.05076 -385.105271) (xy 123.085787 -385.070218) (xy 123.125864 -385.041072)
			(xy 123.170004 -385.01855) (xy 123.217123 -385.003206) (xy 123.266061 -384.995418) (xy 123.290838 -384.994912)
			(xy 123.291346 -384.994912) (xy 123.316794 -384.995389) (xy 123.367033 -385.003545) (xy 123.415313 -385.019655)
			(xy 123.460382 -385.043302) (xy 123.501075 -385.073873) (xy 123.536336 -385.110576) (xy 123.565252 -385.152461)
			(xy 123.587075 -385.198442) (xy 123.594622 -385.22275) (xy 123.596146 -385.228592) (xy 123.915932 -385.78155)
			(xy 123.919996 -385.785868) (xy 123.936194 -385.803548) (xy 123.963594 -385.842895) (xy 123.984727 -385.885934)
			(xy 123.999105 -385.931675) (xy 124.006398 -385.979065) (xy 124.006864 -386.003038) (xy 124.006864 -386.003546)
			(xy 124.006102 -386.023866) (xy 124.00534 -386.033772) (xy 124.01169 -386.052822) (xy 124.072396 -386.122164)
			(xy 124.090176 -386.131054) (xy 124.100336 -386.131816) (xy 124.12531 -386.134033) (xy 124.174168 -386.145281)
			(xy 124.220655 -386.164056) (xy 124.26362 -386.189892) (xy 124.301999 -386.22215) (xy 124.318776 -386.240782)
			(xy 124.321236 -386.243557) (xy 124.32685 -386.248402) (xy 124.329952 -386.250434) (xy 124.342025 -386.258479)
			(xy 124.361981 -386.279527) (xy 124.376053 -386.304889) (xy 124.38335 -386.332961) (xy 124.3838 -386.347462)
			(xy 124.3838 -386.3594) (xy 124.385324 -386.366004) (xy 124.390515 -386.386377) (xy 124.396126 -386.428042)
			(xy 124.3965 -386.449062) (xy 124.396119 -386.470082) (xy 124.390518 -386.511748) (xy 124.385324 -386.53212)
			(xy 124.3838 -386.538724) (xy 124.3838 -386.576824) (xy 124.384268 -386.586833) (xy 124.391936 -386.605326)
			(xy 124.406095 -386.619478) (xy 124.424591 -386.627136) (xy 124.4346 -386.627624) (xy 124.93498 -386.627624)
			(xy 124.944529 -386.627679) (xy 124.963593 -386.628825) (xy 124.97308 -386.62991) (xy 124.97308 -386.538724)
			(xy 124.971556 -386.53212) (xy 124.96635 -386.511751) (xy 124.960749 -386.470083) (xy 124.96038 -386.449062)
			(xy 124.961142 -386.426456) (xy 124.961904 -386.416296) (xy 124.955808 -386.3975) (xy 124.902214 -386.335524)
			(xy 124.895282 -386.328267) (xy 124.877374 -386.319251) (xy 124.867416 -386.317998) (xy 124.843605 -386.315792)
			(xy 124.797013 -386.305034) (xy 124.752578 -386.287368) (xy 124.711316 -386.2632) (xy 124.674175 -386.233082)
			(xy 124.642002 -386.197705) (xy 124.615537 -386.157879) (xy 124.595383 -386.114515) (xy 124.58827 -386.091684)
			(xy 124.586746 -386.085842) (xy 124.266452 -385.532122) (xy 124.262388 -385.527804) (xy 124.246158 -385.510119)
			(xy 124.218738 -385.470722) (xy 124.1976 -385.427626) (xy 124.183233 -385.381827) (xy 124.175967 -385.33438)
			(xy 124.17552 -385.31038) (xy 124.175998 -385.285603) (xy 124.183749 -385.236659) (xy 124.199056 -385.189529)
			(xy 124.221544 -385.145371) (xy 124.250659 -385.105273) (xy 124.285685 -385.070219) (xy 124.325761 -385.041073)
			(xy 124.369901 -385.018551) (xy 124.41702 -385.003207) (xy 124.465957 -384.995418) (xy 124.490734 -384.994912)
			(xy 124.491242 -384.994912) (xy 124.516639 -384.995358) (xy 124.566776 -385.003496) (xy 124.614963 -385.019555)
			(xy 124.659959 -385.043121) (xy 124.700601 -385.073586) (xy 124.735843 -385.110165) (xy 124.764774 -385.151913)
			(xy 124.786649 -385.197755) (xy 124.794264 -385.221988) (xy 124.795788 -385.22783) (xy 125.116082 -385.78155)
			(xy 125.120146 -385.785868) (xy 125.136301 -385.803572) (xy 125.163645 -385.842931) (xy 125.184725 -385.885971)
			(xy 125.199056 -385.931703) (xy 125.20631 -385.979076) (xy 125.20676 -386.003038) (xy 125.20676 -386.003546)
			(xy 125.206252 -386.023866) (xy 125.20549 -386.033772) (xy 125.21184 -386.052822) (xy 125.272546 -386.122164)
			(xy 125.290326 -386.131054) (xy 125.300486 -386.131816) (xy 125.325435 -386.134042) (xy 125.374234 -386.14532)
			(xy 125.420664 -386.164106) (xy 125.463577 -386.189934) (xy 125.501913 -386.222168) (xy 125.518672 -386.240782)
			(xy 125.521132 -386.243556) (xy 125.526746 -386.248402) (xy 125.529848 -386.250434) (xy 125.54192 -386.25848)
			(xy 125.561877 -386.279527) (xy 125.575949 -386.304889) (xy 125.583246 -386.332961) (xy 125.583696 -386.347462)
			(xy 125.583696 -386.3594) (xy 125.58522 -386.366004) (xy 125.590411 -386.386377) (xy 125.596022 -386.428042)
			(xy 125.596396 -386.449062) (xy 125.596015 -386.470082) (xy 125.590414 -386.511748) (xy 125.58522 -386.53212)
			(xy 125.583696 -386.538724) (xy 125.583696 -386.62102) (xy 125.584171 -386.631028) (xy 125.591837 -386.64952)
			(xy 125.605993 -386.663672) (xy 125.624487 -386.671332) (xy 125.634496 -386.67182) (xy 125.97384 -386.67182)
			(xy 125.986286 -386.668518) (xy 125.991874 -386.66547) (xy 126.018873 -386.651319) (xy 126.076971 -386.632897)
			(xy 126.10719 -386.628894) (xy 126.116033 -386.627595) (xy 126.132031 -386.61964) (xy 126.138432 -386.6134)
			(xy 126.159514 -386.591302) (xy 126.165873 -386.583967) (xy 126.173055 -386.565948) (xy 126.173484 -386.55625)
			(xy 126.173484 -386.538724) (xy 126.171706 -386.53212) (xy 126.166501 -386.511751) (xy 126.160899 -386.470083)
			(xy 126.16053 -386.449062) (xy 126.161292 -386.426456) (xy 126.162054 -386.41655) (xy 126.155704 -386.397246)
			(xy 126.095506 -386.327904) (xy 126.077472 -386.31876) (xy 126.067566 -386.317998) (xy 126.043745 -386.31575)
			(xy 125.997117 -386.305031) (xy 125.952642 -386.287394) (xy 125.911341 -386.263242) (xy 125.87416 -386.23313)
			(xy 125.841954 -386.197749) (xy 125.81546 -386.15791) (xy 125.795287 -386.114526) (xy 125.788166 -386.091684)
			(xy 125.786642 -386.085842) (xy 125.466348 -385.532122) (xy 125.462284 -385.527804) (xy 125.446053 -385.510119)
			(xy 125.418633 -385.470722) (xy 125.397496 -385.427626) (xy 125.383129 -385.381827) (xy 125.375863 -385.33438)
			(xy 125.375416 -385.31038) (xy 125.375898 -385.285603) (xy 125.383649 -385.23666) (xy 125.398956 -385.18953)
			(xy 125.421443 -385.145373) (xy 125.450558 -385.105274) (xy 125.485584 -385.070221) (xy 125.525659 -385.041074)
			(xy 125.569798 -385.018552) (xy 125.616916 -385.003207) (xy 125.665854 -384.995418) (xy 125.69063 -384.994912)
			(xy 125.691138 -384.994912) (xy 125.716534 -384.995362) (xy 125.766671 -385.003499) (xy 125.814859 -385.019558)
			(xy 125.859854 -385.043123) (xy 125.900497 -385.073588) (xy 125.935739 -385.110166) (xy 125.96467 -385.151914)
			(xy 125.986545 -385.197755) (xy 125.99416 -385.221988) (xy 125.995684 -385.22783) (xy 126.043728 -385.310888)
			(xy 126.57582 -385.310888) (xy 126.57582 -385.31038) (xy 126.576299 -385.28559) (xy 126.584058 -385.236622)
			(xy 126.599381 -385.18947) (xy 126.621891 -385.145295) (xy 126.651034 -385.105186) (xy 126.686092 -385.070128)
			(xy 126.726202 -385.040987) (xy 126.770378 -385.018478) (xy 126.81753 -385.003156) (xy 126.866498 -384.995399)
			(xy 126.891288 -384.994912) (xy 126.916683 -384.995406) (xy 126.966818 -385.003535) (xy 127.015004 -385.019587)
			(xy 127.06 -385.043145) (xy 127.100643 -385.073604) (xy 127.135885 -385.110177) (xy 127.164818 -385.15192)
			(xy 127.186695 -385.197757) (xy 127.19431 -385.221988) (xy 127.195834 -385.22783) (xy 127.243878 -385.310888)
			(xy 127.775716 -385.310888) (xy 127.775716 -385.31038) (xy 127.776199 -385.285591) (xy 127.783958 -385.236623)
			(xy 127.79928 -385.189471) (xy 127.82179 -385.145297) (xy 127.850932 -385.105187) (xy 127.88599 -385.07013)
			(xy 127.9261 -385.040988) (xy 127.970275 -385.018479) (xy 128.017427 -385.003157) (xy 128.066395 -384.995399)
			(xy 128.091184 -384.994912) (xy 128.116579 -384.995409) (xy 128.166713 -385.003538) (xy 128.2149 -385.019589)
			(xy 128.259895 -385.043147) (xy 128.300539 -385.073605) (xy 128.335781 -385.110177) (xy 128.364714 -385.15192)
			(xy 128.386591 -385.197757) (xy 128.394206 -385.221988) (xy 128.39573 -385.22783) (xy 128.44348 -385.31038)
			(xy 128.975612 -385.31038) (xy 128.976098 -385.285604) (xy 128.983849 -385.23666) (xy 128.999156 -385.189531)
			(xy 129.021643 -385.145374) (xy 129.050757 -385.105275) (xy 129.085782 -385.070222) (xy 129.125857 -385.041076)
			(xy 129.169996 -385.018553) (xy 129.217113 -385.003208) (xy 129.26605 -384.995418) (xy 129.290826 -384.994912)
			(xy 129.291334 -384.994912) (xy 129.316782 -384.995399) (xy 129.36702 -385.003554) (xy 129.4153 -385.019662)
			(xy 129.460369 -385.043308) (xy 129.501062 -385.073877) (xy 129.536323 -385.110579) (xy 129.56524 -385.152462)
			(xy 129.587063 -385.198442) (xy 129.59461 -385.22275) (xy 129.596134 -385.228592) (xy 129.643434 -385.31038)
			(xy 130.175508 -385.31038) (xy 130.175998 -385.285604) (xy 130.183749 -385.236661) (xy 130.199055 -385.189532)
			(xy 130.221542 -385.145375) (xy 130.250656 -385.105277) (xy 130.28568 -385.070223) (xy 130.325755 -385.041077)
			(xy 130.369893 -385.018554) (xy 130.41701 -385.003209) (xy 130.465946 -384.995419) (xy 130.490722 -384.994912)
			(xy 130.49123 -384.994912) (xy 130.516626 -384.995369) (xy 130.566763 -385.003505) (xy 130.61495 -385.019562)
			(xy 130.659946 -385.043127) (xy 130.700588 -385.07359) (xy 130.73583 -385.110167) (xy 130.764762 -385.151915)
			(xy 130.786637 -385.197755) (xy 130.794252 -385.221988) (xy 130.795776 -385.22783) (xy 130.843526 -385.31038)
			(xy 131.375912 -385.31038) (xy 131.376399 -385.285591) (xy 131.384158 -385.236623) (xy 131.39948 -385.189472)
			(xy 131.421989 -385.145298) (xy 131.451131 -385.105188) (xy 131.486188 -385.070131) (xy 131.526298 -385.040989)
			(xy 131.570472 -385.01848) (xy 131.617623 -385.003158) (xy 131.666591 -384.995399) (xy 131.69138 -384.994912)
			(xy 131.716829 -384.995359) (xy 131.76707 -385.00352) (xy 131.81535 -385.019636) (xy 131.86042 -385.043287)
			(xy 131.901112 -385.073862) (xy 131.936372 -385.110569) (xy 131.965288 -385.152457) (xy 131.987109 -385.19844)
			(xy 131.994656 -385.22275) (xy 131.99618 -385.228592) (xy 132.043773 -385.310888) (xy 132.575808 -385.310888)
			(xy 132.575808 -385.31038) (xy 132.576299 -385.285591) (xy 132.584058 -385.236624) (xy 132.59938 -385.189473)
			(xy 132.621889 -385.145299) (xy 132.65103 -385.10519) (xy 132.686087 -385.070133) (xy 132.726196 -385.040991)
			(xy 132.770369 -385.018481) (xy 132.81752 -385.003159) (xy 132.866487 -384.9954) (xy 132.891276 -384.994912)
			(xy 132.916671 -384.995416) (xy 132.966805 -385.003544) (xy 133.014991 -385.019593) (xy 133.059987 -385.043151)
			(xy 133.10063 -385.073608) (xy 133.135873 -385.110179) (xy 133.164806 -385.151921) (xy 133.186682 -385.197757)
			(xy 133.194298 -385.221988) (xy 133.195822 -385.22783) (xy 133.516116 -385.78155) (xy 133.52018 -385.785868)
			(xy 133.536375 -385.80355) (xy 133.563777 -385.842896) (xy 133.58491 -385.885935) (xy 133.599289 -385.931675)
			(xy 133.606582 -385.979065) (xy 133.607048 -386.003038) (xy 133.607048 -386.003546) (xy 133.606286 -386.023612)
			(xy 133.606107 -386.033661) (xy 133.612642 -386.052649) (xy 133.618986 -386.060442) (xy 133.673596 -386.122164)
			(xy 133.69163 -386.131054) (xy 133.70179 -386.131562) (xy 133.727167 -386.13354) (xy 133.776874 -386.144488)
			(xy 133.824202 -386.163211) (xy 133.867946 -386.18923) (xy 133.906989 -386.221883) (xy 133.92404 -386.240782)
			(xy 133.926504 -386.243553) (xy 133.932115 -386.2484) (xy 133.935216 -386.250434) (xy 133.947281 -386.25849)
			(xy 133.96724 -386.279533) (xy 133.981315 -386.304892) (xy 133.988613 -386.332961) (xy 133.989064 -386.347462)
			(xy 133.989064 -386.3594) (xy 133.990588 -386.366004) (xy 133.995779 -386.386377) (xy 134.00139 -386.428042)
			(xy 134.001764 -386.449062) (xy 134.001384 -386.470082) (xy 133.995783 -386.511749) (xy 133.990588 -386.53212)
			(xy 133.989064 -386.538724) (xy 133.989064 -386.652262) (xy 133.988534 -386.667255) (xy 133.980792 -386.696225)
			(xy 133.965825 -386.722208) (xy 133.944649 -386.74344) (xy 133.918705 -386.758476) (xy 133.889756 -386.766294)
			(xy 133.874764 -386.766816) (xy 133.692646 -386.766816) (xy 133.692138 -386.76707) (xy 133.675374 -386.76707)
			(xy 133.674866 -386.766816) (xy 133.493256 -386.766816) (xy 133.478226 -386.766359) (xy 133.449188 -386.75858)
			(xy 133.423147 -386.743563) (xy 133.401871 -386.722326) (xy 133.386804 -386.696314) (xy 133.37897 -386.667291)
			(xy 133.378448 -386.652262) (xy 133.378448 -386.538724) (xy 133.376924 -386.53212) (xy 133.371717 -386.511751)
			(xy 133.366117 -386.470083) (xy 133.365748 -386.449062) (xy 133.36651 -386.42671) (xy 133.367272 -386.41655)
			(xy 133.360922 -386.3975) (xy 133.299708 -386.32765) (xy 133.281674 -386.31876) (xy 133.271514 -386.318252)
			(xy 133.247426 -386.316317) (xy 133.200219 -386.305981) (xy 133.155141 -386.288568) (xy 133.113245 -386.264485)
			(xy 133.075512 -386.234294) (xy 133.042825 -386.198702) (xy 133.015947 -386.158541) (xy 132.995508 -386.114752)
			(xy 132.988304 -386.091684) (xy 132.98678 -386.085842) (xy 132.666486 -385.532122) (xy 132.662422 -385.527804)
			(xy 132.646265 -385.510136) (xy 132.618947 -385.470818) (xy 132.59788 -385.427826) (xy 132.583545 -385.382146)
			(xy 132.576273 -385.334826) (xy 132.575808 -385.310888) (xy 132.043773 -385.310888) (xy 132.315966 -385.78155)
			(xy 132.32003 -385.785868) (xy 132.336182 -385.803575) (xy 132.363527 -385.842932) (xy 132.384608 -385.885972)
			(xy 132.39894 -385.931703) (xy 132.406194 -385.979076) (xy 132.406644 -386.003038) (xy 132.406644 -386.003546)
			(xy 132.406136 -386.023866) (xy 132.405374 -386.033772) (xy 132.411724 -386.052822) (xy 132.47243 -386.122164)
			(xy 132.49021 -386.131054) (xy 132.50037 -386.131816) (xy 132.525347 -386.134013) (xy 132.574204 -386.145266)
			(xy 132.620691 -386.164045) (xy 132.663656 -386.189886) (xy 132.702034 -386.222148) (xy 132.71881 -386.240782)
			(xy 132.721278 -386.243549) (xy 132.726886 -386.248399) (xy 132.729986 -386.250434) (xy 132.742017 -386.258511)
			(xy 132.76191 -386.27957) (xy 132.775918 -386.304927) (xy 132.783156 -386.332978) (xy 132.78358 -386.347462)
			(xy 132.78358 -386.3594) (xy 132.785358 -386.366004) (xy 132.79055 -386.386376) (xy 132.79616 -386.428042)
			(xy 132.796534 -386.449062) (xy 132.796152 -386.470082) (xy 132.790552 -386.511748) (xy 132.785358 -386.53212)
			(xy 132.78358 -386.538724) (xy 132.78358 -386.652262) (xy 132.783075 -386.667281) (xy 132.77531 -386.696297)
			(xy 132.760299 -386.722314) (xy 132.739065 -386.74356) (xy 132.713056 -386.758585) (xy 132.684045 -386.766367)
			(xy 132.669026 -386.766816) (xy 132.487416 -386.766816) (xy 132.486908 -386.76707) (xy 132.470144 -386.76707)
			(xy 132.469636 -386.766816) (xy 132.288026 -386.766816) (xy 132.273001 -386.766385) (xy 132.243975 -386.758611)
			(xy 132.217951 -386.743588) (xy 132.196705 -386.722339) (xy 132.181684 -386.696314) (xy 132.173914 -386.667287)
			(xy 132.173472 -386.652262) (xy 132.173472 -386.538724) (xy 132.171694 -386.53212) (xy 132.166488 -386.511751)
			(xy 132.160887 -386.470083) (xy 132.160518 -386.449062) (xy 132.16128 -386.426456) (xy 132.162042 -386.41655)
			(xy 132.155692 -386.397246) (xy 132.095494 -386.327904) (xy 132.07746 -386.31876) (xy 132.067554 -386.317998)
			(xy 132.043732 -386.315759) (xy 131.997103 -386.305039) (xy 131.952628 -386.2874) (xy 131.911327 -386.263247)
			(xy 131.874147 -386.233134) (xy 131.841941 -386.197751) (xy 131.815448 -386.157911) (xy 131.795274 -386.114527)
			(xy 131.788154 -386.091684) (xy 131.78663 -386.085842) (xy 131.466082 -385.53136) (xy 131.462018 -385.527042)
			(xy 131.445936 -385.509366) (xy 131.418747 -385.470071) (xy 131.397792 -385.427126) (xy 131.383551 -385.381512)
			(xy 131.37635 -385.334273) (xy 131.375912 -385.31038) (xy 130.843526 -385.31038) (xy 131.11607 -385.78155)
			(xy 131.120134 -385.785868) (xy 131.136287 -385.803574) (xy 131.163631 -385.842932) (xy 131.184712 -385.885971)
			(xy 131.199044 -385.931703) (xy 131.206298 -385.979076) (xy 131.206748 -386.003038) (xy 131.206748 -386.003546)
			(xy 131.20624 -386.023866) (xy 131.205478 -386.033772) (xy 131.211828 -386.052822) (xy 131.272534 -386.122164)
			(xy 131.290314 -386.131054) (xy 131.300474 -386.131816) (xy 131.325451 -386.13401) (xy 131.374309 -386.145264)
			(xy 131.420796 -386.164044) (xy 131.46376 -386.189885) (xy 131.502138 -386.222148) (xy 131.518914 -386.240782)
			(xy 131.521381 -386.24355) (xy 131.52699 -386.248399) (xy 131.53009 -386.250434) (xy 131.542122 -386.258509)
			(xy 131.562014 -386.279569) (xy 131.576022 -386.304927) (xy 131.58326 -386.332977) (xy 131.583684 -386.347462)
			(xy 131.583684 -386.3594) (xy 131.585462 -386.366004) (xy 131.590654 -386.386376) (xy 131.596264 -386.428042)
			(xy 131.596638 -386.449062) (xy 131.596255 -386.470082) (xy 131.590656 -386.511748) (xy 131.585462 -386.53212)
			(xy 131.583684 -386.538724) (xy 131.583684 -386.652262) (xy 131.583175 -386.66728) (xy 131.57541 -386.696296)
			(xy 131.5604 -386.722313) (xy 131.539167 -386.743558) (xy 131.513159 -386.758584) (xy 131.484148 -386.766366)
			(xy 131.46913 -386.766816) (xy 131.28752 -386.766816) (xy 131.287012 -386.76707) (xy 131.270248 -386.76707)
			(xy 131.26974 -386.766816) (xy 131.08813 -386.766816) (xy 131.073106 -386.766381) (xy 131.04408 -386.758609)
			(xy 131.018056 -386.743586) (xy 130.996809 -386.722338) (xy 130.981788 -386.696313) (xy 130.974018 -386.667286)
			(xy 130.973576 -386.652262) (xy 130.973576 -386.538724) (xy 130.971798 -386.53212) (xy 130.966592 -386.511751)
			(xy 130.960991 -386.470083) (xy 130.960622 -386.449062) (xy 130.961384 -386.426456) (xy 130.962146 -386.41655)
			(xy 130.955796 -386.397246) (xy 130.895598 -386.327904) (xy 130.877564 -386.31876) (xy 130.867658 -386.317998)
			(xy 130.843836 -386.315756) (xy 130.797208 -386.305036) (xy 130.752733 -386.287398) (xy 130.711432 -386.263245)
			(xy 130.674252 -386.233133) (xy 130.642045 -386.19775) (xy 130.615552 -386.15791) (xy 130.595379 -386.114526)
			(xy 130.588258 -386.091684) (xy 130.586734 -386.085842) (xy 130.26644 -385.532122) (xy 130.262376 -385.527804)
			(xy 130.246144 -385.510121) (xy 130.218725 -385.470723) (xy 130.197588 -385.427627) (xy 130.18322 -385.381827)
			(xy 130.175955 -385.33438) (xy 130.175508 -385.31038) (xy 129.643434 -385.31038) (xy 129.91592 -385.78155)
			(xy 129.919984 -385.785868) (xy 129.93618 -385.803549) (xy 129.963581 -385.842896) (xy 129.984714 -385.885935)
			(xy 129.999093 -385.931675) (xy 130.006386 -385.979065) (xy 130.006852 -386.003038) (xy 130.006852 -386.003546)
			(xy 130.00609 -386.023866) (xy 130.005328 -386.033772) (xy 130.011678 -386.052822) (xy 130.072384 -386.122164)
			(xy 130.090164 -386.131054) (xy 130.100324 -386.131816) (xy 130.125304 -386.13398) (xy 130.174163 -386.145241)
			(xy 130.22065 -386.164029) (xy 130.263613 -386.189877) (xy 130.301989 -386.222145) (xy 130.318764 -386.240782)
			(xy 130.321225 -386.243556) (xy 130.326838 -386.248402) (xy 130.32994 -386.250434) (xy 130.342011 -386.258482)
			(xy 130.361968 -386.279529) (xy 130.37604 -386.30489) (xy 130.383338 -386.332961) (xy 130.383788 -386.347462)
			(xy 130.383788 -386.3594) (xy 130.385312 -386.366004) (xy 130.390503 -386.386377) (xy 130.396114 -386.428042)
			(xy 130.396488 -386.449062) (xy 130.396107 -386.470082) (xy 130.390506 -386.511748) (xy 130.385312 -386.53212)
			(xy 130.383788 -386.538724) (xy 130.383788 -386.652262) (xy 130.383234 -386.667253) (xy 130.375494 -386.696219)
			(xy 130.360531 -386.722201) (xy 130.33936 -386.743431) (xy 130.313422 -386.758469) (xy 130.284478 -386.766291)
			(xy 130.269488 -386.766816) (xy 130.08737 -386.766816) (xy 130.086862 -386.76707) (xy 130.070098 -386.76707)
			(xy 130.06959 -386.766816) (xy 129.88798 -386.766816) (xy 129.872951 -386.766338) (xy 129.843914 -386.758565)
			(xy 129.817873 -386.743552) (xy 129.796596 -386.72232) (xy 129.781528 -386.69631) (xy 129.773694 -386.66729)
			(xy 129.773172 -386.652262) (xy 129.773172 -386.538724) (xy 129.771648 -386.53212) (xy 129.766441 -386.511751)
			(xy 129.760841 -386.470083) (xy 129.760472 -386.449062) (xy 129.761234 -386.426456) (xy 129.761996 -386.41655)
			(xy 129.755646 -386.397246) (xy 129.695448 -386.327904) (xy 129.677414 -386.31876) (xy 129.667508 -386.317998)
			(xy 129.643682 -386.315797) (xy 129.597052 -386.305069) (xy 129.552577 -386.287424) (xy 129.511276 -386.263265)
			(xy 129.474097 -386.233147) (xy 129.441892 -386.19776) (xy 129.4154 -386.157916) (xy 129.395228 -386.114528)
			(xy 129.388108 -386.091684) (xy 129.386584 -386.085842) (xy 129.066036 -385.53136) (xy 129.061972 -385.527042)
			(xy 129.045848 -385.509391) (xy 129.018601 -385.470107) (xy 128.997594 -385.427162) (xy 128.983307 -385.38154)
			(xy 128.976067 -385.334283) (xy 128.975612 -385.31038) (xy 128.44348 -385.31038) (xy 128.716024 -385.78155)
			(xy 128.720088 -385.785868) (xy 128.736285 -385.803549) (xy 128.763685 -385.842895) (xy 128.784818 -385.885934)
			(xy 128.799197 -385.931675) (xy 128.80649 -385.979065) (xy 128.806956 -386.003038) (xy 128.806956 -386.003546)
			(xy 128.806194 -386.023866) (xy 128.805432 -386.033772) (xy 128.811782 -386.052822) (xy 128.872488 -386.122164)
			(xy 128.890268 -386.131054) (xy 128.900428 -386.131816) (xy 128.925402 -386.134038) (xy 128.974259 -386.145284)
			(xy 129.020746 -386.164058) (xy 129.063712 -386.189893) (xy 129.102091 -386.22215) (xy 129.118868 -386.240782)
			(xy 129.121329 -386.243556) (xy 129.126942 -386.248402) (xy 129.130044 -386.250434) (xy 129.142116 -386.258481)
			(xy 129.162072 -386.279528) (xy 129.176145 -386.30489) (xy 129.183442 -386.332961) (xy 129.183892 -386.347462)
			(xy 129.183892 -386.3594) (xy 129.185416 -386.366004) (xy 129.190607 -386.386377) (xy 129.196218 -386.428042)
			(xy 129.196592 -386.449062) (xy 129.196211 -386.470082) (xy 129.19061 -386.511748) (xy 129.185416 -386.53212)
			(xy 129.183892 -386.538724) (xy 129.183892 -386.652262) (xy 129.183334 -386.667253) (xy 129.175595 -386.696218)
			(xy 129.160632 -386.722199) (xy 129.139462 -386.74343) (xy 129.113524 -386.758468) (xy 129.084581 -386.766291)
			(xy 129.069592 -386.766816) (xy 128.887474 -386.766816) (xy 128.886966 -386.76707) (xy 128.870202 -386.76707)
			(xy 128.869694 -386.766816) (xy 128.688084 -386.766816) (xy 128.673055 -386.766334) (xy 128.644019 -386.758562)
			(xy 128.617977 -386.74355) (xy 128.5967 -386.722319) (xy 128.581633 -386.69631) (xy 128.573798 -386.66729)
			(xy 128.573276 -386.652262) (xy 128.573276 -386.538724) (xy 128.571752 -386.53212) (xy 128.566546 -386.511751)
			(xy 128.560945 -386.470083) (xy 128.560576 -386.449062) (xy 128.561338 -386.426456) (xy 128.5621 -386.41655)
			(xy 128.55575 -386.397246) (xy 128.495552 -386.327904) (xy 128.477518 -386.31876) (xy 128.467612 -386.317998)
			(xy 128.443786 -386.315793) (xy 128.397157 -386.305067) (xy 128.352681 -386.287422) (xy 128.311381 -386.263264)
			(xy 128.274201 -386.233146) (xy 128.241996 -386.197759) (xy 128.215504 -386.157915) (xy 128.195332 -386.114528)
			(xy 128.188212 -386.091684) (xy 128.186688 -386.085842) (xy 127.866394 -385.532122) (xy 127.86233 -385.527804)
			(xy 127.846174 -385.510135) (xy 127.818856 -385.470818) (xy 127.797788 -385.427826) (xy 127.783453 -385.382146)
			(xy 127.776181 -385.334826) (xy 127.775716 -385.310888) (xy 127.243878 -385.310888) (xy 127.516128 -385.78155)
			(xy 127.520192 -385.785868) (xy 127.536389 -385.803548) (xy 127.56379 -385.842895) (xy 127.584923 -385.885934)
			(xy 127.599301 -385.931675) (xy 127.606594 -385.979065) (xy 127.60706 -386.003038) (xy 127.60706 -386.003546)
			(xy 127.606298 -386.023866) (xy 127.605536 -386.033772) (xy 127.611886 -386.052822) (xy 127.672592 -386.122164)
			(xy 127.690372 -386.131054) (xy 127.700532 -386.131816) (xy 127.725484 -386.134014) (xy 127.774284 -386.1453)
			(xy 127.820714 -386.164092) (xy 127.863626 -386.189926) (xy 127.90196 -386.222165) (xy 127.918718 -386.240782)
			(xy 127.921185 -386.24355) (xy 127.926794 -386.248399) (xy 127.929894 -386.250434) (xy 127.941927 -386.258508)
			(xy 127.961819 -386.279569) (xy 127.975826 -386.304927) (xy 127.983064 -386.332977) (xy 127.983488 -386.347462)
			(xy 127.983488 -386.3594) (xy 127.985266 -386.366004) (xy 127.990458 -386.386376) (xy 127.996068 -386.428042)
			(xy 127.996442 -386.449062) (xy 127.996059 -386.470082) (xy 127.99046 -386.511748) (xy 127.985266 -386.53212)
			(xy 127.983488 -386.538724) (xy 127.983488 -386.652262) (xy 127.982835 -386.670382) (xy 127.971576 -386.704827)
			(xy 127.96139 -386.719826) (xy 127.956909 -386.726492) (xy 127.951982 -386.74177) (xy 127.951738 -386.749798)
			(xy 127.951738 -386.783326) (xy 127.952041 -386.791345) (xy 127.956955 -386.806611) (xy 127.96139 -386.813298)
			(xy 127.97148 -386.828346) (xy 127.982734 -386.86276) (xy 127.983488 -386.880862) (xy 127.983488 -386.9944)
			(xy 127.985266 -387.001004) (xy 127.990458 -387.021376) (xy 127.996068 -387.063042) (xy 127.996442 -387.084062)
			(xy 127.996059 -387.105082) (xy 127.99046 -387.146748) (xy 127.985266 -387.16712) (xy 127.983488 -387.173724)
			(xy 127.983488 -387.185662) (xy 127.983021 -387.201034) (xy 127.974889 -387.230683) (xy 127.959195 -387.25712)
			(xy 127.93706 -387.278457) (xy 127.923798 -387.286246) (xy 127.919988 -387.290818) (xy 127.912676 -387.300283)
			(xy 127.906995 -387.323487) (xy 127.909066 -387.335268) (xy 127.916178 -387.367018) (xy 127.91946 -387.378528)
			(xy 127.934697 -387.396945) (xy 127.945388 -387.402324) (xy 127.966817 -387.412056) (xy 128.006769 -387.436935)
			(xy 128.042617 -387.467431) (xy 128.058418 -387.484874) (xy 128.060886 -387.487642) (xy 128.066494 -387.492491)
			(xy 128.069594 -387.494526) (xy 128.081749 -387.502593) (xy 128.101835 -387.523738) (xy 128.115978 -387.549243)
			(xy 128.123274 -387.57748) (xy 128.123696 -387.592062) (xy 128.123696 -387.604508) (xy 128.125474 -387.610858)
			(xy 128.130608 -387.631172) (xy 128.136082 -387.672712) (xy 128.136396 -387.693662) (xy 128.136063 -387.714611)
			(xy 128.130587 -387.756148) (xy 128.125474 -387.776466) (xy 128.123696 -387.782816) (xy 128.123696 -388.239508)
			(xy 128.125474 -388.245858) (xy 128.130608 -388.266172) (xy 128.136082 -388.307712) (xy 128.136396 -388.328662)
			(xy 128.70053 -388.328662) (xy 128.700896 -388.307641) (xy 128.706506 -388.265975) (xy 128.711706 -388.245604)
			(xy 128.713484 -388.239) (xy 128.713484 -388.125462) (xy 128.713903 -388.11044) (xy 128.721689 -388.081423)
			(xy 128.736719 -388.055409) (xy 128.75797 -388.034173) (xy 128.783994 -388.019159) (xy 128.813016 -388.011393)
			(xy 128.828038 -388.010908) (xy 129.009648 -388.010908) (xy 129.010156 -388.010654) (xy 129.02692 -388.010654)
			(xy 129.027428 -388.010908) (xy 129.209038 -388.010908) (xy 129.224053 -388.011402) (xy 129.253059 -388.019181)
			(xy 129.279065 -388.0342) (xy 129.3003 -388.055435) (xy 129.315319 -388.081441) (xy 129.323098 -388.110447)
			(xy 129.323592 -388.125462) (xy 129.323592 -388.239) (xy 129.32537 -388.245604) (xy 129.330562 -388.265976)
			(xy 129.336172 -388.307642) (xy 129.336546 -388.328662) (xy 129.900426 -388.328662) (xy 129.900792 -388.307641)
			(xy 129.906403 -388.265975) (xy 129.911602 -388.245604) (xy 129.91338 -388.239) (xy 129.91338 -388.125462)
			(xy 129.913803 -388.110441) (xy 129.921588 -388.081424) (xy 129.936618 -388.055411) (xy 129.957868 -388.034174)
			(xy 129.983891 -388.01916) (xy 130.012912 -388.011394) (xy 130.027934 -388.010908) (xy 130.209544 -388.010908)
			(xy 130.210052 -388.010654) (xy 130.226816 -388.010654) (xy 130.227324 -388.010908) (xy 130.408934 -388.010908)
			(xy 130.423949 -388.011406) (xy 130.452955 -388.019184) (xy 130.478961 -388.034201) (xy 130.500196 -388.055436)
			(xy 130.515215 -388.081441) (xy 130.522994 -388.110447) (xy 130.523488 -388.125462) (xy 130.523488 -388.239)
			(xy 130.525266 -388.245604) (xy 130.530458 -388.265976) (xy 130.536068 -388.307642) (xy 130.536442 -388.328662)
			(xy 131.100576 -388.328662) (xy 131.100943 -388.307641) (xy 131.106553 -388.265975) (xy 131.111752 -388.245604)
			(xy 131.113276 -388.239) (xy 131.113276 -388.125462) (xy 131.1137 -388.110462) (xy 131.121463 -388.081484)
			(xy 131.136452 -388.055496) (xy 131.157648 -388.034266) (xy 131.183611 -388.019235) (xy 131.212577 -388.011425)
			(xy 131.227576 -388.010908) (xy 131.409694 -388.010908) (xy 131.410202 -388.010654) (xy 131.426966 -388.010654)
			(xy 131.427474 -388.010908) (xy 131.609084 -388.010908) (xy 131.624114 -388.011394) (xy 131.653152 -388.019161)
			(xy 131.679196 -388.03417) (xy 131.700475 -388.055401) (xy 131.715542 -388.081412) (xy 131.723372 -388.110433)
			(xy 131.723892 -388.125462) (xy 131.723892 -388.239) (xy 131.725416 -388.245604) (xy 131.730607 -388.265977)
			(xy 131.736218 -388.307642) (xy 131.736592 -388.328662) (xy 132.300472 -388.328662) (xy 132.300839 -388.307641)
			(xy 132.306449 -388.265975) (xy 132.311648 -388.245604) (xy 132.313172 -388.239) (xy 132.313172 -388.125462)
			(xy 132.3136 -388.110462) (xy 132.321363 -388.081485) (xy 132.336351 -388.055498) (xy 132.357546 -388.034267)
			(xy 132.383508 -388.019236) (xy 132.412473 -388.011425) (xy 132.427472 -388.010908) (xy 132.60959 -388.010908)
			(xy 132.610098 -388.010654) (xy 132.626862 -388.010654) (xy 132.62737 -388.010908) (xy 132.80898 -388.010908)
			(xy 132.82401 -388.011398) (xy 132.853048 -388.019163) (xy 132.879092 -388.034172) (xy 132.900371 -388.055403)
			(xy 132.915438 -388.081413) (xy 132.923268 -388.110434) (xy 132.923788 -388.125462) (xy 132.923788 -388.239)
			(xy 132.925312 -388.245604) (xy 132.930503 -388.265977) (xy 132.936114 -388.307642) (xy 132.936488 -388.328662)
			(xy 132.936488 -388.32917) (xy 132.936318 -388.343795) (xy 132.933651 -388.372924) (xy 132.931154 -388.387336)
			(xy 132.929783 -388.39651) (xy 132.933059 -388.414753) (xy 132.937504 -388.422896) (xy 132.954014 -388.44982)
			(xy 132.959194 -388.45759) (xy 132.973913 -388.469056) (xy 132.982716 -388.472172) (xy 133.007599 -388.48023)
			(xy 133.054478 -388.503421) (xy 133.09689 -388.534026) (xy 133.133673 -388.571207) (xy 133.16382 -388.613946)
			(xy 133.186504 -388.661072) (xy 133.194298 -388.68604) (xy 133.195822 -388.691882) (xy 133.516116 -389.245602)
			(xy 133.52018 -389.24992) (xy 133.536368 -389.267642) (xy 133.563796 -389.307028) (xy 133.584942 -389.350114)
			(xy 133.599319 -389.395906) (xy 133.606596 -389.443346) (xy 133.607048 -389.467344) (xy 133.606624 -389.492123)
			(xy 133.598868 -389.541071) (xy 133.583556 -389.588204) (xy 133.561062 -389.632364) (xy 133.531941 -389.672464)
			(xy 133.496909 -389.707518) (xy 133.456826 -389.736663) (xy 133.41268 -389.759183) (xy 133.365556 -389.774524)
			(xy 133.316613 -389.782309) (xy 133.291834 -389.782812) (xy 133.291326 -389.782812) (xy 133.265932 -389.782289)
			(xy 133.2158 -389.774162) (xy 133.167615 -389.758114) (xy 133.12262 -389.73456) (xy 133.081977 -389.704105)
			(xy 133.046734 -389.667537) (xy 133.0178 -389.625798) (xy 132.995921 -389.579966) (xy 132.988304 -389.555736)
			(xy 132.98678 -389.549894) (xy 132.666486 -388.996174) (xy 132.662422 -388.991856) (xy 132.646257 -388.974127)
			(xy 132.618891 -388.934723) (xy 132.597802 -388.891632) (xy 132.583476 -388.845846) (xy 132.576242 -388.79842)
			(xy 132.575808 -388.774432) (xy 132.575989 -388.760384) (xy 132.578529 -388.732402) (xy 132.580888 -388.718552)
			(xy 132.582212 -388.709273) (xy 132.578684 -388.690875) (xy 132.57403 -388.682738) (xy 132.557266 -388.655814)
			(xy 132.552047 -388.648124) (xy 132.537334 -388.636793) (xy 132.528564 -388.633716) (xy 132.50694 -388.62691)
			(xy 132.465725 -388.60803) (xy 132.427604 -388.583496) (xy 132.393348 -388.553805) (xy 132.378196 -388.536942)
			(xy 132.375737 -388.534166) (xy 132.370122 -388.529322) (xy 132.36702 -388.52729) (xy 132.354952 -388.519239)
			(xy 132.334997 -388.498192) (xy 132.320925 -388.472832) (xy 132.313625 -388.444762) (xy 132.313172 -388.430262)
			(xy 132.313172 -388.418324) (xy 132.311648 -388.41172) (xy 132.306441 -388.391351) (xy 132.300841 -388.349683)
			(xy 132.300472 -388.328662) (xy 131.736592 -388.328662) (xy 131.736592 -388.32917) (xy 131.736422 -388.343795)
			(xy 131.733755 -388.372924) (xy 131.731258 -388.387336) (xy 131.7299 -388.39651) (xy 131.73317 -388.414751)
			(xy 131.737608 -388.422896) (xy 131.754118 -388.44982) (xy 131.759297 -388.457591) (xy 131.774016 -388.469057)
			(xy 131.78282 -388.472172) (xy 131.807743 -388.48031) (xy 131.854709 -388.503602) (xy 131.897189 -388.534323)
			(xy 131.934018 -388.571631) (xy 131.964189 -388.614504) (xy 131.986873 -388.661767) (xy 131.994656 -388.686802)
			(xy 131.99618 -388.692644) (xy 132.315966 -389.245602) (xy 132.32003 -389.24992) (xy 132.336191 -389.267585)
			(xy 132.36351 -389.306903) (xy 132.384577 -389.349895) (xy 132.398911 -389.395576) (xy 132.406181 -389.442898)
			(xy 132.406644 -389.466836) (xy 132.406644 -389.467344) (xy 132.406147 -389.492793) (xy 132.397975 -389.54303)
			(xy 132.381852 -389.591306) (xy 132.358193 -389.63637) (xy 132.327612 -389.677056) (xy 132.290901 -389.71231)
			(xy 132.270246 -389.727186) (xy 132.261716 -389.733635) (xy 132.250507 -389.751823) (xy 132.247663 -389.772996)
			(xy 132.253676 -389.793496) (xy 132.267506 -389.80978) (xy 132.286763 -389.819031) (xy 132.297424 -389.819896)
			(xy 132.307076 -389.819388) (xy 132.31559 -389.818099) (xy 132.332755 -389.816697) (xy 132.341366 -389.816594)
			(xy 132.34162 -389.816848) (xy 132.640832 -389.816848) (xy 132.641086 -389.816594) (xy 132.662131 -389.817046)
			(xy 132.703449 -389.825033) (xy 132.742404 -389.840955) (xy 132.777486 -389.864198) (xy 132.807338 -389.89386)
			(xy 132.830804 -389.928794) (xy 132.846974 -389.967646) (xy 132.855224 -390.008913) (xy 132.855716 -390.029954)
			(xy 132.855716 -390.233916) (xy 133.480556 -390.233916) (xy 133.480556 -390.029954) (xy 133.481073 -390.008892)
			(xy 133.489319 -389.967584) (xy 133.505501 -389.928694) (xy 133.528993 -389.89373) (xy 133.558882 -389.864048)
			(xy 133.594009 -389.840801) (xy 133.633011 -389.82489) (xy 133.674376 -389.816932) (xy 133.69544 -389.816594)
			(xy 133.695694 -389.816848) (xy 133.994906 -389.816848) (xy 133.99516 -389.816594) (xy 134.016222 -389.816999)
			(xy 134.057581 -389.824953) (xy 134.096579 -389.840858) (xy 134.131705 -389.864096) (xy 134.161597 -389.893766)
			(xy 134.185095 -389.928718) (xy 134.201289 -389.967597) (xy 134.20955 -390.008896) (xy 134.210044 -390.029954)
			(xy 134.210044 -390.284716) (xy 134.2009 -390.284716) (xy 134.190877 -390.28512) (xy 134.172357 -390.292793)
			(xy 134.158184 -390.30697) (xy 134.150517 -390.325493) (xy 134.1501 -390.335516) (xy 134.1501 -390.499092)
			(xy 134.149674 -390.509113) (xy 134.142007 -390.52763) (xy 134.127836 -390.541802) (xy 134.109321 -390.549472)
			(xy 134.0993 -390.549892) (xy 133.5913 -390.549892) (xy 133.581278 -390.54948) (xy 133.562759 -390.541809)
			(xy 133.548587 -390.527634) (xy 133.540918 -390.509114) (xy 133.5405 -390.499092) (xy 133.5405 -390.284716)
			(xy 133.531356 -390.284716) (xy 133.521348 -390.284248) (xy 133.502858 -390.276577) (xy 133.488707 -390.262419)
			(xy 133.481046 -390.243925) (xy 133.480556 -390.233916) (xy 132.855716 -390.233916) (xy 132.855716 -390.284716)
			(xy 132.846572 -390.284716) (xy 132.836561 -390.285165) (xy 132.818065 -390.292837) (xy 132.803912 -390.307002)
			(xy 132.796257 -390.325504) (xy 132.795772 -390.335516) (xy 132.795772 -390.499092) (xy 132.795373 -390.509116)
			(xy 132.787701 -390.527638) (xy 132.773522 -390.541812) (xy 132.754996 -390.549477) (xy 132.744972 -390.549892)
			(xy 132.23748 -390.549892) (xy 132.22747 -390.549428) (xy 132.208976 -390.541761) (xy 132.194824 -390.5276)
			(xy 132.187166 -390.509102) (xy 132.18668 -390.499092) (xy 132.18668 -390.335516) (xy 132.186267 -390.325493)
			(xy 132.178599 -390.306973) (xy 132.164424 -390.292799) (xy 132.145903 -390.285132) (xy 132.13588 -390.284716)
			(xy 132.126736 -390.284716) (xy 132.126736 -390.029446) (xy 132.127519 -390.003724) (xy 132.139853 -389.953777)
			(xy 132.15112 -389.93064) (xy 132.156962 -389.91921) (xy 132.156708 -389.89381) (xy 132.103114 -389.796782)
			(xy 132.081524 -389.783066) (xy 132.06857 -389.78205) (xy 132.044677 -389.779895) (xy 131.997891 -389.769301)
			(xy 131.953251 -389.75174) (xy 131.911786 -389.727618) (xy 131.874455 -389.697492) (xy 131.84212 -389.662057)
			(xy 131.815527 -389.622132) (xy 131.795291 -389.578639) (xy 131.788154 -389.555736) (xy 131.78663 -389.549894)
			(xy 131.466082 -388.995412) (xy 131.462018 -388.991094) (xy 131.445913 -388.973438) (xy 131.418727 -388.934137)
			(xy 131.397777 -388.891187) (xy 131.383542 -388.845569) (xy 131.376347 -388.798326) (xy 131.375912 -388.774432)
			(xy 131.376093 -388.760384) (xy 131.378633 -388.732402) (xy 131.380992 -388.718552) (xy 131.382316 -388.709273)
			(xy 131.378788 -388.690875) (xy 131.374134 -388.682738) (xy 131.35737 -388.655814) (xy 131.352149 -388.648125)
			(xy 131.337437 -388.636794) (xy 131.328668 -388.633716) (xy 131.307044 -388.626909) (xy 131.26583 -388.608029)
			(xy 131.227709 -388.583496) (xy 131.193452 -388.553804) (xy 131.1783 -388.536942) (xy 131.175841 -388.534167)
			(xy 131.170226 -388.529322) (xy 131.167124 -388.52729) (xy 131.155057 -388.519238) (xy 131.135102 -388.498191)
			(xy 131.121029 -388.472831) (xy 131.113729 -388.444762) (xy 131.113276 -388.430262) (xy 131.113276 -388.418324)
			(xy 131.111752 -388.41172) (xy 131.106546 -388.391351) (xy 131.100945 -388.349683) (xy 131.100576 -388.328662)
			(xy 130.536442 -388.328662) (xy 130.536442 -388.32917) (xy 130.536272 -388.343795) (xy 130.533605 -388.372924)
			(xy 130.531108 -388.387336) (xy 130.529744 -388.39651) (xy 130.533017 -388.414752) (xy 130.537458 -388.422896)
			(xy 130.553968 -388.44982) (xy 130.559129 -388.457605) (xy 130.573861 -388.469064) (xy 130.58267 -388.472172)
			(xy 130.607545 -388.480256) (xy 130.654424 -388.50344) (xy 130.696838 -388.534039) (xy 130.733623 -388.571216)
			(xy 130.763771 -388.613951) (xy 130.786457 -388.661074) (xy 130.794252 -388.68604) (xy 130.795776 -388.691882)
			(xy 131.11607 -389.245602) (xy 131.120134 -389.24992) (xy 131.136295 -389.267585) (xy 131.163614 -389.306902)
			(xy 131.184682 -389.349895) (xy 131.199015 -389.395576) (xy 131.206285 -389.442898) (xy 131.206748 -389.466836)
			(xy 131.206748 -389.467344) (xy 131.206249 -389.492793) (xy 131.198078 -389.54303) (xy 131.181954 -389.591306)
			(xy 131.158296 -389.63637) (xy 131.127715 -389.677056) (xy 131.091004 -389.71231) (xy 131.07035 -389.727186)
			(xy 131.061818 -389.733634) (xy 131.050607 -389.751821) (xy 131.047763 -389.772996) (xy 131.053776 -389.793497)
			(xy 131.067608 -389.809781) (xy 131.086866 -389.819032) (xy 131.097528 -389.819896) (xy 131.10718 -389.819388)
			(xy 131.115694 -389.818098) (xy 131.132859 -389.816697) (xy 131.14147 -389.816594) (xy 131.141724 -389.816848)
			(xy 131.440936 -389.816848) (xy 131.44119 -389.816594) (xy 131.462235 -389.817042) (xy 131.503553 -389.82503)
			(xy 131.542508 -389.840953) (xy 131.57759 -389.864196) (xy 131.607442 -389.893859) (xy 131.630908 -389.928793)
			(xy 131.647078 -389.967645) (xy 131.655328 -390.008912) (xy 131.65582 -390.029954) (xy 131.65582 -390.284716)
			(xy 131.646676 -390.284716) (xy 131.636665 -390.285169) (xy 131.618169 -390.292839) (xy 131.604017 -390.307003)
			(xy 131.596361 -390.325504) (xy 131.595876 -390.335516) (xy 131.595876 -390.499092) (xy 131.595473 -390.509116)
			(xy 131.587802 -390.527637) (xy 131.573624 -390.541811) (xy 131.5551 -390.549477) (xy 131.545076 -390.549892)
			(xy 131.037584 -390.549892) (xy 131.027574 -390.549425) (xy 131.009081 -390.541759) (xy 130.994928 -390.527599)
			(xy 130.98727 -390.509102) (xy 130.986784 -390.499092) (xy 130.986784 -390.335516) (xy 130.986367 -390.325494)
			(xy 130.978699 -390.306974) (xy 130.964526 -390.292801) (xy 130.946006 -390.285133) (xy 130.935984 -390.284716)
			(xy 130.92684 -390.284716) (xy 130.92684 -390.029446) (xy 130.927622 -390.003724) (xy 130.939957 -389.953777)
			(xy 130.951224 -389.93064) (xy 130.957066 -389.91921) (xy 130.956812 -389.89381) (xy 130.903218 -389.796782)
			(xy 130.881628 -389.783066) (xy 130.868674 -389.78205) (xy 130.844773 -389.779972) (xy 130.797985 -389.769364)
			(xy 130.753343 -389.75179) (xy 130.71188 -389.727657) (xy 130.674551 -389.69752) (xy 130.642218 -389.662076)
			(xy 130.615627 -389.622143) (xy 130.595394 -389.578642) (xy 130.588258 -389.555736) (xy 130.586734 -389.549894)
			(xy 130.26644 -388.996174) (xy 130.262376 -388.991856) (xy 130.246169 -388.974151) (xy 130.218746 -388.934759)
			(xy 130.197604 -388.891669) (xy 130.183231 -388.845874) (xy 130.175958 -388.798431) (xy 130.175508 -388.774432)
			(xy 130.175687 -388.760384) (xy 130.17823 -388.732402) (xy 130.180588 -388.718552) (xy 130.181879 -388.709296)
			(xy 130.178481 -388.690932) (xy 130.173984 -388.682738) (xy 130.15722 -388.655814) (xy 130.152017 -388.648111)
			(xy 130.137292 -388.636788) (xy 130.128518 -388.633716) (xy 130.106887 -388.626928) (xy 130.065674 -388.608042)
			(xy 130.027555 -388.583503) (xy 129.993301 -388.553807) (xy 129.97815 -388.536942) (xy 129.975684 -388.534173)
			(xy 129.970074 -388.529324) (xy 129.966974 -388.52729) (xy 129.954945 -388.519211) (xy 129.935055 -388.49815)
			(xy 129.921048 -388.472794) (xy 129.913807 -388.444746) (xy 129.91338 -388.430262) (xy 129.91338 -388.418324)
			(xy 129.911602 -388.41172) (xy 129.906396 -388.391351) (xy 129.900795 -388.349683) (xy 129.900426 -388.328662)
			(xy 129.336546 -388.328662) (xy 129.336546 -388.32917) (xy 129.336376 -388.343795) (xy 129.333709 -388.372924)
			(xy 129.331212 -388.387336) (xy 129.329847 -388.39651) (xy 129.33312 -388.414752) (xy 129.337562 -388.422896)
			(xy 129.354072 -388.44982) (xy 129.359231 -388.457606) (xy 129.373965 -388.469064) (xy 129.382774 -388.472172)
			(xy 129.407707 -388.480279) (xy 129.454672 -388.50358) (xy 129.49715 -388.534308) (xy 129.533977 -388.571621)
			(xy 129.564146 -388.614499) (xy 129.586828 -388.661765) (xy 129.59461 -388.686802) (xy 129.596134 -388.692644)
			(xy 129.91592 -389.245602) (xy 129.919984 -389.24992) (xy 129.936173 -389.267641) (xy 129.9636 -389.307028)
			(xy 129.984746 -389.350114) (xy 129.999123 -389.395906) (xy 130.0064 -389.443346) (xy 130.006852 -389.467344)
			(xy 130.006351 -389.492806) (xy 129.998153 -389.543065) (xy 129.981993 -389.591357) (xy 129.958291 -389.636428)
			(xy 129.92766 -389.67711) (xy 129.890896 -389.712347) (xy 129.8702 -389.727186) (xy 129.861693 -389.733657)
			(xy 129.8505 -389.751838) (xy 129.847662 -389.772999) (xy 129.853669 -389.793487) (xy 129.867485 -389.809765)
			(xy 129.886724 -389.819023) (xy 129.897378 -389.819896) (xy 129.90703 -389.819388) (xy 129.915544 -389.818093)
			(xy 129.932709 -389.816695) (xy 129.94132 -389.816594) (xy 129.941574 -389.816848) (xy 130.240786 -389.816848)
			(xy 130.24104 -389.816594) (xy 130.262101 -389.817017) (xy 130.303459 -389.824968) (xy 130.342458 -389.840869)
			(xy 130.377584 -389.864104) (xy 130.407476 -389.893772) (xy 130.430974 -389.928722) (xy 130.447168 -389.967599)
			(xy 130.45543 -390.008896) (xy 130.455924 -390.029954) (xy 130.455924 -390.284716) (xy 130.44678 -390.284716)
			(xy 130.436769 -390.285172) (xy 130.418274 -390.292841) (xy 130.404121 -390.307004) (xy 130.396465 -390.325505)
			(xy 130.39598 -390.335516) (xy 130.39598 -390.499092) (xy 130.395574 -390.509115) (xy 130.387902 -390.527636)
			(xy 130.373726 -390.541809) (xy 130.355203 -390.549476) (xy 130.34518 -390.549892) (xy 129.83718 -390.549892)
			(xy 129.82717 -390.549428) (xy 129.808676 -390.541761) (xy 129.794524 -390.5276) (xy 129.786866 -390.509102)
			(xy 129.78638 -390.499092) (xy 129.78638 -390.284716) (xy 129.777236 -390.284716) (xy 129.767219 -390.284251)
			(xy 129.748706 -390.276596) (xy 129.734533 -390.262438) (xy 129.726859 -390.243933) (xy 129.726436 -390.233916)
			(xy 129.726436 -390.029954) (xy 129.726779 -390.012721) (xy 129.73235 -389.978708) (xy 129.743323 -389.946035)
			(xy 129.751074 -389.93064) (xy 129.756916 -389.91921) (xy 129.756662 -389.89381) (xy 129.703068 -389.796782)
			(xy 129.681478 -389.783066) (xy 129.668524 -389.78205) (xy 129.644627 -389.779932) (xy 129.59784 -389.769331)
			(xy 129.553199 -389.751764) (xy 129.511735 -389.727636) (xy 129.474405 -389.697505) (xy 129.442071 -389.662066)
			(xy 129.41548 -389.622137) (xy 129.395244 -389.578641) (xy 129.388108 -389.555736) (xy 129.386584 -389.549894)
			(xy 129.066036 -388.995412) (xy 129.061972 -388.991094) (xy 129.045872 -388.973421) (xy 129.018623 -388.934143)
			(xy 128.997611 -388.891204) (xy 128.983318 -388.845586) (xy 128.976071 -388.798334) (xy 128.975612 -388.774432)
			(xy 128.975791 -388.760384) (xy 128.978334 -388.732402) (xy 128.980692 -388.718552) (xy 128.981983 -388.709296)
			(xy 128.978585 -388.690932) (xy 128.974088 -388.682738) (xy 128.957324 -388.655814) (xy 128.952119 -388.648113)
			(xy 128.937396 -388.636788) (xy 128.928622 -388.633716) (xy 128.906992 -388.626927) (xy 128.865778 -388.608041)
			(xy 128.827659 -388.583503) (xy 128.793405 -388.553807) (xy 128.778254 -388.536942) (xy 128.775788 -388.534173)
			(xy 128.770178 -388.529324) (xy 128.767078 -388.52729) (xy 128.75505 -388.519209) (xy 128.73516 -388.498149)
			(xy 128.721152 -388.472794) (xy 128.713911 -388.444746) (xy 128.713484 -388.430262) (xy 128.713484 -388.418324)
			(xy 128.711706 -388.41172) (xy 128.706501 -388.391351) (xy 128.700899 -388.349683) (xy 128.70053 -388.328662)
			(xy 128.136396 -388.328662) (xy 128.136255 -388.343415) (xy 128.13358 -388.372799) (xy 128.131062 -388.387336)
			(xy 128.129704 -388.39651) (xy 128.132974 -388.414751) (xy 128.137412 -388.422896) (xy 128.153922 -388.44982)
			(xy 128.1591 -388.457592) (xy 128.17382 -388.469057) (xy 128.182624 -388.472172) (xy 128.207509 -388.480225)
			(xy 128.254388 -388.503417) (xy 128.2968 -388.534023) (xy 128.333582 -388.571206) (xy 128.363729 -388.613945)
			(xy 128.386413 -388.661072) (xy 128.394206 -388.68604) (xy 128.39573 -388.691882) (xy 128.716024 -389.245602)
			(xy 128.720088 -389.24992) (xy 128.736278 -389.26764) (xy 128.763704 -389.307028) (xy 128.78485 -389.350114)
			(xy 128.799227 -389.395906) (xy 128.806504 -389.443346) (xy 128.806956 -389.467344) (xy 128.806453 -389.492806)
			(xy 128.798255 -389.543065) (xy 128.782096 -389.591356) (xy 128.758394 -389.636428) (xy 128.727764 -389.677109)
			(xy 128.691 -389.712347) (xy 128.670304 -389.727186) (xy 128.661795 -389.733655) (xy 128.6506 -389.751837)
			(xy 128.647762 -389.772999) (xy 128.65377 -389.793488) (xy 128.667587 -389.809766) (xy 128.686827 -389.819024)
			(xy 128.697482 -389.819896) (xy 128.707134 -389.819388) (xy 128.715647 -389.818092) (xy 128.732813 -389.816695)
			(xy 128.741424 -389.816594) (xy 128.741678 -389.816848) (xy 129.04089 -389.816848) (xy 129.041144 -389.816594)
			(xy 129.062205 -389.817013) (xy 129.103564 -389.824965) (xy 129.142562 -389.840867) (xy 129.177688 -389.864102)
			(xy 129.20758 -389.893771) (xy 129.231078 -389.928721) (xy 129.247272 -389.967599) (xy 129.255534 -390.008896)
			(xy 129.256028 -390.029954) (xy 129.256028 -390.284716) (xy 129.246884 -390.284716) (xy 129.236873 -390.285175)
			(xy 129.218378 -390.292843) (xy 129.204225 -390.307005) (xy 129.196569 -390.325505) (xy 129.196084 -390.335516)
			(xy 129.196084 -390.499092) (xy 129.195674 -390.509115) (xy 129.188003 -390.527635) (xy 129.173828 -390.541808)
			(xy 129.155307 -390.549475) (xy 129.145284 -390.549892) (xy 128.637284 -390.549892) (xy 128.627274 -390.549425)
			(xy 128.608781 -390.541759) (xy 128.594628 -390.527599) (xy 128.58697 -390.509102) (xy 128.586484 -390.499092)
			(xy 128.586484 -390.284716) (xy 128.57734 -390.284716) (xy 128.567323 -390.284248) (xy 128.54881 -390.276594)
			(xy 128.534637 -390.262437) (xy 128.526963 -390.243932) (xy 128.52654 -390.233916) (xy 128.52654 -390.029954)
			(xy 128.526882 -390.012721) (xy 128.532454 -389.978708) (xy 128.543427 -389.946035) (xy 128.551178 -389.93064)
			(xy 128.55702 -389.91921) (xy 128.556766 -389.89381) (xy 128.503172 -389.796782) (xy 128.481582 -389.783066)
			(xy 128.468628 -389.78205) (xy 128.444732 -389.779929) (xy 128.397945 -389.769328) (xy 128.353304 -389.751762)
			(xy 128.31184 -389.727635) (xy 128.274509 -389.697504) (xy 128.242175 -389.662065) (xy 128.215584 -389.622137)
			(xy 128.195348 -389.578641) (xy 128.188212 -389.555736) (xy 128.186688 -389.549894) (xy 127.866394 -388.996174)
			(xy 127.86233 -388.991856) (xy 127.846167 -388.974126) (xy 127.8188 -388.934722) (xy 127.79771 -388.891631)
			(xy 127.783384 -388.845846) (xy 127.77615 -388.79842) (xy 127.775716 -388.774432) (xy 127.775896 -388.760384)
			(xy 127.778437 -388.732402) (xy 127.780796 -388.718552) (xy 127.782119 -388.709273) (xy 127.778591 -388.690875)
			(xy 127.773938 -388.682738) (xy 127.757174 -388.655814) (xy 127.751987 -388.648098) (xy 127.737251 -388.636781)
			(xy 127.728472 -388.633716) (xy 127.706897 -388.626963) (xy 127.665771 -388.608189) (xy 127.627718 -388.583783)
			(xy 127.593502 -388.554236) (xy 127.578358 -388.53745) (xy 127.57589 -388.534682) (xy 127.570282 -388.529833)
			(xy 127.567182 -388.527798) (xy 127.555033 -388.519724) (xy 127.534948 -388.49858) (xy 127.520804 -388.473077)
			(xy 127.513504 -388.444843) (xy 127.51308 -388.430262) (xy 127.51308 -388.417816) (xy 127.511302 -388.411466)
			(xy 127.506172 -388.391151) (xy 127.500696 -388.349612) (xy 127.50038 -388.328662) (xy 127.500718 -388.307714)
			(xy 127.506191 -388.266176) (xy 127.511302 -388.245858) (xy 127.51308 -388.239508) (xy 127.51308 -387.782816)
			(xy 127.511302 -387.776466) (xy 127.506172 -387.756151) (xy 127.500696 -387.714612) (xy 127.50038 -387.693662)
			(xy 127.500718 -387.672714) (xy 127.506191 -387.631176) (xy 127.511302 -387.610858) (xy 127.51308 -387.604508)
			(xy 127.51308 -387.592062) (xy 127.513546 -387.576597) (xy 127.521777 -387.54678) (xy 127.537612 -387.520209)
			(xy 127.559921 -387.498782) (xy 127.573278 -387.49097) (xy 127.576834 -387.486906) (xy 127.584191 -387.477386)
			(xy 127.589885 -387.454044) (xy 127.587756 -387.442202) (xy 127.580644 -387.410706) (xy 127.577388 -387.399187)
			(xy 127.562131 -387.380776) (xy 127.551434 -387.3754) (xy 127.529942 -387.365597) (xy 127.48988 -387.340571)
			(xy 127.453965 -387.309889) (xy 127.43815 -387.292342) (xy 127.435684 -387.289573) (xy 127.430074 -387.284724)
			(xy 127.426974 -387.28269) (xy 127.414945 -387.274611) (xy 127.395055 -387.25355) (xy 127.381048 -387.228194)
			(xy 127.373807 -387.200146) (xy 127.37338 -387.185662) (xy 127.37338 -387.173724) (xy 127.371602 -387.16712)
			(xy 127.366396 -387.146751) (xy 127.360795 -387.105083) (xy 127.360426 -387.084062) (xy 127.360792 -387.063041)
			(xy 127.366403 -387.021375) (xy 127.371602 -387.001004) (xy 127.37338 -386.9944) (xy 127.37338 -386.880862)
			(xy 127.374031 -386.862742) (xy 127.38529 -386.828296) (xy 127.395478 -386.813298) (xy 127.399947 -386.806624)
			(xy 127.404882 -386.791352) (xy 127.40513 -386.783326) (xy 127.40513 -386.749798) (xy 127.404804 -386.741781)
			(xy 127.399905 -386.726516) (xy 127.395478 -386.719826) (xy 127.385394 -386.704775) (xy 127.374137 -386.670363)
			(xy 127.37338 -386.652262) (xy 127.37338 -386.538724) (xy 127.371602 -386.53212) (xy 127.366396 -386.511751)
			(xy 127.360795 -386.470083) (xy 127.360426 -386.449062) (xy 127.361188 -386.426456) (xy 127.36195 -386.416296)
			(xy 127.355854 -386.3975) (xy 127.30226 -386.335524) (xy 127.295311 -386.328285) (xy 127.277415 -386.319259)
			(xy 127.267462 -386.317998) (xy 127.243656 -386.315754) (xy 127.197064 -386.305003) (xy 127.152629 -386.287343)
			(xy 127.111368 -386.263181) (xy 127.074225 -386.233069) (xy 127.042052 -386.197696) (xy 127.015585 -386.157874)
			(xy 126.99543 -386.114513) (xy 126.988316 -386.091684) (xy 126.986792 -386.085842) (xy 126.666498 -385.532122)
			(xy 126.662434 -385.527804) (xy 126.646279 -385.510134) (xy 126.61896 -385.470817) (xy 126.597892 -385.427826)
			(xy 126.583558 -385.382146) (xy 126.576285 -385.334826) (xy 126.57582 -385.310888) (xy 126.043728 -385.310888)
			(xy 126.315978 -385.78155) (xy 126.320042 -385.785868) (xy 126.336196 -385.803573) (xy 126.36354 -385.842931)
			(xy 126.38462 -385.885971) (xy 126.398952 -385.931703) (xy 126.406206 -385.979076) (xy 126.406656 -386.003038)
			(xy 126.406656 -386.003546) (xy 126.406148 -386.023866) (xy 126.405386 -386.033772) (xy 126.411736 -386.052822)
			(xy 126.472442 -386.122164) (xy 126.490222 -386.131054) (xy 126.500382 -386.131816) (xy 126.525359 -386.134005)
			(xy 126.574217 -386.14526) (xy 126.620704 -386.164041) (xy 126.663669 -386.189884) (xy 126.702046 -386.222147)
			(xy 126.718822 -386.240782) (xy 126.721288 -386.243551) (xy 126.726898 -386.2484) (xy 126.729998 -386.250434)
			(xy 126.742032 -386.258507) (xy 126.761923 -386.279568) (xy 126.77593 -386.304926) (xy 126.783168 -386.332977)
			(xy 126.783592 -386.347462) (xy 126.783592 -386.3594) (xy 126.78537 -386.366004) (xy 126.790562 -386.386376)
			(xy 126.796172 -386.428042) (xy 126.796546 -386.449062) (xy 126.796163 -386.470082) (xy 126.790564 -386.511748)
			(xy 126.78537 -386.53212) (xy 126.783592 -386.538724) (xy 126.783592 -386.576316) (xy 126.784075 -386.586324)
			(xy 126.791738 -386.604814) (xy 126.805892 -386.618967) (xy 126.824384 -386.626627) (xy 126.834392 -386.627116)
			(xy 126.903988 -386.627116) (xy 126.914057 -386.627544) (xy 126.932655 -386.635262) (xy 126.940056 -386.642102)
			(xy 126.954788 -386.656834) (xy 126.962194 -386.663666) (xy 126.980789 -386.671389) (xy 126.990856 -386.67182)
			(xy 127.02286 -386.67182) (xy 127.032881 -386.672253) (xy 127.051401 -386.679913) (xy 127.065575 -386.694082)
			(xy 127.073243 -386.712599) (xy 127.07366 -386.72262) (xy 127.07366 -386.754624) (xy 127.074057 -386.764697)
			(xy 127.081796 -386.783295) (xy 127.088646 -386.790692) (xy 127.120142 -386.821934) (xy 127.126995 -386.829323)
			(xy 127.134706 -386.847931) (xy 127.135128 -386.858002) (xy 127.135128 -388.5565) (xy 127.135383 -388.564614)
			(xy 127.140444 -388.58003) (xy 127.145034 -388.586726) (xy 127.160679 -388.608827) (xy 127.184937 -388.657235)
			(xy 127.193294 -388.682992) (xy 127.196088 -388.692136) (xy 127.199136 -388.69747) (xy 127.615188 -389.113522)
			(xy 127.621905 -389.120906) (xy 127.629494 -389.139352) (xy 127.629484 -389.159298) (xy 127.621877 -389.177737)
			(xy 127.615188 -389.18515) (xy 127.55245 -389.247888) (xy 127.548386 -389.283448) (xy 127.558038 -389.298434)
			(xy 127.569629 -389.317477) (xy 127.58796 -389.358111) (xy 127.60039 -389.400922) (xy 127.606672 -389.445055)
			(xy 127.60706 -389.467344) (xy 127.606531 -389.492072) (xy 127.598795 -389.540919) (xy 127.583535 -389.587961)
			(xy 127.561124 -389.632048) (xy 127.532112 -389.6721) (xy 127.497207 -389.707136) (xy 127.47752 -389.722106)
			(xy 127.46822 -389.729684) (xy 127.45734 -389.751022) (xy 127.456692 -389.763) (xy 127.456692 -389.767826)
			(xy 127.457166 -389.777834) (xy 127.464833 -389.796325) (xy 127.47899 -389.810477) (xy 127.497483 -389.818137)
			(xy 127.507492 -389.818626) (xy 127.510794 -389.818626) (xy 127.513842 -389.818372) (xy 127.541274 -389.816594)
			(xy 127.541528 -389.816848) (xy 127.84074 -389.816848) (xy 127.840994 -389.816594) (xy 127.862039 -389.817039)
			(xy 127.903358 -389.825027) (xy 127.942312 -389.840951) (xy 127.977395 -389.864194) (xy 128.007246 -389.893858)
			(xy 128.030712 -389.928792) (xy 128.046882 -389.967645) (xy 128.055132 -390.008912) (xy 128.055624 -390.029954)
			(xy 128.055624 -390.284716) (xy 128.04648 -390.284716) (xy 128.036469 -390.285172) (xy 128.017974 -390.292841)
			(xy 128.003821 -390.307004) (xy 127.996165 -390.325505) (xy 127.99568 -390.335516) (xy 127.99568 -390.499092)
			(xy 127.995274 -390.509115) (xy 127.987602 -390.527636) (xy 127.973426 -390.541809) (xy 127.954903 -390.549476)
			(xy 127.94488 -390.549892) (xy 127.491744 -390.549892) (xy 127.481727 -390.550355) (xy 127.463212 -390.558009)
			(xy 127.449039 -390.572168) (xy 127.441366 -390.590675) (xy 127.440944 -390.600692) (xy 127.440944 -391.446766)
			(xy 127.44069 -391.454386) (xy 127.44069 -392.833098) (xy 127.440944 -392.840972) (xy 127.440944 -392.881104)
			(xy 127.44069 -392.888978) (xy 127.44069 -393.292838) (xy 127.735076 -393.292838) (xy 127.735076 -392.42873)
			(xy 127.735523 -392.403263) (xy 127.742325 -392.352783) (xy 127.755785 -392.303659) (xy 127.775664 -392.256763)
			(xy 127.801607 -392.21293) (xy 127.833154 -392.17294) (xy 127.851154 -392.154918) (xy 127.857758 -392.148568)
			(xy 127.865632 -392.131804) (xy 127.87249 -392.04646) (xy 127.86741 -392.02868) (xy 127.861822 -392.021314)
			(xy 127.84697 -392.000567) (xy 127.823335 -391.955353) (xy 127.807234 -391.906941) (xy 127.799082 -391.856578)
			(xy 127.798576 -391.831068) (xy 127.798576 -391.830814) (xy 127.799066 -391.805825) (xy 127.806885 -391.756462)
			(xy 127.822329 -391.70893) (xy 127.845019 -391.664398) (xy 127.874395 -391.623965) (xy 127.909735 -391.588625)
			(xy 127.950168 -391.559249) (xy 127.9947 -391.536559) (xy 128.042232 -391.521115) (xy 128.091595 -391.513296)
			(xy 128.141573 -391.513296) (xy 128.190936 -391.521115) (xy 128.238468 -391.536559) (xy 128.283 -391.559249)
			(xy 128.323433 -391.588625) (xy 128.358773 -391.623965) (xy 128.388149 -391.664398) (xy 128.410839 -391.70893)
			(xy 128.426283 -391.756462) (xy 128.434102 -391.805825) (xy 128.434592 -391.830814) (xy 128.434592 -391.831068)
			(xy 128.434101 -391.856577) (xy 128.425923 -391.906937) (xy 128.409821 -391.955348) (xy 128.386205 -392.000572)
			(xy 128.371346 -392.021314) (xy 128.365758 -392.02868) (xy 128.360678 -392.04646) (xy 128.367536 -392.131804)
			(xy 128.37541 -392.148568) (xy 128.382014 -392.154918) (xy 128.400024 -392.172929) (xy 128.431562 -392.212927)
			(xy 128.4575 -392.256763) (xy 128.477378 -392.30366) (xy 128.490841 -392.352784) (xy 128.497651 -392.403262)
			(xy 128.498092 -392.42873) (xy 128.498092 -393.292838) (xy 128.498083 -393.293346) (xy 128.934972 -393.293346)
			(xy 128.934972 -392.42873) (xy 128.93542 -392.403263) (xy 128.942222 -392.352784) (xy 128.955682 -392.303659)
			(xy 128.975561 -392.256763) (xy 129.001504 -392.21293) (xy 129.03305 -392.17294) (xy 129.05105 -392.154918)
			(xy 129.057654 -392.148568) (xy 129.065528 -392.131804) (xy 129.072386 -392.04646) (xy 129.067306 -392.02868)
			(xy 129.061718 -392.021314) (xy 129.046866 -392.000567) (xy 129.023231 -391.955353) (xy 129.00713 -391.906941)
			(xy 128.998978 -391.856578) (xy 128.998472 -391.831068) (xy 128.998472 -391.830814) (xy 128.998962 -391.805825)
			(xy 129.006781 -391.756462) (xy 129.022225 -391.70893) (xy 129.044915 -391.664398) (xy 129.074291 -391.623965)
			(xy 129.109631 -391.588625) (xy 129.150064 -391.559249) (xy 129.194596 -391.536559) (xy 129.242128 -391.521115)
			(xy 129.291491 -391.513296) (xy 129.341469 -391.513296) (xy 129.390832 -391.521115) (xy 129.438364 -391.536559)
			(xy 129.482896 -391.559249) (xy 129.523329 -391.588625) (xy 129.558669 -391.623965) (xy 129.588045 -391.664398)
			(xy 129.610735 -391.70893) (xy 129.626179 -391.756462) (xy 129.633998 -391.805825) (xy 129.634488 -391.830814)
			(xy 129.634488 -391.831068) (xy 129.633978 -391.856576) (xy 129.625803 -391.906934) (xy 129.609705 -391.955345)
			(xy 129.586097 -392.000571) (xy 129.571242 -392.021314) (xy 129.565654 -392.02868) (xy 129.560574 -392.04646)
			(xy 129.567432 -392.131804) (xy 129.575306 -392.148568) (xy 129.58191 -392.154918) (xy 129.59992 -392.17293)
			(xy 129.631458 -392.212927) (xy 129.657396 -392.256763) (xy 129.677274 -392.30366) (xy 129.690737 -392.352784)
			(xy 129.697547 -392.403263) (xy 129.697988 -392.42873) (xy 129.697988 -393.292838) (xy 130.134868 -393.292838)
			(xy 130.134868 -392.42873) (xy 130.135318 -392.403263) (xy 130.142119 -392.352784) (xy 130.155579 -392.303659)
			(xy 130.175457 -392.256763) (xy 130.2014 -392.21293) (xy 130.232946 -392.17294) (xy 130.250946 -392.154918)
			(xy 130.25755 -392.148568) (xy 130.265424 -392.131804) (xy 130.272282 -392.04646) (xy 130.267202 -392.02868)
			(xy 130.261614 -392.021314) (xy 130.246761 -392.000567) (xy 130.223127 -391.955353) (xy 130.207026 -391.906941)
			(xy 130.198874 -391.856578) (xy 130.198368 -391.831068) (xy 130.198368 -391.830814) (xy 130.198858 -391.805825)
			(xy 130.206677 -391.756462) (xy 130.222121 -391.70893) (xy 130.244811 -391.664398) (xy 130.274187 -391.623965)
			(xy 130.309527 -391.588625) (xy 130.34996 -391.559249) (xy 130.394492 -391.536559) (xy 130.442024 -391.521115)
			(xy 130.491387 -391.513296) (xy 130.541365 -391.513296) (xy 130.590728 -391.521115) (xy 130.63826 -391.536559)
			(xy 130.682792 -391.559249) (xy 130.723225 -391.588625) (xy 130.758565 -391.623965) (xy 130.787941 -391.664398)
			(xy 130.810631 -391.70893) (xy 130.826075 -391.756462) (xy 130.833894 -391.805825) (xy 130.834384 -391.830814)
			(xy 130.834384 -391.831068) (xy 130.833875 -391.856576) (xy 130.8257 -391.906934) (xy 130.809602 -391.955345)
			(xy 130.785993 -392.000571) (xy 130.771138 -392.021314) (xy 130.76555 -392.02868) (xy 130.76047 -392.04646)
			(xy 130.767328 -392.131804) (xy 130.775202 -392.148568) (xy 130.781806 -392.154918) (xy 130.799815 -392.172931)
			(xy 130.831353 -392.212927) (xy 130.857292 -392.256764) (xy 130.877169 -392.30366) (xy 130.890633 -392.352784)
			(xy 130.897443 -392.403263) (xy 130.897884 -392.42873) (xy 130.897884 -393.292838) (xy 131.334764 -393.292838)
			(xy 131.334764 -392.429238) (xy 131.335182 -392.403718) (xy 131.341972 -392.353131) (xy 131.35545 -392.303902)
			(xy 131.375375 -392.256911) (xy 131.40139 -392.212998) (xy 131.43303 -392.172948) (xy 131.451096 -392.154918)
			(xy 131.4577 -392.148568) (xy 131.465574 -392.131804) (xy 131.472432 -392.04646) (xy 131.467352 -392.02868)
			(xy 131.461764 -392.021314) (xy 131.446918 -392.000563) (xy 131.42328 -391.955351) (xy 131.407177 -391.90694)
			(xy 131.399024 -391.856577) (xy 131.398518 -391.831068) (xy 131.398518 -391.830814) (xy 131.399008 -391.805825)
			(xy 131.406827 -391.756462) (xy 131.422271 -391.70893) (xy 131.444961 -391.664398) (xy 131.474337 -391.623965)
			(xy 131.509677 -391.588625) (xy 131.55011 -391.559249) (xy 131.594642 -391.536559) (xy 131.642174 -391.521115)
			(xy 131.691537 -391.513296) (xy 131.741515 -391.513296) (xy 131.790878 -391.521115) (xy 131.83841 -391.536559)
			(xy 131.882942 -391.559249) (xy 131.923375 -391.588625) (xy 131.958715 -391.623965) (xy 131.988091 -391.664398)
			(xy 132.010781 -391.70893) (xy 132.026225 -391.756462) (xy 132.034044 -391.805825) (xy 132.034534 -391.830814)
			(xy 132.034534 -391.831068) (xy 132.034034 -391.856577) (xy 132.025858 -391.906936) (xy 132.009758 -391.955347)
			(xy 131.986145 -392.000572) (xy 131.971288 -392.021314) (xy 131.9657 -392.02868) (xy 131.96062 -392.04646)
			(xy 131.967478 -392.131804) (xy 131.975352 -392.148568) (xy 131.981956 -392.154918) (xy 131.99999 -392.172976)
			(xy 132.031621 -392.213028) (xy 132.057632 -392.256937) (xy 132.07756 -392.303921) (xy 132.091049 -392.353141)
			(xy 132.097858 -392.40372) (xy 132.098288 -392.429238) (xy 132.098288 -393.292838) (xy 132.53466 -393.292838)
			(xy 132.53466 -392.429238) (xy 132.535079 -392.403718) (xy 132.541869 -392.353131) (xy 132.555347 -392.303902)
			(xy 132.575271 -392.256911) (xy 132.601286 -392.212998) (xy 132.632926 -392.172948) (xy 132.650992 -392.154918)
			(xy 132.657596 -392.148568) (xy 132.66547 -392.131804) (xy 132.672328 -392.04646) (xy 132.667248 -392.02868)
			(xy 132.66166 -392.021314) (xy 132.646813 -392.000563) (xy 132.623176 -391.955351) (xy 132.607073 -391.90694)
			(xy 132.59892 -391.856577) (xy 132.598414 -391.831068) (xy 132.598414 -391.830814) (xy 132.598904 -391.805825)
			(xy 132.606723 -391.756462) (xy 132.622167 -391.70893) (xy 132.644857 -391.664398) (xy 132.674233 -391.623965)
			(xy 132.709573 -391.588625) (xy 132.750006 -391.559249) (xy 132.794538 -391.536559) (xy 132.84207 -391.521115)
			(xy 132.891433 -391.513296) (xy 132.941411 -391.513296) (xy 132.990774 -391.521115) (xy 133.038306 -391.536559)
			(xy 133.082838 -391.559249) (xy 133.123271 -391.588625) (xy 133.158611 -391.623965) (xy 133.187987 -391.664398)
			(xy 133.210677 -391.70893) (xy 133.226121 -391.756462) (xy 133.23394 -391.805825) (xy 133.23443 -391.830814)
			(xy 133.23443 -391.831068) (xy 133.233931 -391.856577) (xy 133.225755 -391.906936) (xy 133.209654 -391.955347)
			(xy 133.186041 -392.000572) (xy 133.171184 -392.021314) (xy 133.165596 -392.02868) (xy 133.160516 -392.04646)
			(xy 133.167374 -392.131804) (xy 133.175248 -392.148568) (xy 133.181852 -392.154918) (xy 133.199886 -392.172977)
			(xy 133.231516 -392.213028) (xy 133.257528 -392.256937) (xy 133.277456 -392.303921) (xy 133.290945 -392.353142)
			(xy 133.297754 -392.40372) (xy 133.298184 -392.429238) (xy 133.298184 -393.285247) (xy 133.969818 -393.285247)
			(xy 133.969818 -393.230753) (xy 133.977573 -393.176815) (xy 133.992924 -393.124529) (xy 134.01556 -393.07496)
			(xy 134.045019 -393.029116) (xy 134.080703 -392.987931) (xy 134.121884 -392.952243) (xy 134.167724 -392.922779)
			(xy 134.217291 -392.900138) (xy 134.269576 -392.884781) (xy 134.323514 -392.877021) (xy 134.35076 -392.876532)
			(xy 134.351268 -392.876532) (xy 134.376397 -392.876949) (xy 134.426218 -392.88357) (xy 134.450582 -392.88974)
			(xy 134.46552 -392.89325) (xy 134.496172 -392.892174) (xy 134.525124 -392.882054) (xy 134.549773 -392.863803)
			(xy 134.567898 -392.839061) (xy 134.577869 -392.810057) (xy 134.578852 -392.794744) (xy 134.580071 -392.768036)
			(xy 134.589099 -392.715339) (xy 134.605399 -392.664419) (xy 134.628652 -392.616275) (xy 134.658401 -392.571852)
			(xy 134.694065 -392.532019) (xy 134.734942 -392.497558) (xy 134.780233 -392.469146) (xy 134.829048 -392.447338)
			(xy 134.88043 -392.432562) (xy 134.933373 -392.425109) (xy 134.960106 -392.424666) (xy 134.987355 -392.425205)
			(xy 135.041298 -392.432961) (xy 135.093589 -392.448316) (xy 135.143162 -392.470956) (xy 135.189008 -392.50042)
			(xy 135.230195 -392.536109) (xy 135.265883 -392.577296) (xy 135.295347 -392.623143) (xy 135.317986 -392.672717)
			(xy 135.33334 -392.725007) (xy 135.341096 -392.778951) (xy 135.341096 -392.833449) (xy 135.33334 -392.887393)
			(xy 135.317986 -392.939683) (xy 135.295347 -392.989257) (xy 135.265883 -393.035104) (xy 135.230195 -393.076291)
			(xy 135.189008 -393.11198) (xy 135.143162 -393.141444) (xy 135.093589 -393.164084) (xy 135.041298 -393.179439)
			(xy 134.987355 -393.187195) (xy 134.960106 -393.187682) (xy 134.959598 -393.187682) (xy 134.934468 -393.187271)
			(xy 134.884647 -393.180646) (xy 134.860284 -393.174474) (xy 134.845356 -393.170913) (xy 134.814697 -393.171998)
			(xy 134.785739 -393.182126) (xy 134.761088 -393.200388) (xy 134.742963 -393.22514) (xy 134.732995 -393.254153)
			(xy 134.732014 -393.26947) (xy 134.730742 -393.296174) (xy 134.721715 -393.348866) (xy 134.705416 -393.399781)
			(xy 134.682167 -393.447921) (xy 134.652422 -393.492341) (xy 134.616765 -393.532172) (xy 134.575894 -393.566633)
			(xy 134.53061 -393.595047) (xy 134.481803 -393.616859) (xy 134.430427 -393.63164) (xy 134.37749 -393.639101)
			(xy 134.35076 -393.639548) (xy 134.323514 -393.638979) (xy 134.269576 -393.631219) (xy 134.217291 -393.615862)
			(xy 134.167724 -393.593221) (xy 134.121884 -393.563757) (xy 134.080703 -393.528069) (xy 134.045019 -393.486884)
			(xy 134.01556 -393.44104) (xy 133.992924 -393.391471) (xy 133.977573 -393.339185) (xy 133.969818 -393.285247)
			(xy 133.298184 -393.285247) (xy 133.298184 -393.292838) (xy 133.297684 -393.320713) (xy 133.289576 -393.37587)
			(xy 133.273525 -393.429258) (xy 133.249871 -393.479741) (xy 133.21912 -393.526242) (xy 133.200902 -393.547346)
			(xy 133.19506 -393.55395) (xy 133.188202 -393.570714) (xy 133.18617 -393.645136) (xy 133.186274 -393.654042)
			(xy 133.191875 -393.670936) (xy 133.197092 -393.678156) (xy 133.197346 -393.67841) (xy 133.212112 -393.697587)
			(xy 133.236941 -393.739134) (xy 133.255978 -393.783633) (xy 133.26888 -393.830281) (xy 133.275415 -393.878238)
			(xy 133.275832 -393.902438) (xy 133.27533 -393.929334) (xy 133.267312 -393.982526) (xy 133.251456 -394.033929)
			(xy 133.228117 -394.082395) (xy 133.197814 -394.126841) (xy 133.161226 -394.166274) (xy 133.119169 -394.199813)
			(xy 133.072583 -394.226709) (xy 133.022509 -394.246362) (xy 132.970064 -394.258332) (xy 132.916422 -394.262352)
			(xy 132.86278 -394.258332) (xy 132.810335 -394.246362) (xy 132.760261 -394.226709) (xy 132.713675 -394.199813)
			(xy 132.671618 -394.166274) (xy 132.63503 -394.126841) (xy 132.604727 -394.082395) (xy 132.581388 -394.033929)
			(xy 132.565532 -393.982526) (xy 132.557514 -393.929334) (xy 132.557012 -393.902438) (xy 132.557411 -393.878235)
			(xy 132.563913 -393.830267) (xy 132.576803 -393.783609) (xy 132.595848 -393.739106) (xy 132.620702 -393.697568)
			(xy 132.635498 -393.67841) (xy 132.635752 -393.678156) (xy 132.641026 -393.67097) (xy 132.646608 -393.65405)
			(xy 132.646674 -393.645136) (xy 132.644642 -393.570714) (xy 132.637784 -393.55395) (xy 132.631942 -393.547346)
			(xy 132.613733 -393.526236) (xy 132.58299 -393.479732) (xy 132.55934 -393.42925) (xy 132.543286 -393.375865)
			(xy 132.53517 -393.320712) (xy 132.53466 -393.292838) (xy 132.098288 -393.292838) (xy 132.097718 -393.322001)
			(xy 132.088798 -393.379642) (xy 132.071216 -393.435256) (xy 132.045382 -393.48755) (xy 132.011897 -393.535307)
			(xy 131.992116 -393.556744) (xy 131.985949 -393.56382) (xy 131.978798 -393.581161) (xy 131.978146 -393.590526)
			(xy 131.976368 -393.659106) (xy 131.976519 -393.668362) (xy 131.982648 -393.685814) (xy 131.988306 -393.693142)
			(xy 131.988814 -393.69365) (xy 132.005165 -393.713265) (xy 132.032699 -393.756273) (xy 132.053857 -393.80275)
			(xy 132.068212 -393.851758) (xy 132.075475 -393.902305) (xy 132.075936 -393.927838) (xy 132.075434 -393.954734)
			(xy 132.067416 -394.007926) (xy 132.05156 -394.059329) (xy 132.028221 -394.107795) (xy 131.997918 -394.152241)
			(xy 131.96133 -394.191674) (xy 131.919273 -394.225213) (xy 131.872687 -394.252109) (xy 131.822613 -394.271762)
			(xy 131.770168 -394.283732) (xy 131.716526 -394.287752) (xy 131.662884 -394.283732) (xy 131.610439 -394.271762)
			(xy 131.560365 -394.252109) (xy 131.513779 -394.225213) (xy 131.471722 -394.191674) (xy 131.435134 -394.152241)
			(xy 131.404831 -394.107795) (xy 131.381492 -394.059329) (xy 131.365636 -394.007926) (xy 131.357618 -393.954734)
			(xy 131.357116 -393.927838) (xy 131.357601 -393.902271) (xy 131.364876 -393.851656) (xy 131.379271 -393.802589)
			(xy 131.400492 -393.756066) (xy 131.428109 -393.71303) (xy 131.444492 -393.693396) (xy 131.444746 -393.693142)
			(xy 131.450407 -393.685819) (xy 131.45652 -393.668362) (xy 131.456684 -393.659106) (xy 131.454652 -393.580874)
			(xy 131.44754 -393.563856) (xy 131.440936 -393.556744) (xy 131.421156 -393.535306) (xy 131.387663 -393.487553)
			(xy 131.361825 -393.43526) (xy 131.344246 -393.379644) (xy 131.335335 -393.322002) (xy 131.334764 -393.292838)
			(xy 130.897884 -393.292838) (xy 130.897342 -393.321992) (xy 130.888471 -393.379621) (xy 130.87094 -393.435231)
			(xy 130.845157 -393.487529) (xy 130.811723 -393.535298) (xy 130.791966 -393.556744) (xy 130.785806 -393.563825)
			(xy 130.77865 -393.581162) (xy 130.777996 -393.590526) (xy 130.776218 -393.659106) (xy 130.776358 -393.668363)
			(xy 130.782494 -393.685816) (xy 130.788156 -393.693142) (xy 130.788664 -393.69365) (xy 130.804974 -393.713286)
			(xy 130.832449 -393.756307) (xy 130.853553 -393.802785) (xy 130.867862 -393.851784) (xy 130.875086 -393.902315)
			(xy 130.875532 -393.927838) (xy 130.87503 -393.954715) (xy 130.867018 -394.00787) (xy 130.851174 -394.059236)
			(xy 130.82785 -394.107668) (xy 130.797569 -394.152082) (xy 130.761007 -394.191487) (xy 130.718979 -394.225003)
			(xy 130.672426 -394.25188) (xy 130.622387 -394.271519) (xy 130.56998 -394.28348) (xy 130.516376 -394.287498)
			(xy 130.462772 -394.28348) (xy 130.410365 -394.271519) (xy 130.360326 -394.25188) (xy 130.313773 -394.225003)
			(xy 130.271745 -394.191487) (xy 130.235183 -394.152082) (xy 130.204902 -394.107668) (xy 130.181578 -394.059236)
			(xy 130.165734 -394.00787) (xy 130.157722 -393.954715) (xy 130.15722 -393.927838) (xy 130.1577 -393.902281)
			(xy 130.164935 -393.851682) (xy 130.179279 -393.802623) (xy 130.200441 -393.756096) (xy 130.227993 -393.713044)
			(xy 130.244342 -393.693396) (xy 130.244596 -393.693142) (xy 130.250263 -393.685823) (xy 130.256371 -393.668362)
			(xy 130.256534 -393.659106) (xy 130.254502 -393.580874) (xy 130.24739 -393.563856) (xy 130.240786 -393.556744)
			(xy 130.221048 -393.535282) (xy 130.187611 -393.487517) (xy 130.161827 -393.435223) (xy 130.144295 -393.379617)
			(xy 130.135423 -393.32199) (xy 130.134868 -393.292838) (xy 129.697988 -393.292838) (xy 129.697988 -393.293346)
			(xy 129.697502 -393.321743) (xy 129.68909 -393.377911) (xy 129.67243 -393.432207) (xy 129.64789 -393.483426)
			(xy 129.616015 -393.530433) (xy 129.59715 -393.551664) (xy 129.591282 -393.558594) (xy 129.584381 -393.575376)
			(xy 129.583688 -393.58443) (xy 129.582672 -393.615418) (xy 129.582732 -393.624569) (xy 129.588597 -393.641889)
			(xy 129.594102 -393.6492) (xy 129.609436 -393.668555) (xy 129.635213 -393.710672) (xy 129.654995 -393.755916)
			(xy 129.668409 -393.803439) (xy 129.675204 -393.852349) (xy 129.675636 -393.877038) (xy 129.675134 -393.903915)
			(xy 129.667122 -393.95707) (xy 129.651278 -394.008436) (xy 129.627954 -394.056868) (xy 129.597673 -394.101282)
			(xy 129.561111 -394.140687) (xy 129.519083 -394.174203) (xy 129.47253 -394.20108) (xy 129.422491 -394.220719)
			(xy 129.370084 -394.23268) (xy 129.31648 -394.236698) (xy 129.262876 -394.23268) (xy 129.210469 -394.220719)
			(xy 129.16043 -394.20108) (xy 129.113877 -394.174203) (xy 129.071849 -394.140687) (xy 129.035287 -394.101282)
			(xy 129.005006 -394.056868) (xy 128.981682 -394.008436) (xy 128.965838 -393.95707) (xy 128.957826 -393.903915)
			(xy 128.957324 -393.877038) (xy 128.95774 -393.852345) (xy 128.964495 -393.803424) (xy 128.977896 -393.755891)
			(xy 128.997691 -393.710646) (xy 129.023504 -393.668543) (xy 129.038858 -393.6492) (xy 129.04434 -393.641881)
			(xy 129.050185 -393.624563) (xy 129.050288 -393.615418) (xy 129.049272 -393.58443) (xy 129.048624 -393.575367)
			(xy 129.041711 -393.558575) (xy 129.03581 -393.551664) (xy 129.016998 -393.530395) (xy 128.985176 -393.48337)
			(xy 128.960659 -393.432157) (xy 128.943986 -393.37788) (xy 128.935523 -393.321735) (xy 128.934972 -393.293346)
			(xy 128.498083 -393.293346) (xy 128.497548 -393.321992) (xy 128.488677 -393.379621) (xy 128.471146 -393.43523)
			(xy 128.445364 -393.487528) (xy 128.41193 -393.535298) (xy 128.392174 -393.556744) (xy 128.386015 -393.563826)
			(xy 128.378858 -393.581162) (xy 128.378204 -393.590526) (xy 128.376426 -393.659106) (xy 128.376564 -393.668363)
			(xy 128.382701 -393.685817) (xy 128.388364 -393.693142) (xy 128.388872 -393.69365) (xy 128.405183 -393.713285)
			(xy 128.432657 -393.756306) (xy 128.453761 -393.802785) (xy 128.46807 -393.851784) (xy 128.475294 -393.902315)
			(xy 128.47574 -393.927838) (xy 128.475238 -393.954715) (xy 128.467226 -394.00787) (xy 128.451382 -394.059236)
			(xy 128.428058 -394.107668) (xy 128.397777 -394.152082) (xy 128.361215 -394.191487) (xy 128.319187 -394.225003)
			(xy 128.272634 -394.25188) (xy 128.222595 -394.271519) (xy 128.170188 -394.28348) (xy 128.116584 -394.287498)
			(xy 128.06298 -394.28348) (xy 128.010573 -394.271519) (xy 127.960534 -394.25188) (xy 127.913981 -394.225003)
			(xy 127.871953 -394.191487) (xy 127.835391 -394.152082) (xy 127.80511 -394.107668) (xy 127.781786 -394.059236)
			(xy 127.765942 -394.00787) (xy 127.75793 -393.954715) (xy 127.757428 -393.927838) (xy 127.757906 -393.902281)
			(xy 127.765141 -393.851682) (xy 127.779486 -393.802623) (xy 127.800648 -393.756096) (xy 127.8282 -393.713044)
			(xy 127.84455 -393.693396) (xy 127.844804 -393.693142) (xy 127.850472 -393.685824) (xy 127.856579 -393.668362)
			(xy 127.856742 -393.659106) (xy 127.85471 -393.580874) (xy 127.847598 -393.563856) (xy 127.840994 -393.556744)
			(xy 127.821258 -393.535281) (xy 127.78782 -393.487516) (xy 127.762035 -393.435223) (xy 127.744503 -393.379616)
			(xy 127.735631 -393.32199) (xy 127.735076 -393.292838) (xy 127.44069 -393.292838) (xy 127.44069 -394.428218)
			(xy 127.440276 -394.438289) (xy 127.432548 -394.456886) (xy 127.425704 -394.464286) (xy 127.139954 -394.750036)
			(xy 127.132495 -394.756792) (xy 127.113936 -394.764515) (xy 127.103886 -394.765022) (xy 120.287034 -394.765022)
			(xy 120.276964 -394.7646) (xy 120.258365 -394.756879) (xy 120.250966 -394.750036) (xy 119.800116 -394.299186)
			(xy 119.791604 -394.291466) (xy 119.769924 -394.283921) (xy 119.75846 -394.284708) (xy 119.757952 -394.284708)
			(xy 119.74764 -394.285868) (xy 119.726926 -394.287138) (xy 119.71655 -394.287248) (xy 119.690878 -394.286799)
			(xy 119.640057 -394.279486) (xy 119.590793 -394.265016) (xy 119.54409 -394.243683) (xy 119.500897 -394.215922)
			(xy 119.462095 -394.182297) (xy 119.428471 -394.143493) (xy 119.400711 -394.1003) (xy 119.37938 -394.053596)
			(xy 119.364912 -394.004332) (xy 119.3576 -393.95351) (xy 119.35714 -393.927838) (xy 119.357619 -393.90227)
			(xy 119.364895 -393.851655) (xy 119.37929 -393.802588) (xy 119.400513 -393.756065) (xy 119.428132 -393.71303)
			(xy 119.444516 -393.693396) (xy 119.44477 -393.693142) (xy 119.450434 -393.685821) (xy 119.456545 -393.668362)
			(xy 119.456708 -393.659106) (xy 119.454676 -393.580874) (xy 119.447564 -393.563856) (xy 119.44096 -393.556744)
			(xy 119.421184 -393.535302) (xy 119.387689 -393.487551) (xy 119.361851 -393.435259) (xy 119.344271 -393.379644)
			(xy 119.335359 -393.322001) (xy 119.334788 -393.292838) (xy 119.334788 -392.429238) (xy 119.335229 -392.403719)
			(xy 119.342018 -392.353134) (xy 119.355493 -392.303906) (xy 119.375413 -392.256916) (xy 119.401423 -392.213002)
			(xy 119.433057 -392.172949) (xy 119.45112 -392.154918) (xy 119.457724 -392.148568) (xy 119.465598 -392.131804)
			(xy 119.472456 -392.04646) (xy 119.467376 -392.02868) (xy 119.461788 -392.021314) (xy 119.446932 -392.00057)
			(xy 119.423299 -391.955354) (xy 119.4072 -391.906942) (xy 119.399048 -391.856578) (xy 119.398542 -391.831068)
			(xy 119.398542 -391.830814) (xy 119.399008 -391.807126) (xy 119.406022 -391.760274) (xy 119.41991 -391.71498)
			(xy 119.440366 -391.672249) (xy 119.466936 -391.633027) (xy 119.499033 -391.598182) (xy 119.535945 -391.568485)
			(xy 119.576855 -391.544595) (xy 119.598694 -391.535412) (xy 119.613172 -391.52957) (xy 119.630698 -391.503916)
			(xy 119.630698 -390.815576) (xy 119.630312 -390.805502) (xy 119.622567 -390.786903) (xy 119.615712 -390.779508)
			(xy 119.400828 -390.564878) (xy 119.393415 -390.558054) (xy 119.374826 -390.550326) (xy 119.36476 -390.549892)
			(xy 119.037608 -390.549892) (xy 119.027586 -390.549474) (xy 119.009068 -390.541805) (xy 118.994895 -390.527632)
			(xy 118.987226 -390.509114) (xy 118.986808 -390.499092) (xy 118.986808 -390.284716) (xy 118.977664 -390.284716)
			(xy 118.967656 -390.284242) (xy 118.949166 -390.276573) (xy 118.935015 -390.262417) (xy 118.927354 -390.243924)
			(xy 118.926864 -390.233916) (xy 118.926864 -390.029446) (xy 118.927439 -390.007372) (xy 118.936553 -389.964173)
			(xy 118.954341 -389.923765) (xy 118.966742 -389.905494) (xy 118.971568 -389.899144) (xy 118.976394 -389.883904)
			(xy 118.976394 -389.854694) (xy 118.97605 -389.843994) (xy 118.967481 -389.824393) (xy 118.959884 -389.816848)
			(xy 118.936516 -389.795766) (xy 118.928976 -389.789607) (xy 118.910692 -389.782955) (xy 118.900956 -389.782812)
			(xy 118.891304 -389.782812) (xy 118.86591 -389.782308) (xy 118.815776 -389.774178) (xy 118.767591 -389.758127)
			(xy 118.722596 -389.734569) (xy 118.681954 -389.704112) (xy 118.646711 -389.667542) (xy 118.617777 -389.625801)
			(xy 118.595899 -389.579966) (xy 118.588282 -389.555736) (xy 118.586758 -389.549894) (xy 118.266464 -388.996174)
			(xy 118.2624 -388.991856) (xy 118.246197 -388.974147) (xy 118.218772 -388.934757) (xy 118.19763 -388.891667)
			(xy 118.183256 -388.845873) (xy 118.175982 -388.79843) (xy 118.175532 -388.774432) (xy 118.17571 -388.760384)
			(xy 118.178254 -388.732402) (xy 118.180612 -388.718552) (xy 118.1819 -388.709296) (xy 118.178503 -388.690932)
			(xy 118.174008 -388.682738) (xy 118.157244 -388.655814) (xy 118.152033 -388.648118) (xy 118.137314 -388.63679)
			(xy 118.128542 -388.633716) (xy 118.106915 -388.626919) (xy 118.065701 -388.608036) (xy 118.027581 -388.5835)
			(xy 117.993325 -388.553806) (xy 117.978174 -388.536942) (xy 117.975706 -388.534175) (xy 117.970097 -388.529325)
			(xy 117.966998 -388.52729) (xy 117.954974 -388.519203) (xy 117.935082 -388.498146) (xy 117.921073 -388.472792)
			(xy 117.913831 -388.444745) (xy 117.913404 -388.430262) (xy 117.913404 -388.418324) (xy 117.911626 -388.41172)
			(xy 117.906419 -388.391351) (xy 117.900819 -388.349683) (xy 117.90045 -388.328662) (xy 117.33657 -388.328662)
			(xy 117.33657 -388.32917) (xy 117.3364 -388.343795) (xy 117.333733 -388.372924) (xy 117.331236 -388.387336)
			(xy 117.329868 -388.39651) (xy 117.333143 -388.414753) (xy 117.337586 -388.422896) (xy 117.354096 -388.44982)
			(xy 117.359247 -388.457613) (xy 117.373986 -388.469067) (xy 117.382798 -388.472172) (xy 117.407717 -388.480322)
			(xy 117.454683 -388.503611) (xy 117.497164 -388.53433) (xy 117.533994 -388.571636) (xy 117.564165 -388.614506)
			(xy 117.58685 -388.661767) (xy 117.594634 -388.686802) (xy 117.596158 -388.692644) (xy 117.915944 -389.245602)
			(xy 117.920008 -389.24992) (xy 117.936201 -389.267637) (xy 117.963627 -389.307026) (xy 117.984771 -389.350113)
			(xy 117.999147 -389.395905) (xy 118.006424 -389.443346) (xy 118.006876 -389.467344) (xy 118.006407 -389.492807)
			(xy 117.998207 -389.54307) (xy 117.982043 -389.591364) (xy 117.958335 -389.636436) (xy 117.927697 -389.677116)
			(xy 117.890925 -389.71235) (xy 117.870224 -389.727186) (xy 117.861705 -389.733646) (xy 117.850503 -389.75183)
			(xy 117.847662 -389.772998) (xy 117.853673 -389.793492) (xy 117.867496 -389.809773) (xy 117.886744 -389.819027)
			(xy 117.897402 -389.819896) (xy 117.907054 -389.819388) (xy 117.915567 -389.81809) (xy 117.932733 -389.816694)
			(xy 117.941344 -389.816594) (xy 117.941598 -389.816848) (xy 118.24081 -389.816848) (xy 118.241064 -389.816594)
			(xy 118.262126 -389.816995) (xy 118.303485 -389.82495) (xy 118.342483 -389.840855) (xy 118.377609 -389.864094)
			(xy 118.407501 -389.893765) (xy 118.430999 -389.928717) (xy 118.447193 -389.967597) (xy 118.455454 -390.008896)
			(xy 118.455948 -390.029954) (xy 118.455948 -390.284716) (xy 118.446804 -390.284716) (xy 118.436781 -390.285123)
			(xy 118.418261 -390.292795) (xy 118.404088 -390.306971) (xy 118.396421 -390.325493) (xy 118.396004 -390.335516)
			(xy 118.396004 -390.499092) (xy 118.395574 -390.509112) (xy 118.387908 -390.527628) (xy 118.373738 -390.541801)
			(xy 118.355224 -390.549472) (xy 118.345204 -390.549892) (xy 117.837204 -390.549892) (xy 117.827182 -390.549477)
			(xy 117.808664 -390.541807) (xy 117.794491 -390.527633) (xy 117.786822 -390.509114) (xy 117.786404 -390.499092)
			(xy 117.786404 -390.284716) (xy 117.77726 -390.284716) (xy 117.767252 -390.284245) (xy 117.748762 -390.276575)
			(xy 117.734611 -390.262418) (xy 117.72695 -390.243924) (xy 117.72646 -390.233916) (xy 117.72646 -390.029954)
			(xy 117.7268 -390.012721) (xy 117.732372 -389.978708) (xy 117.743346 -389.946035) (xy 117.751098 -389.93064)
			(xy 117.75694 -389.91921) (xy 117.756686 -389.89381) (xy 117.703092 -389.796782) (xy 117.681502 -389.783066)
			(xy 117.668548 -389.78205) (xy 117.644653 -389.779913) (xy 117.597867 -389.769315) (xy 117.553226 -389.751751)
			(xy 117.511762 -389.727627) (xy 117.474431 -389.697498) (xy 117.442097 -389.662062) (xy 117.415504 -389.622135)
			(xy 117.395269 -389.57864) (xy 117.388132 -389.555736) (xy 117.386608 -389.549894) (xy 117.06606 -388.995412)
			(xy 117.061996 -388.991094) (xy 117.0459 -388.973418) (xy 117.018649 -388.934141) (xy 116.997636 -388.891203)
			(xy 116.983343 -388.845586) (xy 116.976095 -388.798334) (xy 116.975636 -388.774432) (xy 116.975814 -388.760384)
			(xy 116.978358 -388.732402) (xy 116.980716 -388.718552) (xy 116.982003 -388.709296) (xy 116.978607 -388.690932)
			(xy 116.974112 -388.682738) (xy 116.957348 -388.655814) (xy 116.952135 -388.648119) (xy 116.937417 -388.636791)
			(xy 116.928646 -388.633716) (xy 116.907019 -388.626918) (xy 116.865805 -388.608035) (xy 116.827685 -388.583499)
			(xy 116.793429 -388.553806) (xy 116.778278 -388.536942) (xy 116.775809 -388.534176) (xy 116.770201 -388.529325)
			(xy 116.767102 -388.52729) (xy 116.755079 -388.519202) (xy 116.735187 -388.498146) (xy 116.721177 -388.472792)
			(xy 116.713935 -388.444745) (xy 116.713508 -388.430262) (xy 116.713508 -388.418324) (xy 116.71173 -388.41172)
			(xy 116.706523 -388.391351) (xy 116.700923 -388.349683) (xy 116.700554 -388.328662) (xy 116.13642 -388.328662)
			(xy 116.13642 -388.32917) (xy 116.136249 -388.343795) (xy 116.133582 -388.372924) (xy 116.131086 -388.387336)
			(xy 116.129724 -388.39651) (xy 116.132996 -388.414752) (xy 116.137436 -388.422896) (xy 116.153946 -388.44982)
			(xy 116.159115 -388.457599) (xy 116.173841 -388.469061) (xy 116.182648 -388.472172) (xy 116.207538 -388.480212)
			(xy 116.254416 -388.503407) (xy 116.296827 -388.534016) (xy 116.333609 -388.571201) (xy 116.363754 -388.613943)
			(xy 116.386437 -388.661071) (xy 116.39423 -388.68604) (xy 116.395754 -388.691882) (xy 116.716048 -389.245602)
			(xy 116.720112 -389.24992) (xy 116.736306 -389.267637) (xy 116.763731 -389.307025) (xy 116.784875 -389.350113)
			(xy 116.799252 -389.395905) (xy 116.806528 -389.443346) (xy 116.80698 -389.467344) (xy 116.806509 -389.492807)
			(xy 116.79831 -389.54307) (xy 116.782146 -389.591364) (xy 116.758438 -389.636436) (xy 116.7278 -389.677116)
			(xy 116.691028 -389.712349) (xy 116.670328 -389.727186) (xy 116.661807 -389.733644) (xy 116.650604 -389.751829)
			(xy 116.647763 -389.772998) (xy 116.653773 -389.793493) (xy 116.667598 -389.809774) (xy 116.686848 -389.819028)
			(xy 116.697506 -389.819896) (xy 116.707158 -389.819388) (xy 116.715671 -389.818089) (xy 116.732837 -389.816694)
			(xy 116.741448 -389.816594) (xy 116.741702 -389.816848) (xy 117.040914 -389.816848) (xy 117.041168 -389.816594)
			(xy 117.06223 -389.816991) (xy 117.103589 -389.824947) (xy 117.142588 -389.840853) (xy 117.177714 -389.864092)
			(xy 117.207605 -389.893763) (xy 117.231103 -389.928716) (xy 117.247297 -389.967596) (xy 117.255558 -390.008895)
			(xy 117.256052 -390.029954) (xy 117.256052 -390.284716) (xy 117.246908 -390.284716) (xy 117.236885 -390.285126)
			(xy 117.218365 -390.292797) (xy 117.204192 -390.306972) (xy 117.196525 -390.325493) (xy 117.196108 -390.335516)
			(xy 117.196108 -390.499092) (xy 117.195606 -390.509098) (xy 117.18795 -390.527588) (xy 117.173802 -390.541741)
			(xy 117.155314 -390.549402) (xy 117.145308 -390.549892) (xy 116.637308 -390.549892) (xy 116.627286 -390.549474)
			(xy 116.608768 -390.541805) (xy 116.594595 -390.527632) (xy 116.586926 -390.509114) (xy 116.586508 -390.499092)
			(xy 116.586508 -390.284716) (xy 116.577364 -390.284716) (xy 116.567356 -390.284242) (xy 116.548866 -390.276573)
			(xy 116.534715 -390.262417) (xy 116.527054 -390.243924) (xy 116.526564 -390.233916) (xy 116.526564 -390.029954)
			(xy 116.526915 -390.012722) (xy 116.532484 -389.978709) (xy 116.543453 -389.946036) (xy 116.551202 -389.93064)
			(xy 116.557044 -389.91921) (xy 116.55679 -389.89381) (xy 116.503196 -389.796782) (xy 116.481606 -389.783066)
			(xy 116.468652 -389.78205) (xy 116.444758 -389.779909) (xy 116.397971 -389.769313) (xy 116.35333 -389.751749)
			(xy 116.311866 -389.727625) (xy 116.274536 -389.697497) (xy 116.242201 -389.662061) (xy 116.215609 -389.622134)
			(xy 116.195373 -389.57864) (xy 116.188236 -389.555736) (xy 116.186712 -389.549894) (xy 115.866418 -388.996174)
			(xy 115.862354 -388.991856) (xy 115.846195 -388.974122) (xy 115.818826 -388.93472) (xy 115.797736 -388.89163)
			(xy 115.783408 -388.845845) (xy 115.776174 -388.798419) (xy 115.77574 -388.774432) (xy 115.775922 -388.760384)
			(xy 115.778462 -388.732402) (xy 115.78082 -388.718552) (xy 115.782139 -388.709272) (xy 115.778613 -388.690876)
			(xy 115.773962 -388.682738) (xy 115.757198 -388.655814) (xy 115.752003 -388.648105) (xy 115.737272 -388.636785)
			(xy 115.728496 -388.633716) (xy 115.706876 -388.626898) (xy 115.66566 -388.608022) (xy 115.627539 -388.583492)
			(xy 115.593281 -388.553803) (xy 115.578128 -388.536942) (xy 115.575665 -388.53417) (xy 115.570053 -388.529323)
			(xy 115.566952 -388.52729) (xy 115.554891 -388.519229) (xy 115.534933 -388.498186) (xy 115.520859 -388.472829)
			(xy 115.513557 -388.444762) (xy 115.513104 -388.430262) (xy 115.513104 -388.418324) (xy 115.51158 -388.41172)
			(xy 115.506374 -388.391351) (xy 115.500773 -388.349683) (xy 115.500404 -388.328662) (xy 114.936524 -388.328662)
			(xy 114.936524 -388.32917) (xy 114.936353 -388.343795) (xy 114.933686 -388.372924) (xy 114.93119 -388.387336)
			(xy 114.929828 -388.39651) (xy 114.9331 -388.414752) (xy 114.93754 -388.422896) (xy 114.95405 -388.44982)
			(xy 114.959217 -388.4576) (xy 114.973945 -388.469061) (xy 114.982752 -388.472172) (xy 115.007642 -388.48021)
			(xy 115.054521 -388.503406) (xy 115.096931 -388.534015) (xy 115.133713 -388.5712) (xy 115.163858 -388.613943)
			(xy 115.186541 -388.661071) (xy 115.194334 -388.68604) (xy 115.195858 -388.691882) (xy 115.516152 -389.245602)
			(xy 115.520216 -389.24992) (xy 115.53641 -389.267636) (xy 115.563835 -389.307025) (xy 115.58498 -389.350113)
			(xy 115.599356 -389.395905) (xy 115.606632 -389.443346) (xy 115.607084 -389.467344) (xy 115.606612 -389.492807)
			(xy 115.598412 -389.54307) (xy 115.582248 -389.591363) (xy 115.558541 -389.636435) (xy 115.527903 -389.677116)
			(xy 115.491132 -389.712349) (xy 115.470432 -389.727186) (xy 115.461918 -389.733621) (xy 115.450719 -389.751764)
			(xy 115.447847 -389.772891) (xy 115.453796 -389.793366) (xy 115.467542 -389.809664) (xy 115.486721 -389.81898)
			(xy 115.497356 -389.819896) (xy 115.507262 -389.819388) (xy 115.515712 -389.818097) (xy 115.53275 -389.816701)
			(xy 115.541298 -389.816594) (xy 115.541552 -389.816848) (xy 115.840764 -389.816848) (xy 115.841018 -389.816594)
			(xy 115.862064 -389.817017) (xy 115.903383 -389.825009) (xy 115.942338 -389.840937) (xy 115.97742 -389.864184)
			(xy 116.007272 -389.89385) (xy 116.030737 -389.928787) (xy 116.046907 -389.967642) (xy 116.055156 -390.008911)
			(xy 116.055648 -390.029954) (xy 116.055648 -390.284716) (xy 116.046504 -390.284716) (xy 116.036481 -390.285123)
			(xy 116.017961 -390.292795) (xy 116.003788 -390.306971) (xy 115.996121 -390.325493) (xy 115.995704 -390.335516)
			(xy 115.995704 -390.499092) (xy 115.995274 -390.509112) (xy 115.987608 -390.527628) (xy 115.973438 -390.541801)
			(xy 115.954924 -390.549472) (xy 115.944904 -390.549892) (xy 115.437412 -390.549892) (xy 115.42739 -390.549471)
			(xy 115.408872 -390.541803) (xy 115.394699 -390.527631) (xy 115.38703 -390.509114) (xy 115.386612 -390.499092)
			(xy 115.386612 -390.335516) (xy 115.386168 -390.325497) (xy 115.378505 -390.306983) (xy 115.364341 -390.29281)
			(xy 115.345831 -390.285138) (xy 115.335812 -390.284716) (xy 115.326668 -390.284716) (xy 115.326668 -390.029446)
			(xy 115.327447 -390.003723) (xy 115.339783 -389.953777) (xy 115.351052 -389.93064) (xy 115.356894 -389.91921)
			(xy 115.35664 -389.89381) (xy 115.309142 -389.808212) (xy 115.302433 -389.797423) (xy 115.2811 -389.78369)
			(xy 115.268502 -389.78205) (xy 115.244627 -389.779882) (xy 115.197882 -389.769249) (xy 115.153286 -389.751664)
			(xy 115.111864 -389.727532) (xy 115.074573 -389.697409) (xy 115.04227 -389.661988) (xy 115.0157 -389.622086)
			(xy 114.995476 -389.578623) (xy 114.98834 -389.555736) (xy 114.986816 -389.549894) (xy 114.666522 -388.996174)
			(xy 114.662458 -388.991856) (xy 114.646299 -388.974121) (xy 114.618931 -388.93472) (xy 114.59784 -388.89163)
			(xy 114.583512 -388.845845) (xy 114.576278 -388.798419) (xy 114.575844 -388.774432) (xy 114.576026 -388.760384)
			(xy 114.578566 -388.732402) (xy 114.580924 -388.718552) (xy 114.582243 -388.709272) (xy 114.578717 -388.690876)
			(xy 114.574066 -388.682738) (xy 114.557302 -388.655814) (xy 114.552105 -388.648106) (xy 114.537376 -388.636785)
			(xy 114.5286 -388.633716) (xy 114.50698 -388.626896) (xy 114.465765 -388.608021) (xy 114.427643 -388.583491)
			(xy 114.393385 -388.553803) (xy 114.378232 -388.536942) (xy 114.375769 -388.53417) (xy 114.370157 -388.529323)
			(xy 114.367056 -388.52729) (xy 114.354995 -388.519228) (xy 114.335038 -388.498186) (xy 114.320963 -388.472829)
			(xy 114.313661 -388.444762) (xy 114.313208 -388.430262) (xy 114.313208 -388.418324) (xy 114.311684 -388.41172)
			(xy 114.306478 -388.391351) (xy 114.300877 -388.349683) (xy 114.300508 -388.328662) (xy 112.534192 -388.328662)
			(xy 112.534192 -388.487412) (xy 112.533676 -388.504108) (xy 112.525041 -388.536363) (xy 112.508361 -388.565291)
			(xy 112.484771 -388.588923) (xy 112.455873 -388.605654) (xy 112.423633 -388.614346) (xy 112.406938 -388.61492)
			(xy 112.293654 -388.61492) (xy 112.287558 -388.616444) (xy 112.267272 -388.621334) (xy 112.225872 -388.626557)
			(xy 112.205008 -388.626858) (xy 112.184144 -388.626554) (xy 112.142744 -388.621329) (xy 112.122458 -388.616444)
			(xy 112.116362 -388.61492) (xy 112.102138 -388.61492) (xy 112.085759 -388.614482) (xy 112.054075 -388.606159)
			(xy 112.02555 -388.590052) (xy 112.00206 -388.567219) (xy 111.993172 -388.553452) (xy 111.991205 -388.550242)
			(xy 111.986488 -388.544377) (xy 111.983774 -388.541768) (xy 111.963574 -388.522793) (xy 111.929147 -388.479367)
			(xy 111.902432 -388.430815) (xy 111.884177 -388.378491) (xy 111.87489 -388.323858) (xy 111.8743 -388.29615)
			(xy 111.672342 -388.29615) (xy 111.67237 -388.297674) (xy 111.671861 -388.32556) (xy 111.663741 -388.380736)
			(xy 111.647673 -388.434143) (xy 111.624001 -388.48464) (xy 111.593228 -388.531153) (xy 111.556011 -388.57269)
			(xy 111.513143 -388.608365) (xy 111.465537 -388.637419) (xy 111.414208 -388.659231) (xy 111.360251 -388.673337)
			(xy 111.304814 -388.679437) (xy 111.24908 -388.6774) (xy 111.194237 -388.66727) (xy 111.141453 -388.649263)
			(xy 111.091853 -388.623762) (xy 111.046495 -388.591311) (xy 111.006346 -388.552602) (xy 110.97226 -388.508459)
			(xy 110.944964 -388.459824) (xy 110.925041 -388.407733) (xy 110.912915 -388.353296) (xy 110.908844 -388.297674)
			(xy 109.833918 -388.297674) (xy 109.833918 -389.310368) (xy 111.286272 -389.310368) (xy 111.286272 -389.250432)
			(xy 111.294095 -389.19101) (xy 111.309608 -389.133117) (xy 111.332544 -389.077744) (xy 111.362511 -389.025838)
			(xy 111.398998 -388.978288) (xy 111.441378 -388.935908) (xy 111.488928 -388.899421) (xy 111.540834 -388.869454)
			(xy 111.596207 -388.846518) (xy 111.6541 -388.831005) (xy 111.713522 -388.823182) (xy 111.773458 -388.823182)
			(xy 111.83288 -388.831005) (xy 111.890773 -388.846518) (xy 111.946146 -388.869454) (xy 111.998052 -388.899421)
			(xy 112.045602 -388.935908) (xy 112.087982 -388.978288) (xy 112.124469 -389.025838) (xy 112.154436 -389.077744)
			(xy 112.177372 -389.133117) (xy 112.192885 -389.19101) (xy 112.200708 -389.250432) (xy 112.201198 -389.2804)
			(xy 112.200708 -389.310368) (xy 112.192885 -389.36979) (xy 112.177372 -389.427683) (xy 112.154436 -389.483056)
			(xy 112.124469 -389.534962) (xy 112.087982 -389.582512) (xy 112.045602 -389.624892) (xy 111.998052 -389.661379)
			(xy 111.946146 -389.691346) (xy 111.890773 -389.714282) (xy 111.83288 -389.729795) (xy 111.773458 -389.737618)
			(xy 111.713522 -389.737618) (xy 111.6541 -389.729795) (xy 111.596207 -389.714282) (xy 111.540834 -389.691346)
			(xy 111.488928 -389.661379) (xy 111.441378 -389.624892) (xy 111.398998 -389.582512) (xy 111.362511 -389.534962)
			(xy 111.332544 -389.483056) (xy 111.309608 -389.427683) (xy 111.294095 -389.36979) (xy 111.286272 -389.310368)
			(xy 109.833918 -389.310368) (xy 109.833918 -390.626092) (xy 111.862616 -390.626092) (xy 111.863023 -390.602859)
			(xy 111.869518 -390.556848) (xy 111.882391 -390.5122) (xy 111.901391 -390.469795) (xy 111.926142 -390.430469)
			(xy 111.940848 -390.412478) (xy 111.94669 -390.40562) (xy 111.95304 -390.388602) (xy 111.95304 -390.304782)
			(xy 111.94669 -390.287764) (xy 111.940848 -390.280906) (xy 111.926135 -390.26292) (xy 111.901388 -390.22359)
			(xy 111.882389 -390.181184) (xy 111.869511 -390.136537) (xy 111.863009 -390.090526) (xy 111.862616 -390.067292)
			(xy 111.863126 -390.041305) (xy 111.871256 -389.98997) (xy 111.887317 -389.94054) (xy 111.910913 -389.89423)
			(xy 111.941463 -389.852182) (xy 111.978214 -389.815431) (xy 112.020262 -389.784881) (xy 112.066572 -389.761285)
			(xy 112.116002 -389.745224) (xy 112.167337 -389.737094) (xy 112.219311 -389.737094) (xy 112.270646 -389.745224)
			(xy 112.320076 -389.761285) (xy 112.366386 -389.784881) (xy 112.408434 -389.815431) (xy 112.445185 -389.852182)
			(xy 112.475735 -389.89423) (xy 112.499331 -389.94054) (xy 112.515392 -389.98997) (xy 112.523522 -390.041305)
			(xy 112.524032 -390.067292) (xy 112.523663 -390.090527) (xy 112.517157 -390.136539) (xy 112.504274 -390.181186)
			(xy 112.485267 -390.223591) (xy 112.478767 -390.233916) (xy 114.126264 -390.233916) (xy 114.126264 -390.029954)
			(xy 114.126773 -390.008892) (xy 114.135019 -389.967583) (xy 114.151202 -389.928692) (xy 114.174695 -389.893727)
			(xy 114.204585 -389.864045) (xy 114.239714 -389.840798) (xy 114.278717 -389.824888) (xy 114.320083 -389.816931)
			(xy 114.341148 -389.816594) (xy 114.341402 -389.816848) (xy 114.640614 -389.816848) (xy 114.640868 -389.816594)
			(xy 114.66193 -389.816991) (xy 114.703289 -389.824947) (xy 114.742288 -389.840853) (xy 114.777414 -389.864092)
			(xy 114.807305 -389.893763) (xy 114.830803 -389.928716) (xy 114.846997 -389.967596) (xy 114.855258 -390.008895)
			(xy 114.855752 -390.029954) (xy 114.855752 -390.284716) (xy 114.846608 -390.284716) (xy 114.836585 -390.285126)
			(xy 114.818065 -390.292797) (xy 114.803892 -390.306972) (xy 114.796225 -390.325493) (xy 114.795808 -390.335516)
			(xy 114.795808 -390.499092) (xy 114.795306 -390.509098) (xy 114.78765 -390.527588) (xy 114.773502 -390.541741)
			(xy 114.755014 -390.549402) (xy 114.745008 -390.549892) (xy 114.237008 -390.549892) (xy 114.226986 -390.549474)
			(xy 114.208468 -390.541805) (xy 114.194295 -390.527632) (xy 114.186626 -390.509114) (xy 114.186208 -390.499092)
			(xy 114.186208 -390.284716) (xy 114.177064 -390.284716) (xy 114.167056 -390.284242) (xy 114.148566 -390.276573)
			(xy 114.134415 -390.262417) (xy 114.126754 -390.243924) (xy 114.126264 -390.233916) (xy 112.478767 -390.233916)
			(xy 112.460509 -390.262916) (xy 112.4458 -390.280906) (xy 112.439958 -390.287764) (xy 112.433608 -390.304782)
			(xy 112.433608 -390.388602) (xy 112.439958 -390.40562) (xy 112.4458 -390.412478) (xy 112.460513 -390.430464)
			(xy 112.485258 -390.469794) (xy 112.504257 -390.512201) (xy 112.517135 -390.556848) (xy 112.523638 -390.602858)
			(xy 112.524032 -390.626092) (xy 112.524032 -390.626346) (xy 112.5236 -390.650396) (xy 112.51661 -390.697986)
			(xy 112.502812 -390.744065) (xy 112.493044 -390.766046) (xy 112.48771 -390.777476) (xy 112.48898 -390.802622)
			(xy 112.538764 -390.88568) (xy 112.545716 -390.896031) (xy 112.567011 -390.908948) (xy 112.579404 -390.910318)
			(xy 112.604403 -390.912126) (xy 112.653449 -390.922464) (xy 112.700373 -390.940083) (xy 112.744101 -390.964581)
			(xy 112.783633 -390.995396) (xy 112.818063 -391.031822) (xy 112.846603 -391.073026) (xy 112.8686 -391.118065)
			(xy 112.883549 -391.165907) (xy 112.891108 -391.215456) (xy 112.89157 -391.240518) (xy 112.89106 -391.266505)
			(xy 112.88293 -391.31784) (xy 112.866869 -391.36727) (xy 112.843273 -391.41358) (xy 112.812723 -391.455628)
			(xy 112.775972 -391.492379) (xy 112.733924 -391.522929) (xy 112.687614 -391.546525) (xy 112.638184 -391.562586)
			(xy 112.586849 -391.570716) (xy 112.534875 -391.570716) (xy 112.48354 -391.562586) (xy 112.43411 -391.546525)
			(xy 112.3878 -391.522929) (xy 112.345752 -391.492379) (xy 112.309001 -391.455628) (xy 112.278451 -391.41358)
			(xy 112.254855 -391.36727) (xy 112.238794 -391.31784) (xy 112.230664 -391.266505) (xy 112.230154 -391.240518)
			(xy 112.230154 -391.240264) (xy 112.230591 -391.216214) (xy 112.237579 -391.168625) (xy 112.251375 -391.122546)
			(xy 112.261142 -391.100564) (xy 112.266476 -391.089134) (xy 112.265206 -391.063988) (xy 112.215422 -390.98093)
			(xy 112.208474 -390.970575) (xy 112.187176 -390.95766) (xy 112.174782 -390.956292) (xy 112.14979 -390.9544)
			(xy 112.100747 -390.944075) (xy 112.053825 -390.926467) (xy 112.010096 -390.901981) (xy 111.970563 -390.871176)
			(xy 111.936132 -390.834758) (xy 111.90759 -390.793562) (xy 111.885591 -390.74853) (xy 111.87064 -390.700695)
			(xy 111.863078 -390.651151) (xy 111.862616 -390.626092) (xy 109.833918 -390.626092) (xy 109.833918 -391.146284)
			(xy 109.83348 -391.156348) (xy 109.825746 -391.174932) (xy 109.818932 -391.182352) (xy 109.617764 -391.38352)
			(xy 109.610367 -391.39037) (xy 109.591768 -391.398104) (xy 109.581696 -391.398506) (xy 109.137704 -391.398506)
			(xy 109.127634 -391.398929) (xy 109.109029 -391.406643) (xy 109.101636 -391.413492) (xy 109.096302 -391.418826)
			(xy 109.07776 -391.4267) (xy 108.37291 -391.4267) (xy 108.362881 -391.427145) (xy 108.344315 -391.434729)
			(xy 108.336842 -391.441432) (xy 108.260642 -391.517632) (xy 108.253796 -391.52503) (xy 108.246067 -391.543629)
			(xy 108.245656 -391.5537) (xy 108.245656 -391.870946) (xy 113.222532 -391.870946) (xy 113.222532 -391.616184)
			(xy 113.231676 -391.616184) (xy 113.241698 -391.61576) (xy 113.260217 -391.608095) (xy 113.274391 -391.593924)
			(xy 113.282059 -391.575406) (xy 113.282476 -391.565384) (xy 113.282476 -391.401808) (xy 113.282994 -391.391804)
			(xy 113.290646 -391.373317) (xy 113.30479 -391.359164) (xy 113.323272 -391.3515) (xy 113.333276 -391.351008)
			(xy 113.841276 -391.351008) (xy 113.851297 -391.35144) (xy 113.869815 -391.359103) (xy 113.883988 -391.373272)
			(xy 113.891657 -391.391787) (xy 113.892076 -391.401808) (xy 113.892076 -391.616184) (xy 113.90122 -391.616184)
			(xy 113.911227 -391.616671) (xy 113.929716 -391.624334) (xy 113.943868 -391.638487) (xy 113.95153 -391.656977)
			(xy 113.95202 -391.666984) (xy 113.95202 -391.870946) (xy 113.951469 -391.893554) (xy 113.941944 -391.937756)
			(xy 113.923332 -391.978964) (xy 113.896465 -392.015333) (xy 113.879884 -392.030712) (xy 113.873026 -392.036808)
			(xy 113.86439 -392.05281) (xy 113.85423 -392.12774) (xy 113.853355 -392.136623) (xy 113.857116 -392.154057)
			(xy 113.861596 -392.161776) (xy 113.86185 -392.161776) (xy 113.86185 -392.162284) (xy 113.873901 -392.181648)
			(xy 113.892968 -392.223081) (xy 113.905918 -392.266812) (xy 113.912486 -392.311946) (xy 113.912904 -392.33475)
			(xy 113.912414 -392.359739) (xy 113.904595 -392.409102) (xy 113.889151 -392.456634) (xy 113.866461 -392.501166)
			(xy 113.837085 -392.541599) (xy 113.801745 -392.576939) (xy 113.761312 -392.606315) (xy 113.71678 -392.629005)
			(xy 113.669248 -392.644449) (xy 113.619885 -392.652268) (xy 113.569907 -392.652268) (xy 113.520544 -392.644449)
			(xy 113.473012 -392.629005) (xy 113.42848 -392.606315) (xy 113.388047 -392.576939) (xy 113.352707 -392.541599)
			(xy 113.323331 -392.501166) (xy 113.300641 -392.456634) (xy 113.285197 -392.409102) (xy 113.277378 -392.359739)
			(xy 113.276888 -392.33475) (xy 113.277569 -392.305549) (xy 113.288218 -392.248127) (xy 113.309167 -392.193613)
			(xy 113.323878 -392.16838) (xy 113.328345 -392.160382) (xy 113.331865 -392.142419) (xy 113.330736 -392.133328)
			(xy 113.317782 -392.05789) (xy 113.308892 -392.042396) (xy 113.30178 -392.036554) (xy 113.301272 -392.036046)
			(xy 113.286846 -392.023803) (xy 113.262177 -391.99512) (xy 113.242941 -391.962542) (xy 113.22974 -391.927087)
			(xy 113.222986 -391.889861) (xy 113.222532 -391.870946) (xy 108.245656 -391.870946) (xy 108.245656 -392.275568)
			(xy 110.803436 -392.275568) (xy 110.803922 -392.248317) (xy 110.811678 -392.194369) (xy 110.827033 -392.142074)
			(xy 110.849675 -392.092497) (xy 110.879141 -392.046647) (xy 110.914832 -392.005456) (xy 110.956023 -391.969765)
			(xy 111.001873 -391.940299) (xy 111.05145 -391.917657) (xy 111.103745 -391.902302) (xy 111.157693 -391.894546)
			(xy 111.212195 -391.894546) (xy 111.266143 -391.902302) (xy 111.318438 -391.917657) (xy 111.368015 -391.940299)
			(xy 111.413865 -391.969765) (xy 111.455056 -392.005456) (xy 111.490747 -392.046647) (xy 111.520213 -392.092497)
			(xy 111.542855 -392.142074) (xy 111.55821 -392.194369) (xy 111.565966 -392.248317) (xy 111.566452 -392.275568)
			(xy 111.566452 -392.276076) (xy 111.565904 -392.304504) (xy 111.557418 -392.360725) (xy 111.540689 -392.415066)
			(xy 111.52886 -392.440922) (xy 111.524288 -392.450574) (xy 111.523272 -392.471402) (xy 111.557562 -392.560048)
			(xy 111.572294 -392.575034) (xy 111.581946 -392.578844) (xy 111.607905 -392.589973) (xy 111.656485 -392.618781)
			(xy 111.700289 -392.654433) (xy 111.73836 -392.696153) (xy 111.769867 -392.743027) (xy 111.794121 -392.794033)
			(xy 111.810593 -392.848057) (xy 111.818923 -392.903918) (xy 111.819436 -392.932158) (xy 111.81895 -392.959409)
			(xy 111.811194 -393.013357) (xy 111.795839 -393.065652) (xy 111.773197 -393.115229) (xy 111.743731 -393.161079)
			(xy 111.70804 -393.20227) (xy 111.666849 -393.237961) (xy 111.620999 -393.267427) (xy 111.571422 -393.290069)
			(xy 111.561992 -393.292838) (xy 114.534696 -393.292838) (xy 114.534696 -392.429238) (xy 114.535135 -392.403718)
			(xy 114.541924 -392.353133) (xy 114.555399 -392.303906) (xy 114.57532 -392.256915) (xy 114.60133 -392.213001)
			(xy 114.632965 -392.172949) (xy 114.651028 -392.154918) (xy 114.657632 -392.148568) (xy 114.665506 -392.131804)
			(xy 114.672364 -392.04646) (xy 114.667284 -392.02868) (xy 114.661696 -392.021314) (xy 114.646841 -392.000569)
			(xy 114.623208 -391.955354) (xy 114.607108 -391.906941) (xy 114.598956 -391.856578) (xy 114.59845 -391.831068)
			(xy 114.59845 -391.830814) (xy 114.59894 -391.805825) (xy 114.606759 -391.756462) (xy 114.622203 -391.70893)
			(xy 114.644893 -391.664398) (xy 114.674269 -391.623965) (xy 114.709609 -391.588625) (xy 114.750042 -391.559249)
			(xy 114.794574 -391.536559) (xy 114.842106 -391.521115) (xy 114.891469 -391.513296) (xy 114.941447 -391.513296)
			(xy 114.99081 -391.521115) (xy 115.038342 -391.536559) (xy 115.082874 -391.559249) (xy 115.123307 -391.588625)
			(xy 115.158647 -391.623965) (xy 115.188023 -391.664398) (xy 115.210713 -391.70893) (xy 115.226157 -391.756462)
			(xy 115.233976 -391.805825) (xy 115.234466 -391.830814) (xy 115.234466 -391.831068) (xy 115.23396 -391.856576)
			(xy 115.225785 -391.906935) (xy 115.209686 -391.955346) (xy 115.186076 -392.000571) (xy 115.17122 -392.021314)
			(xy 115.165632 -392.02868) (xy 115.160552 -392.04646) (xy 115.16741 -392.131804) (xy 115.175284 -392.148568)
			(xy 115.181888 -392.154918) (xy 115.199928 -392.172971) (xy 115.231557 -392.213024) (xy 115.257567 -392.256935)
			(xy 115.277493 -392.30392) (xy 115.290981 -392.353141) (xy 115.29779 -392.40372) (xy 115.29822 -392.429238)
			(xy 115.29822 -393.292838) (xy 115.734592 -393.292838) (xy 115.734592 -392.429238) (xy 115.735032 -392.403719)
			(xy 115.741821 -392.353133) (xy 115.755296 -392.303906) (xy 115.775216 -392.256915) (xy 115.801226 -392.213002)
			(xy 115.832861 -392.172949) (xy 115.850924 -392.154918) (xy 115.857782 -392.148568) (xy 115.865656 -392.131804)
			(xy 115.871752 -392.05535) (xy 115.872107 -392.046285) (xy 115.867161 -392.028843) (xy 115.8621 -392.021314)
			(xy 115.861846 -392.02106) (xy 115.846979 -392.000324) (xy 115.823356 -391.955102) (xy 115.807261 -391.906688)
			(xy 115.799108 -391.856324) (xy 115.7986 -391.830814) (xy 115.79909 -391.805825) (xy 115.806909 -391.756462)
			(xy 115.822353 -391.70893) (xy 115.845043 -391.664398) (xy 115.874419 -391.623965) (xy 115.909759 -391.588625)
			(xy 115.950192 -391.559249) (xy 115.994724 -391.536559) (xy 116.042256 -391.521115) (xy 116.091619 -391.513296)
			(xy 116.141597 -391.513296) (xy 116.19096 -391.521115) (xy 116.238492 -391.536559) (xy 116.283024 -391.559249)
			(xy 116.323457 -391.588625) (xy 116.358797 -391.623965) (xy 116.388173 -391.664398) (xy 116.410863 -391.70893)
			(xy 116.426307 -391.756462) (xy 116.434126 -391.805825) (xy 116.434616 -391.830814) (xy 116.434108 -391.856367)
			(xy 116.42592 -391.906813) (xy 116.409758 -391.955296) (xy 116.386039 -392.000565) (xy 116.371116 -392.021314)
			(xy 116.365528 -392.02868) (xy 116.360448 -392.04646) (xy 116.366544 -392.122914) (xy 116.367634 -392.131914)
			(xy 116.37531 -392.148322) (xy 116.38153 -392.154918) (xy 116.381784 -392.155172) (xy 116.399829 -392.173193)
			(xy 116.431445 -392.213206) (xy 116.457447 -392.257076) (xy 116.477372 -392.30402) (xy 116.490863 -392.3532)
			(xy 116.49768 -392.40374) (xy 116.498116 -392.429238) (xy 116.498116 -393.292838) (xy 116.934996 -393.292838)
			(xy 116.934996 -392.42873) (xy 116.935437 -392.403262) (xy 116.942239 -392.352783) (xy 116.9557 -392.303658)
			(xy 116.97558 -392.256762) (xy 117.001525 -392.212929) (xy 117.033073 -392.172939) (xy 117.051074 -392.154918)
			(xy 117.057678 -392.148568) (xy 117.065552 -392.131804) (xy 117.07241 -392.04646) (xy 117.06733 -392.02868)
			(xy 117.061742 -392.021314) (xy 117.046893 -392.000565) (xy 117.023257 -391.955352) (xy 117.007155 -391.90694)
			(xy 116.999002 -391.856577) (xy 116.998496 -391.831068) (xy 116.998496 -391.830814) (xy 116.998986 -391.805825)
			(xy 117.006805 -391.756462) (xy 117.022249 -391.70893) (xy 117.044939 -391.664398) (xy 117.074315 -391.623965)
			(xy 117.109655 -391.588625) (xy 117.150088 -391.559249) (xy 117.19462 -391.536559) (xy 117.242152 -391.521115)
			(xy 117.291515 -391.513296) (xy 117.341493 -391.513296) (xy 117.390856 -391.521115) (xy 117.438388 -391.536559)
			(xy 117.48292 -391.559249) (xy 117.523353 -391.588625) (xy 117.558693 -391.623965) (xy 117.588069 -391.664398)
			(xy 117.610759 -391.70893) (xy 117.626203 -391.756462) (xy 117.634022 -391.805825) (xy 117.634512 -391.830814)
			(xy 117.634512 -391.831068) (xy 117.634017 -391.856577) (xy 117.62584 -391.906936) (xy 117.609738 -391.955347)
			(xy 117.586124 -392.000572) (xy 117.571266 -392.021314) (xy 117.565678 -392.02868) (xy 117.560598 -392.04646)
			(xy 117.567456 -392.131804) (xy 117.57533 -392.148568) (xy 117.581934 -392.154918) (xy 117.59993 -392.172944)
			(xy 117.631472 -392.212936) (xy 117.657414 -392.256769) (xy 117.677294 -392.303664) (xy 117.69076 -392.352786)
			(xy 117.697571 -392.403263) (xy 117.698012 -392.42873) (xy 117.698012 -393.292838) (xy 117.698002 -393.293346)
			(xy 118.134892 -393.293346) (xy 118.134892 -392.42873) (xy 118.135334 -392.403262) (xy 118.142137 -392.352783)
			(xy 118.155597 -392.303658) (xy 118.175477 -392.256762) (xy 118.201421 -392.212929) (xy 118.232969 -392.172939)
			(xy 118.25097 -392.154918) (xy 118.257574 -392.148568) (xy 118.265448 -392.131804) (xy 118.272306 -392.04646)
			(xy 118.267226 -392.02868) (xy 118.261638 -392.021314) (xy 118.246788 -392.000565) (xy 118.223153 -391.955352)
			(xy 118.207051 -391.906941) (xy 118.198898 -391.856577) (xy 118.198392 -391.831068) (xy 118.198392 -391.830814)
			(xy 118.198882 -391.805825) (xy 118.206701 -391.756462) (xy 118.222145 -391.70893) (xy 118.244835 -391.664398)
			(xy 118.274211 -391.623965) (xy 118.309551 -391.588625) (xy 118.349984 -391.559249) (xy 118.394516 -391.536559)
			(xy 118.442048 -391.521115) (xy 118.491411 -391.513296) (xy 118.541389 -391.513296) (xy 118.590752 -391.521115)
			(xy 118.638284 -391.536559) (xy 118.682816 -391.559249) (xy 118.723249 -391.588625) (xy 118.758589 -391.623965)
			(xy 118.787965 -391.664398) (xy 118.810655 -391.70893) (xy 118.826099 -391.756462) (xy 118.833918 -391.805825)
			(xy 118.834408 -391.830814) (xy 118.834408 -391.831068) (xy 118.833913 -391.856577) (xy 118.825736 -391.906936)
			(xy 118.809635 -391.955348) (xy 118.78602 -392.000572) (xy 118.771162 -392.021314) (xy 118.765574 -392.02868)
			(xy 118.760494 -392.04646) (xy 118.767352 -392.131804) (xy 118.775226 -392.148568) (xy 118.78183 -392.154918)
			(xy 118.799825 -392.172944) (xy 118.831367 -392.212937) (xy 118.85731 -392.25677) (xy 118.87719 -392.303664)
			(xy 118.890656 -392.352786) (xy 118.897467 -392.403263) (xy 118.897908 -392.42873) (xy 118.897908 -393.293346)
			(xy 118.897417 -393.321743) (xy 118.889006 -393.377911) (xy 118.872346 -393.432206) (xy 118.847807 -393.483425)
			(xy 118.815934 -393.530432) (xy 118.79707 -393.551664) (xy 118.791204 -393.558596) (xy 118.784301 -393.575377)
			(xy 118.783608 -393.58443) (xy 118.782592 -393.615418) (xy 118.782648 -393.624569) (xy 118.788515 -393.64189)
			(xy 118.794022 -393.6492) (xy 118.809359 -393.668553) (xy 118.835135 -393.710671) (xy 118.854916 -393.755916)
			(xy 118.868329 -393.803439) (xy 118.875124 -393.852349) (xy 118.875556 -393.877038) (xy 118.875054 -393.903915)
			(xy 118.867042 -393.95707) (xy 118.851198 -394.008436) (xy 118.827874 -394.056868) (xy 118.797593 -394.101282)
			(xy 118.761031 -394.140687) (xy 118.719003 -394.174203) (xy 118.67245 -394.20108) (xy 118.622411 -394.220719)
			(xy 118.570004 -394.23268) (xy 118.5164 -394.236698) (xy 118.462796 -394.23268) (xy 118.410389 -394.220719)
			(xy 118.36035 -394.20108) (xy 118.313797 -394.174203) (xy 118.271769 -394.140687) (xy 118.235207 -394.101282)
			(xy 118.204926 -394.056868) (xy 118.181602 -394.008436) (xy 118.165758 -393.95707) (xy 118.157746 -393.903915)
			(xy 118.157244 -393.877038) (xy 118.157655 -393.852345) (xy 118.164411 -393.803423) (xy 118.177813 -393.75589)
			(xy 118.197609 -393.710645) (xy 118.223423 -393.668543) (xy 118.238778 -393.6492) (xy 118.244263 -393.641882)
			(xy 118.250106 -393.624564) (xy 118.250208 -393.615418) (xy 118.249192 -393.58443) (xy 118.248539 -393.575368)
			(xy 118.241629 -393.558576) (xy 118.23573 -393.551664) (xy 118.216921 -393.530392) (xy 118.185098 -393.483369)
			(xy 118.16058 -393.432156) (xy 118.143906 -393.37788) (xy 118.135443 -393.321735) (xy 118.134892 -393.293346)
			(xy 117.698002 -393.293346) (xy 117.697463 -393.321991) (xy 117.688592 -393.37962) (xy 117.671062 -393.435229)
			(xy 117.645282 -393.487527) (xy 117.611849 -393.535297) (xy 117.592094 -393.556744) (xy 117.585938 -393.563828)
			(xy 117.578779 -393.581162) (xy 117.578124 -393.590526) (xy 117.576346 -393.659106) (xy 117.57648 -393.668363)
			(xy 117.582619 -393.685817) (xy 117.588284 -393.693142) (xy 117.588792 -393.69365) (xy 117.605106 -393.713283)
			(xy 117.632579 -393.756305) (xy 117.653682 -393.802784) (xy 117.66799 -393.851783) (xy 117.675214 -393.902315)
			(xy 117.67566 -393.927838) (xy 117.675158 -393.954715) (xy 117.667146 -394.00787) (xy 117.651302 -394.059236)
			(xy 117.627978 -394.107668) (xy 117.597697 -394.152082) (xy 117.561135 -394.191487) (xy 117.519107 -394.225003)
			(xy 117.472554 -394.25188) (xy 117.422515 -394.271519) (xy 117.370108 -394.28348) (xy 117.316504 -394.287498)
			(xy 117.2629 -394.28348) (xy 117.210493 -394.271519) (xy 117.160454 -394.25188) (xy 117.113901 -394.225003)
			(xy 117.071873 -394.191487) (xy 117.035311 -394.152082) (xy 117.00503 -394.107668) (xy 116.981706 -394.059236)
			(xy 116.965862 -394.00787) (xy 116.95785 -393.954715) (xy 116.957348 -393.927838) (xy 116.957821 -393.902281)
			(xy 116.965057 -393.851682) (xy 116.979402 -393.802622) (xy 117.000566 -393.756095) (xy 117.02812 -393.713044)
			(xy 117.04447 -393.693396) (xy 117.044724 -393.693142) (xy 117.050394 -393.685825) (xy 117.0565 -393.668363)
			(xy 117.056662 -393.659106) (xy 117.05463 -393.580874) (xy 117.047518 -393.563856) (xy 117.040914 -393.556744)
			(xy 117.021181 -393.535278) (xy 116.987742 -393.487515) (xy 116.961957 -393.435222) (xy 116.944423 -393.379616)
			(xy 116.935551 -393.32199) (xy 116.934996 -393.292838) (xy 116.498116 -393.292838) (xy 116.497608 -393.320712)
			(xy 116.489501 -393.375868) (xy 116.473451 -393.429257) (xy 116.449799 -393.47974) (xy 116.419051 -393.526242)
			(xy 116.400834 -393.547346) (xy 116.394992 -393.55395) (xy 116.388134 -393.570714) (xy 116.386102 -393.645136)
			(xy 116.386219 -393.654041) (xy 116.391813 -393.670934) (xy 116.397024 -393.678156) (xy 116.397278 -393.67841)
			(xy 116.412049 -393.697584) (xy 116.436876 -393.739132) (xy 116.455912 -393.783631) (xy 116.468813 -393.830281)
			(xy 116.475347 -393.878238) (xy 116.475764 -393.902438) (xy 116.475262 -393.929334) (xy 116.467244 -393.982526)
			(xy 116.451388 -394.033929) (xy 116.428049 -394.082395) (xy 116.397746 -394.126841) (xy 116.361158 -394.166274)
			(xy 116.319101 -394.199813) (xy 116.272515 -394.226709) (xy 116.222441 -394.246362) (xy 116.169996 -394.258332)
			(xy 116.116354 -394.262352) (xy 116.062712 -394.258332) (xy 116.010267 -394.246362) (xy 115.960193 -394.226709)
			(xy 115.913607 -394.199813) (xy 115.87155 -394.166274) (xy 115.834962 -394.126841) (xy 115.804659 -394.082395)
			(xy 115.78132 -394.033929) (xy 115.765464 -393.982526) (xy 115.757446 -393.929334) (xy 115.756944 -393.902438)
			(xy 115.757358 -393.878235) (xy 115.763858 -393.830269) (xy 115.776746 -393.783611) (xy 115.795787 -393.739109)
			(xy 115.820636 -393.697569) (xy 115.83543 -393.67841) (xy 115.835684 -393.678156) (xy 115.84095 -393.670965)
			(xy 115.846539 -393.65405) (xy 115.846606 -393.645136) (xy 115.844574 -393.570714) (xy 115.837716 -393.55395)
			(xy 115.831874 -393.547346) (xy 115.81367 -393.526232) (xy 115.782925 -393.479729) (xy 115.759274 -393.429249)
			(xy 115.743219 -393.375864) (xy 115.735102 -393.320711) (xy 115.734592 -393.292838) (xy 115.29822 -393.292838)
			(xy 115.297711 -393.320712) (xy 115.289604 -393.375868) (xy 115.273554 -393.429257) (xy 115.249903 -393.47974)
			(xy 115.219154 -393.526242) (xy 115.200938 -393.547346) (xy 115.195096 -393.55395) (xy 115.188238 -393.570714)
			(xy 115.186206 -393.645136) (xy 115.186322 -393.654041) (xy 115.191916 -393.670934) (xy 115.197128 -393.678156)
			(xy 115.197382 -393.67841) (xy 115.212153 -393.697583) (xy 115.23698 -393.739131) (xy 115.256016 -393.783631)
			(xy 115.268917 -393.830281) (xy 115.275451 -393.878238) (xy 115.275868 -393.902438) (xy 115.275366 -393.929334)
			(xy 115.267348 -393.982526) (xy 115.251492 -394.033929) (xy 115.228153 -394.082395) (xy 115.19785 -394.126841)
			(xy 115.161262 -394.166274) (xy 115.119205 -394.199813) (xy 115.072619 -394.226709) (xy 115.022545 -394.246362)
			(xy 114.9701 -394.258332) (xy 114.916458 -394.262352) (xy 114.862816 -394.258332) (xy 114.810371 -394.246362)
			(xy 114.760297 -394.226709) (xy 114.713711 -394.199813) (xy 114.671654 -394.166274) (xy 114.635066 -394.126841)
			(xy 114.604763 -394.082395) (xy 114.581424 -394.033929) (xy 114.565568 -393.982526) (xy 114.55755 -393.929334)
			(xy 114.557048 -393.902438) (xy 114.557461 -393.878235) (xy 114.563961 -393.830269) (xy 114.576849 -393.783611)
			(xy 114.595891 -393.739109) (xy 114.62074 -393.697569) (xy 114.635534 -393.67841) (xy 114.635788 -393.678156)
			(xy 114.641055 -393.670965) (xy 114.646643 -393.65405) (xy 114.64671 -393.645136) (xy 114.644678 -393.570714)
			(xy 114.63782 -393.55395) (xy 114.631978 -393.547346) (xy 114.613775 -393.526231) (xy 114.58303 -393.479729)
			(xy 114.559378 -393.429249) (xy 114.543323 -393.375864) (xy 114.535206 -393.320711) (xy 114.534696 -393.292838)
			(xy 111.561992 -393.292838) (xy 111.519127 -393.305424) (xy 111.465179 -393.31318) (xy 111.410677 -393.31318)
			(xy 111.356729 -393.305424) (xy 111.304434 -393.290069) (xy 111.254857 -393.267427) (xy 111.209007 -393.237961)
			(xy 111.167816 -393.20227) (xy 111.132125 -393.161079) (xy 111.102659 -393.115229) (xy 111.080017 -393.065652)
			(xy 111.064662 -393.013357) (xy 111.056906 -392.959409) (xy 111.05642 -392.932158) (xy 111.05642 -392.93165)
			(xy 111.05697 -392.903222) (xy 111.065454 -392.847001) (xy 111.082182 -392.79266) (xy 111.094012 -392.766804)
			(xy 111.098584 -392.757152) (xy 111.0996 -392.736324) (xy 111.06531 -392.647678) (xy 111.050578 -392.632692)
			(xy 111.040926 -392.628882) (xy 111.014993 -392.617695) (xy 110.966411 -392.588899) (xy 110.922605 -392.553256)
			(xy 110.88453 -392.511546) (xy 110.85302 -392.464679) (xy 110.828761 -392.41368) (xy 110.812285 -392.359662)
			(xy 110.803951 -392.303805) (xy 110.803436 -392.275568) (xy 108.245656 -392.275568) (xy 108.245656 -392.661902)
			(xy 108.246081 -392.671971) (xy 108.253802 -392.690569) (xy 108.260642 -392.69797) (xy 108.398818 -392.835892)
			(xy 108.405674 -392.843286) (xy 108.413425 -392.861885) (xy 108.413804 -392.87196) (xy 108.413804 -393.484608)
			(xy 108.414312 -393.485116) (xy 108.414312 -393.51331) (xy 108.414737 -393.523379) (xy 108.422456 -393.54198)
			(xy 108.429298 -393.549378) (xy 108.850938 -393.971272) (xy 108.85778 -393.978671) (xy 108.865498 -393.99727)
			(xy 108.865924 -394.00734) (xy 108.865924 -394.062966) (xy 108.86636 -394.07303) (xy 108.874094 -394.091615)
			(xy 108.88091 -394.099034) (xy 108.939076 -394.1572) (xy 108.945925 -394.164597) (xy 108.953663 -394.183196)
			(xy 108.954062 -394.193268) (xy 108.954062 -394.725101) (xy 110.721134 -394.725101) (xy 110.721134 -394.661179)
			(xy 110.729145 -394.597761) (xy 110.745042 -394.535847) (xy 110.768574 -394.476414) (xy 110.799368 -394.420399)
			(xy 110.836941 -394.368684) (xy 110.880698 -394.322087) (xy 110.929951 -394.281342) (xy 110.983922 -394.247091)
			(xy 111.041761 -394.219874) (xy 111.102554 -394.200121) (xy 111.165344 -394.188143) (xy 111.22914 -394.18413)
			(xy 111.292936 -394.188143) (xy 111.355726 -394.200121) (xy 111.416519 -394.219874) (xy 111.474358 -394.247091)
			(xy 111.528329 -394.281342) (xy 111.577582 -394.322087) (xy 111.605689 -394.352018) (xy 113.30508 -394.352018)
			(xy 113.309151 -394.296396) (xy 113.321277 -394.241959) (xy 113.3412 -394.189868) (xy 113.368496 -394.141233)
			(xy 113.402582 -394.09709) (xy 113.442731 -394.058381) (xy 113.488089 -394.02593) (xy 113.537689 -394.000429)
			(xy 113.590473 -393.982422) (xy 113.645316 -393.972292) (xy 113.70105 -393.970255) (xy 113.756487 -393.976355)
			(xy 113.810444 -393.990461) (xy 113.861773 -394.012273) (xy 113.909379 -394.041327) (xy 113.952247 -394.077002)
			(xy 113.989464 -394.118539) (xy 114.020237 -394.165052) (xy 114.043909 -394.215549) (xy 114.059977 -394.268956)
			(xy 114.068097 -394.324132) (xy 114.068606 -394.352018) (xy 114.068097 -394.379904) (xy 114.059977 -394.43508)
			(xy 114.043909 -394.488487) (xy 114.020237 -394.538984) (xy 113.989464 -394.585497) (xy 113.952247 -394.627034)
			(xy 113.909379 -394.662709) (xy 113.861773 -394.691763) (xy 113.810444 -394.713575) (xy 113.756487 -394.727681)
			(xy 113.70105 -394.733781) (xy 113.645316 -394.731744) (xy 113.590473 -394.721614) (xy 113.537689 -394.703607)
			(xy 113.488089 -394.678106) (xy 113.442731 -394.645655) (xy 113.402582 -394.606946) (xy 113.368496 -394.562803)
			(xy 113.3412 -394.514168) (xy 113.321277 -394.462077) (xy 113.309151 -394.40764) (xy 113.30508 -394.352018)
			(xy 111.605689 -394.352018) (xy 111.621339 -394.368684) (xy 111.658912 -394.420399) (xy 111.689706 -394.476414)
			(xy 111.713238 -394.535847) (xy 111.729135 -394.597761) (xy 111.737146 -394.661179) (xy 111.737648 -394.69314)
			(xy 111.737146 -394.725101) (xy 111.729135 -394.788519) (xy 111.713238 -394.850433) (xy 111.689706 -394.909866)
			(xy 111.658912 -394.965881) (xy 111.621339 -395.017596) (xy 111.577582 -395.064193) (xy 111.528329 -395.104938)
			(xy 111.474358 -395.139189) (xy 111.416519 -395.166406) (xy 111.355726 -395.186159) (xy 111.292936 -395.198137)
			(xy 111.22914 -395.202151) (xy 111.165344 -395.198137) (xy 111.102554 -395.186159) (xy 111.041761 -395.166406)
			(xy 110.983922 -395.139189) (xy 110.929951 -395.104938) (xy 110.880698 -395.064193) (xy 110.836941 -395.017596)
			(xy 110.799368 -394.965881) (xy 110.768574 -394.909866) (xy 110.745042 -394.850433) (xy 110.729145 -394.788519)
			(xy 110.721134 -394.725101) (xy 108.954062 -394.725101) (xy 108.954062 -395.120368) (xy 108.954499 -395.130431)
			(xy 108.962238 -395.149012) (xy 108.969048 -395.156436) (xy 109.838998 -396.026386) (xy 109.843283 -396.030407)
			(xy 109.853288 -396.036567) (xy 109.85881 -396.038578) (xy 109.887112 -396.048394) (xy 109.940487 -396.075583)
			(xy 109.988959 -396.110775) (xy 110.03134 -396.153107) (xy 110.066588 -396.201539) (xy 110.093838 -396.254882)
			(xy 110.103666 -396.28318) (xy 110.103666 -396.283688) (xy 110.107476 -396.294864) (xy 111.327692 -397.51508)
			(xy 113.108232 -397.51508) (xy 113.108754 -397.486102) (xy 113.117517 -397.428811) (xy 113.134838 -397.373503)
			(xy 113.16032 -397.321449) (xy 113.193377 -397.273844) (xy 113.23325 -397.231783) (xy 113.255806 -397.213582)
			(xy 113.264696 -397.206724) (xy 113.27511 -397.186658) (xy 113.278412 -397.08582) (xy 113.269522 -397.065246)
			(xy 113.26114 -397.057626) (xy 113.241468 -397.039428) (xy 113.206868 -396.998506) (xy 113.178335 -396.953145)
			(xy 113.156429 -396.904239) (xy 113.141582 -396.852748) (xy 113.134085 -396.799686) (xy 113.133632 -396.772892)
			(xy 113.134118 -396.745641) (xy 113.141874 -396.691693) (xy 113.157229 -396.639398) (xy 113.179871 -396.589821)
			(xy 113.209337 -396.543971) (xy 113.245028 -396.50278) (xy 113.286219 -396.467089) (xy 113.332069 -396.437623)
			(xy 113.381646 -396.414981) (xy 113.433941 -396.399626) (xy 113.487889 -396.39187) (xy 113.542391 -396.39187)
			(xy 113.596339 -396.399626) (xy 113.648634 -396.414981) (xy 113.698211 -396.437623) (xy 113.744061 -396.467089)
			(xy 113.785252 -396.50278) (xy 113.820943 -396.543971) (xy 113.850409 -396.589821) (xy 113.873051 -396.639398)
			(xy 113.888406 -396.691693) (xy 113.896162 -396.745641) (xy 113.896648 -396.772892) (xy 113.896113 -396.80187)
			(xy 113.887354 -396.85916) (xy 113.870035 -396.914468) (xy 113.844556 -396.966523) (xy 113.811501 -397.014128)
			(xy 113.771629 -397.056189) (xy 113.749074 -397.07439) (xy 113.740184 -397.081248) (xy 113.72977 -397.101314)
			(xy 113.726468 -397.202152) (xy 113.735358 -397.222726) (xy 113.74374 -397.230346) (xy 113.763443 -397.248512)
			(xy 113.798041 -397.289441) (xy 113.826571 -397.334808) (xy 113.848471 -397.383721) (xy 113.863312 -397.435217)
			(xy 113.8708 -397.488284) (xy 113.871248 -397.51508) (xy 113.870762 -397.542331) (xy 113.863006 -397.596279)
			(xy 113.847651 -397.648574) (xy 113.825009 -397.698151) (xy 113.795543 -397.744001) (xy 113.759852 -397.785192)
			(xy 113.718661 -397.820883) (xy 113.672811 -397.850349) (xy 113.623234 -397.872991) (xy 113.570939 -397.888346)
			(xy 113.516991 -397.896102) (xy 113.462489 -397.896102) (xy 113.408541 -397.888346) (xy 113.356246 -397.872991)
			(xy 113.306669 -397.850349) (xy 113.260819 -397.820883) (xy 113.219628 -397.785192) (xy 113.183937 -397.744001)
			(xy 113.154471 -397.698151) (xy 113.131829 -397.648574) (xy 113.116474 -397.596279) (xy 113.108718 -397.542331)
			(xy 113.108232 -397.51508) (xy 111.327692 -397.51508) (xy 111.956088 -398.143476) (xy 111.963485 -398.150327)
			(xy 111.982083 -398.158069) (xy 111.992156 -398.158462)
		)
		(stroke
			(width 0)
			(type solid)
		)
		(fill yes)
		(layer "B.Cu")
		(net "P0V9_CPU1_RT3_2A")
	)
	(gr_poly
		(pts
			(xy 389.554212 -406.540462) (xy 389.56428 -406.540036) (xy 389.582878 -406.532314) (xy 389.59028 -406.525476)
			(xy 392.373866 -403.74189) (xy 392.380715 -403.734493) (xy 392.388451 -403.715894) (xy 392.388852 -403.705822)
			(xy 392.388852 -402.160232) (xy 392.388711 -402.154158) (xy 392.38589 -402.142343) (xy 392.383264 -402.136864)
			(xy 392.369652 -402.109678) (xy 392.348278 -402.052758) (xy 392.333851 -401.993694) (xy 392.326578 -401.93333)
			(xy 392.326114 -401.90293) (xy 392.326575 -401.872531) (xy 392.33386 -401.812169) (xy 392.348293 -401.753108)
			(xy 392.36967 -401.696191) (xy 392.383264 -401.668996) (xy 392.383518 -401.668488) (xy 392.385981 -401.663163)
			(xy 392.388679 -401.651747) (xy 392.388852 -401.645882) (xy 392.388852 -401.524978) (xy 392.388704 -401.519109)
			(xy 392.386015 -401.507685) (xy 392.383518 -401.502372) (xy 392.383264 -401.501864) (xy 392.369658 -401.474675)
			(xy 392.348291 -401.417754) (xy 392.333861 -401.358691) (xy 392.326574 -401.29833) (xy 392.326114 -401.26793)
			(xy 392.326639 -401.234543) (xy 392.335377 -401.168342) (xy 392.352707 -401.103856) (xy 392.37833 -401.042193)
			(xy 392.411805 -400.984415) (xy 392.452556 -400.931517) (xy 392.499881 -400.884409) (xy 392.552967 -400.843902)
			(xy 392.610898 -400.810694) (xy 392.641582 -400.797522) (xy 392.651234 -400.793458) (xy 392.70178 -400.742912)
			(xy 392.708631 -400.735515) (xy 392.716373 -400.716917) (xy 392.716766 -400.706844) (xy 392.716766 -397.895572)
			(xy 392.716337 -397.885505) (xy 392.708612 -397.866911) (xy 392.70178 -397.859504) (xy 392.67257 -397.830294)
			(xy 392.665169 -397.823453) (xy 392.646572 -397.815731) (xy 392.636502 -397.815308) (xy 391.66038 -397.815308)
			(xy 391.650311 -397.814882) (xy 391.631711 -397.807163) (xy 391.624312 -397.800322) (xy 391.390378 -397.566388)
			(xy 391.381837 -397.558577) (xy 391.36002 -397.550918) (xy 391.348468 -397.551656) (xy 391.268966 -397.561308)
			(xy 391.257637 -397.563257) (xy 391.238231 -397.575521) (xy 391.231628 -397.58493) (xy 391.231628 -397.585184)
			(xy 391.217271 -397.607749) (xy 391.18245 -397.64834) (xy 391.14155 -397.682798) (xy 391.118852 -397.696944)
			(xy 391.107168 -397.703802) (xy 391.094214 -397.726916) (xy 391.094214 -397.828008) (xy 391.094607 -397.836663)
			(xy 391.100457 -397.852959) (xy 391.111387 -397.866386) (xy 391.118598 -397.871188) (xy 391.118852 -397.871442)
			(xy 391.139563 -397.884318) (xy 391.177303 -397.915201) (xy 391.210095 -397.951295) (xy 391.237228 -397.991816)
			(xy 391.258111 -398.035883) (xy 391.272293 -398.082542) (xy 391.279465 -398.130777) (xy 391.279888 -398.15516)
			(xy 391.279472 -398.178932) (xy 391.272654 -398.225986) (xy 391.259168 -398.271578) (xy 391.239292 -398.314769)
			(xy 391.213435 -398.354668) (xy 391.1981 -398.372838) (xy 391.19242 -398.37996) (xy 391.186044 -398.397011)
			(xy 391.185654 -398.406112) (xy 391.185654 -398.437608) (xy 391.186034 -398.44671) (xy 391.192421 -398.463758)
			(xy 391.1981 -398.470882) (xy 391.213446 -398.489043) (xy 391.239308 -398.52894) (xy 391.259181 -398.572133)
			(xy 391.272654 -398.61773) (xy 391.279449 -398.664787) (xy 391.279888 -398.68856) (xy 391.279336 -398.716166)
			(xy 391.270167 -398.770612) (xy 391.252078 -398.822778) (xy 391.225571 -398.871211) (xy 391.191385 -398.914567)
			(xy 391.150468 -398.951638) (xy 391.127488 -398.966944) (xy 391.119987 -398.972227) (xy 391.10905 -398.986941)
			(xy 391.106152 -398.995646) (xy 391.097516 -399.025618) (xy 391.095379 -399.034509) (xy 391.096822 -399.052724)
			(xy 391.10031 -399.061178) (xy 391.110093 -399.083199) (xy 391.123901 -399.129363) (xy 391.130876 -399.17704)
			(xy 391.131298 -399.201132) (xy 391.130788 -399.227119) (xy 391.122658 -399.278454) (xy 391.106597 -399.327884)
			(xy 391.083001 -399.374194) (xy 391.052451 -399.416242) (xy 391.0157 -399.452993) (xy 390.973652 -399.483543)
			(xy 390.927342 -399.507139) (xy 390.877912 -399.5232) (xy 390.826577 -399.53133) (xy 390.774603 -399.53133)
			(xy 390.723268 -399.5232) (xy 390.673838 -399.507139) (xy 390.627528 -399.483543) (xy 390.58548 -399.452993)
			(xy 390.548729 -399.416242) (xy 390.518179 -399.374194) (xy 390.494583 -399.327884) (xy 390.478522 -399.278454)
			(xy 390.470392 -399.227119) (xy 390.469882 -399.201132) (xy 390.470435 -399.173527) (xy 390.479606 -399.119084)
			(xy 390.497699 -399.066922) (xy 390.524209 -399.018494) (xy 390.5584 -398.975145) (xy 390.599321 -398.938082)
			(xy 390.622282 -398.922748) (xy 390.629775 -398.917459) (xy 390.640694 -398.902741) (xy 390.643618 -398.894046)
			(xy 390.652254 -398.864074) (xy 390.654391 -398.855184) (xy 390.652944 -398.836969) (xy 390.64946 -398.828514)
			(xy 390.639679 -398.806493) (xy 390.625873 -398.760329) (xy 390.618899 -398.712652) (xy 390.618472 -398.68856)
			(xy 390.618887 -398.664787) (xy 390.625701 -398.617731) (xy 390.639184 -398.572137) (xy 390.659056 -398.528942)
			(xy 390.68491 -398.489039) (xy 390.70026 -398.470882) (xy 390.705937 -398.463759) (xy 390.712313 -398.446709)
			(xy 390.712706 -398.437608) (xy 390.712706 -398.406112) (xy 390.712328 -398.397009) (xy 390.705943 -398.37996)
			(xy 390.70026 -398.372838) (xy 390.68491 -398.354679) (xy 390.659042 -398.314784) (xy 390.639163 -398.271591)
			(xy 390.625684 -398.225993) (xy 390.618884 -398.178934) (xy 390.618472 -398.15516) (xy 390.618905 -398.130749)
			(xy 390.626078 -398.082458) (xy 390.640276 -398.035747) (xy 390.661191 -397.991633) (xy 390.688368 -397.951075)
			(xy 390.721215 -397.914956) (xy 390.759017 -397.884061) (xy 390.779762 -397.871188) (xy 390.791446 -397.86433)
			(xy 390.8044 -397.841216) (xy 390.8044 -397.740124) (xy 390.80401 -397.731469) (xy 390.798161 -397.715173)
			(xy 390.787224 -397.701751) (xy 390.780016 -397.696944) (xy 390.779762 -397.69669) (xy 390.759054 -397.683814)
			(xy 390.721319 -397.652929) (xy 390.688533 -397.616834) (xy 390.661407 -397.576312) (xy 390.640531 -397.532244)
			(xy 390.626358 -397.485587) (xy 390.619196 -397.437353) (xy 390.618726 -397.412972) (xy 390.619283 -397.385352)
			(xy 390.628462 -397.330879) (xy 390.646559 -397.278687) (xy 390.673073 -397.230226) (xy 390.707267 -397.18684)
			(xy 390.748191 -397.149736) (xy 390.771126 -397.134334) (xy 390.782556 -397.127222) (xy 390.795002 -397.103346)
			(xy 390.791446 -396.9893) (xy 390.77773 -396.966694) (xy 390.765792 -396.96009) (xy 390.744097 -396.947458)
			(xy 390.704453 -396.916664) (xy 390.669916 -396.880233) (xy 390.641281 -396.839001) (xy 390.619205 -396.793916)
			(xy 390.604195 -396.746013) (xy 390.596596 -396.696392) (xy 390.59612 -396.671292) (xy 390.59612 -396.671038)
			(xy 390.596457 -396.648924) (xy 390.60232 -396.605088) (xy 390.607804 -396.583662) (xy 390.609762 -396.575653)
			(xy 390.608977 -396.559195) (xy 390.60628 -396.551404) (xy 390.595358 -396.523972) (xy 390.591967 -396.516372)
			(xy 390.581205 -396.503691) (xy 390.574276 -396.49908) (xy 390.548917 -396.483207) (xy 390.502722 -396.445191)
			(xy 390.462596 -396.400817) (xy 390.429404 -396.351043) (xy 390.403863 -396.296943) (xy 390.386523 -396.239685)
			(xy 390.377759 -396.180505) (xy 390.377172 -396.150592) (xy 390.377691 -396.121526) (xy 390.385965 -396.063987)
			(xy 390.402343 -396.00821) (xy 390.426491 -395.955332) (xy 390.457919 -395.906429) (xy 390.495987 -395.862495)
			(xy 390.539919 -395.824427) (xy 390.588821 -395.792997) (xy 390.641699 -395.768847) (xy 390.697475 -395.752467)
			(xy 390.755014 -395.744192) (xy 390.78408 -395.743684) (xy 390.9441 -395.743684) (xy 390.95412 -395.743264)
			(xy 390.972634 -395.735594) (xy 390.986803 -395.721421) (xy 390.994468 -395.702904) (xy 390.9949 -395.692884)
			(xy 390.9949 -395.446504) (xy 390.994477 -395.436433) (xy 390.986764 -395.417828) (xy 390.979914 -395.410436)
			(xy 390.074404 -394.504926) (xy 390.067569 -394.497524) (xy 390.059861 -394.478925) (xy 390.059418 -394.468858)
			(xy 390.059418 -394.33754) (xy 390.058886 -394.326517) (xy 390.04968 -394.306487) (xy 390.041638 -394.298932)
			(xy 390.018915 -394.278793) (xy 389.978456 -394.233518) (xy 389.944338 -394.183291) (xy 389.917161 -394.128995)
			(xy 389.897401 -394.071581) (xy 389.885406 -394.012059) (xy 389.881387 -393.951474) (xy 389.885413 -393.890889)
			(xy 389.897415 -393.831368) (xy 389.917181 -393.773957) (xy 389.944364 -393.719664) (xy 389.978488 -393.669441)
			(xy 390.018952 -393.624171) (xy 390.041638 -393.603988) (xy 390.049655 -393.596413) (xy 390.058863 -393.576397)
			(xy 390.059418 -393.56538) (xy 390.059418 -392.650218) (xy 390.056878 -392.639042) (xy 390.054338 -392.633962)
			(xy 390.041972 -392.607283) (xy 390.023417 -392.551482) (xy 390.012162 -392.493765) (xy 390.008391 -392.435082)
			(xy 390.012166 -392.376399) (xy 390.023426 -392.318683) (xy 390.041986 -392.262884) (xy 390.054338 -392.236198)
			(xy 390.056878 -392.231118) (xy 390.059418 -392.219942) (xy 390.059418 -392.190224) (xy 390.059003 -392.180198)
			(xy 390.051338 -392.16167) (xy 390.037165 -392.147486) (xy 390.018643 -392.139806) (xy 390.008618 -392.139424)
			(xy 389.951722 -392.139424) (xy 389.941671 -392.138919) (xy 389.92311 -392.131198) (xy 389.915654 -392.124438)
			(xy 389.582914 -391.791698) (xy 389.576067 -391.7843) (xy 389.568331 -391.765702) (xy 389.567928 -391.75563)
			(xy 389.567928 -391.001504) (xy 389.568351 -390.991434) (xy 389.576068 -390.972831) (xy 389.582914 -390.965436)
			(xy 389.696452 -390.851898) (xy 389.703303 -390.844502) (xy 389.711045 -390.825903) (xy 389.711438 -390.81583)
			(xy 389.711438 -388.017004) (xy 389.711014 -388.006935) (xy 389.703294 -387.988335) (xy 389.696452 -387.980936)
			(xy 389.471662 -387.756146) (xy 389.464264 -387.749301) (xy 389.445665 -387.741573) (xy 389.435594 -387.74116)
			(xy 383.76606 -387.74116) (xy 383.755994 -387.741592) (xy 383.737406 -387.749323) (xy 383.729992 -387.756146)
			(xy 383.617724 -387.868414) (xy 383.610877 -387.875812) (xy 383.603144 -387.89441) (xy 383.602738 -387.904482)
			(xy 383.602738 -391.001758) (xy 383.602303 -391.011822) (xy 383.594566 -391.030405) (xy 383.587752 -391.037826)
			(xy 383.364661 -391.260917) (xy 383.786382 -391.260917) (xy 383.786382 -391.208943) (xy 383.794512 -391.157608)
			(xy 383.810573 -391.108178) (xy 383.834169 -391.061868) (xy 383.864719 -391.01982) (xy 383.90147 -390.983069)
			(xy 383.943518 -390.952519) (xy 383.989828 -390.928923) (xy 384.039258 -390.912862) (xy 384.090593 -390.904732)
			(xy 384.142567 -390.904732) (xy 384.193902 -390.912862) (xy 384.243332 -390.928923) (xy 384.289642 -390.952519)
			(xy 384.33169 -390.983069) (xy 384.368441 -391.01982) (xy 384.398991 -391.061868) (xy 384.422587 -391.108178)
			(xy 384.438648 -391.157608) (xy 384.446778 -391.208943) (xy 384.447288 -391.23493) (xy 384.446778 -391.260917)
			(xy 384.986278 -391.260917) (xy 384.986278 -391.208943) (xy 384.994408 -391.157608) (xy 385.010469 -391.108178)
			(xy 385.034065 -391.061868) (xy 385.064615 -391.01982) (xy 385.101366 -390.983069) (xy 385.143414 -390.952519)
			(xy 385.189724 -390.928923) (xy 385.239154 -390.912862) (xy 385.290489 -390.904732) (xy 385.342463 -390.904732)
			(xy 385.393798 -390.912862) (xy 385.443228 -390.928923) (xy 385.489538 -390.952519) (xy 385.531586 -390.983069)
			(xy 385.568337 -391.01982) (xy 385.598887 -391.061868) (xy 385.622483 -391.108178) (xy 385.638544 -391.157608)
			(xy 385.646674 -391.208943) (xy 385.647184 -391.23493) (xy 385.646674 -391.260917) (xy 386.186174 -391.260917)
			(xy 386.186174 -391.208943) (xy 386.194304 -391.157608) (xy 386.210365 -391.108178) (xy 386.233961 -391.061868)
			(xy 386.264511 -391.01982) (xy 386.301262 -390.983069) (xy 386.34331 -390.952519) (xy 386.38962 -390.928923)
			(xy 386.43905 -390.912862) (xy 386.490385 -390.904732) (xy 386.542359 -390.904732) (xy 386.593694 -390.912862)
			(xy 386.643124 -390.928923) (xy 386.689434 -390.952519) (xy 386.731482 -390.983069) (xy 386.768233 -391.01982)
			(xy 386.798783 -391.061868) (xy 386.822379 -391.108178) (xy 386.83844 -391.157608) (xy 386.84657 -391.208943)
			(xy 386.84708 -391.23493) (xy 386.84657 -391.260917) (xy 387.386324 -391.260917) (xy 387.386324 -391.208943)
			(xy 387.394454 -391.157608) (xy 387.410515 -391.108178) (xy 387.434111 -391.061868) (xy 387.464661 -391.01982)
			(xy 387.501412 -390.983069) (xy 387.54346 -390.952519) (xy 387.58977 -390.928923) (xy 387.6392 -390.912862)
			(xy 387.690535 -390.904732) (xy 387.742509 -390.904732) (xy 387.793844 -390.912862) (xy 387.843274 -390.928923)
			(xy 387.889584 -390.952519) (xy 387.931632 -390.983069) (xy 387.968383 -391.01982) (xy 387.998933 -391.061868)
			(xy 388.022529 -391.108178) (xy 388.03859 -391.157608) (xy 388.04672 -391.208943) (xy 388.04723 -391.23493)
			(xy 388.04672 -391.260917) (xy 388.58622 -391.260917) (xy 388.58622 -391.208943) (xy 388.59435 -391.157608)
			(xy 388.610411 -391.108178) (xy 388.634007 -391.061868) (xy 388.664557 -391.01982) (xy 388.701308 -390.983069)
			(xy 388.743356 -390.952519) (xy 388.789666 -390.928923) (xy 388.839096 -390.912862) (xy 388.890431 -390.904732)
			(xy 388.942405 -390.904732) (xy 388.99374 -390.912862) (xy 389.04317 -390.928923) (xy 389.08948 -390.952519)
			(xy 389.131528 -390.983069) (xy 389.168279 -391.01982) (xy 389.198829 -391.061868) (xy 389.222425 -391.108178)
			(xy 389.238486 -391.157608) (xy 389.246616 -391.208943) (xy 389.247126 -391.23493) (xy 389.246616 -391.260917)
			(xy 389.238486 -391.312252) (xy 389.222425 -391.361682) (xy 389.198829 -391.407992) (xy 389.168279 -391.45004)
			(xy 389.131528 -391.486791) (xy 389.08948 -391.517341) (xy 389.04317 -391.540937) (xy 388.99374 -391.556998)
			(xy 388.942405 -391.565128) (xy 388.890431 -391.565128) (xy 388.839096 -391.556998) (xy 388.789666 -391.540937)
			(xy 388.743356 -391.517341) (xy 388.701308 -391.486791) (xy 388.664557 -391.45004) (xy 388.634007 -391.407992)
			(xy 388.610411 -391.361682) (xy 388.59435 -391.312252) (xy 388.58622 -391.260917) (xy 388.04672 -391.260917)
			(xy 388.03859 -391.312252) (xy 388.022529 -391.361682) (xy 387.998933 -391.407992) (xy 387.968383 -391.45004)
			(xy 387.931632 -391.486791) (xy 387.889584 -391.517341) (xy 387.843274 -391.540937) (xy 387.793844 -391.556998)
			(xy 387.742509 -391.565128) (xy 387.690535 -391.565128) (xy 387.6392 -391.556998) (xy 387.58977 -391.540937)
			(xy 387.54346 -391.517341) (xy 387.501412 -391.486791) (xy 387.464661 -391.45004) (xy 387.434111 -391.407992)
			(xy 387.410515 -391.361682) (xy 387.394454 -391.312252) (xy 387.386324 -391.260917) (xy 386.84657 -391.260917)
			(xy 386.83844 -391.312252) (xy 386.822379 -391.361682) (xy 386.798783 -391.407992) (xy 386.768233 -391.45004)
			(xy 386.731482 -391.486791) (xy 386.689434 -391.517341) (xy 386.643124 -391.540937) (xy 386.593694 -391.556998)
			(xy 386.542359 -391.565128) (xy 386.490385 -391.565128) (xy 386.43905 -391.556998) (xy 386.38962 -391.540937)
			(xy 386.34331 -391.517341) (xy 386.301262 -391.486791) (xy 386.264511 -391.45004) (xy 386.233961 -391.407992)
			(xy 386.210365 -391.361682) (xy 386.194304 -391.312252) (xy 386.186174 -391.260917) (xy 385.646674 -391.260917)
			(xy 385.638544 -391.312252) (xy 385.622483 -391.361682) (xy 385.598887 -391.407992) (xy 385.568337 -391.45004)
			(xy 385.531586 -391.486791) (xy 385.489538 -391.517341) (xy 385.443228 -391.540937) (xy 385.393798 -391.556998)
			(xy 385.342463 -391.565128) (xy 385.290489 -391.565128) (xy 385.239154 -391.556998) (xy 385.189724 -391.540937)
			(xy 385.143414 -391.517341) (xy 385.101366 -391.486791) (xy 385.064615 -391.45004) (xy 385.034065 -391.407992)
			(xy 385.010469 -391.361682) (xy 384.994408 -391.312252) (xy 384.986278 -391.260917) (xy 384.446778 -391.260917)
			(xy 384.438648 -391.312252) (xy 384.422587 -391.361682) (xy 384.398991 -391.407992) (xy 384.368441 -391.45004)
			(xy 384.33169 -391.486791) (xy 384.289642 -391.517341) (xy 384.243332 -391.540937) (xy 384.193902 -391.556998)
			(xy 384.142567 -391.565128) (xy 384.090593 -391.565128) (xy 384.039258 -391.556998) (xy 383.989828 -391.540937)
			(xy 383.943518 -391.517341) (xy 383.90147 -391.486791) (xy 383.864719 -391.45004) (xy 383.834169 -391.407992)
			(xy 383.810573 -391.361682) (xy 383.794512 -391.312252) (xy 383.786382 -391.260917) (xy 383.364661 -391.260917)
			(xy 383.043684 -391.581894) (xy 383.036285 -391.588738) (xy 383.017687 -391.596468) (xy 383.007616 -391.59688)
			(xy 376.7582 -391.59688) (xy 376.74813 -391.596456) (xy 376.729528 -391.58874) (xy 376.722132 -391.581894)
			(xy 376.711718 -391.57148) (xy 376.711718 -391.56894) (xy 376.571764 -391.428986) (xy 376.564913 -391.42159)
			(xy 376.557174 -391.402991) (xy 376.556778 -391.392918) (xy 376.556778 -387.861302) (xy 376.556355 -387.851232)
			(xy 376.548638 -387.832629) (xy 376.541792 -387.825234) (xy 376.462798 -387.74624) (xy 376.45537 -387.739469)
			(xy 376.436774 -387.731885) (xy 376.42673 -387.731508) (xy 369.293648 -387.731508) (xy 369.283582 -387.731941)
			(xy 369.264992 -387.739669) (xy 369.25758 -387.746494) (xy 369.010184 -387.993636) (xy 369.003334 -388.001032)
			(xy 368.995599 -388.019631) (xy 368.995198 -388.029704) (xy 368.995198 -390.888728) (xy 368.995603 -390.898341)
			(xy 369.002638 -390.916235) (xy 369.008914 -390.923526) (xy 369.029234 -390.94537) (xy 369.035528 -390.951582)
			(xy 369.051248 -390.959654) (xy 369.059968 -390.961118) (xy 369.084301 -390.964674) (xy 369.131622 -390.97805)
			(xy 369.176437 -390.998292) (xy 369.217758 -391.024951) (xy 369.236498 -391.040874) (xy 369.243356 -391.04697)
			(xy 369.26012 -391.053574) (xy 369.334796 -391.054844) (xy 369.343693 -391.054653) (xy 369.360489 -391.048812)
			(xy 369.367562 -391.043414) (xy 369.367816 -391.043414) (xy 369.38923 -391.026687) (xy 369.436578 -391.000037)
			(xy 369.487768 -390.981825) (xy 369.541309 -390.972582) (xy 369.568476 -390.97204) (xy 369.593465 -390.972503)
			(xy 369.642827 -390.980318) (xy 369.690359 -390.995759) (xy 369.73489 -391.018446) (xy 369.775324 -391.04782)
			(xy 369.810665 -391.083158) (xy 369.840042 -391.123589) (xy 369.862732 -391.168119) (xy 369.878177 -391.21565)
			(xy 369.885189 -391.259919) (xy 370.598936 -391.259919) (xy 370.598936 -391.209941) (xy 370.606755 -391.160578)
			(xy 370.622199 -391.113046) (xy 370.644889 -391.068514) (xy 370.674265 -391.028081) (xy 370.709605 -390.992741)
			(xy 370.750038 -390.963365) (xy 370.79457 -390.940675) (xy 370.842102 -390.925231) (xy 370.891465 -390.917412)
			(xy 370.941443 -390.917412) (xy 370.990806 -390.925231) (xy 371.038338 -390.940675) (xy 371.08287 -390.963365)
			(xy 371.123303 -390.992741) (xy 371.158643 -391.028081) (xy 371.188019 -391.068514) (xy 371.210709 -391.113046)
			(xy 371.226153 -391.160578) (xy 371.233972 -391.209941) (xy 371.234462 -391.23493) (xy 371.233972 -391.259919)
			(xy 371.233814 -391.260917) (xy 371.786406 -391.260917) (xy 371.786406 -391.208943) (xy 371.794536 -391.157608)
			(xy 371.810597 -391.108178) (xy 371.834193 -391.061868) (xy 371.864743 -391.01982) (xy 371.901494 -390.983069)
			(xy 371.943542 -390.952519) (xy 371.989852 -390.928923) (xy 372.039282 -390.912862) (xy 372.090617 -390.904732)
			(xy 372.142591 -390.904732) (xy 372.193926 -390.912862) (xy 372.243356 -390.928923) (xy 372.289666 -390.952519)
			(xy 372.331714 -390.983069) (xy 372.368465 -391.01982) (xy 372.399015 -391.061868) (xy 372.422611 -391.108178)
			(xy 372.438672 -391.157608) (xy 372.446802 -391.208943) (xy 372.447312 -391.23493) (xy 372.446802 -391.260917)
			(xy 372.986302 -391.260917) (xy 372.986302 -391.208943) (xy 372.994432 -391.157608) (xy 373.010493 -391.108178)
			(xy 373.034089 -391.061868) (xy 373.064639 -391.01982) (xy 373.10139 -390.983069) (xy 373.143438 -390.952519)
			(xy 373.189748 -390.928923) (xy 373.239178 -390.912862) (xy 373.290513 -390.904732) (xy 373.342487 -390.904732)
			(xy 373.393822 -390.912862) (xy 373.443252 -390.928923) (xy 373.489562 -390.952519) (xy 373.53161 -390.983069)
			(xy 373.568361 -391.01982) (xy 373.598911 -391.061868) (xy 373.622507 -391.108178) (xy 373.638568 -391.157608)
			(xy 373.646698 -391.208943) (xy 373.647208 -391.23493) (xy 373.646698 -391.260917) (xy 374.186198 -391.260917)
			(xy 374.186198 -391.208943) (xy 374.194328 -391.157608) (xy 374.210389 -391.108178) (xy 374.233985 -391.061868)
			(xy 374.264535 -391.01982) (xy 374.301286 -390.983069) (xy 374.343334 -390.952519) (xy 374.389644 -390.928923)
			(xy 374.439074 -390.912862) (xy 374.490409 -390.904732) (xy 374.542383 -390.904732) (xy 374.593718 -390.912862)
			(xy 374.643148 -390.928923) (xy 374.689458 -390.952519) (xy 374.731506 -390.983069) (xy 374.768257 -391.01982)
			(xy 374.798807 -391.061868) (xy 374.822403 -391.108178) (xy 374.838464 -391.157608) (xy 374.846594 -391.208943)
			(xy 374.847104 -391.23493) (xy 374.846594 -391.260917) (xy 375.386348 -391.260917) (xy 375.386348 -391.208943)
			(xy 375.394478 -391.157608) (xy 375.410539 -391.108178) (xy 375.434135 -391.061868) (xy 375.464685 -391.01982)
			(xy 375.501436 -390.983069) (xy 375.543484 -390.952519) (xy 375.589794 -390.928923) (xy 375.639224 -390.912862)
			(xy 375.690559 -390.904732) (xy 375.742533 -390.904732) (xy 375.793868 -390.912862) (xy 375.843298 -390.928923)
			(xy 375.889608 -390.952519) (xy 375.931656 -390.983069) (xy 375.968407 -391.01982) (xy 375.998957 -391.061868)
			(xy 376.022553 -391.108178) (xy 376.038614 -391.157608) (xy 376.046744 -391.208943) (xy 376.047254 -391.23493)
			(xy 376.046744 -391.260917) (xy 376.038614 -391.312252) (xy 376.022553 -391.361682) (xy 375.998957 -391.407992)
			(xy 375.968407 -391.45004) (xy 375.931656 -391.486791) (xy 375.889608 -391.517341) (xy 375.843298 -391.540937)
			(xy 375.793868 -391.556998) (xy 375.742533 -391.565128) (xy 375.690559 -391.565128) (xy 375.639224 -391.556998)
			(xy 375.589794 -391.540937) (xy 375.543484 -391.517341) (xy 375.501436 -391.486791) (xy 375.464685 -391.45004)
			(xy 375.434135 -391.407992) (xy 375.410539 -391.361682) (xy 375.394478 -391.312252) (xy 375.386348 -391.260917)
			(xy 374.846594 -391.260917) (xy 374.838464 -391.312252) (xy 374.822403 -391.361682) (xy 374.798807 -391.407992)
			(xy 374.768257 -391.45004) (xy 374.731506 -391.486791) (xy 374.689458 -391.517341) (xy 374.643148 -391.540937)
			(xy 374.593718 -391.556998) (xy 374.542383 -391.565128) (xy 374.490409 -391.565128) (xy 374.439074 -391.556998)
			(xy 374.389644 -391.540937) (xy 374.343334 -391.517341) (xy 374.301286 -391.486791) (xy 374.264535 -391.45004)
			(xy 374.233985 -391.407992) (xy 374.210389 -391.361682) (xy 374.194328 -391.312252) (xy 374.186198 -391.260917)
			(xy 373.646698 -391.260917) (xy 373.638568 -391.312252) (xy 373.622507 -391.361682) (xy 373.598911 -391.407992)
			(xy 373.568361 -391.45004) (xy 373.53161 -391.486791) (xy 373.489562 -391.517341) (xy 373.443252 -391.540937)
			(xy 373.393822 -391.556998) (xy 373.342487 -391.565128) (xy 373.290513 -391.565128) (xy 373.239178 -391.556998)
			(xy 373.189748 -391.540937) (xy 373.143438 -391.517341) (xy 373.10139 -391.486791) (xy 373.064639 -391.45004)
			(xy 373.034089 -391.407992) (xy 373.010493 -391.361682) (xy 372.994432 -391.312252) (xy 372.986302 -391.260917)
			(xy 372.446802 -391.260917) (xy 372.438672 -391.312252) (xy 372.422611 -391.361682) (xy 372.399015 -391.407992)
			(xy 372.368465 -391.45004) (xy 372.331714 -391.486791) (xy 372.289666 -391.517341) (xy 372.243356 -391.540937)
			(xy 372.193926 -391.556998) (xy 372.142591 -391.565128) (xy 372.090617 -391.565128) (xy 372.039282 -391.556998)
			(xy 371.989852 -391.540937) (xy 371.943542 -391.517341) (xy 371.901494 -391.486791) (xy 371.864743 -391.45004)
			(xy 371.834193 -391.407992) (xy 371.810597 -391.361682) (xy 371.794536 -391.312252) (xy 371.786406 -391.260917)
			(xy 371.233814 -391.260917) (xy 371.226153 -391.309282) (xy 371.210709 -391.356814) (xy 371.188019 -391.401346)
			(xy 371.158643 -391.441779) (xy 371.123303 -391.477119) (xy 371.08287 -391.506495) (xy 371.038338 -391.529185)
			(xy 370.990806 -391.544629) (xy 370.941443 -391.552448) (xy 370.891465 -391.552448) (xy 370.842102 -391.544629)
			(xy 370.79457 -391.529185) (xy 370.750038 -391.506495) (xy 370.709605 -391.477119) (xy 370.674265 -391.441779)
			(xy 370.644889 -391.401346) (xy 370.622199 -391.356814) (xy 370.606755 -391.309282) (xy 370.598936 -391.259919)
			(xy 369.885189 -391.259919) (xy 369.885995 -391.265011) (xy 369.885995 -391.314989) (xy 369.878177 -391.36435)
			(xy 369.862732 -391.411881) (xy 369.840042 -391.456411) (xy 369.810665 -391.496842) (xy 369.775324 -391.53218)
			(xy 369.73489 -391.561554) (xy 369.690359 -391.584241) (xy 369.642827 -391.599682) (xy 369.593465 -391.607497)
			(xy 369.568476 -391.608056) (xy 369.541192 -391.6075) (xy 369.487422 -391.598203) (xy 369.436026 -391.579868)
			(xy 369.388512 -391.553034) (xy 369.367054 -391.536174) (xy 369.359873 -391.530678) (xy 369.342821 -391.524702)
			(xy 369.33378 -391.52449) (xy 369.259104 -391.52576) (xy 369.242594 -391.53211) (xy 369.235736 -391.538206)
			(xy 369.217575 -391.553553) (xy 369.177679 -391.579416) (xy 369.134486 -391.599291) (xy 369.088889 -391.612767)
			(xy 369.041831 -391.619564) (xy 369.018058 -391.619994) (xy 368.994825 -391.619598) (xy 368.948818 -391.613089)
			(xy 368.904174 -391.600207) (xy 368.861772 -391.581203) (xy 368.822447 -391.556453) (xy 368.804444 -391.541762)
			(xy 368.797586 -391.53592) (xy 368.780568 -391.52957) (xy 368.696748 -391.52957) (xy 368.67973 -391.53592)
			(xy 368.672872 -391.541762) (xy 368.647953 -391.561864) (xy 368.592063 -391.593078) (xy 368.561874 -391.603738)
			(xy 368.55621 -391.60578) (xy 368.545942 -391.612061) (xy 368.541554 -391.616184) (xy 368.429286 -391.728452)
			(xy 368.422439 -391.735849) (xy 368.41471 -391.754448) (xy 368.4143 -391.76452) (xy 368.4143 -391.806938)
			(xy 368.41473 -391.817005) (xy 368.422454 -391.835599) (xy 368.429286 -391.843006) (xy 368.718846 -392.132312)
			(xy 368.735613 -392.149754) (xy 368.764046 -392.188897) (xy 368.786007 -392.232005) (xy 368.800955 -392.278017)
			(xy 368.808523 -392.3258) (xy 368.809016 -392.34999) (xy 368.809016 -392.61796) (xy 368.812064 -392.626342)
			(xy 368.821279 -392.653557) (xy 368.831236 -392.710139) (xy 368.831876 -392.738864) (xy 368.831876 -392.739372)
			(xy 368.831364 -392.765754) (xy 368.822993 -392.817848) (xy 368.806457 -392.867953) (xy 368.782178 -392.914798)
			(xy 368.750769 -392.957194) (xy 368.713029 -392.994067) (xy 368.669914 -393.024481) (xy 368.669444 -393.024711)
			(xy 370.24486 -393.024711) (xy 370.24486 -392.974733) (xy 370.252679 -392.92537) (xy 370.268123 -392.877838)
			(xy 370.290813 -392.833306) (xy 370.320189 -392.792873) (xy 370.355529 -392.757533) (xy 370.395962 -392.728157)
			(xy 370.440494 -392.705467) (xy 370.488026 -392.690023) (xy 370.537389 -392.682204) (xy 370.587367 -392.682204)
			(xy 370.63673 -392.690023) (xy 370.684262 -392.705467) (xy 370.728794 -392.728157) (xy 370.769227 -392.757533)
			(xy 370.804567 -392.792873) (xy 370.833943 -392.833306) (xy 370.856633 -392.877838) (xy 370.872077 -392.92537)
			(xy 370.879896 -392.974733) (xy 370.880386 -392.999722) (xy 370.879896 -393.024711) (xy 370.879738 -393.025709)
			(xy 371.432076 -393.025709) (xy 371.432076 -392.973735) (xy 371.440206 -392.9224) (xy 371.456267 -392.87297)
			(xy 371.479863 -392.82666) (xy 371.510413 -392.784612) (xy 371.547164 -392.747861) (xy 371.589212 -392.717311)
			(xy 371.635522 -392.693715) (xy 371.684952 -392.677654) (xy 371.736287 -392.669524) (xy 371.788261 -392.669524)
			(xy 371.839596 -392.677654) (xy 371.889026 -392.693715) (xy 371.935336 -392.717311) (xy 371.977384 -392.747861)
			(xy 372.014135 -392.784612) (xy 372.044685 -392.82666) (xy 372.068281 -392.87297) (xy 372.084342 -392.9224)
			(xy 372.092472 -392.973735) (xy 372.092982 -392.999722) (xy 372.092472 -393.025709) (xy 372.632226 -393.025709)
			(xy 372.632226 -392.973735) (xy 372.640356 -392.9224) (xy 372.656417 -392.87297) (xy 372.680013 -392.82666)
			(xy 372.710563 -392.784612) (xy 372.747314 -392.747861) (xy 372.789362 -392.717311) (xy 372.835672 -392.693715)
			(xy 372.885102 -392.677654) (xy 372.936437 -392.669524) (xy 372.988411 -392.669524) (xy 373.039746 -392.677654)
			(xy 373.089176 -392.693715) (xy 373.135486 -392.717311) (xy 373.177534 -392.747861) (xy 373.214285 -392.784612)
			(xy 373.244835 -392.82666) (xy 373.268431 -392.87297) (xy 373.284492 -392.9224) (xy 373.292622 -392.973735)
			(xy 373.293132 -392.999722) (xy 373.292622 -393.025709) (xy 373.832122 -393.025709) (xy 373.832122 -392.973735)
			(xy 373.840252 -392.9224) (xy 373.856313 -392.87297) (xy 373.879909 -392.82666) (xy 373.910459 -392.784612)
			(xy 373.94721 -392.747861) (xy 373.989258 -392.717311) (xy 374.035568 -392.693715) (xy 374.084998 -392.677654)
			(xy 374.136333 -392.669524) (xy 374.188307 -392.669524) (xy 374.239642 -392.677654) (xy 374.289072 -392.693715)
			(xy 374.335382 -392.717311) (xy 374.37743 -392.747861) (xy 374.414181 -392.784612) (xy 374.444731 -392.82666)
			(xy 374.468327 -392.87297) (xy 374.484388 -392.9224) (xy 374.492518 -392.973735) (xy 374.493028 -392.999722)
			(xy 374.492518 -393.025709) (xy 375.032272 -393.025709) (xy 375.032272 -392.973735) (xy 375.040402 -392.9224)
			(xy 375.056463 -392.87297) (xy 375.080059 -392.82666) (xy 375.110609 -392.784612) (xy 375.14736 -392.747861)
			(xy 375.189408 -392.717311) (xy 375.235718 -392.693715) (xy 375.285148 -392.677654) (xy 375.336483 -392.669524)
			(xy 375.388457 -392.669524) (xy 375.439792 -392.677654) (xy 375.489222 -392.693715) (xy 375.535532 -392.717311)
			(xy 375.57758 -392.747861) (xy 375.614331 -392.784612) (xy 375.644881 -392.82666) (xy 375.668477 -392.87297)
			(xy 375.684538 -392.9224) (xy 375.692668 -392.973735) (xy 375.693178 -392.999722) (xy 375.692668 -393.025709)
			(xy 376.232168 -393.025709) (xy 376.232168 -392.973735) (xy 376.240298 -392.9224) (xy 376.256359 -392.87297)
			(xy 376.279955 -392.82666) (xy 376.310505 -392.784612) (xy 376.347256 -392.747861) (xy 376.389304 -392.717311)
			(xy 376.435614 -392.693715) (xy 376.485044 -392.677654) (xy 376.536379 -392.669524) (xy 376.588353 -392.669524)
			(xy 376.639688 -392.677654) (xy 376.689118 -392.693715) (xy 376.735428 -392.717311) (xy 376.777476 -392.747861)
			(xy 376.814227 -392.784612) (xy 376.844777 -392.82666) (xy 376.868373 -392.87297) (xy 376.884434 -392.9224)
			(xy 376.892564 -392.973735) (xy 376.893074 -392.999722) (xy 376.892564 -393.025709) (xy 377.432064 -393.025709)
			(xy 377.432064 -392.973735) (xy 377.440194 -392.9224) (xy 377.456255 -392.87297) (xy 377.479851 -392.82666)
			(xy 377.510401 -392.784612) (xy 377.547152 -392.747861) (xy 377.5892 -392.717311) (xy 377.63551 -392.693715)
			(xy 377.68494 -392.677654) (xy 377.736275 -392.669524) (xy 377.788249 -392.669524) (xy 377.839584 -392.677654)
			(xy 377.889014 -392.693715) (xy 377.935324 -392.717311) (xy 377.977372 -392.747861) (xy 378.014123 -392.784612)
			(xy 378.044673 -392.82666) (xy 378.068269 -392.87297) (xy 378.08433 -392.9224) (xy 378.09246 -392.973735)
			(xy 378.09297 -392.999722) (xy 378.09246 -393.025709) (xy 378.632214 -393.025709) (xy 378.632214 -392.973735)
			(xy 378.640344 -392.9224) (xy 378.656405 -392.87297) (xy 378.680001 -392.82666) (xy 378.710551 -392.784612)
			(xy 378.747302 -392.747861) (xy 378.78935 -392.717311) (xy 378.83566 -392.693715) (xy 378.88509 -392.677654)
			(xy 378.936425 -392.669524) (xy 378.988399 -392.669524) (xy 379.039734 -392.677654) (xy 379.089164 -392.693715)
			(xy 379.135474 -392.717311) (xy 379.177522 -392.747861) (xy 379.214273 -392.784612) (xy 379.244823 -392.82666)
			(xy 379.268419 -392.87297) (xy 379.28448 -392.9224) (xy 379.29261 -392.973735) (xy 379.29312 -392.999722)
			(xy 379.29261 -393.025709) (xy 379.83211 -393.025709) (xy 379.83211 -392.973735) (xy 379.84024 -392.9224)
			(xy 379.856301 -392.87297) (xy 379.879897 -392.82666) (xy 379.910447 -392.784612) (xy 379.947198 -392.747861)
			(xy 379.989246 -392.717311) (xy 380.035556 -392.693715) (xy 380.084986 -392.677654) (xy 380.136321 -392.669524)
			(xy 380.188295 -392.669524) (xy 380.23963 -392.677654) (xy 380.28906 -392.693715) (xy 380.33537 -392.717311)
			(xy 380.377418 -392.747861) (xy 380.414169 -392.784612) (xy 380.444719 -392.82666) (xy 380.468315 -392.87297)
			(xy 380.484376 -392.9224) (xy 380.492506 -392.973735) (xy 380.493016 -392.999722) (xy 380.492506 -393.025709)
			(xy 381.03226 -393.025709) (xy 381.03226 -392.973735) (xy 381.04039 -392.9224) (xy 381.056451 -392.87297)
			(xy 381.080047 -392.82666) (xy 381.110597 -392.784612) (xy 381.147348 -392.747861) (xy 381.189396 -392.717311)
			(xy 381.235706 -392.693715) (xy 381.285136 -392.677654) (xy 381.336471 -392.669524) (xy 381.388445 -392.669524)
			(xy 381.43978 -392.677654) (xy 381.48921 -392.693715) (xy 381.53552 -392.717311) (xy 381.577568 -392.747861)
			(xy 381.614319 -392.784612) (xy 381.644869 -392.82666) (xy 381.668465 -392.87297) (xy 381.684526 -392.9224)
			(xy 381.692656 -392.973735) (xy 381.693166 -392.999722) (xy 381.692656 -393.025709) (xy 382.232156 -393.025709)
			(xy 382.232156 -392.973735) (xy 382.240286 -392.9224) (xy 382.256347 -392.87297) (xy 382.279943 -392.82666)
			(xy 382.310493 -392.784612) (xy 382.347244 -392.747861) (xy 382.389292 -392.717311) (xy 382.435602 -392.693715)
			(xy 382.485032 -392.677654) (xy 382.536367 -392.669524) (xy 382.588341 -392.669524) (xy 382.639676 -392.677654)
			(xy 382.689106 -392.693715) (xy 382.735416 -392.717311) (xy 382.777464 -392.747861) (xy 382.814215 -392.784612)
			(xy 382.844765 -392.82666) (xy 382.868361 -392.87297) (xy 382.884422 -392.9224) (xy 382.892552 -392.973735)
			(xy 382.893062 -392.999722) (xy 382.892552 -393.025709) (xy 383.432052 -393.025709) (xy 383.432052 -392.973735)
			(xy 383.440182 -392.9224) (xy 383.456243 -392.87297) (xy 383.479839 -392.82666) (xy 383.510389 -392.784612)
			(xy 383.54714 -392.747861) (xy 383.589188 -392.717311) (xy 383.635498 -392.693715) (xy 383.684928 -392.677654)
			(xy 383.736263 -392.669524) (xy 383.788237 -392.669524) (xy 383.839572 -392.677654) (xy 383.889002 -392.693715)
			(xy 383.935312 -392.717311) (xy 383.97736 -392.747861) (xy 384.014111 -392.784612) (xy 384.044661 -392.82666)
			(xy 384.068257 -392.87297) (xy 384.084318 -392.9224) (xy 384.092448 -392.973735) (xy 384.092958 -392.999722)
			(xy 384.092448 -393.025709) (xy 384.632202 -393.025709) (xy 384.632202 -392.973735) (xy 384.640332 -392.9224)
			(xy 384.656393 -392.87297) (xy 384.679989 -392.82666) (xy 384.710539 -392.784612) (xy 384.74729 -392.747861)
			(xy 384.789338 -392.717311) (xy 384.835648 -392.693715) (xy 384.885078 -392.677654) (xy 384.936413 -392.669524)
			(xy 384.988387 -392.669524) (xy 385.039722 -392.677654) (xy 385.089152 -392.693715) (xy 385.135462 -392.717311)
			(xy 385.17751 -392.747861) (xy 385.214261 -392.784612) (xy 385.244811 -392.82666) (xy 385.268407 -392.87297)
			(xy 385.284468 -392.9224) (xy 385.292598 -392.973735) (xy 385.293108 -392.999722) (xy 385.292598 -393.025709)
			(xy 385.832098 -393.025709) (xy 385.832098 -392.973735) (xy 385.840228 -392.9224) (xy 385.856289 -392.87297)
			(xy 385.879885 -392.82666) (xy 385.910435 -392.784612) (xy 385.947186 -392.747861) (xy 385.989234 -392.717311)
			(xy 386.035544 -392.693715) (xy 386.084974 -392.677654) (xy 386.136309 -392.669524) (xy 386.188283 -392.669524)
			(xy 386.239618 -392.677654) (xy 386.289048 -392.693715) (xy 386.335358 -392.717311) (xy 386.377406 -392.747861)
			(xy 386.414157 -392.784612) (xy 386.444707 -392.82666) (xy 386.468303 -392.87297) (xy 386.484364 -392.9224)
			(xy 386.492494 -392.973735) (xy 386.493004 -392.999722) (xy 386.492494 -393.025709) (xy 387.032248 -393.025709)
			(xy 387.032248 -392.973735) (xy 387.040378 -392.9224) (xy 387.056439 -392.87297) (xy 387.080035 -392.82666)
			(xy 387.110585 -392.784612) (xy 387.147336 -392.747861) (xy 387.189384 -392.717311) (xy 387.235694 -392.693715)
			(xy 387.285124 -392.677654) (xy 387.336459 -392.669524) (xy 387.388433 -392.669524) (xy 387.439768 -392.677654)
			(xy 387.489198 -392.693715) (xy 387.535508 -392.717311) (xy 387.577556 -392.747861) (xy 387.614307 -392.784612)
			(xy 387.644857 -392.82666) (xy 387.668453 -392.87297) (xy 387.684514 -392.9224) (xy 387.692644 -392.973735)
			(xy 387.693154 -392.999722) (xy 387.692644 -393.025709) (xy 388.232144 -393.025709) (xy 388.232144 -392.973735)
			(xy 388.240274 -392.9224) (xy 388.256335 -392.87297) (xy 388.279931 -392.82666) (xy 388.310481 -392.784612)
			(xy 388.347232 -392.747861) (xy 388.38928 -392.717311) (xy 388.43559 -392.693715) (xy 388.48502 -392.677654)
			(xy 388.536355 -392.669524) (xy 388.588329 -392.669524) (xy 388.639664 -392.677654) (xy 388.689094 -392.693715)
			(xy 388.735404 -392.717311) (xy 388.777452 -392.747861) (xy 388.814203 -392.784612) (xy 388.844753 -392.82666)
			(xy 388.868349 -392.87297) (xy 388.88441 -392.9224) (xy 388.89254 -392.973735) (xy 388.89305 -392.999722)
			(xy 388.89254 -393.025709) (xy 388.88441 -393.077044) (xy 388.868349 -393.126474) (xy 388.844753 -393.172784)
			(xy 388.814203 -393.214832) (xy 388.777452 -393.251583) (xy 388.735404 -393.282133) (xy 388.689094 -393.305729)
			(xy 388.639664 -393.32179) (xy 388.588329 -393.32992) (xy 388.536355 -393.32992) (xy 388.48502 -393.32179)
			(xy 388.43559 -393.305729) (xy 388.38928 -393.282133) (xy 388.347232 -393.251583) (xy 388.310481 -393.214832)
			(xy 388.279931 -393.172784) (xy 388.256335 -393.126474) (xy 388.240274 -393.077044) (xy 388.232144 -393.025709)
			(xy 387.692644 -393.025709) (xy 387.684514 -393.077044) (xy 387.668453 -393.126474) (xy 387.644857 -393.172784)
			(xy 387.614307 -393.214832) (xy 387.577556 -393.251583) (xy 387.535508 -393.282133) (xy 387.489198 -393.305729)
			(xy 387.439768 -393.32179) (xy 387.388433 -393.32992) (xy 387.336459 -393.32992) (xy 387.285124 -393.32179)
			(xy 387.235694 -393.305729) (xy 387.189384 -393.282133) (xy 387.147336 -393.251583) (xy 387.110585 -393.214832)
			(xy 387.080035 -393.172784) (xy 387.056439 -393.126474) (xy 387.040378 -393.077044) (xy 387.032248 -393.025709)
			(xy 386.492494 -393.025709) (xy 386.484364 -393.077044) (xy 386.468303 -393.126474) (xy 386.444707 -393.172784)
			(xy 386.414157 -393.214832) (xy 386.377406 -393.251583) (xy 386.335358 -393.282133) (xy 386.289048 -393.305729)
			(xy 386.239618 -393.32179) (xy 386.188283 -393.32992) (xy 386.136309 -393.32992) (xy 386.084974 -393.32179)
			(xy 386.035544 -393.305729) (xy 385.989234 -393.282133) (xy 385.947186 -393.251583) (xy 385.910435 -393.214832)
			(xy 385.879885 -393.172784) (xy 385.856289 -393.126474) (xy 385.840228 -393.077044) (xy 385.832098 -393.025709)
			(xy 385.292598 -393.025709) (xy 385.284468 -393.077044) (xy 385.268407 -393.126474) (xy 385.244811 -393.172784)
			(xy 385.214261 -393.214832) (xy 385.17751 -393.251583) (xy 385.135462 -393.282133) (xy 385.089152 -393.305729)
			(xy 385.039722 -393.32179) (xy 384.988387 -393.32992) (xy 384.936413 -393.32992) (xy 384.885078 -393.32179)
			(xy 384.835648 -393.305729) (xy 384.789338 -393.282133) (xy 384.74729 -393.251583) (xy 384.710539 -393.214832)
			(xy 384.679989 -393.172784) (xy 384.656393 -393.126474) (xy 384.640332 -393.077044) (xy 384.632202 -393.025709)
			(xy 384.092448 -393.025709) (xy 384.084318 -393.077044) (xy 384.068257 -393.126474) (xy 384.044661 -393.172784)
			(xy 384.014111 -393.214832) (xy 383.97736 -393.251583) (xy 383.935312 -393.282133) (xy 383.889002 -393.305729)
			(xy 383.839572 -393.32179) (xy 383.788237 -393.32992) (xy 383.736263 -393.32992) (xy 383.684928 -393.32179)
			(xy 383.635498 -393.305729) (xy 383.589188 -393.282133) (xy 383.54714 -393.251583) (xy 383.510389 -393.214832)
			(xy 383.479839 -393.172784) (xy 383.456243 -393.126474) (xy 383.440182 -393.077044) (xy 383.432052 -393.025709)
			(xy 382.892552 -393.025709) (xy 382.884422 -393.077044) (xy 382.868361 -393.126474) (xy 382.844765 -393.172784)
			(xy 382.814215 -393.214832) (xy 382.777464 -393.251583) (xy 382.735416 -393.282133) (xy 382.689106 -393.305729)
			(xy 382.639676 -393.32179) (xy 382.588341 -393.32992) (xy 382.536367 -393.32992) (xy 382.485032 -393.32179)
			(xy 382.435602 -393.305729) (xy 382.389292 -393.282133) (xy 382.347244 -393.251583) (xy 382.310493 -393.214832)
			(xy 382.279943 -393.172784) (xy 382.256347 -393.126474) (xy 382.240286 -393.077044) (xy 382.232156 -393.025709)
			(xy 381.692656 -393.025709) (xy 381.684526 -393.077044) (xy 381.668465 -393.126474) (xy 381.644869 -393.172784)
			(xy 381.614319 -393.214832) (xy 381.577568 -393.251583) (xy 381.53552 -393.282133) (xy 381.48921 -393.305729)
			(xy 381.43978 -393.32179) (xy 381.388445 -393.32992) (xy 381.336471 -393.32992) (xy 381.285136 -393.32179)
			(xy 381.235706 -393.305729) (xy 381.189396 -393.282133) (xy 381.147348 -393.251583) (xy 381.110597 -393.214832)
			(xy 381.080047 -393.172784) (xy 381.056451 -393.126474) (xy 381.04039 -393.077044) (xy 381.03226 -393.025709)
			(xy 380.492506 -393.025709) (xy 380.484376 -393.077044) (xy 380.468315 -393.126474) (xy 380.444719 -393.172784)
			(xy 380.414169 -393.214832) (xy 380.377418 -393.251583) (xy 380.33537 -393.282133) (xy 380.28906 -393.305729)
			(xy 380.23963 -393.32179) (xy 380.188295 -393.32992) (xy 380.136321 -393.32992) (xy 380.084986 -393.32179)
			(xy 380.035556 -393.305729) (xy 379.989246 -393.282133) (xy 379.947198 -393.251583) (xy 379.910447 -393.214832)
			(xy 379.879897 -393.172784) (xy 379.856301 -393.126474) (xy 379.84024 -393.077044) (xy 379.83211 -393.025709)
			(xy 379.29261 -393.025709) (xy 379.28448 -393.077044) (xy 379.268419 -393.126474) (xy 379.244823 -393.172784)
			(xy 379.214273 -393.214832) (xy 379.177522 -393.251583) (xy 379.135474 -393.282133) (xy 379.089164 -393.305729)
			(xy 379.039734 -393.32179) (xy 378.988399 -393.32992) (xy 378.936425 -393.32992) (xy 378.88509 -393.32179)
			(xy 378.83566 -393.305729) (xy 378.78935 -393.282133) (xy 378.747302 -393.251583) (xy 378.710551 -393.214832)
			(xy 378.680001 -393.172784) (xy 378.656405 -393.126474) (xy 378.640344 -393.077044) (xy 378.632214 -393.025709)
			(xy 378.09246 -393.025709) (xy 378.08433 -393.077044) (xy 378.068269 -393.126474) (xy 378.044673 -393.172784)
			(xy 378.014123 -393.214832) (xy 377.977372 -393.251583) (xy 377.935324 -393.282133) (xy 377.889014 -393.305729)
			(xy 377.839584 -393.32179) (xy 377.788249 -393.32992) (xy 377.736275 -393.32992) (xy 377.68494 -393.32179)
			(xy 377.63551 -393.305729) (xy 377.5892 -393.282133) (xy 377.547152 -393.251583) (xy 377.510401 -393.214832)
			(xy 377.479851 -393.172784) (xy 377.456255 -393.126474) (xy 377.440194 -393.077044) (xy 377.432064 -393.025709)
			(xy 376.892564 -393.025709) (xy 376.884434 -393.077044) (xy 376.868373 -393.126474) (xy 376.844777 -393.172784)
			(xy 376.814227 -393.214832) (xy 376.777476 -393.251583) (xy 376.735428 -393.282133) (xy 376.689118 -393.305729)
			(xy 376.639688 -393.32179) (xy 376.588353 -393.32992) (xy 376.536379 -393.32992) (xy 376.485044 -393.32179)
			(xy 376.435614 -393.305729) (xy 376.389304 -393.282133) (xy 376.347256 -393.251583) (xy 376.310505 -393.214832)
			(xy 376.279955 -393.172784) (xy 376.256359 -393.126474) (xy 376.240298 -393.077044) (xy 376.232168 -393.025709)
			(xy 375.692668 -393.025709) (xy 375.684538 -393.077044) (xy 375.668477 -393.126474) (xy 375.644881 -393.172784)
			(xy 375.614331 -393.214832) (xy 375.57758 -393.251583) (xy 375.535532 -393.282133) (xy 375.489222 -393.305729)
			(xy 375.439792 -393.32179) (xy 375.388457 -393.32992) (xy 375.336483 -393.32992) (xy 375.285148 -393.32179)
			(xy 375.235718 -393.305729) (xy 375.189408 -393.282133) (xy 375.14736 -393.251583) (xy 375.110609 -393.214832)
			(xy 375.080059 -393.172784) (xy 375.056463 -393.126474) (xy 375.040402 -393.077044) (xy 375.032272 -393.025709)
			(xy 374.492518 -393.025709) (xy 374.484388 -393.077044) (xy 374.468327 -393.126474) (xy 374.444731 -393.172784)
			(xy 374.414181 -393.214832) (xy 374.37743 -393.251583) (xy 374.335382 -393.282133) (xy 374.289072 -393.305729)
			(xy 374.239642 -393.32179) (xy 374.188307 -393.32992) (xy 374.136333 -393.32992) (xy 374.084998 -393.32179)
			(xy 374.035568 -393.305729) (xy 373.989258 -393.282133) (xy 373.94721 -393.251583) (xy 373.910459 -393.214832)
			(xy 373.879909 -393.172784) (xy 373.856313 -393.126474) (xy 373.840252 -393.077044) (xy 373.832122 -393.025709)
			(xy 373.292622 -393.025709) (xy 373.284492 -393.077044) (xy 373.268431 -393.126474) (xy 373.244835 -393.172784)
			(xy 373.214285 -393.214832) (xy 373.177534 -393.251583) (xy 373.135486 -393.282133) (xy 373.089176 -393.305729)
			(xy 373.039746 -393.32179) (xy 372.988411 -393.32992) (xy 372.936437 -393.32992) (xy 372.885102 -393.32179)
			(xy 372.835672 -393.305729) (xy 372.789362 -393.282133) (xy 372.747314 -393.251583) (xy 372.710563 -393.214832)
			(xy 372.680013 -393.172784) (xy 372.656417 -393.126474) (xy 372.640356 -393.077044) (xy 372.632226 -393.025709)
			(xy 372.092472 -393.025709) (xy 372.084342 -393.077044) (xy 372.068281 -393.126474) (xy 372.044685 -393.172784)
			(xy 372.014135 -393.214832) (xy 371.977384 -393.251583) (xy 371.935336 -393.282133) (xy 371.889026 -393.305729)
			(xy 371.839596 -393.32179) (xy 371.788261 -393.32992) (xy 371.736287 -393.32992) (xy 371.684952 -393.32179)
			(xy 371.635522 -393.305729) (xy 371.589212 -393.282133) (xy 371.547164 -393.251583) (xy 371.510413 -393.214832)
			(xy 371.479863 -393.172784) (xy 371.456267 -393.126474) (xy 371.440206 -393.077044) (xy 371.432076 -393.025709)
			(xy 370.879738 -393.025709) (xy 370.872077 -393.074074) (xy 370.856633 -393.121606) (xy 370.833943 -393.166138)
			(xy 370.804567 -393.206571) (xy 370.769227 -393.241911) (xy 370.728794 -393.271287) (xy 370.684262 -393.293977)
			(xy 370.63673 -393.309421) (xy 370.587367 -393.31724) (xy 370.537389 -393.31724) (xy 370.488026 -393.309421)
			(xy 370.440494 -393.293977) (xy 370.395962 -393.271287) (xy 370.355529 -393.241911) (xy 370.320189 -393.206571)
			(xy 370.290813 -393.166138) (xy 370.268123 -393.121606) (xy 370.252679 -393.074074) (xy 370.24486 -393.024711)
			(xy 368.669444 -393.024711) (xy 368.622517 -393.047664) (xy 368.597434 -393.055856) (xy 368.58829 -393.05865)
			(xy 368.573558 -393.07008) (xy 368.5286 -393.145772) (xy 368.525552 -393.164314) (xy 368.527584 -393.173712)
			(xy 368.532204 -393.196997) (xy 368.53717 -393.24421) (xy 368.53749 -393.267946) (xy 368.536919 -393.30051)
			(xy 368.527688 -393.36498) (xy 368.509406 -393.427488) (xy 368.482442 -393.486771) (xy 368.447342 -393.541631)
			(xy 368.426492 -393.56665) (xy 368.4209 -393.573735) (xy 368.414643 -393.590652) (xy 368.4143 -393.59967)
			(xy 368.4143 -394.25753) (xy 369.933982 -394.25753) (xy 369.934545 -394.22995) (xy 369.943744 -394.175561)
			(xy 369.95227 -394.149326) (xy 369.955064 -394.141452) (xy 369.955064 -393.99718) (xy 369.955617 -393.980488)
			(xy 369.96425 -393.948238) (xy 369.980924 -393.919315) (xy 370.004506 -393.895684) (xy 370.033395 -393.878951)
			(xy 370.065627 -393.870251) (xy 370.082318 -393.869672) (xy 370.463318 -393.869672) (xy 370.473224 -393.87018)
			(xy 370.485001 -393.870556) (xy 370.506851 -393.861799) (xy 370.515134 -393.853416) (xy 370.576856 -393.784836)
			(xy 370.583206 -393.761976) (xy 370.582444 -393.758166) (xy 370.582444 -393.757404) (xy 370.579319 -393.741331)
			(xy 370.57601 -393.708753) (xy 370.57584 -393.69238) (xy 370.5763 -393.667589) (xy 370.584059 -393.618619)
			(xy 370.599383 -393.571465) (xy 370.621894 -393.52729) (xy 370.651039 -393.487179) (xy 370.6861 -393.452121)
			(xy 370.726213 -393.42298) (xy 370.770391 -393.400472) (xy 370.817546 -393.385152) (xy 370.866517 -393.377397)
			(xy 370.891308 -393.376912) (xy 370.914921 -393.377339) (xy 370.961619 -393.384388) (xy 371.006747 -393.398312)
			(xy 371.049298 -393.418802) (xy 371.088323 -393.445399) (xy 371.122952 -393.477512) (xy 371.152413 -393.514423)
			(xy 371.164612 -393.534646) (xy 371.173832 -393.551159) (xy 371.188736 -393.585921) (xy 371.19433 -393.603988)
			(xy 371.194838 -393.60602) (xy 371.195854 -393.610084) (xy 371.243773 -393.692888) (xy 371.775736 -393.692888)
			(xy 371.775736 -393.69238) (xy 371.7762 -393.66759) (xy 371.783959 -393.61862) (xy 371.799282 -393.571466)
			(xy 371.821794 -393.527291) (xy 371.850938 -393.48718) (xy 371.885999 -393.452123) (xy 371.926111 -393.422981)
			(xy 371.970289 -393.400473) (xy 372.017443 -393.385153) (xy 372.066414 -393.377398) (xy 372.091204 -393.376912)
			(xy 372.116599 -393.377392) (xy 372.166735 -393.385524) (xy 372.214922 -393.401577) (xy 372.259917 -393.425138)
			(xy 372.30056 -393.455599) (xy 372.335803 -393.492173) (xy 372.364735 -393.533918) (xy 372.386611 -393.579756)
			(xy 372.394226 -393.603988) (xy 372.39575 -393.60983) (xy 372.4435 -393.69238) (xy 372.975632 -393.69238)
			(xy 372.976098 -393.667603) (xy 372.983849 -393.618657) (xy 372.999158 -393.571526) (xy 373.021646 -393.527368)
			(xy 373.050763 -393.487269) (xy 373.08579 -393.452215) (xy 373.125868 -393.423069) (xy 373.17001 -393.400547)
			(xy 373.21713 -393.385204) (xy 373.266069 -393.377417) (xy 373.290846 -393.376912) (xy 373.291354 -393.376912)
			(xy 373.316803 -393.377382) (xy 373.367042 -393.385539) (xy 373.415321 -393.401651) (xy 373.460391 -393.425299)
			(xy 373.501084 -393.455871) (xy 373.536345 -393.492575) (xy 373.565261 -393.53446) (xy 373.587083 -393.580441)
			(xy 373.59463 -393.60475) (xy 373.596154 -393.610592) (xy 373.91594 -394.16355) (xy 373.920004 -394.167868)
			(xy 373.936203 -394.185546) (xy 373.963603 -394.224894) (xy 373.984735 -394.267934) (xy 373.999113 -394.313675)
			(xy 374.006406 -394.361065) (xy 374.006872 -394.385038) (xy 374.006872 -394.385546) (xy 374.00611 -394.405866)
			(xy 374.005348 -394.415772) (xy 374.011698 -394.434822) (xy 374.072404 -394.504164) (xy 374.090184 -394.513054)
			(xy 374.100344 -394.513816) (xy 374.125319 -394.516028) (xy 374.174176 -394.527277) (xy 374.220663 -394.546053)
			(xy 374.263629 -394.57189) (xy 374.302008 -394.604149) (xy 374.318784 -394.622782) (xy 374.321243 -394.625558)
			(xy 374.326858 -394.630402) (xy 374.32996 -394.632434) (xy 374.342035 -394.640476) (xy 374.36199 -394.661525)
			(xy 374.376061 -394.686888) (xy 374.383358 -394.71496) (xy 374.383808 -394.729462) (xy 374.383808 -394.7414)
			(xy 374.385332 -394.748004) (xy 374.390524 -394.768376) (xy 374.396134 -394.810042) (xy 374.396508 -394.831062)
			(xy 374.396126 -394.852082) (xy 374.390526 -394.893748) (xy 374.385332 -394.91412) (xy 374.383808 -394.920724)
			(xy 374.383808 -395.034262) (xy 374.383333 -395.04926) (xy 374.375586 -395.078238) (xy 374.36061 -395.104227)
			(xy 374.339423 -395.12546) (xy 374.313466 -395.140492) (xy 374.284505 -395.148301) (xy 374.269508 -395.148816)
			(xy 374.08739 -395.148816) (xy 374.086882 -395.14907) (xy 374.070118 -395.14907) (xy 374.06961 -395.148816)
			(xy 373.888 -395.148816) (xy 373.872972 -395.14832) (xy 373.843936 -395.140552) (xy 373.817895 -395.125543)
			(xy 373.796617 -395.104314) (xy 373.781549 -395.078307) (xy 373.773714 -395.049289) (xy 373.773192 -395.034262)
			(xy 373.773192 -394.920724) (xy 373.771668 -394.91412) (xy 373.766462 -394.893751) (xy 373.760861 -394.852083)
			(xy 373.760492 -394.831062) (xy 373.761254 -394.808456) (xy 373.762016 -394.79855) (xy 373.755666 -394.779246)
			(xy 373.695468 -394.709904) (xy 373.677434 -394.70076) (xy 373.667528 -394.699998) (xy 373.643704 -394.69778)
			(xy 373.597074 -394.687056) (xy 373.552599 -394.669414) (xy 373.511298 -394.645257) (xy 373.474119 -394.615141)
			(xy 373.441913 -394.579756) (xy 373.415421 -394.539914) (xy 373.395248 -394.496527) (xy 373.388128 -394.473684)
			(xy 373.386604 -394.467842) (xy 373.066056 -393.91336) (xy 373.061992 -393.909042) (xy 373.045871 -393.891388)
			(xy 373.018624 -393.852105) (xy 372.997616 -393.809161) (xy 372.983328 -393.763539) (xy 372.976087 -393.716283)
			(xy 372.975632 -393.69238) (xy 372.4435 -393.69238) (xy 372.716044 -394.16355) (xy 372.720108 -394.167868)
			(xy 372.736308 -394.185546) (xy 372.763708 -394.224893) (xy 372.784839 -394.267933) (xy 372.799217 -394.313675)
			(xy 372.80651 -394.361065) (xy 372.806976 -394.385038) (xy 372.806976 -394.385546) (xy 372.806214 -394.405866)
			(xy 372.805452 -394.415772) (xy 372.811802 -394.434822) (xy 372.872508 -394.504164) (xy 372.890288 -394.513054)
			(xy 372.900448 -394.513816) (xy 372.925423 -394.516026) (xy 372.974281 -394.527275) (xy 373.020768 -394.546052)
			(xy 373.063733 -394.57189) (xy 373.102112 -394.604149) (xy 373.118888 -394.622782) (xy 373.121346 -394.625558)
			(xy 373.126962 -394.630402) (xy 373.130064 -394.632434) (xy 373.14214 -394.640475) (xy 373.162095 -394.661525)
			(xy 373.176165 -394.686888) (xy 373.183462 -394.71496) (xy 373.183912 -394.729462) (xy 373.183912 -394.7414)
			(xy 373.185436 -394.748004) (xy 373.190628 -394.768376) (xy 373.196238 -394.810042) (xy 373.196612 -394.831062)
			(xy 373.19623 -394.852082) (xy 373.19063 -394.893748) (xy 373.185436 -394.91412) (xy 373.183912 -394.920724)
			(xy 373.183912 -395.034262) (xy 373.183433 -395.04926) (xy 373.175687 -395.078237) (xy 373.160711 -395.104226)
			(xy 373.139525 -395.125458) (xy 373.113569 -395.140491) (xy 373.084608 -395.1483) (xy 373.069612 -395.148816)
			(xy 372.887494 -395.148816) (xy 372.886986 -395.14907) (xy 372.870222 -395.14907) (xy 372.869714 -395.148816)
			(xy 372.688104 -395.148816) (xy 372.673076 -395.148317) (xy 372.64404 -395.140549) (xy 372.617999 -395.125542)
			(xy 372.596721 -395.104313) (xy 372.581653 -395.078307) (xy 372.573818 -395.049289) (xy 372.573296 -395.034262)
			(xy 372.573296 -394.920724) (xy 372.571772 -394.91412) (xy 372.566566 -394.893751) (xy 372.560965 -394.852083)
			(xy 372.560596 -394.831062) (xy 372.561358 -394.808456) (xy 372.56212 -394.79855) (xy 372.55577 -394.779246)
			(xy 372.495572 -394.709904) (xy 372.477538 -394.70076) (xy 372.467632 -394.699998) (xy 372.443808 -394.697777)
			(xy 372.397179 -394.687054) (xy 372.352704 -394.669412) (xy 372.311403 -394.645256) (xy 372.274223 -394.61514)
			(xy 372.242018 -394.579755) (xy 372.215525 -394.539913) (xy 372.195352 -394.496527) (xy 372.188232 -394.473684)
			(xy 372.186708 -394.467842) (xy 371.866414 -393.914122) (xy 371.86235 -393.909804) (xy 371.846197 -393.892132)
			(xy 371.818878 -393.852816) (xy 371.797809 -393.809825) (xy 371.783474 -393.764146) (xy 371.776201 -393.716826)
			(xy 371.775736 -393.692888) (xy 371.243773 -393.692888) (xy 371.516148 -394.16355) (xy 371.520212 -394.167868)
			(xy 371.536413 -394.185545) (xy 371.563812 -394.224893) (xy 371.584944 -394.267933) (xy 371.599321 -394.313675)
			(xy 371.606614 -394.361064) (xy 371.60708 -394.385038) (xy 371.60708 -394.385546) (xy 371.606318 -394.405866)
			(xy 371.605556 -394.415772) (xy 371.611906 -394.434822) (xy 371.672612 -394.504164) (xy 371.690392 -394.513054)
			(xy 371.700552 -394.513816) (xy 371.725505 -394.516002) (xy 371.774306 -394.52729) (xy 371.820735 -394.546085)
			(xy 371.863647 -394.571923) (xy 371.90198 -394.604164) (xy 371.918738 -394.622782) (xy 371.921202 -394.625553)
			(xy 371.926813 -394.6304) (xy 371.929914 -394.632434) (xy 371.941951 -394.640502) (xy 371.961841 -394.661566)
			(xy 371.975847 -394.686925) (xy 371.983084 -394.714977) (xy 371.983508 -394.729462) (xy 371.983508 -394.7414)
			(xy 371.985286 -394.748004) (xy 371.990479 -394.768376) (xy 371.996088 -394.810042) (xy 371.996462 -394.831062)
			(xy 371.996079 -394.852082) (xy 371.990479 -394.893748) (xy 371.985286 -394.91412) (xy 371.983508 -394.920724)
			(xy 371.983508 -395.034262) (xy 371.983074 -395.049287) (xy 371.975303 -395.078314) (xy 371.960281 -395.104338)
			(xy 371.939032 -395.125586) (xy 371.913006 -395.140606) (xy 371.883979 -395.148375) (xy 371.868954 -395.148816)
			(xy 371.687344 -395.148816) (xy 371.686836 -395.14907) (xy 371.670072 -395.14907) (xy 371.669564 -395.148816)
			(xy 371.487954 -395.148816) (xy 371.472932 -395.148404) (xy 371.443914 -395.140617) (xy 371.417901 -395.125585)
			(xy 371.396664 -395.104332) (xy 371.381651 -395.078308) (xy 371.373885 -395.049284) (xy 371.3734 -395.034262)
			(xy 371.3734 -394.920724) (xy 371.371622 -394.91412) (xy 371.366415 -394.893751) (xy 371.360815 -394.852083)
			(xy 371.360446 -394.831062) (xy 371.361208 -394.808456) (xy 371.36197 -394.798296) (xy 371.355874 -394.7795)
			(xy 371.30228 -394.717524) (xy 371.29536 -394.710254) (xy 371.277443 -394.701245) (xy 371.267482 -394.699998)
			(xy 371.243668 -394.697819) (xy 371.197075 -394.687056) (xy 371.15264 -394.669386) (xy 371.111379 -394.645213)
			(xy 371.074237 -394.615092) (xy 371.042066 -394.579712) (xy 371.015601 -394.539882) (xy 370.995449 -394.496516)
			(xy 370.988336 -394.473684) (xy 370.986812 -394.467842) (xy 370.669312 -393.919202) (xy 370.662454 -393.909804)
			(xy 370.654072 -393.90066) (xy 370.613686 -393.924028) (xy 370.605033 -393.92963) (xy 370.592692 -393.946112)
			(xy 370.587823 -393.966119) (xy 370.589048 -393.976352) (xy 370.590572 -393.996926) (xy 370.590572 -393.997434)
			(xy 370.590572 -394.201904) (xy 370.591334 -394.205714) (xy 370.593237 -394.21852) (xy 370.595275 -394.24433)
			(xy 370.595398 -394.257276) (xy 370.595398 -394.25753) (xy 370.595228 -394.273119) (xy 370.592302 -394.30416)
			(xy 370.589556 -394.319506) (xy 370.589048 -394.321538) (xy 370.585492 -394.338048) (xy 370.584984 -394.339572)
			(xy 370.580493 -394.356211) (xy 370.568534 -394.388535) (xy 370.561108 -394.404088) (xy 370.561108 -394.404342)
			(xy 370.557107 -394.413623) (xy 370.555913 -394.433781) (xy 370.558822 -394.443458) (xy 370.586762 -394.522198)
			(xy 370.600732 -394.537184) (xy 370.61013 -394.541502) (xy 370.630712 -394.551335) (xy 370.669098 -394.575973)
			(xy 370.703589 -394.605822) (xy 370.718842 -394.622782) (xy 370.721306 -394.625553) (xy 370.726917 -394.630401)
			(xy 370.730018 -394.632434) (xy 370.742056 -394.640501) (xy 370.761946 -394.661565) (xy 370.775951 -394.686925)
			(xy 370.783188 -394.714977) (xy 370.783612 -394.729462) (xy 370.783612 -394.7414) (xy 370.78539 -394.748004)
			(xy 370.790581 -394.768377) (xy 370.796192 -394.810042) (xy 370.796566 -394.831062) (xy 370.796186 -394.852082)
			(xy 370.790585 -394.893749) (xy 370.78539 -394.91412) (xy 370.783612 -394.920724) (xy 370.783612 -395.034262)
			(xy 370.783174 -395.049286) (xy 370.775403 -395.078313) (xy 370.760382 -395.104337) (xy 370.739134 -395.125584)
			(xy 370.713109 -395.140605) (xy 370.684082 -395.148375) (xy 370.669058 -395.148816) (xy 370.487448 -395.148816)
			(xy 370.48694 -395.14907) (xy 370.470176 -395.14907) (xy 370.469668 -395.148816) (xy 370.288058 -395.148816)
			(xy 370.273036 -395.1484) (xy 370.244019 -395.140614) (xy 370.218005 -395.125583) (xy 370.196768 -395.104331)
			(xy 370.181755 -395.078307) (xy 370.173989 -395.049284) (xy 370.173504 -395.034262) (xy 370.173504 -394.920724)
			(xy 370.171726 -394.91412) (xy 370.166519 -394.893751) (xy 370.160919 -394.852083) (xy 370.16055 -394.831062)
			(xy 370.160918 -394.810041) (xy 370.166528 -394.768375) (xy 370.171726 -394.748004) (xy 370.173504 -394.7414)
			(xy 370.173504 -394.729462) (xy 370.173703 -394.718867) (xy 370.177534 -394.698029) (xy 370.181124 -394.68806)
			(xy 370.18468 -394.678916) (xy 370.184426 -394.659612) (xy 370.15039 -394.576554) (xy 370.137436 -394.562838)
			(xy 370.128292 -394.558774) (xy 370.103831 -394.547145) (xy 370.058789 -394.517071) (xy 370.019252 -394.480058)
			(xy 369.986275 -394.437095) (xy 369.960742 -394.389332) (xy 369.943335 -394.338047) (xy 369.934519 -394.28461)
			(xy 369.933982 -394.25753) (xy 368.4143 -394.25753) (xy 368.4143 -394.616178) (xy 368.414616 -394.625533)
			(xy 368.421275 -394.643012) (xy 368.427254 -394.650214) (xy 368.443195 -394.668502) (xy 368.47009 -394.708879)
			(xy 368.490781 -394.752759) (xy 368.50482 -394.799197) (xy 368.511905 -394.847191) (xy 368.512344 -394.871448)
			(xy 368.512344 -394.871956) (xy 368.511775 -394.899093) (xy 368.502864 -394.952632) (xy 368.485324 -395.003995)
			(xy 368.472974 -395.028166) (xy 368.46891 -395.035532) (xy 368.466116 -395.051788) (xy 368.478562 -395.129004)
			(xy 368.486436 -395.14399) (xy 368.492278 -395.149578) (xy 368.504304 -395.161884) (xy 368.521921 -395.191427)
			(xy 368.531073 -395.224583) (xy 368.531648 -395.24178) (xy 368.531648 -395.377162) (xy 368.532156 -395.380972)
			(xy 368.533827 -395.393095) (xy 368.535604 -395.417503) (xy 368.535712 -395.42974) (xy 368.535623 -395.441977)
			(xy 368.533845 -395.466387) (xy 368.532156 -395.478508) (xy 368.531648 -395.482318) (xy 368.531648 -395.62278)
			(xy 368.531105 -395.639499) (xy 368.522457 -395.671798) (xy 368.505745 -395.700759) (xy 368.482107 -395.724408)
			(xy 368.453154 -395.741134) (xy 368.420858 -395.749798) (xy 368.40414 -395.750288) (xy 368.287046 -395.750288)
			(xy 368.281204 -395.751558) (xy 368.256138 -395.756993) (xy 368.205004 -395.760961) (xy 368.15387 -395.756993)
			(xy 368.128804 -395.751558) (xy 368.122962 -395.750288) (xy 368.09934 -395.750288) (xy 368.082036 -395.749699)
			(xy 368.048704 -395.74039) (xy 368.019096 -395.722472) (xy 367.995388 -395.697261) (xy 367.986818 -395.682216)
			(xy 367.984823 -395.678579) (xy 367.979842 -395.671945) (xy 367.976912 -395.669008) (xy 367.957874 -395.650171)
			(xy 367.925544 -395.607477) (xy 367.90052 -395.560129) (xy 367.883457 -395.509366) (xy 367.874801 -395.456517)
			(xy 367.874296 -395.42974) (xy 367.874427 -395.417821) (xy 367.876208 -395.394048) (xy 367.877852 -395.382242)
			(xy 367.877852 -395.381988) (xy 367.878862 -395.371113) (xy 367.872661 -395.350193) (xy 367.865914 -395.341602)
			(xy 367.815622 -395.283436) (xy 367.808068 -395.275525) (xy 367.788193 -395.266445) (xy 367.777268 -395.26591)
			(xy 366.461802 -395.26591) (xy 366.451732 -395.266333) (xy 366.433128 -395.274048) (xy 366.425734 -395.280896)
			(xy 365.848646 -395.857984) (xy 365.841808 -395.865385) (xy 365.834097 -395.883984) (xy 365.83366 -395.894052)
			(xy 365.83366 -396.679674) (xy 366.90884 -396.679674) (xy 366.912911 -396.624052) (xy 366.925037 -396.569615)
			(xy 366.94496 -396.517524) (xy 366.972256 -396.468889) (xy 367.006342 -396.424746) (xy 367.046491 -396.386037)
			(xy 367.091849 -396.353586) (xy 367.141449 -396.328085) (xy 367.194233 -396.310078) (xy 367.249076 -396.299948)
			(xy 367.30481 -396.297911) (xy 367.360247 -396.304011) (xy 367.414204 -396.318117) (xy 367.465533 -396.339929)
			(xy 367.513139 -396.368983) (xy 367.556007 -396.404658) (xy 367.593224 -396.446195) (xy 367.623997 -396.492708)
			(xy 367.647669 -396.543205) (xy 367.663737 -396.596612) (xy 367.671857 -396.651788) (xy 367.672338 -396.67815)
			(xy 367.874296 -396.67815) (xy 367.874471 -396.661462) (xy 367.877783 -396.628251) (xy 367.8809 -396.611856)
			(xy 367.881916 -396.606776) (xy 367.881916 -396.571978) (xy 367.882534 -396.554052) (xy 367.892489 -396.519609)
			(xy 367.91161 -396.489281) (xy 367.938395 -396.46545) (xy 367.954306 -396.45717) (xy 367.958308 -396.455144)
			(xy 367.96559 -396.449906) (xy 367.968784 -396.446756) (xy 367.987588 -396.42832) (xy 368.029917 -396.397001)
			(xy 368.076678 -396.372791) (xy 368.126686 -396.356303) (xy 368.178676 -396.347953) (xy 368.205004 -396.347442)
			(xy 368.232826 -396.348016) (xy 368.287684 -396.357336) (xy 368.340206 -396.375712) (xy 368.388909 -396.402626)
			(xy 368.432415 -396.437317) (xy 368.451384 -396.457678) (xy 368.461036 -396.46606) (xy 368.473045 -396.474593)
			(xy 368.493123 -396.496141) (xy 368.507748 -396.521706) (xy 368.516146 -396.549936) (xy 368.517424 -396.564612)
			(xy 368.51971 -396.577058) (xy 368.527153 -396.601667) (xy 368.535187 -396.652445) (xy 368.535712 -396.67815)
			(xy 368.535255 -396.703582) (xy 368.534158 -396.710662) (xy 370.300504 -396.710662) (xy 370.30087 -396.689641)
			(xy 370.306481 -396.647975) (xy 370.31168 -396.627604) (xy 370.313204 -396.621) (xy 370.313204 -396.507462)
			(xy 370.313699 -396.492468) (xy 370.321456 -396.4635) (xy 370.336434 -396.43752) (xy 370.357615 -396.416291)
			(xy 370.383561 -396.401255) (xy 370.412511 -396.393433) (xy 370.427504 -396.392908) (xy 370.609622 -396.392908)
			(xy 370.61013 -396.392654) (xy 370.626894 -396.392654) (xy 370.627402 -396.392908) (xy 370.809012 -396.392908)
			(xy 370.824043 -396.39337) (xy 370.853083 -396.401143) (xy 370.879126 -396.416158) (xy 370.900404 -396.437394)
			(xy 370.91547 -396.463408) (xy 370.923301 -396.492432) (xy 370.92382 -396.507462) (xy 370.92382 -396.621)
			(xy 370.925344 -396.627604) (xy 370.930536 -396.647976) (xy 370.936146 -396.689642) (xy 370.93652 -396.710662)
			(xy 371.5004 -396.710662) (xy 371.500767 -396.689641) (xy 371.506377 -396.647975) (xy 371.511576 -396.627604)
			(xy 371.5131 -396.621) (xy 371.5131 -396.507462) (xy 371.513599 -396.492468) (xy 371.521356 -396.463501)
			(xy 371.536333 -396.437522) (xy 371.557513 -396.416293) (xy 371.583458 -396.401257) (xy 371.612408 -396.393434)
			(xy 371.6274 -396.392908) (xy 371.809518 -396.392908) (xy 371.810026 -396.392654) (xy 371.82679 -396.392654)
			(xy 371.827298 -396.392908) (xy 372.008908 -396.392908) (xy 372.023939 -396.393373) (xy 372.052978 -396.401145)
			(xy 372.079022 -396.416159) (xy 372.1003 -396.437395) (xy 372.115366 -396.463408) (xy 372.123197 -396.492432)
			(xy 372.123716 -396.507462) (xy 372.123716 -396.621) (xy 372.12524 -396.627604) (xy 372.130432 -396.647976)
			(xy 372.136042 -396.689642) (xy 372.136416 -396.710662) (xy 372.70055 -396.710662) (xy 372.700918 -396.689641)
			(xy 372.706528 -396.647975) (xy 372.711726 -396.627604) (xy 372.713504 -396.621) (xy 372.713504 -396.507462)
			(xy 372.714002 -396.492447) (xy 372.721781 -396.463442) (xy 372.736799 -396.437436) (xy 372.758033 -396.416201)
			(xy 372.784038 -396.401182) (xy 372.813043 -396.393403) (xy 372.828058 -396.392908) (xy 373.009668 -396.392908)
			(xy 373.010176 -396.392654) (xy 373.02694 -396.392654) (xy 373.027448 -396.392908) (xy 373.209058 -396.392908)
			(xy 373.224076 -396.393428) (xy 373.25309 -396.401191) (xy 373.279106 -396.4162) (xy 373.300351 -396.43743)
			(xy 373.315378 -396.463436) (xy 373.323161 -396.492445) (xy 373.323612 -396.507462) (xy 373.323612 -396.621)
			(xy 373.32539 -396.627604) (xy 373.330581 -396.647977) (xy 373.336192 -396.689642) (xy 373.336566 -396.710662)
			(xy 373.900446 -396.710662) (xy 373.900814 -396.689641) (xy 373.906424 -396.647975) (xy 373.911622 -396.627604)
			(xy 373.9134 -396.621) (xy 373.9134 -396.507462) (xy 373.913902 -396.492447) (xy 373.92168 -396.463443)
			(xy 373.936698 -396.437437) (xy 373.957931 -396.416202) (xy 373.983935 -396.401184) (xy 374.012939 -396.393403)
			(xy 374.027954 -396.392908) (xy 374.209564 -396.392908) (xy 374.210072 -396.392654) (xy 374.226836 -396.392654)
			(xy 374.227344 -396.392908) (xy 374.408954 -396.392908) (xy 374.423971 -396.393432) (xy 374.452986 -396.401194)
			(xy 374.479002 -396.416201) (xy 374.500247 -396.437431) (xy 374.515274 -396.463436) (xy 374.523057 -396.492445)
			(xy 374.523508 -396.507462) (xy 374.523508 -396.621) (xy 374.525286 -396.627604) (xy 374.530479 -396.647976)
			(xy 374.536088 -396.689642) (xy 374.536462 -396.710662) (xy 374.536462 -396.71117) (xy 374.536292 -396.725795)
			(xy 374.533625 -396.754924) (xy 374.531128 -396.769336) (xy 374.529761 -396.77851) (xy 374.533035 -396.796753)
			(xy 374.537478 -396.804896) (xy 374.553988 -396.83182) (xy 374.559142 -396.839611) (xy 374.573879 -396.851066)
			(xy 374.58269 -396.854172) (xy 374.607568 -396.862245) (xy 374.654448 -396.885432) (xy 374.696861 -396.916034)
			(xy 374.733645 -396.953212) (xy 374.763792 -396.995949) (xy 374.786478 -397.043073) (xy 374.794272 -397.06804)
			(xy 374.795796 -397.073882) (xy 374.89003 -397.236696) (xy 374.92178 -397.249904) (xy 374.938544 -397.245586)
			(xy 374.949186 -397.242153) (xy 374.966265 -397.22776) (xy 374.975624 -397.207481) (xy 374.976136 -397.19631)
			(xy 374.976136 -396.0495) (xy 374.989598 -396.0495) (xy 374.989598 -395.877542) (xy 374.990019 -395.867472)
			(xy 374.99774 -395.848872) (xy 375.004584 -395.841474) (xy 375.068846 -395.777212) (xy 375.075564 -395.769838)
			(xy 375.083191 -395.751423) (xy 375.083253 -395.731492) (xy 375.075741 -395.713029) (xy 375.0691 -395.705584)
			(xy 375.06783 -395.704314) (xy 375.066814 -395.703298) (xy 375.059229 -395.696477) (xy 375.044868 -395.681985)
			(xy 375.038112 -395.674342) (xy 375.035651 -395.671568) (xy 375.030038 -395.666722) (xy 375.026936 -395.66469)
			(xy 375.014871 -395.656634) (xy 374.994915 -395.635589) (xy 374.980842 -395.61023) (xy 374.973541 -395.582162)
			(xy 374.973088 -395.567662) (xy 374.973088 -395.555724) (xy 374.971564 -395.54912) (xy 374.966358 -395.528751)
			(xy 374.960757 -395.487083) (xy 374.960388 -395.466062) (xy 374.960755 -395.445041) (xy 374.966365 -395.403375)
			(xy 374.971564 -395.383004) (xy 374.973088 -395.3764) (xy 374.973088 -395.262862) (xy 374.973755 -395.244744)
			(xy 374.985005 -395.210299) (xy 374.995186 -395.195298) (xy 374.999686 -395.188629) (xy 375.00473 -395.173363)
			(xy 375.005092 -395.165326) (xy 375.005092 -395.131798) (xy 375.00478 -395.123751) (xy 374.999738 -395.108468)
			(xy 374.995186 -395.101826) (xy 374.985103 -395.086774) (xy 374.973845 -395.052363) (xy 374.973088 -395.034262)
			(xy 374.973088 -394.920724) (xy 374.971564 -394.91412) (xy 374.966358 -394.893751) (xy 374.960757 -394.852083)
			(xy 374.960388 -394.831062) (xy 374.96115 -394.808456) (xy 374.961912 -394.798296) (xy 374.955816 -394.7795)
			(xy 374.902222 -394.717524) (xy 374.895287 -394.71027) (xy 374.877381 -394.701253) (xy 374.867424 -394.699998)
			(xy 374.843614 -394.697786) (xy 374.797022 -394.687028) (xy 374.752587 -394.669364) (xy 374.711325 -394.645197)
			(xy 374.674183 -394.61508) (xy 374.642011 -394.579704) (xy 374.615545 -394.539878) (xy 374.595391 -394.496514)
			(xy 374.588278 -394.473684) (xy 374.586754 -394.467842) (xy 374.26646 -393.914122) (xy 374.262396 -393.909804)
			(xy 374.246167 -393.892118) (xy 374.218747 -393.852721) (xy 374.197609 -393.809626) (xy 374.183241 -393.763827)
			(xy 374.175975 -393.71638) (xy 374.175528 -393.69238) (xy 374.175998 -393.667603) (xy 374.183749 -393.618658)
			(xy 374.199057 -393.571527) (xy 374.221546 -393.527369) (xy 374.250662 -393.48727) (xy 374.285689 -393.452216)
			(xy 374.325766 -393.42307) (xy 374.369907 -393.400548) (xy 374.417026 -393.385205) (xy 374.465965 -393.377417)
			(xy 374.490742 -393.376912) (xy 374.49125 -393.376912) (xy 374.516644 -393.377439) (xy 374.566777 -393.385563)
			(xy 374.614963 -393.401609) (xy 374.659958 -393.425162) (xy 374.700602 -393.455616) (xy 374.735845 -393.492185)
			(xy 374.764779 -393.533924) (xy 374.786656 -393.579758) (xy 374.794272 -393.603988) (xy 374.795796 -393.60983)
			(xy 375.11609 -394.16355) (xy 375.120154 -394.167868) (xy 375.13631 -394.185571) (xy 375.163654 -394.22493)
			(xy 375.184733 -394.26797) (xy 375.199065 -394.313703) (xy 375.206318 -394.361076) (xy 375.206768 -394.385038)
			(xy 375.206768 -394.385546) (xy 375.20626 -394.405866) (xy 375.205498 -394.415772) (xy 375.211848 -394.434822)
			(xy 375.272554 -394.504164) (xy 375.290334 -394.513054) (xy 375.300494 -394.513816) (xy 375.325443 -394.516037)
			(xy 375.374243 -394.527317) (xy 375.420673 -394.546103) (xy 375.463585 -394.571933) (xy 375.501921 -394.604167)
			(xy 375.51868 -394.622782) (xy 375.521139 -394.625557) (xy 375.526754 -394.630402) (xy 375.529856 -394.632434)
			(xy 375.54193 -394.640478) (xy 375.561886 -394.661526) (xy 375.575957 -394.686889) (xy 375.583254 -394.714961)
			(xy 375.583704 -394.729462) (xy 375.583704 -394.7414) (xy 375.585228 -394.748004) (xy 375.590419 -394.768376)
			(xy 375.59603 -394.810042) (xy 375.596404 -394.831062) (xy 375.596023 -394.852082) (xy 375.590422 -394.893748)
			(xy 375.585228 -394.91412) (xy 375.583704 -394.920724) (xy 375.583704 -394.980922) (xy 375.58417 -394.990932)
			(xy 375.591838 -395.009425) (xy 375.605997 -395.023577) (xy 375.624494 -395.031235) (xy 375.634504 -395.031722)
			(xy 375.638314 -395.031722) (xy 375.642124 -395.031214) (xy 375.653792 -395.029455) (xy 375.677315 -395.027551)
			(xy 375.689114 -395.027404) (xy 376.122692 -395.027404) (xy 376.132712 -395.026974) (xy 376.151228 -395.019308)
			(xy 376.165401 -395.005138) (xy 376.173072 -394.986624) (xy 376.173492 -394.976604) (xy 376.173492 -394.920724)
			(xy 376.171714 -394.91412) (xy 376.166507 -394.893751) (xy 376.160907 -394.852083) (xy 376.160538 -394.831062)
			(xy 376.1613 -394.808456) (xy 376.162062 -394.79855) (xy 376.155712 -394.779246) (xy 376.095514 -394.709904)
			(xy 376.07748 -394.70076) (xy 376.067574 -394.699998) (xy 376.043754 -394.697743) (xy 375.997126 -394.687026)
			(xy 375.952651 -394.66939) (xy 375.911349 -394.645239) (xy 375.874169 -394.615128) (xy 375.841962 -394.579747)
			(xy 375.815468 -394.539909) (xy 375.795295 -394.496526) (xy 375.788174 -394.473684) (xy 375.78665 -394.467842)
			(xy 375.466356 -393.914122) (xy 375.462292 -393.909804) (xy 375.446063 -393.892118) (xy 375.418642 -393.852721)
			(xy 375.397504 -393.809626) (xy 375.383137 -393.763827) (xy 375.375871 -393.71638) (xy 375.375424 -393.69238)
			(xy 375.375898 -393.667603) (xy 375.383649 -393.618659) (xy 375.398957 -393.571528) (xy 375.421445 -393.52737)
			(xy 375.45056 -393.487271) (xy 375.485587 -393.452218) (xy 375.525664 -393.423072) (xy 375.569804 -393.40055)
			(xy 375.616923 -393.385206) (xy 375.665861 -393.377418) (xy 375.690638 -393.376912) (xy 375.691146 -393.376912)
			(xy 375.716543 -393.377355) (xy 375.76668 -393.385493) (xy 375.814868 -393.401553) (xy 375.859863 -393.425119)
			(xy 375.900506 -393.455585) (xy 375.935747 -393.492164) (xy 375.964678 -393.533913) (xy 375.986553 -393.579754)
			(xy 375.994168 -393.603988) (xy 375.995692 -393.60983) (xy 376.315986 -394.16355) (xy 376.32005 -394.167868)
			(xy 376.336205 -394.185572) (xy 376.363549 -394.224931) (xy 376.384629 -394.267971) (xy 376.39896 -394.313703)
			(xy 376.406214 -394.361076) (xy 376.406664 -394.385038) (xy 376.406664 -394.385546) (xy 376.406156 -394.405866)
			(xy 376.405394 -394.415772) (xy 376.411744 -394.434822) (xy 376.47245 -394.504164) (xy 376.49023 -394.513054)
			(xy 376.50039 -394.513816) (xy 376.525368 -394.516) (xy 376.574226 -394.527257) (xy 376.620713 -394.546039)
			(xy 376.663677 -394.571882) (xy 376.702055 -394.604147) (xy 376.71883 -394.622782) (xy 376.721295 -394.625552)
			(xy 376.726906 -394.6304) (xy 376.730006 -394.632434) (xy 376.742042 -394.640505) (xy 376.761932 -394.661567)
			(xy 376.775939 -394.686926) (xy 376.783176 -394.714977) (xy 376.7836 -394.729462) (xy 376.7836 -394.7414)
			(xy 376.785378 -394.748004) (xy 376.79057 -394.768376) (xy 376.79618 -394.810042) (xy 376.796554 -394.831062)
			(xy 376.796171 -394.852082) (xy 376.790571 -394.893748) (xy 376.785378 -394.91412) (xy 376.7836 -394.920724)
			(xy 376.7836 -394.976604) (xy 376.784085 -394.986612) (xy 376.791746 -395.005104) (xy 376.8059 -395.019256)
			(xy 376.824392 -395.026916) (xy 376.8344 -395.027404) (xy 376.911108 -395.027404) (xy 376.940567 -395.028141)
			(xy 376.998379 -395.039518) (xy 377.025916 -395.05001) (xy 377.035314 -395.05382) (xy 377.336304 -395.05382)
			(xy 377.342662 -395.053639) (xy 377.354999 -395.050566) (xy 377.360688 -395.047724) (xy 377.373388 -395.04112)
			(xy 377.373388 -394.920724) (xy 377.37161 -394.91412) (xy 377.366405 -394.893751) (xy 377.360803 -394.852083)
			(xy 377.360434 -394.831062) (xy 377.361196 -394.808456) (xy 377.361958 -394.798296) (xy 377.355862 -394.7795)
			(xy 377.302268 -394.717524) (xy 377.295352 -394.710249) (xy 377.277432 -394.701243) (xy 377.26747 -394.699998)
			(xy 377.243664 -394.697748) (xy 377.197073 -394.686998) (xy 377.152638 -394.669339) (xy 377.111377 -394.645178)
			(xy 377.074234 -394.615066) (xy 377.04206 -394.579695) (xy 377.015593 -394.539873) (xy 376.995438 -394.496513)
			(xy 376.988324 -394.473684) (xy 376.9868 -394.467842) (xy 376.666506 -393.914122) (xy 376.662442 -393.909804)
			(xy 376.646288 -393.892133) (xy 376.618969 -393.852816) (xy 376.597901 -393.809825) (xy 376.583566 -393.764146)
			(xy 376.576293 -393.716826) (xy 376.575828 -393.692888) (xy 376.575828 -393.69238) (xy 376.5763 -393.66759)
			(xy 376.584058 -393.618621) (xy 376.599382 -393.571468) (xy 376.621892 -393.527293) (xy 376.651036 -393.487183)
			(xy 376.686095 -393.452126) (xy 376.726207 -393.422984) (xy 376.770383 -393.400475) (xy 376.817536 -393.385155)
			(xy 376.866506 -393.377398) (xy 376.891296 -393.376912) (xy 376.916691 -393.377399) (xy 376.966826 -393.38553)
			(xy 377.015013 -393.401582) (xy 377.060008 -393.425142) (xy 377.100652 -393.455601) (xy 377.135894 -393.492175)
			(xy 377.164827 -393.533919) (xy 377.186703 -393.579756) (xy 377.194318 -393.603988) (xy 377.195842 -393.60983)
			(xy 377.516136 -394.16355) (xy 377.5202 -394.167868) (xy 377.536399 -394.185547) (xy 377.563799 -394.224894)
			(xy 377.584931 -394.267934) (xy 377.599309 -394.313675) (xy 377.606602 -394.361065) (xy 377.607068 -394.385038)
			(xy 377.607068 -394.385546) (xy 377.606306 -394.405866) (xy 377.605544 -394.415772) (xy 377.611894 -394.434822)
			(xy 377.6726 -394.504164) (xy 377.69038 -394.513054) (xy 377.70054 -394.513816) (xy 377.725492 -394.516009)
			(xy 377.774293 -394.527296) (xy 377.820722 -394.546089) (xy 377.863634 -394.571925) (xy 377.901968 -394.604165)
			(xy 377.918726 -394.622782) (xy 377.921192 -394.625551) (xy 377.926802 -394.6304) (xy 377.929902 -394.632434)
			(xy 377.941937 -394.640506) (xy 377.961828 -394.661568) (xy 377.975835 -394.686926) (xy 377.983072 -394.714977)
			(xy 377.983496 -394.729462) (xy 377.983496 -394.7414) (xy 377.985274 -394.748004) (xy 377.990466 -394.768376)
			(xy 377.996076 -394.810042) (xy 377.99645 -394.831062) (xy 377.996067 -394.852082) (xy 377.990467 -394.893748)
			(xy 377.985274 -394.91412) (xy 377.983496 -394.920724) (xy 377.983496 -394.958316) (xy 377.983975 -394.968324)
			(xy 377.991639 -394.986816) (xy 378.005794 -395.000968) (xy 378.024288 -395.008628) (xy 378.034296 -395.009116)
			(xy 378.522484 -395.009116) (xy 378.532489 -395.008599) (xy 378.550977 -395.000948) (xy 378.56513 -394.986804)
			(xy 378.572793 -394.96832) (xy 378.573284 -394.958316) (xy 378.573284 -394.920724) (xy 378.57176 -394.91412)
			(xy 378.566554 -394.893751) (xy 378.560953 -394.852083) (xy 378.560584 -394.831062) (xy 378.561346 -394.808456)
			(xy 378.562108 -394.79855) (xy 378.555758 -394.779246) (xy 378.49556 -394.709904) (xy 378.477526 -394.70076)
			(xy 378.46762 -394.699998) (xy 378.443795 -394.697787) (xy 378.397166 -394.687062) (xy 378.35269 -394.669418)
			(xy 378.31139 -394.645261) (xy 378.27421 -394.615144) (xy 378.242005 -394.579758) (xy 378.215512 -394.539915)
			(xy 378.19534 -394.496528) (xy 378.18822 -394.473684) (xy 378.186696 -394.467842) (xy 377.866402 -393.914122)
			(xy 377.862338 -393.909804) (xy 377.846183 -393.892134) (xy 377.818865 -393.852817) (xy 377.797796 -393.809826)
			(xy 377.783462 -393.764146) (xy 377.776189 -393.716826) (xy 377.775724 -393.692888) (xy 377.775724 -393.69238)
			(xy 377.7762 -393.66759) (xy 377.783958 -393.618621) (xy 377.799281 -393.571469) (xy 377.821792 -393.527294)
			(xy 377.850935 -393.487184) (xy 377.885994 -393.452127) (xy 377.926105 -393.422985) (xy 377.97028 -393.400477)
			(xy 378.017433 -393.385155) (xy 378.066402 -393.377399) (xy 378.091192 -393.376912) (xy 378.116587 -393.377402)
			(xy 378.166722 -393.385532) (xy 378.214909 -393.401584) (xy 378.259904 -393.425143) (xy 378.300547 -393.455603)
			(xy 378.33579 -393.492176) (xy 378.364722 -393.533919) (xy 378.386599 -393.579756) (xy 378.394214 -393.603988)
			(xy 378.395738 -393.60983) (xy 378.716032 -394.16355) (xy 378.720096 -394.167868) (xy 378.736294 -394.185548)
			(xy 378.763694 -394.224895) (xy 378.784827 -394.267934) (xy 378.799205 -394.313675) (xy 378.806498 -394.361065)
			(xy 378.806964 -394.385038) (xy 378.806964 -394.385546) (xy 378.806202 -394.405866) (xy 378.80544 -394.415772)
			(xy 378.81179 -394.434822) (xy 378.872496 -394.504164) (xy 378.890276 -394.513054) (xy 378.900436 -394.513816)
			(xy 378.92541 -394.516033) (xy 378.974268 -394.527281) (xy 379.020755 -394.546056) (xy 379.06372 -394.571892)
			(xy 379.102099 -394.60415) (xy 379.118876 -394.622782) (xy 379.121336 -394.625557) (xy 379.12695 -394.630402)
			(xy 379.130052 -394.632434) (xy 379.142125 -394.640479) (xy 379.162081 -394.661527) (xy 379.176153 -394.686889)
			(xy 379.18345 -394.714961) (xy 379.1839 -394.729462) (xy 379.1839 -394.7414) (xy 379.185424 -394.748004)
			(xy 379.190615 -394.768377) (xy 379.196226 -394.810042) (xy 379.1966 -394.831062) (xy 379.196219 -394.852082)
			(xy 379.190618 -394.893748) (xy 379.185424 -394.91412) (xy 379.1839 -394.920724) (xy 379.1839 -394.958316)
			(xy 379.184375 -394.968325) (xy 379.19204 -394.986817) (xy 379.206197 -395.000969) (xy 379.224691 -395.008628)
			(xy 379.2347 -395.009116) (xy 379.72238 -395.009116) (xy 379.732398 -395.008664) (xy 379.750911 -395.001004)
			(xy 379.765084 -394.986842) (xy 379.772757 -394.968334) (xy 379.77318 -394.958316) (xy 379.77318 -394.920724)
			(xy 379.771656 -394.91412) (xy 379.76645 -394.893751) (xy 379.760849 -394.852083) (xy 379.76048 -394.831062)
			(xy 379.761242 -394.808456) (xy 379.762004 -394.79855) (xy 379.755654 -394.779246) (xy 379.695456 -394.709904)
			(xy 379.677422 -394.70076) (xy 379.667516 -394.699998) (xy 379.643691 -394.69779) (xy 379.597061 -394.687064)
			(xy 379.552586 -394.66942) (xy 379.511285 -394.645262) (xy 379.474106 -394.615145) (xy 379.441901 -394.579759)
			(xy 379.415408 -394.539915) (xy 379.395236 -394.496528) (xy 379.388116 -394.473684) (xy 379.386592 -394.467842)
			(xy 379.066044 -393.91336) (xy 379.06198 -393.909042) (xy 379.045857 -393.89139) (xy 379.01861 -393.852106)
			(xy 378.997603 -393.809162) (xy 378.983315 -393.763539) (xy 378.976075 -393.716283) (xy 378.97562 -393.69238)
			(xy 378.976098 -393.667603) (xy 378.983849 -393.618659) (xy 378.999156 -393.571529) (xy 379.021644 -393.527371)
			(xy 379.050759 -393.487273) (xy 379.085785 -393.452219) (xy 379.125861 -393.423073) (xy 379.170001 -393.400551)
			(xy 379.21712 -393.385207) (xy 379.266057 -393.377418) (xy 379.290834 -393.376912) (xy 379.291342 -393.376912)
			(xy 379.31679 -393.377392) (xy 379.367029 -393.385548) (xy 379.415308 -393.401658) (xy 379.460378 -393.425304)
			(xy 379.501071 -393.455875) (xy 379.536332 -393.492577) (xy 379.565248 -393.534461) (xy 379.587071 -393.580442)
			(xy 379.594618 -393.60475) (xy 379.596142 -393.610592) (xy 379.915928 -394.16355) (xy 379.919992 -394.167868)
			(xy 379.936189 -394.185548) (xy 379.96359 -394.224895) (xy 379.984723 -394.267934) (xy 379.999101 -394.313675)
			(xy 380.006394 -394.361065) (xy 380.00686 -394.385038) (xy 380.00686 -394.385546) (xy 380.006098 -394.405866)
			(xy 380.005336 -394.415772) (xy 380.011686 -394.434822) (xy 380.072392 -394.504164) (xy 380.090172 -394.513054)
			(xy 380.100332 -394.513816) (xy 380.125306 -394.516036) (xy 380.174163 -394.527283) (xy 380.22065 -394.546057)
			(xy 380.263616 -394.571893) (xy 380.301995 -394.60415) (xy 380.318772 -394.622782) (xy 380.321232 -394.625556)
			(xy 380.326846 -394.630402) (xy 380.329948 -394.632434) (xy 380.34202 -394.64048) (xy 380.361977 -394.661527)
			(xy 380.376049 -394.686889) (xy 380.383346 -394.714961) (xy 380.383796 -394.729462) (xy 380.383796 -394.7414)
			(xy 380.38532 -394.748004) (xy 380.390511 -394.768377) (xy 380.396122 -394.810042) (xy 380.396496 -394.831062)
			(xy 380.396115 -394.852082) (xy 380.390514 -394.893748) (xy 380.38532 -394.91412) (xy 380.383796 -394.920724)
			(xy 380.383796 -394.958316) (xy 380.384275 -394.968324) (xy 380.391939 -394.986816) (xy 380.406094 -395.000968)
			(xy 380.424588 -395.008628) (xy 380.434596 -395.009116) (xy 380.934722 -395.009116) (xy 380.944338 -395.009231)
			(xy 380.963529 -395.010502) (xy 380.973076 -395.011656) (xy 380.973076 -394.920724) (xy 380.971552 -394.91412)
			(xy 380.966346 -394.893751) (xy 380.960745 -394.852083) (xy 380.960376 -394.831062) (xy 380.961138 -394.808456)
			(xy 380.9619 -394.798296) (xy 380.955804 -394.7795) (xy 380.90221 -394.717524) (xy 380.895279 -394.710266)
			(xy 380.87737 -394.70125) (xy 380.867412 -394.699998) (xy 380.843601 -394.697795) (xy 380.797009 -394.687036)
			(xy 380.752573 -394.66937) (xy 380.711312 -394.645201) (xy 380.67417 -394.615083) (xy 380.641998 -394.579706)
			(xy 380.615532 -394.539879) (xy 380.595379 -394.496515) (xy 380.588266 -394.473684) (xy 380.586742 -394.467842)
			(xy 380.266448 -393.914122) (xy 380.262384 -393.909804) (xy 380.246153 -393.892119) (xy 380.218733 -393.852722)
			(xy 380.197596 -393.809626) (xy 380.183229 -393.763827) (xy 380.175963 -393.71638) (xy 380.175516 -393.69238)
			(xy 380.175998 -393.667603) (xy 380.183749 -393.61866) (xy 380.199056 -393.57153) (xy 380.221543 -393.527373)
			(xy 380.250658 -393.487274) (xy 380.285684 -393.452221) (xy 380.325759 -393.423074) (xy 380.369898 -393.400552)
			(xy 380.417016 -393.385207) (xy 380.465954 -393.377418) (xy 380.49073 -393.376912) (xy 380.491238 -393.376912)
			(xy 380.516634 -393.377362) (xy 380.566771 -393.385499) (xy 380.614959 -393.401558) (xy 380.659954 -393.425123)
			(xy 380.700597 -393.455588) (xy 380.735839 -393.492166) (xy 380.76477 -393.533914) (xy 380.786645 -393.579755)
			(xy 380.79426 -393.603988) (xy 380.795784 -393.60983) (xy 381.116078 -394.16355) (xy 381.120142 -394.167868)
			(xy 381.136296 -394.185573) (xy 381.16364 -394.224931) (xy 381.18472 -394.267971) (xy 381.199052 -394.313703)
			(xy 381.206306 -394.361076) (xy 381.206756 -394.385038) (xy 381.206756 -394.385546) (xy 381.206248 -394.405866)
			(xy 381.205486 -394.415772) (xy 381.211836 -394.434822) (xy 381.272542 -394.504164) (xy 381.290322 -394.513054)
			(xy 381.300482 -394.513816) (xy 381.32543 -394.516044) (xy 381.37423 -394.527322) (xy 381.42066 -394.546107)
			(xy 381.463573 -394.571935) (xy 381.501909 -394.604168) (xy 381.518668 -394.622782) (xy 381.521129 -394.625556)
			(xy 381.526742 -394.630402) (xy 381.529844 -394.632434) (xy 381.541916 -394.640481) (xy 381.561872 -394.661528)
			(xy 381.575945 -394.68689) (xy 381.583242 -394.714961) (xy 381.583692 -394.729462) (xy 381.583692 -394.7414)
			(xy 381.585216 -394.748004) (xy 381.590407 -394.768377) (xy 381.596018 -394.810042) (xy 381.596392 -394.831062)
			(xy 381.596011 -394.852082) (xy 381.59041 -394.893748) (xy 381.585216 -394.91412) (xy 381.583692 -394.920724)
			(xy 381.583692 -395.00302) (xy 381.584171 -395.013028) (xy 381.591836 -395.031519) (xy 381.605991 -395.045671)
			(xy 381.624484 -395.053331) (xy 381.634492 -395.05382) (xy 381.973582 -395.05382) (xy 381.986028 -395.050518)
			(xy 381.991616 -395.04747) (xy 382.018683 -395.033318) (xy 382.076905 -395.014889) (xy 382.107186 -395.010894)
			(xy 382.116029 -395.009592) (xy 382.132026 -395.001639) (xy 382.138428 -394.9954) (xy 382.15951 -394.973302)
			(xy 382.165869 -394.965967) (xy 382.173051 -394.947948) (xy 382.17348 -394.93825) (xy 382.17348 -394.920724)
			(xy 382.171702 -394.91412) (xy 382.166496 -394.893751) (xy 382.160895 -394.852083) (xy 382.160526 -394.831062)
			(xy 382.161288 -394.808456) (xy 382.16205 -394.79855) (xy 382.1557 -394.779246) (xy 382.095502 -394.709904)
			(xy 382.077468 -394.70076) (xy 382.067562 -394.699998) (xy 382.043741 -394.697753) (xy 381.997112 -394.687034)
			(xy 381.952637 -394.669396) (xy 381.911336 -394.645244) (xy 381.874156 -394.615131) (xy 381.84195 -394.57975)
			(xy 381.815456 -394.53991) (xy 381.795283 -394.496526) (xy 381.788162 -394.473684) (xy 381.786638 -394.467842)
			(xy 381.466344 -393.914122) (xy 381.46228 -393.909804) (xy 381.446049 -393.89212) (xy 381.418629 -393.852722)
			(xy 381.397492 -393.809627) (xy 381.383124 -393.763827) (xy 381.375859 -393.71638) (xy 381.375412 -393.69238)
			(xy 381.375898 -393.667604) (xy 381.383649 -393.61866) (xy 381.398956 -393.571531) (xy 381.421443 -393.527374)
			(xy 381.450557 -393.487275) (xy 381.485582 -393.452222) (xy 381.525657 -393.423076) (xy 381.569796 -393.400553)
			(xy 381.616913 -393.385208) (xy 381.66585 -393.377418) (xy 381.690626 -393.376912) (xy 381.691134 -393.376912)
			(xy 381.71653 -393.377365) (xy 381.766667 -393.385502) (xy 381.814855 -393.40156) (xy 381.85985 -393.425125)
			(xy 381.900493 -393.455589) (xy 381.935734 -393.492167) (xy 381.964666 -393.533914) (xy 381.986541 -393.579755)
			(xy 381.994156 -393.603988) (xy 381.99568 -393.60983) (xy 382.043724 -393.692888) (xy 382.575816 -393.692888)
			(xy 382.575816 -393.69238) (xy 382.576299 -393.667591) (xy 382.584058 -393.618623) (xy 382.59938 -393.571471)
			(xy 382.62189 -393.527297) (xy 382.651032 -393.487187) (xy 382.68609 -393.45213) (xy 382.7262 -393.422988)
			(xy 382.770375 -393.400479) (xy 382.817527 -393.385157) (xy 382.866495 -393.377399) (xy 382.891284 -393.376912)
			(xy 382.916679 -393.377409) (xy 382.966813 -393.385538) (xy 383.015 -393.401589) (xy 383.059995 -393.425147)
			(xy 383.100639 -393.455605) (xy 383.135881 -393.492177) (xy 383.164814 -393.53392) (xy 383.186691 -393.579757)
			(xy 383.194306 -393.603988) (xy 383.19583 -393.60983) (xy 383.243874 -393.692888) (xy 383.775712 -393.692888)
			(xy 383.775712 -393.69238) (xy 383.776199 -393.667591) (xy 383.783958 -393.618623) (xy 383.79928 -393.571472)
			(xy 383.821789 -393.527298) (xy 383.850931 -393.487188) (xy 383.885988 -393.452131) (xy 383.926098 -393.422989)
			(xy 383.970272 -393.40048) (xy 384.017423 -393.385158) (xy 384.066391 -393.377399) (xy 384.09118 -393.376912)
			(xy 384.116575 -393.377413) (xy 384.166709 -393.385541) (xy 384.214896 -393.401591) (xy 384.259891 -393.425149)
			(xy 384.300534 -393.455606) (xy 384.335777 -393.492178) (xy 384.36471 -393.533921) (xy 384.386587 -393.579757)
			(xy 384.394202 -393.603988) (xy 384.395726 -393.60983) (xy 384.443476 -393.69238) (xy 384.975608 -393.69238)
			(xy 384.976098 -393.667604) (xy 384.983849 -393.618661) (xy 384.999155 -393.571532) (xy 385.021642 -393.527375)
			(xy 385.050756 -393.487277) (xy 385.08578 -393.452223) (xy 385.125855 -393.423077) (xy 385.169993 -393.400554)
			(xy 385.21711 -393.385209) (xy 385.266046 -393.377419) (xy 385.290822 -393.376912) (xy 385.29133 -393.376912)
			(xy 385.316778 -393.377403) (xy 385.367016 -393.385557) (xy 385.415295 -393.401665) (xy 385.460365 -393.42531)
			(xy 385.501058 -393.455879) (xy 385.536319 -393.49258) (xy 385.565236 -393.534463) (xy 385.587059 -393.580442)
			(xy 385.594606 -393.60475) (xy 385.59613 -393.610592) (xy 385.64343 -393.69238) (xy 386.175504 -393.69238)
			(xy 386.175998 -393.667604) (xy 386.183748 -393.618661) (xy 386.199055 -393.571533) (xy 386.221541 -393.527376)
			(xy 386.250654 -393.487278) (xy 386.285679 -393.452225) (xy 386.325752 -393.423078) (xy 386.36989 -393.400555)
			(xy 386.417006 -393.38521) (xy 386.465942 -393.377419) (xy 386.490718 -393.376912) (xy 386.491226 -393.376912)
			(xy 386.516622 -393.377372) (xy 386.566758 -393.385508) (xy 386.614946 -393.401564) (xy 386.659941 -393.425128)
			(xy 386.700584 -393.455592) (xy 386.735826 -393.492168) (xy 386.764758 -393.533915) (xy 386.786633 -393.579755)
			(xy 386.794248 -393.603988) (xy 386.795772 -393.60983) (xy 386.843522 -393.69238) (xy 387.375908 -393.69238)
			(xy 387.376399 -393.667591) (xy 387.384158 -393.618624) (xy 387.39948 -393.571473) (xy 387.421989 -393.527299)
			(xy 387.45113 -393.48719) (xy 387.486187 -393.452133) (xy 387.526296 -393.422991) (xy 387.570469 -393.400481)
			(xy 387.61762 -393.385159) (xy 387.666587 -393.3774) (xy 387.691376 -393.376912) (xy 387.716825 -393.377362)
			(xy 387.767065 -393.385523) (xy 387.815345 -393.401638) (xy 387.860415 -393.425289) (xy 387.901107 -393.455864)
			(xy 387.936368 -393.49257) (xy 387.965284 -393.534457) (xy 387.987105 -393.580441) (xy 387.994652 -393.60475)
			(xy 387.996176 -393.610592) (xy 388.043769 -393.692888) (xy 388.575804 -393.692888) (xy 388.575804 -393.69238)
			(xy 388.576299 -393.667591) (xy 388.584057 -393.618624) (xy 388.599379 -393.571474) (xy 388.621888 -393.5273)
			(xy 388.651029 -393.487191) (xy 388.686085 -393.452134) (xy 388.726193 -393.422992) (xy 388.770366 -393.400482)
			(xy 388.817517 -393.385159) (xy 388.866483 -393.3774) (xy 388.891272 -393.376912) (xy 388.916666 -393.37742)
			(xy 388.966801 -393.385547) (xy 389.014987 -393.401596) (xy 389.059982 -393.425152) (xy 389.100626 -393.455609)
			(xy 389.135868 -393.49218) (xy 389.164802 -393.533922) (xy 389.186678 -393.579757) (xy 389.194294 -393.603988)
			(xy 389.195818 -393.60983) (xy 389.516112 -394.16355) (xy 389.520176 -394.167868) (xy 389.536371 -394.185551)
			(xy 389.563772 -394.224896) (xy 389.584906 -394.267935) (xy 389.599285 -394.313675) (xy 389.606578 -394.361065)
			(xy 389.607044 -394.385038) (xy 389.607044 -394.385546) (xy 389.606282 -394.405612) (xy 389.606104 -394.415661)
			(xy 389.612638 -394.434648) (xy 389.618982 -394.442442) (xy 389.673592 -394.504164) (xy 389.691626 -394.513054)
			(xy 389.701786 -394.513562) (xy 389.727163 -394.515542) (xy 389.776869 -394.52649) (xy 389.824198 -394.545212)
			(xy 389.867942 -394.571231) (xy 389.906985 -394.603884) (xy 389.924036 -394.622782) (xy 389.926501 -394.625552)
			(xy 389.932111 -394.6304) (xy 389.935212 -394.632434) (xy 389.947276 -394.640491) (xy 389.967236 -394.661533)
			(xy 389.981311 -394.686892) (xy 389.988609 -394.714962) (xy 389.98906 -394.729462) (xy 389.98906 -394.7414)
			(xy 389.990584 -394.748004) (xy 389.995777 -394.768376) (xy 390.001386 -394.810042) (xy 390.00176 -394.831062)
			(xy 390.001377 -394.852082) (xy 389.995777 -394.893748) (xy 389.990584 -394.91412) (xy 389.98906 -394.920724)
			(xy 389.98906 -395.034262) (xy 389.988534 -395.049256) (xy 389.980792 -395.078226) (xy 389.965824 -395.10421)
			(xy 389.944647 -395.125441) (xy 389.918702 -395.140477) (xy 389.889752 -395.148294) (xy 389.87476 -395.148816)
			(xy 389.692642 -395.148816) (xy 389.692134 -395.14907) (xy 389.67537 -395.14907) (xy 389.674862 -395.148816)
			(xy 389.493252 -395.148816) (xy 389.478221 -395.148362) (xy 389.449184 -395.140582) (xy 389.423143 -395.125564)
			(xy 389.401867 -395.104328) (xy 389.3868 -395.078314) (xy 389.378966 -395.049292) (xy 389.378444 -395.034262)
			(xy 389.378444 -394.920724) (xy 389.37692 -394.91412) (xy 389.371713 -394.893751) (xy 389.366113 -394.852083)
			(xy 389.365744 -394.831062) (xy 389.366506 -394.80871) (xy 389.367268 -394.79855) (xy 389.360918 -394.7795)
			(xy 389.299704 -394.70965) (xy 389.28167 -394.70076) (xy 389.27151 -394.700252) (xy 389.247421 -394.69832)
			(xy 389.200215 -394.687984) (xy 389.155136 -394.67057) (xy 389.113241 -394.646486) (xy 389.075508 -394.616295)
			(xy 389.04282 -394.580703) (xy 389.015943 -394.540542) (xy 388.995504 -394.496752) (xy 388.9883 -394.473684)
			(xy 388.986776 -394.467842) (xy 388.666482 -393.914122) (xy 388.662418 -393.909804) (xy 388.64626 -393.892137)
			(xy 388.618943 -393.852819) (xy 388.597875 -393.809827) (xy 388.583541 -393.764147) (xy 388.576269 -393.716826)
			(xy 388.575804 -393.692888) (xy 388.043769 -393.692888) (xy 388.315962 -394.16355) (xy 388.320026 -394.167868)
			(xy 388.336177 -394.185575) (xy 388.363523 -394.224933) (xy 388.384604 -394.267972) (xy 388.398936 -394.313703)
			(xy 388.40619 -394.361076) (xy 388.40664 -394.385038) (xy 388.40664 -394.385546) (xy 388.406132 -394.405866)
			(xy 388.40537 -394.415772) (xy 388.41172 -394.434822) (xy 388.472426 -394.504164) (xy 388.490206 -394.513054)
			(xy 388.500366 -394.513816) (xy 388.525342 -394.516015) (xy 388.5742 -394.527267) (xy 388.620687 -394.546046)
			(xy 388.663652 -394.571887) (xy 388.70203 -394.604148) (xy 388.718806 -394.622782) (xy 388.721275 -394.625549)
			(xy 388.726883 -394.630399) (xy 388.729982 -394.632434) (xy 388.742013 -394.640512) (xy 388.761905 -394.661571)
			(xy 388.775914 -394.686927) (xy 388.783152 -394.714978) (xy 388.783576 -394.729462) (xy 388.783576 -394.7414)
			(xy 388.785354 -394.748004) (xy 388.790546 -394.768376) (xy 388.796156 -394.810042) (xy 388.79653 -394.831062)
			(xy 388.796148 -394.852082) (xy 388.790548 -394.893748) (xy 388.785354 -394.91412) (xy 388.783576 -394.920724)
			(xy 388.783576 -395.034262) (xy 388.783075 -395.049281) (xy 388.77531 -395.078298) (xy 388.760298 -395.104316)
			(xy 388.739064 -395.125561) (xy 388.713054 -395.140587) (xy 388.684041 -395.148367) (xy 388.669022 -395.148816)
			(xy 388.487412 -395.148816) (xy 388.486904 -395.14907) (xy 388.47014 -395.14907) (xy 388.469632 -395.148816)
			(xy 388.288022 -395.148816) (xy 388.272997 -395.148388) (xy 388.243971 -395.140614) (xy 388.217947 -395.12559)
			(xy 388.1967 -395.10434) (xy 388.18168 -395.078314) (xy 388.17391 -395.049287) (xy 388.173468 -395.034262)
			(xy 388.173468 -394.920724) (xy 388.17169 -394.91412) (xy 388.166484 -394.893751) (xy 388.160883 -394.852083)
			(xy 388.160514 -394.831062) (xy 388.161276 -394.808456) (xy 388.162038 -394.79855) (xy 388.155688 -394.779246)
			(xy 388.09549 -394.709904) (xy 388.077456 -394.70076) (xy 388.06755 -394.699998) (xy 388.043728 -394.697763)
			(xy 387.997099 -394.687042) (xy 387.952624 -394.669402) (xy 387.911323 -394.645249) (xy 387.874143 -394.615135)
			(xy 387.841937 -394.579752) (xy 387.815443 -394.539911) (xy 387.79527 -394.496527) (xy 387.78815 -394.473684)
			(xy 387.786626 -394.467842) (xy 387.466078 -393.91336) (xy 387.462014 -393.909042) (xy 387.445932 -393.891367)
			(xy 387.418742 -393.852071) (xy 387.397788 -393.809126) (xy 387.383547 -393.763512) (xy 387.376346 -393.716273)
			(xy 387.375908 -393.69238) (xy 386.843522 -393.69238) (xy 387.116066 -394.16355) (xy 387.12013 -394.167868)
			(xy 387.136282 -394.185575) (xy 387.163627 -394.224932) (xy 387.184708 -394.267972) (xy 387.19904 -394.313703)
			(xy 387.206294 -394.361076) (xy 387.206744 -394.385038) (xy 387.206744 -394.385546) (xy 387.206236 -394.405866)
			(xy 387.205474 -394.415772) (xy 387.211824 -394.434822) (xy 387.27253 -394.504164) (xy 387.29031 -394.513054)
			(xy 387.30047 -394.513816) (xy 387.325447 -394.516013) (xy 387.374304 -394.527266) (xy 387.420791 -394.546045)
			(xy 387.463756 -394.571886) (xy 387.502134 -394.604148) (xy 387.51891 -394.622782) (xy 387.521378 -394.625549)
			(xy 387.526986 -394.630399) (xy 387.530086 -394.632434) (xy 387.542117 -394.640511) (xy 387.56201 -394.66157)
			(xy 387.576018 -394.686927) (xy 387.583256 -394.714978) (xy 387.58368 -394.729462) (xy 387.58368 -394.7414)
			(xy 387.585458 -394.748004) (xy 387.59065 -394.768376) (xy 387.59626 -394.810042) (xy 387.596634 -394.831062)
			(xy 387.596252 -394.852082) (xy 387.590652 -394.893748) (xy 387.585458 -394.91412) (xy 387.58368 -394.920724)
			(xy 387.58368 -395.034262) (xy 387.583175 -395.049281) (xy 387.57541 -395.078297) (xy 387.560399 -395.104314)
			(xy 387.539165 -395.12556) (xy 387.513156 -395.140585) (xy 387.484145 -395.148367) (xy 387.469126 -395.148816)
			(xy 387.287516 -395.148816) (xy 387.287008 -395.14907) (xy 387.270244 -395.14907) (xy 387.269736 -395.148816)
			(xy 387.088126 -395.148816) (xy 387.073101 -395.148385) (xy 387.044075 -395.140611) (xy 387.018051 -395.125588)
			(xy 386.996805 -395.104339) (xy 386.981784 -395.078314) (xy 386.974014 -395.049287) (xy 386.973572 -395.034262)
			(xy 386.973572 -394.920724) (xy 386.971794 -394.91412) (xy 386.966588 -394.893751) (xy 386.960987 -394.852083)
			(xy 386.960618 -394.831062) (xy 386.96138 -394.808456) (xy 386.962142 -394.79855) (xy 386.955792 -394.779246)
			(xy 386.895594 -394.709904) (xy 386.87756 -394.70076) (xy 386.867654 -394.699998) (xy 386.843832 -394.697759)
			(xy 386.797203 -394.687039) (xy 386.752728 -394.6694) (xy 386.711427 -394.645247) (xy 386.674247 -394.615134)
			(xy 386.642041 -394.579751) (xy 386.615548 -394.539911) (xy 386.595374 -394.496527) (xy 386.588254 -394.473684)
			(xy 386.58673 -394.467842) (xy 386.266436 -393.914122) (xy 386.262372 -393.909804) (xy 386.246139 -393.892121)
			(xy 386.21872 -393.852723) (xy 386.197583 -393.809627) (xy 386.183216 -393.763827) (xy 386.175951 -393.71638)
			(xy 386.175504 -393.69238) (xy 385.64343 -393.69238) (xy 385.915916 -394.16355) (xy 385.91998 -394.167868)
			(xy 385.936175 -394.18555) (xy 385.963577 -394.224896) (xy 385.98471 -394.267935) (xy 385.999089 -394.313675)
			(xy 386.006382 -394.361065) (xy 386.006848 -394.385038) (xy 386.006848 -394.385546) (xy 386.006086 -394.405866)
			(xy 386.005324 -394.415772) (xy 386.011674 -394.434822) (xy 386.07238 -394.504164) (xy 386.09016 -394.513054)
			(xy 386.10032 -394.513816) (xy 386.1253 -394.515982) (xy 386.174158 -394.527243) (xy 386.220645 -394.54603)
			(xy 386.263609 -394.571877) (xy 386.301985 -394.604145) (xy 386.31876 -394.622782) (xy 386.321222 -394.625555)
			(xy 386.326834 -394.630401) (xy 386.329936 -394.632434) (xy 386.342006 -394.640484) (xy 386.361963 -394.66153)
			(xy 386.376036 -394.68689) (xy 386.383333 -394.714961) (xy 386.383784 -394.729462) (xy 386.383784 -394.7414)
			(xy 386.385308 -394.748004) (xy 386.390499 -394.768377) (xy 386.39611 -394.810042) (xy 386.396484 -394.831062)
			(xy 386.396103 -394.852082) (xy 386.390502 -394.893749) (xy 386.385308 -394.91412) (xy 386.383784 -394.920724)
			(xy 386.383784 -395.034262) (xy 386.383234 -395.049254) (xy 386.375494 -395.07822) (xy 386.36053 -395.104202)
			(xy 386.339358 -395.125433) (xy 386.313419 -395.14047) (xy 386.284474 -395.148292) (xy 386.269484 -395.148816)
			(xy 386.087366 -395.148816) (xy 386.086858 -395.14907) (xy 386.070094 -395.14907) (xy 386.069586 -395.148816)
			(xy 385.887976 -395.148816) (xy 385.872947 -395.148341) (xy 385.84391 -395.140567) (xy 385.817869 -395.125554)
			(xy 385.796592 -395.104321) (xy 385.781524 -395.078311) (xy 385.77369 -395.04929) (xy 385.773168 -395.034262)
			(xy 385.773168 -394.920724) (xy 385.771644 -394.91412) (xy 385.766437 -394.893751) (xy 385.760837 -394.852083)
			(xy 385.760468 -394.831062) (xy 385.76123 -394.808456) (xy 385.761992 -394.79855) (xy 385.755642 -394.779246)
			(xy 385.695444 -394.709904) (xy 385.67741 -394.70076) (xy 385.667504 -394.699998) (xy 385.643678 -394.6978)
			(xy 385.597048 -394.687072) (xy 385.552573 -394.669426) (xy 385.511272 -394.645267) (xy 385.474093 -394.615148)
			(xy 385.441888 -394.579761) (xy 385.415396 -394.539916) (xy 385.395224 -394.496528) (xy 385.388104 -394.473684)
			(xy 385.38658 -394.467842) (xy 385.066032 -393.91336) (xy 385.061968 -393.909042) (xy 385.045843 -393.891391)
			(xy 385.018597 -393.852107) (xy 384.99759 -393.809162) (xy 384.983303 -393.76354) (xy 384.976063 -393.716284)
			(xy 384.975608 -393.69238) (xy 384.443476 -393.69238) (xy 384.71602 -394.16355) (xy 384.720084 -394.167868)
			(xy 384.73628 -394.185549) (xy 384.763681 -394.224896) (xy 384.784814 -394.267935) (xy 384.799193 -394.313675)
			(xy 384.806486 -394.361065) (xy 384.806952 -394.385038) (xy 384.806952 -394.385546) (xy 384.80619 -394.405866)
			(xy 384.805428 -394.415772) (xy 384.811778 -394.434822) (xy 384.872484 -394.504164) (xy 384.890264 -394.513054)
			(xy 384.900424 -394.513816) (xy 384.925404 -394.51598) (xy 384.974263 -394.527241) (xy 385.02075 -394.546029)
			(xy 385.063713 -394.571877) (xy 385.102089 -394.604145) (xy 385.118864 -394.622782) (xy 385.121325 -394.625556)
			(xy 385.126938 -394.630402) (xy 385.13004 -394.632434) (xy 385.142111 -394.640482) (xy 385.162068 -394.661529)
			(xy 385.17614 -394.68689) (xy 385.183438 -394.714961) (xy 385.183888 -394.729462) (xy 385.183888 -394.7414)
			(xy 385.185412 -394.748004) (xy 385.190603 -394.768377) (xy 385.196214 -394.810042) (xy 385.196588 -394.831062)
			(xy 385.196207 -394.852082) (xy 385.190606 -394.893748) (xy 385.185412 -394.91412) (xy 385.183888 -394.920724)
			(xy 385.183888 -395.034262) (xy 385.183334 -395.049253) (xy 385.175594 -395.078219) (xy 385.160631 -395.104201)
			(xy 385.13946 -395.125431) (xy 385.113522 -395.140469) (xy 385.084578 -395.148291) (xy 385.069588 -395.148816)
			(xy 384.88747 -395.148816) (xy 384.886962 -395.14907) (xy 384.870198 -395.14907) (xy 384.86969 -395.148816)
			(xy 384.68808 -395.148816) (xy 384.673051 -395.148338) (xy 384.644014 -395.140565) (xy 384.617973 -395.125552)
			(xy 384.596696 -395.10432) (xy 384.581628 -395.07831) (xy 384.573794 -395.04929) (xy 384.573272 -395.034262)
			(xy 384.573272 -394.920724) (xy 384.571748 -394.91412) (xy 384.566541 -394.893751) (xy 384.560941 -394.852083)
			(xy 384.560572 -394.831062) (xy 384.561334 -394.808456) (xy 384.562096 -394.79855) (xy 384.555746 -394.779246)
			(xy 384.495548 -394.709904) (xy 384.477514 -394.70076) (xy 384.467608 -394.699998) (xy 384.443782 -394.697797)
			(xy 384.397152 -394.687069) (xy 384.352677 -394.669424) (xy 384.311376 -394.645265) (xy 384.274197 -394.615147)
			(xy 384.241992 -394.57976) (xy 384.2155 -394.539916) (xy 384.195328 -394.496528) (xy 384.188208 -394.473684)
			(xy 384.186684 -394.467842) (xy 383.86639 -393.914122) (xy 383.862326 -393.909804) (xy 383.846169 -393.892135)
			(xy 383.818851 -393.852818) (xy 383.797784 -393.809826) (xy 383.783449 -393.764146) (xy 383.776177 -393.716826)
			(xy 383.775712 -393.692888) (xy 383.243874 -393.692888) (xy 383.516124 -394.16355) (xy 383.520188 -394.167868)
			(xy 383.536385 -394.185549) (xy 383.563785 -394.224895) (xy 383.584918 -394.267934) (xy 383.599297 -394.313675)
			(xy 383.60659 -394.361065) (xy 383.607056 -394.385038) (xy 383.607056 -394.385546) (xy 383.606294 -394.405866)
			(xy 383.605532 -394.415772) (xy 383.611882 -394.434822) (xy 383.672588 -394.504164) (xy 383.690368 -394.513054)
			(xy 383.700528 -394.513816) (xy 383.725479 -394.516016) (xy 383.77428 -394.527301) (xy 383.820709 -394.546093)
			(xy 383.863621 -394.571927) (xy 383.901956 -394.604165) (xy 383.918714 -394.622782) (xy 383.921181 -394.62555)
			(xy 383.92679 -394.630399) (xy 383.92989 -394.632434) (xy 383.941922 -394.640509) (xy 383.961814 -394.661569)
			(xy 383.975822 -394.686927) (xy 383.98306 -394.714977) (xy 383.983484 -394.729462) (xy 383.983484 -394.7414)
			(xy 383.985262 -394.748004) (xy 383.990454 -394.768376) (xy 383.996064 -394.810042) (xy 383.996438 -394.831062)
			(xy 383.996055 -394.852082) (xy 383.990456 -394.893748) (xy 383.985262 -394.91412) (xy 383.983484 -394.920724)
			(xy 383.983484 -395.034262) (xy 383.982832 -395.052382) (xy 383.971572 -395.086827) (xy 383.961386 -395.101826)
			(xy 383.956905 -395.108492) (xy 383.951978 -395.12377) (xy 383.951734 -395.131798) (xy 383.951734 -395.165326)
			(xy 383.952038 -395.173345) (xy 383.956951 -395.188611) (xy 383.961386 -395.195298) (xy 383.971475 -395.210346)
			(xy 383.98273 -395.24476) (xy 383.983484 -395.262862) (xy 383.983484 -395.3764) (xy 383.985262 -395.383004)
			(xy 383.990454 -395.403376) (xy 383.996064 -395.445042) (xy 383.996438 -395.466062) (xy 383.996055 -395.487082)
			(xy 383.990456 -395.528748) (xy 383.985262 -395.54912) (xy 383.983484 -395.555724) (xy 383.983484 -395.567662)
			(xy 383.983019 -395.583034) (xy 383.974886 -395.612684) (xy 383.959192 -395.639121) (xy 383.937056 -395.660457)
			(xy 383.923794 -395.668246) (xy 383.919984 -395.672818) (xy 383.912672 -395.682282) (xy 383.906991 -395.705487)
			(xy 383.909062 -395.717268) (xy 383.916174 -395.749018) (xy 383.919457 -395.760527) (xy 383.934693 -395.778944)
			(xy 383.945384 -395.784324) (xy 383.966813 -395.794057) (xy 384.006764 -395.818936) (xy 384.042613 -395.849431)
			(xy 384.058414 -395.866874) (xy 384.060882 -395.869641) (xy 384.066491 -395.874491) (xy 384.06959 -395.876526)
			(xy 384.081744 -395.884594) (xy 384.10183 -395.905738) (xy 384.115973 -395.931243) (xy 384.12327 -395.95948)
			(xy 384.123692 -395.974062) (xy 384.123692 -395.986508) (xy 384.12547 -395.992858) (xy 384.130604 -396.013172)
			(xy 384.136078 -396.054712) (xy 384.136392 -396.075662) (xy 384.136059 -396.096611) (xy 384.130583 -396.138148)
			(xy 384.12547 -396.158466) (xy 384.123692 -396.164816) (xy 384.123692 -396.621508) (xy 384.12547 -396.627858)
			(xy 384.130604 -396.648172) (xy 384.136078 -396.689712) (xy 384.136392 -396.710662) (xy 384.700526 -396.710662)
			(xy 384.700892 -396.689641) (xy 384.706503 -396.647975) (xy 384.711702 -396.627604) (xy 384.71348 -396.621)
			(xy 384.71348 -396.507462) (xy 384.713903 -396.492441) (xy 384.721688 -396.463424) (xy 384.736718 -396.437411)
			(xy 384.757968 -396.416174) (xy 384.783991 -396.40116) (xy 384.813012 -396.393394) (xy 384.828034 -396.392908)
			(xy 385.009644 -396.392908) (xy 385.010152 -396.392654) (xy 385.026916 -396.392654) (xy 385.027424 -396.392908)
			(xy 385.209034 -396.392908) (xy 385.224049 -396.393406) (xy 385.253055 -396.401184) (xy 385.279061 -396.416201)
			(xy 385.300296 -396.437436) (xy 385.315315 -396.463441) (xy 385.323094 -396.492447) (xy 385.323588 -396.507462)
			(xy 385.323588 -396.621) (xy 385.325366 -396.627604) (xy 385.330558 -396.647976) (xy 385.336168 -396.689642)
			(xy 385.336542 -396.710662) (xy 385.900422 -396.710662) (xy 385.900788 -396.689641) (xy 385.906399 -396.647975)
			(xy 385.911598 -396.627604) (xy 385.913376 -396.621) (xy 385.913376 -396.507462) (xy 385.913803 -396.492441)
			(xy 385.921588 -396.463425) (xy 385.936617 -396.437412) (xy 385.957866 -396.416175) (xy 385.983888 -396.401162)
			(xy 386.012909 -396.393394) (xy 386.02793 -396.392908) (xy 386.20954 -396.392908) (xy 386.210048 -396.392654)
			(xy 386.226812 -396.392654) (xy 386.22732 -396.392908) (xy 386.40893 -396.392908) (xy 386.423945 -396.393409)
			(xy 386.452951 -396.401186) (xy 386.478957 -396.416203) (xy 386.500192 -396.437437) (xy 386.515211 -396.463442)
			(xy 386.52299 -396.492447) (xy 386.523484 -396.507462) (xy 386.523484 -396.621) (xy 386.525262 -396.627604)
			(xy 386.530454 -396.647976) (xy 386.536064 -396.689642) (xy 386.536438 -396.710662) (xy 387.100572 -396.710662)
			(xy 387.100939 -396.689641) (xy 387.106549 -396.647975) (xy 387.111748 -396.627604) (xy 387.113272 -396.621)
			(xy 387.113272 -396.507462) (xy 387.1137 -396.492462) (xy 387.121463 -396.463485) (xy 387.136451 -396.437498)
			(xy 387.157646 -396.416267) (xy 387.183608 -396.401236) (xy 387.212573 -396.393425) (xy 387.227572 -396.392908)
			(xy 387.40969 -396.392908) (xy 387.410198 -396.392654) (xy 387.426962 -396.392654) (xy 387.42747 -396.392908)
			(xy 387.60908 -396.392908) (xy 387.62411 -396.393398) (xy 387.653148 -396.401163) (xy 387.679192 -396.416172)
			(xy 387.700471 -396.437403) (xy 387.715538 -396.463413) (xy 387.723368 -396.492434) (xy 387.723888 -396.507462)
			(xy 387.723888 -396.621) (xy 387.725412 -396.627604) (xy 387.730603 -396.647977) (xy 387.736214 -396.689642)
			(xy 387.736588 -396.710662) (xy 388.300468 -396.710662) (xy 388.300836 -396.689641) (xy 388.306445 -396.647975)
			(xy 388.311644 -396.627604) (xy 388.313168 -396.621) (xy 388.313168 -396.507462) (xy 388.3136 -396.492463)
			(xy 388.321362 -396.463486) (xy 388.33635 -396.437499) (xy 388.357544 -396.416269) (xy 388.383506 -396.401237)
			(xy 388.41247 -396.393426) (xy 388.427468 -396.392908) (xy 388.609586 -396.392908) (xy 388.610094 -396.392654)
			(xy 388.626858 -396.392654) (xy 388.627366 -396.392908) (xy 388.808976 -396.392908) (xy 388.824005 -396.393402)
			(xy 388.853044 -396.401166) (xy 388.879087 -396.416174) (xy 388.900366 -396.437404) (xy 388.915433 -396.463413)
			(xy 388.923264 -396.492434) (xy 388.923784 -396.507462) (xy 388.923784 -396.621) (xy 388.925308 -396.627604)
			(xy 388.930499 -396.647977) (xy 388.93611 -396.689642) (xy 388.936484 -396.710662) (xy 388.936484 -396.71117)
			(xy 388.936314 -396.725795) (xy 388.933647 -396.754924) (xy 388.93115 -396.769336) (xy 388.92978 -396.77851)
			(xy 388.933056 -396.796753) (xy 388.9375 -396.804896) (xy 388.95401 -396.83182) (xy 388.959192 -396.839589)
			(xy 388.973909 -396.851056) (xy 388.982712 -396.854172) (xy 389.007595 -396.862233) (xy 389.054474 -396.885423)
			(xy 389.096886 -396.916027) (xy 389.133669 -396.953208) (xy 389.163816 -396.995947) (xy 389.1865 -397.043073)
			(xy 389.194294 -397.06804) (xy 389.195818 -397.073882) (xy 389.516112 -397.627602) (xy 389.520176 -397.63192)
			(xy 389.536364 -397.649642) (xy 389.563791 -397.689029) (xy 389.584937 -397.732115) (xy 389.599315 -397.777906)
			(xy 389.606592 -397.825346) (xy 389.607044 -397.849344) (xy 389.606624 -397.874123) (xy 389.598868 -397.923072)
			(xy 389.583555 -397.970205) (xy 389.561062 -398.014365) (xy 389.53194 -398.054465) (xy 389.496907 -398.089519)
			(xy 389.456824 -398.118664) (xy 389.412677 -398.141184) (xy 389.365553 -398.156525) (xy 389.316609 -398.164309)
			(xy 389.29183 -398.164812) (xy 389.291322 -398.164812) (xy 389.265928 -398.164292) (xy 389.215796 -398.156165)
			(xy 389.16761 -398.140117) (xy 389.122616 -398.116561) (xy 389.081973 -398.086107) (xy 389.04673 -398.049538)
			(xy 389.017796 -398.007799) (xy 388.995917 -397.961966) (xy 388.9883 -397.937736) (xy 388.986776 -397.931894)
			(xy 388.666482 -397.378174) (xy 388.662418 -397.373856) (xy 388.646253 -397.356127) (xy 388.618887 -397.316723)
			(xy 388.597798 -397.273632) (xy 388.583472 -397.227846) (xy 388.576238 -397.18042) (xy 388.575804 -397.156432)
			(xy 388.575985 -397.142384) (xy 388.578525 -397.114402) (xy 388.580884 -397.100552) (xy 388.582209 -397.091273)
			(xy 388.57868 -397.072875) (xy 388.574026 -397.064738) (xy 388.557262 -397.037814) (xy 388.552044 -397.030123)
			(xy 388.53733 -397.018793) (xy 388.52856 -397.015716) (xy 388.506935 -397.008912) (xy 388.465721 -396.990031)
			(xy 388.4276 -396.965497) (xy 388.393344 -396.935805) (xy 388.378192 -396.918942) (xy 388.375721 -396.916177)
			(xy 388.370115 -396.911326) (xy 388.367016 -396.90929) (xy 388.354947 -396.90124) (xy 388.334993 -396.880192)
			(xy 388.320921 -396.854832) (xy 388.313621 -396.826763) (xy 388.313168 -396.812262) (xy 388.313168 -396.800324)
			(xy 388.311644 -396.79372) (xy 388.306437 -396.773351) (xy 388.300837 -396.731683) (xy 388.300468 -396.710662)
			(xy 387.736588 -396.710662) (xy 387.736588 -396.71117) (xy 387.736418 -396.725795) (xy 387.733751 -396.754924)
			(xy 387.731254 -396.769336) (xy 387.729883 -396.77851) (xy 387.733159 -396.796753) (xy 387.737604 -396.804896)
			(xy 387.754114 -396.83182) (xy 387.759294 -396.83959) (xy 387.774013 -396.851056) (xy 387.782816 -396.854172)
			(xy 387.807738 -396.862312) (xy 387.854704 -396.885604) (xy 387.897184 -396.916324) (xy 387.934014 -396.953632)
			(xy 387.964184 -396.996505) (xy 387.986869 -397.043767) (xy 387.994652 -397.068802) (xy 387.996176 -397.074644)
			(xy 388.315962 -397.627602) (xy 388.320026 -397.63192) (xy 388.336186 -397.649586) (xy 388.363505 -397.688903)
			(xy 388.384573 -397.731895) (xy 388.398907 -397.777576) (xy 388.406177 -397.824898) (xy 388.40664 -397.848836)
			(xy 388.40664 -397.849344) (xy 388.406144 -397.874793) (xy 388.397973 -397.92503) (xy 388.381849 -397.973306)
			(xy 388.35819 -398.018371) (xy 388.327609 -398.059057) (xy 388.290897 -398.09431) (xy 388.270242 -398.109186)
			(xy 388.261714 -398.115637) (xy 388.250506 -398.133824) (xy 388.247663 -398.154997) (xy 388.253675 -398.175496)
			(xy 388.267504 -398.191778) (xy 388.286759 -398.20103) (xy 388.29742 -398.201896) (xy 388.307072 -398.201388)
			(xy 388.315587 -398.200099) (xy 388.332751 -398.198697) (xy 388.341362 -398.198594) (xy 388.341616 -398.198848)
			(xy 388.640828 -398.198848) (xy 388.641082 -398.198594) (xy 388.66213 -398.198958) (xy 388.703452 -398.206962)
			(xy 388.742407 -398.222901) (xy 388.777489 -398.246157) (xy 388.807339 -398.275831) (xy 388.830803 -398.310774)
			(xy 388.846972 -398.349635) (xy 388.85522 -398.390909) (xy 388.855712 -398.411954) (xy 388.855712 -398.615916)
			(xy 389.480552 -398.615916) (xy 389.480552 -398.411954) (xy 389.481073 -398.390893) (xy 389.489318 -398.349585)
			(xy 389.505501 -398.310695) (xy 389.528992 -398.275731) (xy 389.55888 -398.24605) (xy 389.594006 -398.222802)
			(xy 389.633008 -398.20689) (xy 389.674372 -398.198932) (xy 389.695436 -398.198594) (xy 389.69569 -398.198848)
			(xy 389.994902 -398.198848) (xy 389.995156 -398.198594) (xy 390.016218 -398.199002) (xy 390.057576 -398.206956)
			(xy 390.096575 -398.22286) (xy 390.131701 -398.246097) (xy 390.161592 -398.275767) (xy 390.185091 -398.310719)
			(xy 390.201285 -398.349598) (xy 390.209546 -398.390896) (xy 390.21004 -398.411954) (xy 390.21004 -398.666716)
			(xy 390.200896 -398.666716) (xy 390.190872 -398.667117) (xy 390.172352 -398.674791) (xy 390.15818 -398.688969)
			(xy 390.150513 -398.707492) (xy 390.150096 -398.717516) (xy 390.150096 -398.881092) (xy 390.149674 -398.891113)
			(xy 390.142006 -398.909631) (xy 390.127834 -398.923804) (xy 390.109317 -398.931473) (xy 390.099296 -398.931892)
			(xy 389.591296 -398.931892) (xy 389.581273 -398.931484) (xy 389.562755 -398.923811) (xy 389.548583 -398.909635)
			(xy 389.540914 -398.891115) (xy 389.540496 -398.881092) (xy 389.540496 -398.666716) (xy 389.531352 -398.666716)
			(xy 389.521343 -398.666252) (xy 389.502854 -398.658579) (xy 389.488703 -398.64442) (xy 389.481042 -398.625925)
			(xy 389.480552 -398.615916) (xy 388.855712 -398.615916) (xy 388.855712 -398.666716) (xy 388.846568 -398.666716)
			(xy 388.836556 -398.667162) (xy 388.818061 -398.674835) (xy 388.803908 -398.689001) (xy 388.796253 -398.707504)
			(xy 388.795768 -398.717516) (xy 388.795768 -398.881092) (xy 388.795373 -398.891117) (xy 388.7877 -398.90964)
			(xy 388.77352 -398.923813) (xy 388.754993 -398.931478) (xy 388.744968 -398.931892) (xy 388.237476 -398.931892)
			(xy 388.227466 -398.931432) (xy 388.208972 -398.923763) (xy 388.194819 -398.909601) (xy 388.187162 -398.891103)
			(xy 388.186676 -398.881092) (xy 388.186676 -398.717516) (xy 388.186267 -398.707493) (xy 388.178598 -398.688971)
			(xy 388.164422 -398.674798) (xy 388.145899 -398.667131) (xy 388.135876 -398.666716) (xy 388.126732 -398.666716)
			(xy 388.126732 -398.411446) (xy 388.127515 -398.385724) (xy 388.139849 -398.335777) (xy 388.151116 -398.31264)
			(xy 388.156958 -398.30121) (xy 388.156704 -398.27581) (xy 388.10311 -398.178782) (xy 388.08152 -398.165066)
			(xy 388.068566 -398.16405) (xy 388.044673 -398.161898) (xy 387.997887 -398.151303) (xy 387.953246 -398.133742)
			(xy 387.911782 -398.10962) (xy 387.874451 -398.079493) (xy 387.842116 -398.044058) (xy 387.815523 -398.004133)
			(xy 387.795287 -397.960639) (xy 387.78815 -397.937736) (xy 387.786626 -397.931894) (xy 387.466078 -397.377412)
			(xy 387.462014 -397.373094) (xy 387.445909 -397.355439) (xy 387.418723 -397.316138) (xy 387.397773 -397.273187)
			(xy 387.383537 -397.227569) (xy 387.376343 -397.180326) (xy 387.375908 -397.156432) (xy 387.376089 -397.142384)
			(xy 387.378629 -397.114402) (xy 387.380988 -397.100552) (xy 387.382312 -397.091273) (xy 387.378784 -397.072875)
			(xy 387.37413 -397.064738) (xy 387.357366 -397.037814) (xy 387.352147 -397.030124) (xy 387.337434 -397.018793)
			(xy 387.328664 -397.015716) (xy 387.30704 -397.00891) (xy 387.265825 -396.99003) (xy 387.227704 -396.965496)
			(xy 387.193448 -396.935805) (xy 387.178296 -396.918942) (xy 387.175837 -396.916166) (xy 387.170222 -396.911322)
			(xy 387.16712 -396.90929) (xy 387.155052 -396.901239) (xy 387.135097 -396.880192) (xy 387.121025 -396.854832)
			(xy 387.113725 -396.826762) (xy 387.113272 -396.812262) (xy 387.113272 -396.800324) (xy 387.111748 -396.79372)
			(xy 387.106541 -396.773351) (xy 387.100941 -396.731683) (xy 387.100572 -396.710662) (xy 386.536438 -396.710662)
			(xy 386.536438 -396.71117) (xy 386.536268 -396.725795) (xy 386.533601 -396.754924) (xy 386.531104 -396.769336)
			(xy 386.52974 -396.77851) (xy 386.533013 -396.796752) (xy 386.537454 -396.804896) (xy 386.553964 -396.83182)
			(xy 386.559126 -396.839604) (xy 386.573858 -396.851063) (xy 386.582666 -396.854172) (xy 386.60754 -396.862258)
			(xy 386.65442 -396.885442) (xy 386.696833 -396.916041) (xy 386.733618 -396.953217) (xy 386.763767 -396.995951)
			(xy 386.786453 -397.043074) (xy 386.794248 -397.06804) (xy 386.795772 -397.073882) (xy 387.116066 -397.627602)
			(xy 387.12013 -397.63192) (xy 387.136291 -397.649585) (xy 387.16361 -397.688903) (xy 387.184677 -397.731895)
			(xy 387.199011 -397.777576) (xy 387.206281 -397.824898) (xy 387.206744 -397.848836) (xy 387.206744 -397.849344)
			(xy 387.206247 -397.874793) (xy 387.198075 -397.92503) (xy 387.181952 -397.973306) (xy 387.158293 -398.01837)
			(xy 387.127712 -398.059056) (xy 387.091001 -398.09431) (xy 387.070346 -398.109186) (xy 387.061816 -398.115635)
			(xy 387.050607 -398.133823) (xy 387.047763 -398.154996) (xy 387.053776 -398.175496) (xy 387.067606 -398.19178)
			(xy 387.086863 -398.201031) (xy 387.097524 -398.201896) (xy 387.107176 -398.201388) (xy 387.11569 -398.200099)
			(xy 387.132855 -398.198697) (xy 387.141466 -398.198594) (xy 387.14172 -398.198848) (xy 387.440932 -398.198848)
			(xy 387.441186 -398.198594) (xy 387.462231 -398.199046) (xy 387.503549 -398.207033) (xy 387.542504 -398.222955)
			(xy 387.577586 -398.246198) (xy 387.607438 -398.27586) (xy 387.630904 -398.310794) (xy 387.647074 -398.349646)
			(xy 387.655324 -398.390913) (xy 387.655816 -398.411954) (xy 387.655816 -398.666716) (xy 387.646672 -398.666716)
			(xy 387.636661 -398.667165) (xy 387.618165 -398.674837) (xy 387.604012 -398.689002) (xy 387.596357 -398.707504)
			(xy 387.595872 -398.717516) (xy 387.595872 -398.881092) (xy 387.595473 -398.891116) (xy 387.587801 -398.909638)
			(xy 387.573622 -398.923812) (xy 387.555096 -398.931477) (xy 387.545072 -398.931892) (xy 387.03758 -398.931892)
			(xy 387.02757 -398.931428) (xy 387.009076 -398.923761) (xy 386.994924 -398.9096) (xy 386.987266 -398.891102)
			(xy 386.98678 -398.881092) (xy 386.98678 -398.717516) (xy 386.986367 -398.707493) (xy 386.978699 -398.688973)
			(xy 386.964524 -398.674799) (xy 386.946003 -398.667132) (xy 386.93598 -398.666716) (xy 386.926836 -398.666716)
			(xy 386.926836 -398.411446) (xy 386.927619 -398.385724) (xy 386.939953 -398.335777) (xy 386.95122 -398.31264)
			(xy 386.957062 -398.30121) (xy 386.956808 -398.27581) (xy 386.903214 -398.178782) (xy 386.881624 -398.165066)
			(xy 386.86867 -398.16405) (xy 386.844777 -398.161895) (xy 386.797991 -398.151301) (xy 386.753351 -398.13374)
			(xy 386.711886 -398.109618) (xy 386.674555 -398.079492) (xy 386.64222 -398.044057) (xy 386.615627 -398.004132)
			(xy 386.595391 -397.960639) (xy 386.588254 -397.937736) (xy 386.58673 -397.931894) (xy 386.266436 -397.378174)
			(xy 386.262372 -397.373856) (xy 386.246164 -397.356152) (xy 386.218742 -397.316759) (xy 386.1976 -397.273669)
			(xy 386.183227 -397.227874) (xy 386.175954 -397.180431) (xy 386.175504 -397.156432) (xy 386.175683 -397.142384)
			(xy 386.178226 -397.114402) (xy 386.180584 -397.100552) (xy 386.181876 -397.091296) (xy 386.178477 -397.072932)
			(xy 386.17398 -397.064738) (xy 386.157216 -397.037814) (xy 386.152014 -397.03011) (xy 386.137289 -397.018787)
			(xy 386.128514 -397.015716) (xy 386.106883 -397.00893) (xy 386.06567 -396.990043) (xy 386.027551 -396.965504)
			(xy 385.993297 -396.935807) (xy 385.978146 -396.918942) (xy 385.975681 -396.916172) (xy 385.97007 -396.911324)
			(xy 385.96697 -396.90929) (xy 385.95494 -396.901212) (xy 385.935051 -396.880151) (xy 385.921043 -396.854795)
			(xy 385.913803 -396.826746) (xy 385.913376 -396.812262) (xy 385.913376 -396.800324) (xy 385.911598 -396.79372)
			(xy 385.906392 -396.773351) (xy 385.900791 -396.731683) (xy 385.900422 -396.710662) (xy 385.336542 -396.710662)
			(xy 385.336542 -396.71117) (xy 385.336372 -396.725795) (xy 385.333705 -396.754924) (xy 385.331208 -396.769336)
			(xy 385.329844 -396.77851) (xy 385.333117 -396.796752) (xy 385.337558 -396.804896) (xy 385.354068 -396.83182)
			(xy 385.359229 -396.839605) (xy 385.373961 -396.851064) (xy 385.38277 -396.854172) (xy 385.407703 -396.862282)
			(xy 385.454667 -396.885581) (xy 385.497145 -396.916309) (xy 385.533973 -396.953622) (xy 385.564141 -396.996499)
			(xy 385.586824 -397.043765) (xy 385.594606 -397.068802) (xy 385.59613 -397.074644) (xy 385.915916 -397.627602)
			(xy 385.91998 -397.63192) (xy 385.936168 -397.649642) (xy 385.963596 -397.689028) (xy 385.984742 -397.732114)
			(xy 385.999119 -397.777906) (xy 386.006396 -397.825346) (xy 386.006848 -397.849344) (xy 386.006348 -397.874806)
			(xy 385.99815 -397.925065) (xy 385.98199 -397.973357) (xy 385.958288 -398.018428) (xy 385.927657 -398.05911)
			(xy 385.890893 -398.094347) (xy 385.870196 -398.109186) (xy 385.861691 -398.115659) (xy 385.850499 -398.13384)
			(xy 385.847662 -398.155) (xy 385.853669 -398.175487) (xy 385.867483 -398.191764) (xy 385.886721 -398.201022)
			(xy 385.897374 -398.201896) (xy 385.907026 -398.201388) (xy 385.91554 -398.200093) (xy 385.932705 -398.198695)
			(xy 385.941316 -398.198594) (xy 385.94157 -398.198848) (xy 386.240782 -398.198848) (xy 386.241036 -398.198594)
			(xy 386.262097 -398.199021) (xy 386.303455 -398.206971) (xy 386.342453 -398.222871) (xy 386.377579 -398.246106)
			(xy 386.407471 -398.275773) (xy 386.43097 -398.310723) (xy 386.447164 -398.3496) (xy 386.455426 -398.390897)
			(xy 386.45592 -398.411954) (xy 386.45592 -398.666716) (xy 386.446776 -398.666716) (xy 386.436765 -398.667169)
			(xy 386.418269 -398.674839) (xy 386.404117 -398.689003) (xy 386.396461 -398.707504) (xy 386.395976 -398.717516)
			(xy 386.395976 -398.881092) (xy 386.395573 -398.891116) (xy 386.387902 -398.909637) (xy 386.373724 -398.923811)
			(xy 386.3552 -398.931477) (xy 386.345176 -398.931892) (xy 385.837176 -398.931892) (xy 385.827166 -398.931432)
			(xy 385.808672 -398.923763) (xy 385.794519 -398.909601) (xy 385.786862 -398.891103) (xy 385.786376 -398.881092)
			(xy 385.786376 -398.666716) (xy 385.777232 -398.666716) (xy 385.767215 -398.666255) (xy 385.748702 -398.658598)
			(xy 385.734529 -398.644439) (xy 385.726855 -398.625933) (xy 385.726432 -398.615916) (xy 385.726432 -398.411954)
			(xy 385.726775 -398.394721) (xy 385.732346 -398.360708) (xy 385.743319 -398.328035) (xy 385.75107 -398.31264)
			(xy 385.756912 -398.30121) (xy 385.756658 -398.27581) (xy 385.703064 -398.178782) (xy 385.681474 -398.165066)
			(xy 385.66852 -398.16405) (xy 385.644623 -398.161935) (xy 385.597836 -398.151334) (xy 385.553195 -398.133766)
			(xy 385.511731 -398.109638) (xy 385.474401 -398.079506) (xy 385.442067 -398.044067) (xy 385.415475 -398.004138)
			(xy 385.39524 -397.960641) (xy 385.388104 -397.937736) (xy 385.38658 -397.931894) (xy 385.066032 -397.377412)
			(xy 385.061968 -397.373094) (xy 385.045868 -397.355422) (xy 385.018618 -397.316144) (xy 384.997607 -397.273204)
			(xy 384.983314 -397.227586) (xy 384.976067 -397.180334) (xy 384.975608 -397.156432) (xy 384.975787 -397.142384)
			(xy 384.97833 -397.114402) (xy 384.980688 -397.100552) (xy 384.981979 -397.091296) (xy 384.978581 -397.072932)
			(xy 384.974084 -397.064738) (xy 384.95732 -397.037814) (xy 384.952117 -397.030111) (xy 384.937392 -397.018788)
			(xy 384.928618 -397.015716) (xy 384.906987 -397.008928) (xy 384.865774 -396.990042) (xy 384.827655 -396.965503)
			(xy 384.793401 -396.935807) (xy 384.77825 -396.918942) (xy 384.775784 -396.916173) (xy 384.770174 -396.911324)
			(xy 384.767074 -396.90929) (xy 384.755045 -396.901211) (xy 384.735155 -396.88015) (xy 384.721148 -396.854794)
			(xy 384.713907 -396.826746) (xy 384.71348 -396.812262) (xy 384.71348 -396.800324) (xy 384.711702 -396.79372)
			(xy 384.706496 -396.773351) (xy 384.700895 -396.731683) (xy 384.700526 -396.710662) (xy 384.136392 -396.710662)
			(xy 384.136251 -396.725415) (xy 384.133576 -396.754799) (xy 384.131058 -396.769336) (xy 384.1297 -396.77851)
			(xy 384.13297 -396.796751) (xy 384.137408 -396.804896) (xy 384.153918 -396.83182) (xy 384.159097 -396.839591)
			(xy 384.173816 -396.851057) (xy 384.18262 -396.854172) (xy 384.207504 -396.862228) (xy 384.254383 -396.885419)
			(xy 384.296795 -396.916025) (xy 384.333578 -396.953207) (xy 384.363724 -396.995946) (xy 384.386408 -397.043072)
			(xy 384.394202 -397.06804) (xy 384.395726 -397.073882) (xy 384.71602 -397.627602) (xy 384.720084 -397.63192)
			(xy 384.736273 -397.649641) (xy 384.7637 -397.689028) (xy 384.784846 -397.732114) (xy 384.799223 -397.777906)
			(xy 384.8065 -397.825346) (xy 384.806952 -397.849344) (xy 384.806451 -397.874806) (xy 384.798253 -397.925065)
			(xy 384.782093 -397.973357) (xy 384.758391 -398.018428) (xy 384.72776 -398.05911) (xy 384.690996 -398.094347)
			(xy 384.6703 -398.109186) (xy 384.661793 -398.115657) (xy 384.6506 -398.133838) (xy 384.647762 -398.154999)
			(xy 384.653769 -398.175487) (xy 384.667585 -398.191765) (xy 384.686824 -398.201023) (xy 384.697478 -398.201896)
			(xy 384.70713 -398.201388) (xy 384.715644 -398.200093) (xy 384.732809 -398.198695) (xy 384.74142 -398.198594)
			(xy 384.741674 -398.198848) (xy 385.040886 -398.198848) (xy 385.04114 -398.198594) (xy 385.062201 -398.199017)
			(xy 385.103559 -398.206968) (xy 385.142558 -398.222869) (xy 385.177684 -398.246104) (xy 385.207576 -398.275772)
			(xy 385.231074 -398.310722) (xy 385.247268 -398.349599) (xy 385.25553 -398.390896) (xy 385.256024 -398.411954)
			(xy 385.256024 -398.666716) (xy 385.24688 -398.666716) (xy 385.236869 -398.667172) (xy 385.218374 -398.674841)
			(xy 385.204221 -398.689004) (xy 385.196565 -398.707505) (xy 385.19608 -398.717516) (xy 385.19608 -398.881092)
			(xy 385.195674 -398.891115) (xy 385.188002 -398.909636) (xy 385.173826 -398.923809) (xy 385.155303 -398.931476)
			(xy 385.14528 -398.931892) (xy 384.63728 -398.931892) (xy 384.62727 -398.931428) (xy 384.608776 -398.923761)
			(xy 384.594624 -398.9096) (xy 384.586966 -398.891102) (xy 384.58648 -398.881092) (xy 384.58648 -398.666716)
			(xy 384.577336 -398.666716) (xy 384.567319 -398.666251) (xy 384.548806 -398.658596) (xy 384.534633 -398.644438)
			(xy 384.526959 -398.625933) (xy 384.526536 -398.615916) (xy 384.526536 -398.411954) (xy 384.526879 -398.394721)
			(xy 384.53245 -398.360708) (xy 384.543423 -398.328035) (xy 384.551174 -398.31264) (xy 384.557016 -398.30121)
			(xy 384.556762 -398.27581) (xy 384.503168 -398.178782) (xy 384.481578 -398.165066) (xy 384.468624 -398.16405)
			(xy 384.444727 -398.161932) (xy 384.39794 -398.151331) (xy 384.353299 -398.133764) (xy 384.311835 -398.109636)
			(xy 384.274505 -398.079505) (xy 384.242171 -398.044066) (xy 384.21558 -398.004137) (xy 384.195344 -397.960641)
			(xy 384.188208 -397.937736) (xy 384.186684 -397.931894) (xy 383.86639 -397.378174) (xy 383.862326 -397.373856)
			(xy 383.846162 -397.356126) (xy 383.818796 -397.316723) (xy 383.797706 -397.273632) (xy 383.78338 -397.227846)
			(xy 383.776146 -397.18042) (xy 383.775712 -397.156432) (xy 383.775893 -397.142384) (xy 383.778433 -397.114402)
			(xy 383.780792 -397.100552) (xy 383.782116 -397.091273) (xy 383.778588 -397.072875) (xy 383.773934 -397.064738)
			(xy 383.75717 -397.037814) (xy 383.751949 -397.030125) (xy 383.737237 -397.018794) (xy 383.728468 -397.015716)
			(xy 383.706892 -397.008965) (xy 383.665767 -396.99019) (xy 383.627713 -396.965784) (xy 383.593497 -396.936236)
			(xy 383.578354 -396.91945) (xy 383.575887 -396.916682) (xy 383.570278 -396.911833) (xy 383.567178 -396.909798)
			(xy 383.555028 -396.901725) (xy 383.534944 -396.880581) (xy 383.5208 -396.855078) (xy 383.5135 -396.826843)
			(xy 383.513076 -396.812262) (xy 383.513076 -396.799816) (xy 383.511298 -396.793466) (xy 383.506168 -396.773151)
			(xy 383.500692 -396.731612) (xy 383.500376 -396.710662) (xy 383.500714 -396.689714) (xy 383.506187 -396.648176)
			(xy 383.511298 -396.627858) (xy 383.513076 -396.621508) (xy 383.513076 -396.164816) (xy 383.511298 -396.158466)
			(xy 383.506168 -396.138151) (xy 383.500692 -396.096612) (xy 383.500376 -396.075662) (xy 383.500714 -396.054714)
			(xy 383.506187 -396.013176) (xy 383.511298 -395.992858) (xy 383.513076 -395.986508) (xy 383.513076 -395.974062)
			(xy 383.513544 -395.958597) (xy 383.521774 -395.92878) (xy 383.537609 -395.902209) (xy 383.559917 -395.880782)
			(xy 383.573274 -395.87297) (xy 383.57683 -395.868906) (xy 383.584186 -395.859386) (xy 383.589881 -395.836044)
			(xy 383.587752 -395.824202) (xy 383.58064 -395.792706) (xy 383.577385 -395.781186) (xy 383.562128 -395.762776)
			(xy 383.55143 -395.7574) (xy 383.529938 -395.747598) (xy 383.489876 -395.722571) (xy 383.453961 -395.691889)
			(xy 383.438146 -395.674342) (xy 383.435681 -395.671572) (xy 383.43007 -395.666724) (xy 383.42697 -395.66469)
			(xy 383.41494 -395.656612) (xy 383.395051 -395.635551) (xy 383.381043 -395.610195) (xy 383.373803 -395.582146)
			(xy 383.373376 -395.567662) (xy 383.373376 -395.555724) (xy 383.371598 -395.54912) (xy 383.366392 -395.528751)
			(xy 383.360791 -395.487083) (xy 383.360422 -395.466062) (xy 383.360788 -395.445041) (xy 383.366399 -395.403375)
			(xy 383.371598 -395.383004) (xy 383.373376 -395.3764) (xy 383.373376 -395.262862) (xy 383.374028 -395.244742)
			(xy 383.385287 -395.210296) (xy 383.395474 -395.195298) (xy 383.399942 -395.188624) (xy 383.404878 -395.173352)
			(xy 383.405126 -395.165326) (xy 383.405126 -395.131798) (xy 383.404801 -395.123781) (xy 383.399901 -395.108516)
			(xy 383.395474 -395.101826) (xy 383.38539 -395.086775) (xy 383.374133 -395.052363) (xy 383.373376 -395.034262)
			(xy 383.373376 -394.920724) (xy 383.371598 -394.91412) (xy 383.366392 -394.893751) (xy 383.360791 -394.852083)
			(xy 383.360422 -394.831062) (xy 383.361184 -394.808456) (xy 383.361946 -394.798296) (xy 383.35585 -394.7795)
			(xy 383.302256 -394.717524) (xy 383.295309 -394.710284) (xy 383.277412 -394.701258) (xy 383.267458 -394.699998)
			(xy 383.243651 -394.697758) (xy 383.19706 -394.687005) (xy 383.152625 -394.669346) (xy 383.111363 -394.645183)
			(xy 383.074221 -394.61507) (xy 383.042048 -394.579697) (xy 383.015581 -394.539874) (xy 382.995426 -394.496513)
			(xy 382.988312 -394.473684) (xy 382.986788 -394.467842) (xy 382.666494 -393.914122) (xy 382.66243 -393.909804)
			(xy 382.646274 -393.892135) (xy 382.618956 -393.852818) (xy 382.597888 -393.809826) (xy 382.583553 -393.764146)
			(xy 382.576281 -393.716826) (xy 382.575816 -393.692888) (xy 382.043724 -393.692888) (xy 382.315974 -394.16355)
			(xy 382.320038 -394.167868) (xy 382.336191 -394.185573) (xy 382.363536 -394.224932) (xy 382.384616 -394.267971)
			(xy 382.398948 -394.313703) (xy 382.406202 -394.361076) (xy 382.406652 -394.385038) (xy 382.406652 -394.385546)
			(xy 382.406144 -394.405866) (xy 382.405382 -394.415772) (xy 382.411732 -394.434822) (xy 382.472438 -394.504164)
			(xy 382.490218 -394.513054) (xy 382.500378 -394.513816) (xy 382.525355 -394.516008) (xy 382.574213 -394.527262)
			(xy 382.6207 -394.546043) (xy 382.663665 -394.571885) (xy 382.702042 -394.604148) (xy 382.718818 -394.622782)
			(xy 382.721285 -394.62555) (xy 382.726894 -394.630399) (xy 382.729994 -394.632434) (xy 382.742027 -394.640508)
			(xy 382.761919 -394.661569) (xy 382.775926 -394.686927) (xy 382.783164 -394.714977) (xy 382.783588 -394.729462)
			(xy 382.783588 -394.7414) (xy 382.785366 -394.748004) (xy 382.790558 -394.768376) (xy 382.796168 -394.810042)
			(xy 382.796542 -394.831062) (xy 382.796159 -394.852082) (xy 382.79056 -394.893748) (xy 382.785366 -394.91412)
			(xy 382.783588 -394.920724) (xy 382.783588 -394.958316) (xy 382.784074 -394.968323) (xy 382.791737 -394.986813)
			(xy 382.80589 -395.000965) (xy 382.824381 -395.008626) (xy 382.834388 -395.009116) (xy 382.857248 -395.009116)
			(xy 382.867294 -395.009482) (xy 382.88589 -395.017073) (xy 382.893316 -395.023848) (xy 383.078482 -395.209014)
			(xy 383.085318 -395.216417) (xy 383.093041 -395.235014) (xy 383.093468 -395.245082) (xy 383.093468 -396.89151)
			(xy 383.093947 -396.901788) (xy 383.102087 -396.920666) (xy 383.109216 -396.928086) (xy 383.128818 -396.947574)
			(xy 383.161546 -396.992113) (xy 383.186021 -397.04167) (xy 383.194306 -397.06804) (xy 383.19583 -397.073882)
			(xy 383.4384 -397.492982) (xy 383.446274 -397.503396) (xy 383.507742 -397.565118) (xy 383.505456 -397.567404)
			(xy 383.501138 -397.601694) (xy 383.516124 -397.627602) (xy 383.520188 -397.63192) (xy 383.536378 -397.64964)
			(xy 383.563804 -397.689028) (xy 383.58495 -397.732114) (xy 383.599327 -397.777906) (xy 383.606604 -397.825346)
			(xy 383.607056 -397.849344) (xy 383.606586 -397.874095) (xy 383.598868 -397.922991) (xy 383.583612 -397.970082)
			(xy 383.561192 -398.014216) (xy 383.532159 -398.054308) (xy 383.497223 -398.089377) (xy 383.477516 -398.10436)
			(xy 383.467864 -398.111218) (xy 383.456688 -398.133062) (xy 383.456688 -398.149826) (xy 383.457166 -398.159834)
			(xy 383.464832 -398.178324) (xy 383.478988 -398.192476) (xy 383.49748 -398.200136) (xy 383.507488 -398.200626)
			(xy 383.510536 -398.200626) (xy 383.513584 -398.200372) (xy 383.54127 -398.198594) (xy 383.541524 -398.198848)
			(xy 383.840736 -398.198848) (xy 383.84099 -398.198594) (xy 383.862035 -398.199042) (xy 383.903353 -398.20703)
			(xy 383.942308 -398.222953) (xy 383.97739 -398.246196) (xy 384.007242 -398.275859) (xy 384.030708 -398.310793)
			(xy 384.046878 -398.349645) (xy 384.055128 -398.390912) (xy 384.05562 -398.411954) (xy 384.05562 -398.666716)
			(xy 384.046476 -398.666716) (xy 384.036465 -398.667169) (xy 384.017969 -398.674839) (xy 384.003817 -398.689003)
			(xy 383.996161 -398.707504) (xy 383.995676 -398.717516) (xy 383.995676 -398.881092) (xy 383.995273 -398.891116)
			(xy 383.987602 -398.909637) (xy 383.973424 -398.923811) (xy 383.9549 -398.931477) (xy 383.944876 -398.931892)
			(xy 383.491232 -398.931892) (xy 383.481214 -398.932346) (xy 383.462699 -398.940004) (xy 383.448526 -398.954166)
			(xy 383.440854 -398.972674) (xy 383.440432 -398.982692) (xy 383.440432 -401.674838) (xy 383.735072 -401.674838)
			(xy 383.735072 -400.81073) (xy 383.73552 -400.785263) (xy 383.742322 -400.734784) (xy 383.755782 -400.685659)
			(xy 383.775661 -400.638763) (xy 383.801604 -400.59493) (xy 383.83315 -400.55494) (xy 383.85115 -400.536918)
			(xy 383.857754 -400.530568) (xy 383.865628 -400.513804) (xy 383.872486 -400.42846) (xy 383.867406 -400.41068)
			(xy 383.861818 -400.403314) (xy 383.846966 -400.382567) (xy 383.823331 -400.337353) (xy 383.80723 -400.288941)
			(xy 383.799078 -400.238578) (xy 383.798572 -400.213068) (xy 383.798572 -400.212814) (xy 383.799062 -400.187825)
			(xy 383.806881 -400.138462) (xy 383.822325 -400.09093) (xy 383.845015 -400.046398) (xy 383.874391 -400.005965)
			(xy 383.909731 -399.970625) (xy 383.950164 -399.941249) (xy 383.994696 -399.918559) (xy 384.042228 -399.903115)
			(xy 384.091591 -399.895296) (xy 384.141569 -399.895296) (xy 384.190932 -399.903115) (xy 384.238464 -399.918559)
			(xy 384.282996 -399.941249) (xy 384.323429 -399.970625) (xy 384.358769 -400.005965) (xy 384.388145 -400.046398)
			(xy 384.410835 -400.09093) (xy 384.426279 -400.138462) (xy 384.434098 -400.187825) (xy 384.434588 -400.212814)
			(xy 384.434588 -400.213068) (xy 384.434078 -400.238576) (xy 384.425903 -400.288934) (xy 384.409805 -400.337345)
			(xy 384.386197 -400.382571) (xy 384.371342 -400.403314) (xy 384.365754 -400.41068) (xy 384.360674 -400.42846)
			(xy 384.367532 -400.513804) (xy 384.375406 -400.530568) (xy 384.38201 -400.536918) (xy 384.40002 -400.55493)
			(xy 384.431558 -400.594927) (xy 384.457496 -400.638763) (xy 384.477374 -400.68566) (xy 384.490837 -400.734784)
			(xy 384.497647 -400.785263) (xy 384.498088 -400.81073) (xy 384.498088 -401.674838) (xy 384.498079 -401.675346)
			(xy 384.934968 -401.675346) (xy 384.934968 -400.81073) (xy 384.935418 -400.785263) (xy 384.942219 -400.734784)
			(xy 384.955679 -400.685659) (xy 384.975557 -400.638763) (xy 385.0015 -400.59493) (xy 385.033046 -400.55494)
			(xy 385.051046 -400.536918) (xy 385.05765 -400.530568) (xy 385.065524 -400.513804) (xy 385.072382 -400.42846)
			(xy 385.067302 -400.41068) (xy 385.061714 -400.403314) (xy 385.046861 -400.382567) (xy 385.023227 -400.337353)
			(xy 385.007126 -400.288941) (xy 384.998974 -400.238578) (xy 384.998468 -400.213068) (xy 384.998468 -400.212814)
			(xy 384.998958 -400.187825) (xy 385.006777 -400.138462) (xy 385.022221 -400.09093) (xy 385.044911 -400.046398)
			(xy 385.074287 -400.005965) (xy 385.109627 -399.970625) (xy 385.15006 -399.941249) (xy 385.194592 -399.918559)
			(xy 385.242124 -399.903115) (xy 385.291487 -399.895296) (xy 385.341465 -399.895296) (xy 385.390828 -399.903115)
			(xy 385.43836 -399.918559) (xy 385.482892 -399.941249) (xy 385.523325 -399.970625) (xy 385.558665 -400.005965)
			(xy 385.588041 -400.046398) (xy 385.610731 -400.09093) (xy 385.626175 -400.138462) (xy 385.633994 -400.187825)
			(xy 385.634484 -400.212814) (xy 385.634484 -400.213068) (xy 385.633975 -400.238576) (xy 385.6258 -400.288934)
			(xy 385.609702 -400.337345) (xy 385.586093 -400.382571) (xy 385.571238 -400.403314) (xy 385.56565 -400.41068)
			(xy 385.56057 -400.42846) (xy 385.567428 -400.513804) (xy 385.575302 -400.530568) (xy 385.581906 -400.536918)
			(xy 385.599915 -400.554931) (xy 385.631453 -400.594927) (xy 385.657392 -400.638764) (xy 385.677269 -400.68566)
			(xy 385.690733 -400.734784) (xy 385.697543 -400.785263) (xy 385.697984 -400.81073) (xy 385.697984 -401.674838)
			(xy 386.134864 -401.674838) (xy 386.134864 -400.81073) (xy 386.135315 -400.785263) (xy 386.142117 -400.734784)
			(xy 386.155576 -400.68566) (xy 386.175454 -400.638764) (xy 386.201397 -400.59493) (xy 386.232943 -400.55494)
			(xy 386.250942 -400.536918) (xy 386.257546 -400.530568) (xy 386.26542 -400.513804) (xy 386.272278 -400.42846)
			(xy 386.267198 -400.41068) (xy 386.26161 -400.403314) (xy 386.246757 -400.382568) (xy 386.223123 -400.337353)
			(xy 386.207022 -400.288941) (xy 386.19887 -400.238578) (xy 386.198364 -400.213068) (xy 386.198364 -400.212814)
			(xy 386.198854 -400.187825) (xy 386.206673 -400.138462) (xy 386.222117 -400.09093) (xy 386.244807 -400.046398)
			(xy 386.274183 -400.005965) (xy 386.309523 -399.970625) (xy 386.349956 -399.941249) (xy 386.394488 -399.918559)
			(xy 386.44202 -399.903115) (xy 386.491383 -399.895296) (xy 386.541361 -399.895296) (xy 386.590724 -399.903115)
			(xy 386.638256 -399.918559) (xy 386.682788 -399.941249) (xy 386.723221 -399.970625) (xy 386.758561 -400.005965)
			(xy 386.787937 -400.046398) (xy 386.810627 -400.09093) (xy 386.826071 -400.138462) (xy 386.83389 -400.187825)
			(xy 386.83438 -400.212814) (xy 386.83438 -400.213068) (xy 386.833871 -400.238576) (xy 386.825696 -400.288934)
			(xy 386.809598 -400.337345) (xy 386.785989 -400.382571) (xy 386.771134 -400.403314) (xy 386.765546 -400.41068)
			(xy 386.760466 -400.42846) (xy 386.767324 -400.513804) (xy 386.775198 -400.530568) (xy 386.781802 -400.536918)
			(xy 386.79981 -400.554931) (xy 386.831349 -400.594928) (xy 386.857287 -400.638764) (xy 386.877165 -400.685661)
			(xy 386.890629 -400.734784) (xy 386.897439 -400.785263) (xy 386.89788 -400.81073) (xy 386.89788 -401.674838)
			(xy 387.33476 -401.674838) (xy 387.33476 -400.811238) (xy 387.335179 -400.785718) (xy 387.341969 -400.735131)
			(xy 387.355447 -400.685902) (xy 387.375371 -400.638911) (xy 387.401386 -400.594998) (xy 387.433026 -400.554948)
			(xy 387.451092 -400.536918) (xy 387.457696 -400.530568) (xy 387.46557 -400.513804) (xy 387.472428 -400.42846)
			(xy 387.467348 -400.41068) (xy 387.46176 -400.403314) (xy 387.446913 -400.382563) (xy 387.423276 -400.337351)
			(xy 387.407173 -400.28894) (xy 387.39902 -400.238577) (xy 387.398514 -400.213068) (xy 387.398514 -400.212814)
			(xy 387.399004 -400.187825) (xy 387.406823 -400.138462) (xy 387.422267 -400.09093) (xy 387.444957 -400.046398)
			(xy 387.474333 -400.005965) (xy 387.509673 -399.970625) (xy 387.550106 -399.941249) (xy 387.594638 -399.918559)
			(xy 387.64217 -399.903115) (xy 387.691533 -399.895296) (xy 387.741511 -399.895296) (xy 387.790874 -399.903115)
			(xy 387.838406 -399.918559) (xy 387.882938 -399.941249) (xy 387.923371 -399.970625) (xy 387.958711 -400.005965)
			(xy 387.988087 -400.046398) (xy 388.010777 -400.09093) (xy 388.026221 -400.138462) (xy 388.03404 -400.187825)
			(xy 388.03453 -400.212814) (xy 388.03453 -400.213068) (xy 388.034031 -400.238577) (xy 388.025855 -400.288936)
			(xy 388.009754 -400.337347) (xy 387.986141 -400.382572) (xy 387.971284 -400.403314) (xy 387.965696 -400.41068)
			(xy 387.960616 -400.42846) (xy 387.967474 -400.513804) (xy 387.975348 -400.530568) (xy 387.981952 -400.536918)
			(xy 387.999986 -400.554977) (xy 388.031616 -400.595028) (xy 388.057628 -400.638937) (xy 388.077556 -400.685921)
			(xy 388.091045 -400.735142) (xy 388.097854 -400.78572) (xy 388.098284 -400.811238) (xy 388.098284 -401.674838)
			(xy 388.534656 -401.674838) (xy 388.534656 -400.811238) (xy 388.535076 -400.785718) (xy 388.541867 -400.735131)
			(xy 388.555344 -400.685902) (xy 388.575268 -400.638911) (xy 388.601282 -400.594998) (xy 388.632922 -400.554948)
			(xy 388.650988 -400.536918) (xy 388.657592 -400.530568) (xy 388.665466 -400.513804) (xy 388.672324 -400.42846)
			(xy 388.667244 -400.41068) (xy 388.661656 -400.403314) (xy 388.646809 -400.382564) (xy 388.623172 -400.337351)
			(xy 388.607069 -400.28894) (xy 388.598916 -400.238577) (xy 388.59841 -400.213068) (xy 388.59841 -400.212814)
			(xy 388.5989 -400.187825) (xy 388.606719 -400.138462) (xy 388.622163 -400.09093) (xy 388.644853 -400.046398)
			(xy 388.674229 -400.005965) (xy 388.709569 -399.970625) (xy 388.750002 -399.941249) (xy 388.794534 -399.918559)
			(xy 388.842066 -399.903115) (xy 388.891429 -399.895296) (xy 388.941407 -399.895296) (xy 388.99077 -399.903115)
			(xy 389.038302 -399.918559) (xy 389.082834 -399.941249) (xy 389.123267 -399.970625) (xy 389.158607 -400.005965)
			(xy 389.187983 -400.046398) (xy 389.210673 -400.09093) (xy 389.226117 -400.138462) (xy 389.233936 -400.187825)
			(xy 389.234426 -400.212814) (xy 389.234426 -400.213068) (xy 389.233928 -400.238577) (xy 389.225751 -400.288936)
			(xy 389.209651 -400.337347) (xy 389.186037 -400.382572) (xy 389.17118 -400.403314) (xy 389.165592 -400.41068)
			(xy 389.160512 -400.42846) (xy 389.16737 -400.513804) (xy 389.175244 -400.530568) (xy 389.181848 -400.536918)
			(xy 389.199881 -400.554978) (xy 389.231512 -400.595029) (xy 389.257523 -400.638938) (xy 389.277451 -400.685921)
			(xy 389.29094 -400.735142) (xy 389.29775 -400.78572) (xy 389.29818 -400.811238) (xy 389.29818 -401.227743)
			(xy 390.536183 -401.227743) (xy 390.536187 -401.167808) (xy 390.544013 -401.108386) (xy 390.559528 -401.050494)
			(xy 390.582468 -400.995123) (xy 390.612438 -400.943219) (xy 390.648926 -400.895672) (xy 390.691309 -400.853293)
			(xy 390.738861 -400.81681) (xy 390.790768 -400.786845) (xy 390.846142 -400.763912) (xy 390.904035 -400.748403)
			(xy 390.963458 -400.740583) (xy 391.023393 -400.740587) (xy 391.082815 -400.748413) (xy 391.140706 -400.763929)
			(xy 391.196078 -400.786868) (xy 391.247981 -400.816838) (xy 391.295529 -400.853327) (xy 391.337907 -400.89571)
			(xy 391.37439 -400.943261) (xy 391.404355 -400.995168) (xy 391.427288 -401.050542) (xy 391.442797 -401.108436)
			(xy 391.450617 -401.167858) (xy 391.451084 -401.197826) (xy 391.451023 -401.211319) (xy 391.449498 -401.238261)
			(xy 391.448036 -401.251674) (xy 391.44687 -401.266466) (xy 391.451999 -401.295672) (xy 391.465307 -401.322171)
			(xy 391.48567 -401.343727) (xy 391.511369 -401.35852) (xy 391.540236 -401.365302) (xy 391.569835 -401.3635)
			(xy 391.583926 -401.358862) (xy 391.615658 -401.347973) (xy 391.681703 -401.336221) (xy 391.715244 -401.335494)
			(xy 391.742493 -401.335979) (xy 391.796437 -401.34374) (xy 391.848726 -401.359099) (xy 391.898298 -401.381743)
			(xy 391.944143 -401.411211) (xy 391.985329 -401.446903) (xy 392.021016 -401.488092) (xy 392.050478 -401.53394)
			(xy 392.073116 -401.583515) (xy 392.088469 -401.635806) (xy 392.096224 -401.689751) (xy 392.096224 -401.744249)
			(xy 392.088469 -401.798194) (xy 392.073116 -401.850485) (xy 392.050478 -401.90006) (xy 392.021016 -401.945908)
			(xy 391.985329 -401.987097) (xy 391.944143 -402.022789) (xy 391.898298 -402.052257) (xy 391.848726 -402.074901)
			(xy 391.796437 -402.09026) (xy 391.742493 -402.098021) (xy 391.715244 -402.09851) (xy 391.688005 -402.097982)
			(xy 391.634082 -402.090238) (xy 391.581808 -402.074901) (xy 391.532248 -402.052284) (xy 391.48641 -402.022846)
			(xy 391.445226 -401.987186) (xy 391.409534 -401.94603) (xy 391.38006 -401.900215) (xy 391.357404 -401.850673)
			(xy 391.342026 -401.798412) (xy 391.33424 -401.744494) (xy 391.333736 -401.717256) (xy 391.333736 -401.716748)
			(xy 391.33399 -401.706588) (xy 391.33399 -401.705826) (xy 391.333867 -401.69101) (xy 391.326027 -401.662446)
			(xy 391.310329 -401.637329) (xy 391.288089 -401.617766) (xy 391.261174 -401.6054) (xy 391.231844 -401.601269)
			(xy 391.202561 -401.605719) (xy 391.188956 -401.611592) (xy 391.158242 -401.625475) (xy 391.093748 -401.645053)
			(xy 391.027076 -401.65494) (xy 390.993376 -401.655534) (xy 390.963409 -401.655013) (xy 390.903987 -401.647187)
			(xy 390.846095 -401.631672) (xy 390.790723 -401.608733) (xy 390.73882 -401.578763) (xy 390.691272 -401.542274)
			(xy 390.648894 -401.499891) (xy 390.61241 -401.45234) (xy 390.582446 -401.400433) (xy 390.559513 -401.345059)
			(xy 390.544003 -401.287165) (xy 390.536183 -401.227743) (xy 389.29818 -401.227743) (xy 389.29818 -401.476718)
			(xy 389.298531 -401.48583) (xy 389.304885 -401.502909) (xy 389.316791 -401.516705) (xy 389.324596 -401.521422)
			(xy 389.41502 -401.570952) (xy 389.442452 -401.569936) (xy 389.454136 -401.56257) (xy 389.454644 -401.56257)
			(xy 389.476963 -401.548836) (xy 389.524662 -401.527133) (xy 389.57495 -401.51239) (xy 389.626817 -401.504903)
			(xy 389.653018 -401.504404) (xy 389.680618 -401.504897) (xy 389.7352 -401.513126) (xy 389.787947 -401.529399)
			(xy 389.837679 -401.553351) (xy 389.883286 -401.584447) (xy 389.923749 -401.621993) (xy 389.958164 -401.665151)
			(xy 389.985763 -401.712955) (xy 390.005929 -401.764339) (xy 390.018212 -401.818155) (xy 390.022337 -401.8732)
			(xy 390.018212 -401.928245) (xy 390.005929 -401.982061) (xy 389.985763 -402.033445) (xy 389.958164 -402.081249)
			(xy 389.923749 -402.124407) (xy 389.883286 -402.161953) (xy 389.837679 -402.193049) (xy 389.787947 -402.217001)
			(xy 389.7352 -402.233274) (xy 389.680618 -402.241503) (xy 389.653018 -402.24202) (xy 389.625046 -402.241503)
			(xy 389.569746 -402.233029) (xy 389.516359 -402.216303) (xy 389.46611 -402.191708) (xy 389.42015 -402.159808)
			(xy 389.379534 -402.121334) (xy 389.345192 -402.07717) (xy 389.317912 -402.028326) (xy 389.298319 -401.975924)
			(xy 389.292084 -401.94865) (xy 389.289374 -401.938422) (xy 389.277023 -401.921271) (xy 389.258821 -401.910526)
			(xy 389.237837 -401.907997) (xy 389.227568 -401.91055) (xy 389.220717 -401.912959) (xy 389.208593 -401.92094)
			(xy 389.203692 -401.926298) (xy 389.200898 -401.929346) (xy 389.195056 -401.93595) (xy 389.188198 -401.952714)
			(xy 389.186166 -402.027136) (xy 389.186271 -402.036042) (xy 389.191871 -402.052936) (xy 389.197088 -402.060156)
			(xy 389.197342 -402.06041) (xy 389.212108 -402.079588) (xy 389.236937 -402.121134) (xy 389.255974 -402.165633)
			(xy 389.268876 -402.212281) (xy 389.275411 -402.260238) (xy 389.275828 -402.284438) (xy 389.275326 -402.311334)
			(xy 389.267308 -402.364526) (xy 389.251452 -402.415929) (xy 389.228113 -402.464395) (xy 389.19781 -402.508841)
			(xy 389.161222 -402.548274) (xy 389.119165 -402.581813) (xy 389.072579 -402.608709) (xy 389.022505 -402.628362)
			(xy 388.97006 -402.640332) (xy 388.916418 -402.644352) (xy 388.862776 -402.640332) (xy 388.810331 -402.628362)
			(xy 388.760257 -402.608709) (xy 388.713671 -402.581813) (xy 388.671614 -402.548274) (xy 388.635026 -402.508841)
			(xy 388.604723 -402.464395) (xy 388.581384 -402.415929) (xy 388.565528 -402.364526) (xy 388.55751 -402.311334)
			(xy 388.557008 -402.284438) (xy 388.557408 -402.260235) (xy 388.56391 -402.212267) (xy 388.5768 -402.165609)
			(xy 388.595844 -402.121107) (xy 388.620698 -402.079568) (xy 388.635494 -402.06041) (xy 388.635748 -402.060156)
			(xy 388.641021 -402.052969) (xy 388.646604 -402.03605) (xy 388.64667 -402.027136) (xy 388.644638 -401.952714)
			(xy 388.63778 -401.93595) (xy 388.631938 -401.929346) (xy 388.613729 -401.908236) (xy 388.582986 -401.861732)
			(xy 388.559336 -401.81125) (xy 388.543282 -401.757865) (xy 388.535166 -401.702712) (xy 388.534656 -401.674838)
			(xy 388.098284 -401.674838) (xy 388.097715 -401.704001) (xy 388.088795 -401.761642) (xy 388.071213 -401.817256)
			(xy 388.045379 -401.86955) (xy 388.011893 -401.917307) (xy 387.992112 -401.938744) (xy 387.985945 -401.94582)
			(xy 387.978794 -401.963161) (xy 387.978142 -401.972526) (xy 387.976364 -402.041106) (xy 387.976516 -402.050362)
			(xy 387.982645 -402.067814) (xy 387.988302 -402.075142) (xy 387.98881 -402.07565) (xy 388.005161 -402.095266)
			(xy 388.032694 -402.138274) (xy 388.053853 -402.184751) (xy 388.068208 -402.233758) (xy 388.075471 -402.284305)
			(xy 388.075932 -402.309838) (xy 388.07543 -402.336734) (xy 388.067412 -402.389926) (xy 388.051556 -402.441329)
			(xy 388.028217 -402.489795) (xy 387.997914 -402.534241) (xy 387.961326 -402.573674) (xy 387.919269 -402.607213)
			(xy 387.872683 -402.634109) (xy 387.822609 -402.653762) (xy 387.770164 -402.665732) (xy 387.716522 -402.669752)
			(xy 387.66288 -402.665732) (xy 387.610435 -402.653762) (xy 387.560361 -402.634109) (xy 387.513775 -402.607213)
			(xy 387.471718 -402.573674) (xy 387.43513 -402.534241) (xy 387.404827 -402.489795) (xy 387.381488 -402.441329)
			(xy 387.365632 -402.389926) (xy 387.357614 -402.336734) (xy 387.357112 -402.309838) (xy 387.357598 -402.284271)
			(xy 387.364873 -402.233656) (xy 387.379267 -402.184589) (xy 387.400488 -402.138066) (xy 387.428105 -402.09503)
			(xy 387.444488 -402.075396) (xy 387.444742 -402.075142) (xy 387.450403 -402.067819) (xy 387.456516 -402.050362)
			(xy 387.45668 -402.041106) (xy 387.454648 -401.962874) (xy 387.447536 -401.945856) (xy 387.440932 -401.938744)
			(xy 387.421151 -401.917306) (xy 387.387658 -401.869553) (xy 387.361821 -401.81726) (xy 387.344242 -401.761645)
			(xy 387.335331 -401.704002) (xy 387.33476 -401.674838) (xy 386.89788 -401.674838) (xy 386.89734 -401.703992)
			(xy 386.888468 -401.761621) (xy 386.870937 -401.817231) (xy 386.845154 -401.869529) (xy 386.811719 -401.917298)
			(xy 386.791962 -401.938744) (xy 386.785801 -401.945825) (xy 386.778646 -401.963162) (xy 386.777992 -401.972526)
			(xy 386.776214 -402.041106) (xy 386.776355 -402.050363) (xy 386.78249 -402.067816) (xy 386.788152 -402.075142)
			(xy 386.78866 -402.07565) (xy 386.804969 -402.095287) (xy 386.832444 -402.138307) (xy 386.853549 -402.184785)
			(xy 386.867858 -402.233784) (xy 386.875082 -402.284315) (xy 386.875528 -402.309838) (xy 386.875026 -402.336715)
			(xy 386.867014 -402.38987) (xy 386.85117 -402.441236) (xy 386.827846 -402.489668) (xy 386.797565 -402.534082)
			(xy 386.761003 -402.573487) (xy 386.718975 -402.607003) (xy 386.672422 -402.63388) (xy 386.622383 -402.653519)
			(xy 386.569976 -402.66548) (xy 386.516372 -402.669498) (xy 386.462768 -402.66548) (xy 386.410361 -402.653519)
			(xy 386.360322 -402.63388) (xy 386.313769 -402.607003) (xy 386.271741 -402.573487) (xy 386.235179 -402.534082)
			(xy 386.204898 -402.489668) (xy 386.181574 -402.441236) (xy 386.16573 -402.38987) (xy 386.157718 -402.336715)
			(xy 386.157216 -402.309838) (xy 386.157697 -402.284281) (xy 386.164932 -402.233683) (xy 386.179276 -402.184623)
			(xy 386.200438 -402.138096) (xy 386.227989 -402.095044) (xy 386.244338 -402.075396) (xy 386.244592 -402.075142)
			(xy 386.250258 -402.067823) (xy 386.256367 -402.050362) (xy 386.25653 -402.041106) (xy 386.254498 -401.962874)
			(xy 386.247386 -401.945856) (xy 386.240782 -401.938744) (xy 386.221044 -401.917282) (xy 386.187607 -401.869518)
			(xy 386.161823 -401.817224) (xy 386.144291 -401.761617) (xy 386.135419 -401.703991) (xy 386.134864 -401.674838)
			(xy 385.697984 -401.674838) (xy 385.697984 -401.675346) (xy 385.6975 -401.703743) (xy 385.689087 -401.759911)
			(xy 385.672426 -401.814207) (xy 385.647886 -401.865426) (xy 385.616012 -401.912433) (xy 385.597146 -401.933664)
			(xy 385.591277 -401.940594) (xy 385.584377 -401.957376) (xy 385.583684 -401.96643) (xy 385.582668 -401.997418)
			(xy 385.582708 -402.006571) (xy 385.588584 -402.023892) (xy 385.594098 -402.0312) (xy 385.609447 -402.050544)
			(xy 385.635219 -402.092665) (xy 385.654996 -402.137913) (xy 385.668407 -402.185437) (xy 385.675201 -402.234348)
			(xy 385.675632 -402.259038) (xy 385.67513 -402.285915) (xy 385.667118 -402.33907) (xy 385.651274 -402.390436)
			(xy 385.62795 -402.438868) (xy 385.597669 -402.483282) (xy 385.561107 -402.522687) (xy 385.519079 -402.556203)
			(xy 385.472526 -402.58308) (xy 385.422487 -402.602719) (xy 385.37008 -402.61468) (xy 385.316476 -402.618698)
			(xy 385.262872 -402.61468) (xy 385.210465 -402.602719) (xy 385.160426 -402.58308) (xy 385.113873 -402.556203)
			(xy 385.071845 -402.522687) (xy 385.035283 -402.483282) (xy 385.005002 -402.438868) (xy 384.981678 -402.390436)
			(xy 384.965834 -402.33907) (xy 384.957822 -402.285915) (xy 384.95732 -402.259038) (xy 384.957737 -402.234345)
			(xy 384.964492 -402.185424) (xy 384.977893 -402.137891) (xy 384.997687 -402.092646) (xy 385.0235 -402.050543)
			(xy 385.038854 -402.0312) (xy 385.044336 -402.023881) (xy 385.050181 -402.006563) (xy 385.050284 -401.997418)
			(xy 385.049268 -401.96643) (xy 385.048621 -401.957367) (xy 385.041707 -401.940575) (xy 385.035806 -401.933664)
			(xy 385.016993 -401.912395) (xy 384.985172 -401.865371) (xy 384.960655 -401.814157) (xy 384.943982 -401.759881)
			(xy 384.935519 -401.703735) (xy 384.934968 -401.675346) (xy 384.498079 -401.675346) (xy 384.497545 -401.703992)
			(xy 384.488674 -401.761621) (xy 384.471143 -401.817231) (xy 384.445361 -401.869528) (xy 384.411926 -401.917298)
			(xy 384.39217 -401.938744) (xy 384.38601 -401.945826) (xy 384.378854 -401.963162) (xy 384.3782 -401.972526)
			(xy 384.376422 -402.041106) (xy 384.376561 -402.050363) (xy 384.382697 -402.067816) (xy 384.38836 -402.075142)
			(xy 384.388868 -402.07565) (xy 384.405179 -402.095286) (xy 384.432653 -402.138307) (xy 384.453757 -402.184785)
			(xy 384.468066 -402.233784) (xy 384.47529 -402.284315) (xy 384.475736 -402.309838) (xy 384.475234 -402.336715)
			(xy 384.467222 -402.38987) (xy 384.451378 -402.441236) (xy 384.428054 -402.489668) (xy 384.397773 -402.534082)
			(xy 384.361211 -402.573487) (xy 384.319183 -402.607003) (xy 384.27263 -402.63388) (xy 384.222591 -402.653519)
			(xy 384.170184 -402.66548) (xy 384.11658 -402.669498) (xy 384.062976 -402.66548) (xy 384.010569 -402.653519)
			(xy 383.96053 -402.63388) (xy 383.913977 -402.607003) (xy 383.871949 -402.573487) (xy 383.835387 -402.534082)
			(xy 383.805106 -402.489668) (xy 383.781782 -402.441236) (xy 383.765938 -402.38987) (xy 383.757926 -402.336715)
			(xy 383.757424 -402.309838) (xy 383.757903 -402.284281) (xy 383.765138 -402.233682) (xy 383.779482 -402.184623)
			(xy 383.800645 -402.138096) (xy 383.828197 -402.095044) (xy 383.844546 -402.075396) (xy 383.8448 -402.075142)
			(xy 383.850468 -402.067823) (xy 383.856575 -402.050362) (xy 383.856738 -402.041106) (xy 383.854706 -401.962874)
			(xy 383.847594 -401.945856) (xy 383.84099 -401.938744) (xy 383.821253 -401.917281) (xy 383.787816 -401.869517)
			(xy 383.762031 -401.817223) (xy 383.744499 -401.761617) (xy 383.735627 -401.70399) (xy 383.735072 -401.674838)
			(xy 383.440432 -401.674838) (xy 383.440432 -402.810218) (xy 383.440034 -402.820291) (xy 383.432296 -402.838889)
			(xy 383.425446 -402.846286) (xy 383.139696 -403.132036) (xy 383.132296 -403.138875) (xy 383.113696 -403.146594)
			(xy 383.103628 -403.147022) (xy 376.286776 -403.147022) (xy 376.276703 -403.14663) (xy 376.258104 -403.138888)
			(xy 376.250708 -403.132036) (xy 375.791476 -402.672804) (xy 375.769886 -402.665438) (xy 375.758202 -402.666708)
			(xy 375.747827 -402.667869) (xy 375.726986 -402.669142) (xy 375.716546 -402.669248) (xy 375.690875 -402.668731)
			(xy 375.640053 -402.66143) (xy 375.590789 -402.646972) (xy 375.544083 -402.625649) (xy 375.500887 -402.597896)
			(xy 375.462081 -402.564278) (xy 375.428454 -402.52548) (xy 375.400691 -402.482291) (xy 375.379358 -402.43559)
			(xy 375.364887 -402.386329) (xy 375.357575 -402.335509) (xy 375.357136 -402.309838) (xy 375.357616 -402.28427)
			(xy 375.364892 -402.233655) (xy 375.379287 -402.184588) (xy 375.400509 -402.138065) (xy 375.428128 -402.09503)
			(xy 375.444512 -402.075396) (xy 375.444766 -402.075142) (xy 375.450429 -402.067821) (xy 375.456541 -402.050362)
			(xy 375.456704 -402.041106) (xy 375.454672 -401.962874) (xy 375.44756 -401.945856) (xy 375.440956 -401.938744)
			(xy 375.42118 -401.917303) (xy 375.387685 -401.869551) (xy 375.361847 -401.817259) (xy 375.344267 -401.761644)
			(xy 375.335355 -401.704001) (xy 375.334784 -401.674838) (xy 375.334784 -400.811238) (xy 375.335196 -400.785717)
			(xy 375.341987 -400.73513) (xy 375.355465 -400.685901) (xy 375.375391 -400.63891) (xy 375.401407 -400.594997)
			(xy 375.433049 -400.554947) (xy 375.451116 -400.536918) (xy 375.45772 -400.530568) (xy 375.465594 -400.513804)
			(xy 375.472452 -400.42846) (xy 375.467372 -400.41068) (xy 375.461784 -400.403314) (xy 375.446928 -400.38257)
			(xy 375.423295 -400.337354) (xy 375.407196 -400.288942) (xy 375.399044 -400.238578) (xy 375.398538 -400.213068)
			(xy 375.398538 -400.212814) (xy 375.39899 -400.189141) (xy 375.406015 -400.142318) (xy 375.419897 -400.097052)
			(xy 375.440331 -400.054341) (xy 375.466865 -400.015128) (xy 375.498914 -399.980277) (xy 375.535771 -399.950557)
			(xy 375.576624 -399.926624) (xy 375.598436 -399.917412) (xy 375.612914 -399.91157) (xy 375.63044 -399.885916)
			(xy 375.63044 -399.197576) (xy 375.630043 -399.187503) (xy 375.622304 -399.168905) (xy 375.615454 -399.161508)
			(xy 375.40057 -398.946878) (xy 375.393177 -398.940029) (xy 375.374572 -398.932315) (xy 375.364502 -398.931892)
			(xy 375.037604 -398.931892) (xy 375.027582 -398.931477) (xy 375.009064 -398.923807) (xy 374.994891 -398.909633)
			(xy 374.987222 -398.891114) (xy 374.986804 -398.881092) (xy 374.986804 -398.666716) (xy 374.97766 -398.666716)
			(xy 374.967652 -398.666245) (xy 374.949162 -398.658575) (xy 374.935011 -398.644418) (xy 374.92735 -398.625924)
			(xy 374.92686 -398.615916) (xy 374.92686 -398.411954) (xy 374.927439 -398.389838) (xy 374.936526 -398.346551)
			(xy 374.954321 -398.306057) (xy 374.966738 -398.287748) (xy 374.97131 -398.281144) (xy 374.976136 -398.266412)
			(xy 374.976136 -398.236694) (xy 374.975779 -398.225996) (xy 374.967218 -398.206395) (xy 374.959626 -398.198848)
			(xy 374.936258 -398.177766) (xy 374.928705 -398.171625) (xy 374.910431 -398.164962) (xy 374.900698 -398.164812)
			(xy 374.8913 -398.164812) (xy 374.865906 -398.164312) (xy 374.815772 -398.156181) (xy 374.767586 -398.140129)
			(xy 374.722592 -398.116571) (xy 374.681949 -398.086114) (xy 374.646707 -398.049543) (xy 374.617773 -398.007801)
			(xy 374.595895 -397.961967) (xy 374.588278 -397.937736) (xy 374.586754 -397.931894) (xy 374.26646 -397.378174)
			(xy 374.262396 -397.373856) (xy 374.246192 -397.356148) (xy 374.218768 -397.316757) (xy 374.197625 -397.273668)
			(xy 374.183252 -397.227873) (xy 374.175978 -397.18043) (xy 374.175528 -397.156432) (xy 374.175707 -397.142384)
			(xy 374.17825 -397.114402) (xy 374.180608 -397.100552) (xy 374.181896 -397.091296) (xy 374.178499 -397.072932)
			(xy 374.174004 -397.064738) (xy 374.15724 -397.037814) (xy 374.15203 -397.030117) (xy 374.13731 -397.01879)
			(xy 374.128538 -397.015716) (xy 374.10691 -397.008921) (xy 374.065696 -396.990037) (xy 374.027576 -396.9655)
			(xy 373.993321 -396.935806) (xy 373.97817 -396.918942) (xy 373.975702 -396.916175) (xy 373.970094 -396.911325)
			(xy 373.966994 -396.90929) (xy 373.954969 -396.901205) (xy 373.935078 -396.880147) (xy 373.921068 -396.854793)
			(xy 373.913827 -396.826745) (xy 373.9134 -396.812262) (xy 373.9134 -396.800324) (xy 373.911622 -396.79372)
			(xy 373.906415 -396.773351) (xy 373.900815 -396.731683) (xy 373.900446 -396.710662) (xy 373.336566 -396.710662)
			(xy 373.336566 -396.71117) (xy 373.336396 -396.725795) (xy 373.333729 -396.754924) (xy 373.331232 -396.769336)
			(xy 373.329864 -396.77851) (xy 373.333139 -396.796753) (xy 373.337582 -396.804896) (xy 373.354092 -396.83182)
			(xy 373.359244 -396.839612) (xy 373.373982 -396.851067) (xy 373.382794 -396.854172) (xy 373.407712 -396.862324)
			(xy 373.454678 -396.885613) (xy 373.497159 -396.916331) (xy 373.53399 -396.953636) (xy 373.564161 -396.996507)
			(xy 373.586846 -397.043767) (xy 373.59463 -397.068802) (xy 373.596154 -397.074644) (xy 373.91594 -397.627602)
			(xy 373.920004 -397.63192) (xy 373.936196 -397.649638) (xy 373.963622 -397.689026) (xy 373.984767 -397.732113)
			(xy 373.999143 -397.777905) (xy 374.00642 -397.825346) (xy 374.006872 -397.849344) (xy 374.006405 -397.874807)
			(xy 373.998205 -397.92507) (xy 373.982041 -397.973364) (xy 373.958332 -398.018436) (xy 373.927693 -398.059117)
			(xy 373.890921 -398.09435) (xy 373.87022 -398.109186) (xy 373.861703 -398.115648) (xy 373.850503 -398.133832)
			(xy 373.847662 -398.154998) (xy 373.853672 -398.175491) (xy 373.867494 -398.191771) (xy 373.886741 -398.201026)
			(xy 373.897398 -398.201896) (xy 373.90705 -398.201388) (xy 373.915563 -398.20009) (xy 373.932729 -398.198694)
			(xy 373.94134 -398.198594) (xy 373.941594 -398.198848) (xy 374.240806 -398.198848) (xy 374.24106 -398.198594)
			(xy 374.262122 -398.198999) (xy 374.303481 -398.206953) (xy 374.342479 -398.222858) (xy 374.377605 -398.246096)
			(xy 374.407497 -398.275766) (xy 374.430995 -398.310718) (xy 374.447189 -398.349597) (xy 374.45545 -398.390896)
			(xy 374.455944 -398.411954) (xy 374.455944 -398.666716) (xy 374.4468 -398.666716) (xy 374.436777 -398.66712)
			(xy 374.418257 -398.674793) (xy 374.404084 -398.68897) (xy 374.396417 -398.707493) (xy 374.396 -398.717516)
			(xy 374.396 -398.881092) (xy 374.395574 -398.891113) (xy 374.387907 -398.90963) (xy 374.373736 -398.923802)
			(xy 374.355221 -398.931472) (xy 374.3452 -398.931892) (xy 373.8372 -398.931892) (xy 373.827178 -398.93148)
			(xy 373.808659 -398.923809) (xy 373.794487 -398.909634) (xy 373.786818 -398.891114) (xy 373.7864 -398.881092)
			(xy 373.7864 -398.666716) (xy 373.777256 -398.666716) (xy 373.767248 -398.666248) (xy 373.748758 -398.658577)
			(xy 373.734607 -398.644419) (xy 373.726946 -398.625925) (xy 373.726456 -398.615916) (xy 373.726456 -398.411954)
			(xy 373.726797 -398.394721) (xy 373.732368 -398.360708) (xy 373.743342 -398.328035) (xy 373.751094 -398.31264)
			(xy 373.756936 -398.30121) (xy 373.756682 -398.27581) (xy 373.703088 -398.178782) (xy 373.681498 -398.165066)
			(xy 373.668544 -398.16405) (xy 373.644649 -398.161916) (xy 373.597862 -398.151318) (xy 373.553222 -398.133754)
			(xy 373.511757 -398.109628) (xy 373.474427 -398.079499) (xy 373.442092 -398.044062) (xy 373.4155 -398.004135)
			(xy 373.395265 -397.96064) (xy 373.388128 -397.937736) (xy 373.386604 -397.931894) (xy 373.066056 -397.377412)
			(xy 373.061992 -397.373094) (xy 373.045896 -397.355418) (xy 373.018645 -397.316142) (xy 372.997632 -397.273203)
			(xy 372.983338 -397.227586) (xy 372.976091 -397.180334) (xy 372.975632 -397.156432) (xy 372.97581 -397.142384)
			(xy 372.978354 -397.114402) (xy 372.980712 -397.100552) (xy 372.982 -397.091296) (xy 372.978603 -397.072932)
			(xy 372.974108 -397.064738) (xy 372.957344 -397.037814) (xy 372.952133 -397.030118) (xy 372.937414 -397.01879)
			(xy 372.928642 -397.015716) (xy 372.907015 -397.008919) (xy 372.865801 -396.990036) (xy 372.827681 -396.9655)
			(xy 372.793425 -396.935806) (xy 372.778274 -396.918942) (xy 372.775806 -396.916175) (xy 372.770197 -396.911325)
			(xy 372.767098 -396.90929) (xy 372.755074 -396.901203) (xy 372.735182 -396.880146) (xy 372.721173 -396.854792)
			(xy 372.713931 -396.826745) (xy 372.713504 -396.812262) (xy 372.713504 -396.800324) (xy 372.711726 -396.79372)
			(xy 372.706519 -396.773351) (xy 372.700919 -396.731683) (xy 372.70055 -396.710662) (xy 372.136416 -396.710662)
			(xy 372.136416 -396.71117) (xy 372.136245 -396.725795) (xy 372.133579 -396.754924) (xy 372.131082 -396.769336)
			(xy 372.129721 -396.77851) (xy 372.132992 -396.796752) (xy 372.137432 -396.804896) (xy 372.153942 -396.83182)
			(xy 372.159112 -396.839598) (xy 372.173838 -396.85106) (xy 372.182644 -396.854172) (xy 372.207533 -396.862214)
			(xy 372.254411 -396.885409) (xy 372.296822 -396.916018) (xy 372.333604 -396.953202) (xy 372.36375 -396.995943)
			(xy 372.386433 -397.043071) (xy 372.394226 -397.06804) (xy 372.39575 -397.073882) (xy 372.716044 -397.627602)
			(xy 372.720108 -397.63192) (xy 372.736301 -397.649637) (xy 372.763727 -397.689026) (xy 372.784871 -397.732113)
			(xy 372.799247 -397.777905) (xy 372.806524 -397.825346) (xy 372.806976 -397.849344) (xy 372.806507 -397.874807)
			(xy 372.798307 -397.92507) (xy 372.782143 -397.973364) (xy 372.758435 -398.018436) (xy 372.727797 -398.059116)
			(xy 372.691025 -398.09435) (xy 372.670324 -398.109186) (xy 372.661805 -398.115646) (xy 372.650603 -398.13383)
			(xy 372.647762 -398.154998) (xy 372.653773 -398.175492) (xy 372.667596 -398.191773) (xy 372.686844 -398.201027)
			(xy 372.697502 -398.201896) (xy 372.707154 -398.201388) (xy 372.715667 -398.20009) (xy 372.732833 -398.198694)
			(xy 372.741444 -398.198594) (xy 372.741698 -398.198848) (xy 373.04091 -398.198848) (xy 373.041164 -398.198594)
			(xy 373.062226 -398.198995) (xy 373.103585 -398.20695) (xy 373.142583 -398.222855) (xy 373.177709 -398.246094)
			(xy 373.207601 -398.275765) (xy 373.231099 -398.310717) (xy 373.247293 -398.349597) (xy 373.255554 -398.390896)
			(xy 373.256048 -398.411954) (xy 373.256048 -398.666716) (xy 373.246904 -398.666716) (xy 373.236881 -398.667123)
			(xy 373.218361 -398.674795) (xy 373.204188 -398.688971) (xy 373.196521 -398.707493) (xy 373.196104 -398.717516)
			(xy 373.196104 -398.881092) (xy 373.195674 -398.891112) (xy 373.188008 -398.909628) (xy 373.173838 -398.923801)
			(xy 373.155324 -398.931472) (xy 373.145304 -398.931892) (xy 372.637304 -398.931892) (xy 372.627282 -398.931477)
			(xy 372.608764 -398.923807) (xy 372.594591 -398.909633) (xy 372.586922 -398.891114) (xy 372.586504 -398.881092)
			(xy 372.586504 -398.666716) (xy 372.57736 -398.666716) (xy 372.567352 -398.666245) (xy 372.548862 -398.658575)
			(xy 372.534711 -398.644418) (xy 372.52705 -398.625924) (xy 372.52656 -398.615916) (xy 372.52656 -398.411954)
			(xy 372.5269 -398.394721) (xy 372.532472 -398.360708) (xy 372.543446 -398.328035) (xy 372.551198 -398.31264)
			(xy 372.55704 -398.30121) (xy 372.556786 -398.27581) (xy 372.503192 -398.178782) (xy 372.481602 -398.165066)
			(xy 372.468648 -398.16405) (xy 372.444753 -398.161913) (xy 372.397967 -398.151315) (xy 372.353326 -398.133751)
			(xy 372.311862 -398.109627) (xy 372.274531 -398.079498) (xy 372.242197 -398.044062) (xy 372.215604 -398.004135)
			(xy 372.195369 -397.96064) (xy 372.188232 -397.937736) (xy 372.186708 -397.931894) (xy 371.866414 -397.378174)
			(xy 371.86235 -397.373856) (xy 371.84619 -397.356123) (xy 371.818822 -397.31672) (xy 371.797732 -397.27363)
			(xy 371.783404 -397.227845) (xy 371.77617 -397.180419) (xy 371.775736 -397.156432) (xy 371.775918 -397.142384)
			(xy 371.778458 -397.114402) (xy 371.780816 -397.100552) (xy 371.782136 -397.091272) (xy 371.77861 -397.072876)
			(xy 371.773958 -397.064738) (xy 371.757194 -397.037814) (xy 371.752 -397.030104) (xy 371.737269 -397.018784)
			(xy 371.728492 -397.015716) (xy 371.706871 -397.0089) (xy 371.665656 -396.990023) (xy 371.627534 -396.965492)
			(xy 371.593277 -396.935803) (xy 371.578124 -396.918942) (xy 371.575662 -396.916169) (xy 371.570049 -396.911323)
			(xy 371.566948 -396.90929) (xy 371.554886 -396.90123) (xy 371.534929 -396.880187) (xy 371.520854 -396.854829)
			(xy 371.513553 -396.826762) (xy 371.5131 -396.812262) (xy 371.5131 -396.800324) (xy 371.511576 -396.79372)
			(xy 371.50637 -396.773351) (xy 371.500769 -396.731683) (xy 371.5004 -396.710662) (xy 370.93652 -396.710662)
			(xy 370.93652 -396.71117) (xy 370.936349 -396.725795) (xy 370.933682 -396.754924) (xy 370.931186 -396.769336)
			(xy 370.929824 -396.77851) (xy 370.933096 -396.796752) (xy 370.937536 -396.804896) (xy 370.954046 -396.83182)
			(xy 370.959215 -396.839599) (xy 370.973941 -396.851061) (xy 370.982748 -396.854172) (xy 371.007638 -396.862212)
			(xy 371.054516 -396.885407) (xy 371.096927 -396.916016) (xy 371.133709 -396.953201) (xy 371.163854 -396.995943)
			(xy 371.186537 -397.043071) (xy 371.19433 -397.06804) (xy 371.195854 -397.073882) (xy 371.516148 -397.627602)
			(xy 371.520212 -397.63192) (xy 371.536406 -397.649637) (xy 371.563831 -397.689025) (xy 371.584975 -397.732113)
			(xy 371.599352 -397.777905) (xy 371.606628 -397.825346) (xy 371.60708 -397.849344) (xy 371.606609 -397.874807)
			(xy 371.59841 -397.92507) (xy 371.582246 -397.973364) (xy 371.558538 -398.018436) (xy 371.5279 -398.059116)
			(xy 371.491128 -398.094349) (xy 371.470428 -398.109186) (xy 371.461916 -398.115623) (xy 371.450718 -398.133766)
			(xy 371.447846 -398.154891) (xy 371.453795 -398.175365) (xy 371.467541 -398.191662) (xy 371.486717 -398.200979)
			(xy 371.497352 -398.201896) (xy 371.507258 -398.201388) (xy 371.515708 -398.200097) (xy 371.532747 -398.198701)
			(xy 371.541294 -398.198594) (xy 371.541548 -398.198848) (xy 371.84076 -398.198848) (xy 371.841014 -398.198594)
			(xy 371.86206 -398.199021) (xy 371.903379 -398.207012) (xy 371.942334 -398.222939) (xy 371.977416 -398.246186)
			(xy 372.007267 -398.275852) (xy 372.030732 -398.310788) (xy 372.046903 -398.349643) (xy 372.055152 -398.390912)
			(xy 372.055644 -398.411954) (xy 372.055644 -398.666716) (xy 372.0465 -398.666716) (xy 372.036477 -398.66712)
			(xy 372.017957 -398.674793) (xy 372.003784 -398.68897) (xy 371.996117 -398.707493) (xy 371.9957 -398.717516)
			(xy 371.9957 -398.881092) (xy 371.995274 -398.891113) (xy 371.987607 -398.90963) (xy 371.973436 -398.923802)
			(xy 371.954921 -398.931472) (xy 371.9449 -398.931892) (xy 371.437408 -398.931892) (xy 371.427386 -398.931474)
			(xy 371.408868 -398.923805) (xy 371.394695 -398.909632) (xy 371.387026 -398.891114) (xy 371.386608 -398.881092)
			(xy 371.386608 -398.717516) (xy 371.386168 -398.707497) (xy 371.378505 -398.688982) (xy 371.364339 -398.674809)
			(xy 371.345827 -398.667137) (xy 371.335808 -398.666716) (xy 371.326664 -398.666716) (xy 371.326664 -398.411446)
			(xy 371.327444 -398.385723) (xy 371.339779 -398.335777) (xy 371.351048 -398.31264) (xy 371.35689 -398.30121)
			(xy 371.356636 -398.27581) (xy 371.309138 -398.190212) (xy 371.302431 -398.179422) (xy 371.281097 -398.165689)
			(xy 371.268498 -398.16405) (xy 371.244622 -398.161885) (xy 371.197878 -398.151252) (xy 371.153281 -398.133666)
			(xy 371.11186 -398.109534) (xy 371.074568 -398.07941) (xy 371.042265 -398.043989) (xy 371.015696 -398.004087)
			(xy 370.995472 -397.960623) (xy 370.988336 -397.937736) (xy 370.986812 -397.931894) (xy 370.666518 -397.378174)
			(xy 370.662454 -397.373856) (xy 370.646295 -397.356122) (xy 370.618926 -397.31672) (xy 370.597836 -397.27363)
			(xy 370.583508 -397.227845) (xy 370.576274 -397.180419) (xy 370.57584 -397.156432) (xy 370.576022 -397.142384)
			(xy 370.578562 -397.114402) (xy 370.58092 -397.100552) (xy 370.582239 -397.091272) (xy 370.578713 -397.072876)
			(xy 370.574062 -397.064738) (xy 370.557298 -397.037814) (xy 370.552103 -397.030105) (xy 370.537372 -397.018785)
			(xy 370.528596 -397.015716) (xy 370.506976 -397.008898) (xy 370.46576 -396.990022) (xy 370.427639 -396.965492)
			(xy 370.393381 -396.935803) (xy 370.378228 -396.918942) (xy 370.375765 -396.91617) (xy 370.370153 -396.911323)
			(xy 370.367052 -396.90929) (xy 370.354991 -396.901229) (xy 370.335033 -396.880186) (xy 370.320959 -396.854829)
			(xy 370.313657 -396.826762) (xy 370.313204 -396.812262) (xy 370.313204 -396.800324) (xy 370.31168 -396.79372)
			(xy 370.306474 -396.773351) (xy 370.300873 -396.731683) (xy 370.300504 -396.710662) (xy 368.534158 -396.710662)
			(xy 368.527467 -396.753845) (xy 368.520218 -396.778226) (xy 368.517932 -396.785846) (xy 368.517932 -396.876778)
			(xy 368.517393 -396.893439) (xy 368.508783 -396.925631) (xy 368.492143 -396.954501) (xy 368.468603 -396.978087)
			(xy 368.439766 -396.994785) (xy 368.407592 -397.00346) (xy 368.390932 -397.004032) (xy 368.26063 -397.004032)
			(xy 368.25682 -397.004794) (xy 368.244015 -397.006705) (xy 368.218204 -397.008737) (xy 368.205258 -397.008858)
			(xy 368.20475 -397.008858) (xy 368.191805 -397.008715) (xy 368.165995 -397.006683) (xy 368.153188 -397.004794)
			(xy 368.149378 -397.004032) (xy 368.009424 -397.004032) (xy 367.992733 -397.003445) (xy 367.960485 -396.994822)
			(xy 367.931561 -396.978156) (xy 367.907929 -396.954579) (xy 367.891194 -396.925696) (xy 367.882495 -396.893468)
			(xy 367.881916 -396.876778) (xy 367.881916 -396.749524) (xy 367.8809 -396.744444) (xy 367.877792 -396.728047)
			(xy 367.874481 -396.694838) (xy 367.874296 -396.67815) (xy 367.672338 -396.67815) (xy 367.672366 -396.679674)
			(xy 367.671857 -396.70756) (xy 367.663737 -396.762736) (xy 367.647669 -396.816143) (xy 367.623997 -396.86664)
			(xy 367.593224 -396.913153) (xy 367.556007 -396.95469) (xy 367.513139 -396.990365) (xy 367.465533 -397.019419)
			(xy 367.414204 -397.041231) (xy 367.360247 -397.055337) (xy 367.30481 -397.061437) (xy 367.249076 -397.0594)
			(xy 367.194233 -397.04927) (xy 367.141449 -397.031263) (xy 367.091849 -397.005762) (xy 367.046491 -396.973311)
			(xy 367.006342 -396.934602) (xy 366.972256 -396.890459) (xy 366.94496 -396.841824) (xy 366.925037 -396.789733)
			(xy 366.912911 -396.735296) (xy 366.90884 -396.679674) (xy 365.83366 -396.679674) (xy 365.83366 -399.008092)
			(xy 367.862612 -399.008092) (xy 367.86302 -398.984859) (xy 367.869514 -398.938848) (xy 367.882388 -398.8942)
			(xy 367.901388 -398.851795) (xy 367.926138 -398.812469) (xy 367.940844 -398.794478) (xy 367.946686 -398.78762)
			(xy 367.953036 -398.770602) (xy 367.953036 -398.686782) (xy 367.946686 -398.669764) (xy 367.940844 -398.662906)
			(xy 367.926131 -398.644921) (xy 367.901384 -398.605591) (xy 367.882384 -398.563184) (xy 367.869507 -398.518537)
			(xy 367.863005 -398.472526) (xy 367.862612 -398.449292) (xy 367.863122 -398.423305) (xy 367.871252 -398.37197)
			(xy 367.887313 -398.32254) (xy 367.910909 -398.27623) (xy 367.941459 -398.234182) (xy 367.97821 -398.197431)
			(xy 368.020258 -398.166881) (xy 368.066568 -398.143285) (xy 368.115998 -398.127224) (xy 368.167333 -398.119094)
			(xy 368.219307 -398.119094) (xy 368.270642 -398.127224) (xy 368.320072 -398.143285) (xy 368.366382 -398.166881)
			(xy 368.40843 -398.197431) (xy 368.445181 -398.234182) (xy 368.475731 -398.27623) (xy 368.499327 -398.32254)
			(xy 368.515388 -398.37197) (xy 368.523518 -398.423305) (xy 368.524028 -398.449292) (xy 368.52366 -398.472527)
			(xy 368.517154 -398.518539) (xy 368.504271 -398.563187) (xy 368.485263 -398.605591) (xy 368.478763 -398.615916)
			(xy 370.12626 -398.615916) (xy 370.12626 -398.411954) (xy 370.126773 -398.390892) (xy 370.135019 -398.349584)
			(xy 370.151202 -398.310693) (xy 370.174694 -398.275728) (xy 370.204583 -398.246047) (xy 370.239711 -398.222799)
			(xy 370.278714 -398.206889) (xy 370.320079 -398.198931) (xy 370.341144 -398.198594) (xy 370.341398 -398.198848)
			(xy 370.64061 -398.198848) (xy 370.640864 -398.198594) (xy 370.661926 -398.198995) (xy 370.703285 -398.20695)
			(xy 370.742283 -398.222855) (xy 370.777409 -398.246094) (xy 370.807301 -398.275765) (xy 370.830799 -398.310717)
			(xy 370.846993 -398.349597) (xy 370.855254 -398.390896) (xy 370.855748 -398.411954) (xy 370.855748 -398.666716)
			(xy 370.846604 -398.666716) (xy 370.836581 -398.667123) (xy 370.818061 -398.674795) (xy 370.803888 -398.688971)
			(xy 370.796221 -398.707493) (xy 370.795804 -398.717516) (xy 370.795804 -398.881092) (xy 370.795374 -398.891112)
			(xy 370.787708 -398.909628) (xy 370.773538 -398.923801) (xy 370.755024 -398.931472) (xy 370.745004 -398.931892)
			(xy 370.237004 -398.931892) (xy 370.226982 -398.931477) (xy 370.208464 -398.923807) (xy 370.194291 -398.909633)
			(xy 370.186622 -398.891114) (xy 370.186204 -398.881092) (xy 370.186204 -398.666716) (xy 370.17706 -398.666716)
			(xy 370.167052 -398.666245) (xy 370.148562 -398.658575) (xy 370.134411 -398.644418) (xy 370.12675 -398.625924)
			(xy 370.12626 -398.615916) (xy 368.478763 -398.615916) (xy 368.460505 -398.644916) (xy 368.445796 -398.662906)
			(xy 368.439954 -398.669764) (xy 368.433604 -398.686782) (xy 368.433604 -398.770602) (xy 368.439954 -398.78762)
			(xy 368.445796 -398.794478) (xy 368.460508 -398.812464) (xy 368.485254 -398.851795) (xy 368.504253 -398.894201)
			(xy 368.517131 -398.938848) (xy 368.523634 -398.984858) (xy 368.524028 -399.008092) (xy 368.524028 -399.008346)
			(xy 368.523596 -399.032396) (xy 368.516606 -399.079986) (xy 368.502808 -399.126065) (xy 368.49304 -399.148046)
			(xy 368.487706 -399.159476) (xy 368.488976 -399.184622) (xy 368.53876 -399.26768) (xy 368.545714 -399.278029)
			(xy 368.567008 -399.290947) (xy 368.5794 -399.292318) (xy 368.604399 -399.294129) (xy 368.653444 -399.304467)
			(xy 368.700368 -399.322086) (xy 368.744097 -399.346583) (xy 368.783629 -399.377397) (xy 368.818059 -399.413823)
			(xy 368.846599 -399.455027) (xy 368.868595 -399.500066) (xy 368.883545 -399.547907) (xy 368.891104 -399.597457)
			(xy 368.891566 -399.622518) (xy 368.891056 -399.648505) (xy 368.882926 -399.69984) (xy 368.866865 -399.74927)
			(xy 368.843269 -399.79558) (xy 368.812719 -399.837628) (xy 368.775968 -399.874379) (xy 368.73392 -399.904929)
			(xy 368.68761 -399.928525) (xy 368.63818 -399.944586) (xy 368.586845 -399.952716) (xy 368.534871 -399.952716)
			(xy 368.483536 -399.944586) (xy 368.434106 -399.928525) (xy 368.387796 -399.904929) (xy 368.345748 -399.874379)
			(xy 368.308997 -399.837628) (xy 368.278447 -399.79558) (xy 368.254851 -399.74927) (xy 368.23879 -399.69984)
			(xy 368.23066 -399.648505) (xy 368.23015 -399.622518) (xy 368.23015 -399.622264) (xy 368.230587 -399.598214)
			(xy 368.237575 -399.550625) (xy 368.251371 -399.504546) (xy 368.261138 -399.482564) (xy 368.266472 -399.471134)
			(xy 368.265202 -399.445988) (xy 368.215418 -399.36293) (xy 368.208472 -399.352574) (xy 368.187172 -399.33966)
			(xy 368.174778 -399.338292) (xy 368.149786 -399.336403) (xy 368.100743 -399.326078) (xy 368.05382 -399.30847)
			(xy 368.010092 -399.283983) (xy 367.970559 -399.253177) (xy 367.936127 -399.216759) (xy 367.907585 -399.175563)
			(xy 367.885587 -399.130531) (xy 367.870636 -399.082695) (xy 367.863074 -399.033151) (xy 367.862612 -399.008092)
			(xy 365.83366 -399.008092) (xy 365.83366 -399.528284) (xy 365.83322 -399.538346) (xy 365.82548 -399.556925)
			(xy 365.818674 -399.564352) (xy 365.617506 -399.76552) (xy 365.610112 -399.772376) (xy 365.591513 -399.780125)
			(xy 365.581438 -399.780506) (xy 364.400592 -399.780506) (xy 364.390523 -399.780931) (xy 364.371921 -399.788648)
			(xy 364.364524 -399.795492) (xy 364.260384 -399.899632) (xy 364.253533 -399.907028) (xy 364.245797 -399.925627)
			(xy 364.245398 -399.9357) (xy 364.245398 -400.633946) (xy 367.086896 -400.633946) (xy 367.087386 -400.603978)
			(xy 367.095209 -400.544556) (xy 367.110722 -400.486663) (xy 367.133658 -400.43129) (xy 367.163625 -400.379384)
			(xy 367.200112 -400.331834) (xy 367.242492 -400.289454) (xy 367.290042 -400.252967) (xy 367.341948 -400.223)
			(xy 367.397321 -400.200064) (xy 367.455214 -400.184551) (xy 367.514636 -400.176728) (xy 367.574572 -400.176728)
			(xy 367.633994 -400.184551) (xy 367.691887 -400.200064) (xy 367.74726 -400.223) (xy 367.79913 -400.252946)
			(xy 369.222528 -400.252946) (xy 369.222528 -399.998184) (xy 369.231672 -399.998184) (xy 369.241693 -399.997757)
			(xy 369.260213 -399.990093) (xy 369.274387 -399.975923) (xy 369.282055 -399.957405) (xy 369.282472 -399.947384)
			(xy 369.282472 -399.783808) (xy 369.282994 -399.773804) (xy 369.290646 -399.755318) (xy 369.304788 -399.741166)
			(xy 369.323269 -399.733501) (xy 369.333272 -399.733008) (xy 369.841272 -399.733008) (xy 369.851292 -399.733443)
			(xy 369.86981 -399.741105) (xy 369.883984 -399.755273) (xy 369.891653 -399.773788) (xy 369.892072 -399.783808)
			(xy 369.892072 -399.998184) (xy 369.901216 -399.998184) (xy 369.911223 -399.998674) (xy 369.929712 -400.006336)
			(xy 369.943864 -400.020488) (xy 369.951526 -400.038977) (xy 369.952016 -400.048984) (xy 369.952016 -400.252946)
			(xy 369.951466 -400.275554) (xy 369.941942 -400.319756) (xy 369.923329 -400.360964) (xy 369.896462 -400.397333)
			(xy 369.87988 -400.412712) (xy 369.873022 -400.418808) (xy 369.864386 -400.43481) (xy 369.854226 -400.50974)
			(xy 369.853352 -400.518623) (xy 369.857112 -400.536057) (xy 369.861592 -400.543776) (xy 369.861846 -400.543776)
			(xy 369.861846 -400.544284) (xy 369.873897 -400.563649) (xy 369.892964 -400.605081) (xy 369.905914 -400.648812)
			(xy 369.912482 -400.693946) (xy 369.9129 -400.71675) (xy 369.91241 -400.741739) (xy 369.904591 -400.791102)
			(xy 369.889147 -400.838634) (xy 369.866457 -400.883166) (xy 369.837081 -400.923599) (xy 369.801741 -400.958939)
			(xy 369.761308 -400.988315) (xy 369.716776 -401.011005) (xy 369.669244 -401.026449) (xy 369.619881 -401.034268)
			(xy 369.569903 -401.034268) (xy 369.52054 -401.026449) (xy 369.473008 -401.011005) (xy 369.428476 -400.988315)
			(xy 369.388043 -400.958939) (xy 369.352703 -400.923599) (xy 369.323327 -400.883166) (xy 369.300637 -400.838634)
			(xy 369.285193 -400.791102) (xy 369.277374 -400.741739) (xy 369.276884 -400.71675) (xy 369.277565 -400.687549)
			(xy 369.288214 -400.630127) (xy 369.309163 -400.575613) (xy 369.323874 -400.55038) (xy 369.328341 -400.542382)
			(xy 369.331861 -400.524419) (xy 369.330732 -400.515328) (xy 369.317778 -400.43989) (xy 369.308888 -400.424396)
			(xy 369.301776 -400.418554) (xy 369.301268 -400.418046) (xy 369.286842 -400.405804) (xy 369.262172 -400.37712)
			(xy 369.242937 -400.344542) (xy 369.229736 -400.309087) (xy 369.222982 -400.271861) (xy 369.222528 -400.252946)
			(xy 367.79913 -400.252946) (xy 367.799166 -400.252967) (xy 367.846716 -400.289454) (xy 367.889096 -400.331834)
			(xy 367.925583 -400.379384) (xy 367.95555 -400.43129) (xy 367.978486 -400.486663) (xy 367.993999 -400.544556)
			(xy 368.001822 -400.603978) (xy 368.002312 -400.633946) (xy 368.001707 -400.667261) (xy 367.992012 -400.733183)
			(xy 367.983008 -400.765264) (xy 367.98065 -400.774679) (xy 367.982341 -400.793999) (xy 367.98631 -400.802856)
			(xy 368.018314 -400.86534) (xy 368.023046 -400.873784) (xy 368.037541 -400.886587) (xy 368.046508 -400.890232)
			(xy 368.046762 -400.890232) (xy 368.071296 -400.89927) (xy 368.117794 -400.923179) (xy 368.160592 -400.953214)
			(xy 368.198886 -400.988813) (xy 368.23196 -401.029308) (xy 368.259194 -401.073941) (xy 368.280077 -401.121874)
			(xy 368.294218 -401.172211) (xy 368.301352 -401.224007) (xy 368.301778 -401.25015) (xy 368.301292 -401.277401)
			(xy 368.293536 -401.331349) (xy 368.278181 -401.383644) (xy 368.255539 -401.433221) (xy 368.226073 -401.479071)
			(xy 368.190382 -401.520262) (xy 368.149191 -401.555953) (xy 368.103341 -401.585419) (xy 368.053764 -401.608061)
			(xy 368.001469 -401.623416) (xy 367.947521 -401.631172) (xy 367.893019 -401.631172) (xy 367.839071 -401.623416)
			(xy 367.786776 -401.608061) (xy 367.737199 -401.585419) (xy 367.691349 -401.555953) (xy 367.650158 -401.520262)
			(xy 367.614467 -401.479071) (xy 367.585001 -401.433221) (xy 367.562359 -401.383644) (xy 367.547004 -401.331349)
			(xy 367.539248 -401.277401) (xy 367.538762 -401.25015) (xy 367.538852 -401.236963) (xy 367.540629 -401.21065)
			(xy 367.542318 -401.197572) (xy 367.543588 -401.18792) (xy 367.539016 -401.169124) (xy 367.486438 -401.095972)
			(xy 367.470182 -401.085558) (xy 367.460784 -401.08378) (xy 367.46053 -401.08378) (xy 367.429441 -401.077402)
			(xy 367.369261 -401.057258) (xy 367.312442 -401.02899) (xy 367.260076 -400.993139) (xy 367.213167 -400.950395)
			(xy 367.172616 -400.901578) (xy 367.139202 -400.847625) (xy 367.113565 -400.789571) (xy 367.096198 -400.728532)
			(xy 367.087434 -400.665677) (xy 367.086896 -400.633946) (xy 364.245398 -400.633946) (xy 364.245398 -401.21078)
			(xy 364.249208 -401.220178) (xy 364.253677 -401.231807) (xy 364.258539 -401.256238) (xy 364.25886 -401.268692)
			(xy 364.25886 -401.674838) (xy 370.534692 -401.674838) (xy 370.534692 -400.811238) (xy 370.535132 -400.785719)
			(xy 370.541921 -400.735133) (xy 370.555396 -400.685906) (xy 370.575316 -400.638915) (xy 370.601326 -400.595002)
			(xy 370.632961 -400.554949) (xy 370.651024 -400.536918) (xy 370.657628 -400.530568) (xy 370.665502 -400.513804)
			(xy 370.67236 -400.42846) (xy 370.66728 -400.41068) (xy 370.661692 -400.403314) (xy 370.646837 -400.382569)
			(xy 370.623203 -400.337354) (xy 370.607104 -400.288941) (xy 370.598952 -400.238578) (xy 370.598446 -400.213068)
			(xy 370.598446 -400.212814) (xy 370.598936 -400.187825) (xy 370.606755 -400.138462) (xy 370.622199 -400.09093)
			(xy 370.644889 -400.046398) (xy 370.674265 -400.005965) (xy 370.709605 -399.970625) (xy 370.750038 -399.941249)
			(xy 370.79457 -399.918559) (xy 370.842102 -399.903115) (xy 370.891465 -399.895296) (xy 370.941443 -399.895296)
			(xy 370.990806 -399.903115) (xy 371.038338 -399.918559) (xy 371.08287 -399.941249) (xy 371.123303 -399.970625)
			(xy 371.158643 -400.005965) (xy 371.188019 -400.046398) (xy 371.210709 -400.09093) (xy 371.226153 -400.138462)
			(xy 371.233972 -400.187825) (xy 371.234462 -400.212814) (xy 371.234462 -400.213068) (xy 371.233957 -400.238576)
			(xy 371.225781 -400.288935) (xy 371.209682 -400.337346) (xy 371.186072 -400.382571) (xy 371.171216 -400.403314)
			(xy 371.165628 -400.41068) (xy 371.160548 -400.42846) (xy 371.167406 -400.513804) (xy 371.17528 -400.530568)
			(xy 371.181884 -400.536918) (xy 371.199924 -400.554971) (xy 371.231553 -400.595024) (xy 371.257562 -400.638935)
			(xy 371.277489 -400.68592) (xy 371.290977 -400.735141) (xy 371.297786 -400.78572) (xy 371.298216 -400.811238)
			(xy 371.298216 -401.674838) (xy 371.734588 -401.674838) (xy 371.734588 -400.811238) (xy 371.735029 -400.785719)
			(xy 371.741818 -400.735134) (xy 371.755293 -400.685906) (xy 371.775213 -400.638916) (xy 371.801223 -400.595002)
			(xy 371.832857 -400.554949) (xy 371.85092 -400.536918) (xy 371.857778 -400.530568) (xy 371.865652 -400.513804)
			(xy 371.871748 -400.43735) (xy 371.872086 -400.428286) (xy 371.867149 -400.410846) (xy 371.862096 -400.403314)
			(xy 371.861842 -400.40306) (xy 371.846975 -400.382324) (xy 371.823352 -400.337103) (xy 371.807257 -400.288688)
			(xy 371.799104 -400.238324) (xy 371.798596 -400.212814) (xy 371.799086 -400.187825) (xy 371.806905 -400.138462)
			(xy 371.822349 -400.09093) (xy 371.845039 -400.046398) (xy 371.874415 -400.005965) (xy 371.909755 -399.970625)
			(xy 371.950188 -399.941249) (xy 371.99472 -399.918559) (xy 372.042252 -399.903115) (xy 372.091615 -399.895296)
			(xy 372.141593 -399.895296) (xy 372.190956 -399.903115) (xy 372.238488 -399.918559) (xy 372.28302 -399.941249)
			(xy 372.323453 -399.970625) (xy 372.358793 -400.005965) (xy 372.388169 -400.046398) (xy 372.410859 -400.09093)
			(xy 372.426303 -400.138462) (xy 372.434122 -400.187825) (xy 372.434612 -400.212814) (xy 372.434086 -400.238366)
			(xy 372.4259 -400.28881) (xy 372.409743 -400.337293) (xy 372.38603 -400.382563) (xy 372.371112 -400.403314)
			(xy 372.365524 -400.41068) (xy 372.360444 -400.42846) (xy 372.36654 -400.504914) (xy 372.367631 -400.513914)
			(xy 372.375307 -400.530322) (xy 372.381526 -400.536918) (xy 372.38178 -400.537172) (xy 372.399824 -400.555193)
			(xy 372.43144 -400.595207) (xy 372.457443 -400.639077) (xy 372.477367 -400.68602) (xy 372.490859 -400.7352)
			(xy 372.497676 -400.78574) (xy 372.498112 -400.811238) (xy 372.498112 -401.674838) (xy 372.934992 -401.674838)
			(xy 372.934992 -400.81073) (xy 372.935434 -400.785262) (xy 372.942237 -400.734783) (xy 372.955697 -400.685658)
			(xy 372.975577 -400.638762) (xy 373.001521 -400.594929) (xy 373.033069 -400.554939) (xy 373.05107 -400.536918)
			(xy 373.057674 -400.530568) (xy 373.065548 -400.513804) (xy 373.072406 -400.42846) (xy 373.067326 -400.41068)
			(xy 373.061738 -400.403314) (xy 373.046888 -400.382565) (xy 373.023253 -400.337352) (xy 373.007151 -400.288941)
			(xy 372.998998 -400.238577) (xy 372.998492 -400.213068) (xy 372.998492 -400.212814) (xy 372.998982 -400.187825)
			(xy 373.006801 -400.138462) (xy 373.022245 -400.09093) (xy 373.044935 -400.046398) (xy 373.074311 -400.005965)
			(xy 373.109651 -399.970625) (xy 373.150084 -399.941249) (xy 373.194616 -399.918559) (xy 373.242148 -399.903115)
			(xy 373.291511 -399.895296) (xy 373.341489 -399.895296) (xy 373.390852 -399.903115) (xy 373.438384 -399.918559)
			(xy 373.482916 -399.941249) (xy 373.523349 -399.970625) (xy 373.558689 -400.005965) (xy 373.588065 -400.046398)
			(xy 373.610755 -400.09093) (xy 373.626199 -400.138462) (xy 373.634018 -400.187825) (xy 373.634508 -400.212814)
			(xy 373.634508 -400.213068) (xy 373.634013 -400.238577) (xy 373.625836 -400.288936) (xy 373.609735 -400.337348)
			(xy 373.58612 -400.382572) (xy 373.571262 -400.403314) (xy 373.565674 -400.41068) (xy 373.560594 -400.42846)
			(xy 373.567452 -400.513804) (xy 373.575326 -400.530568) (xy 373.58193 -400.536918) (xy 373.599925 -400.554944)
			(xy 373.631467 -400.594937) (xy 373.65741 -400.63877) (xy 373.67729 -400.685664) (xy 373.690756 -400.734786)
			(xy 373.697567 -400.785263) (xy 373.698008 -400.81073) (xy 373.698008 -401.674838) (xy 373.697998 -401.675346)
			(xy 374.134888 -401.675346) (xy 374.134888 -400.81073) (xy 374.135332 -400.785262) (xy 374.142134 -400.734783)
			(xy 374.155594 -400.685658) (xy 374.175474 -400.638762) (xy 374.201418 -400.594929) (xy 374.232966 -400.554939)
			(xy 374.250966 -400.536918) (xy 374.25757 -400.530568) (xy 374.265444 -400.513804) (xy 374.272302 -400.42846)
			(xy 374.267222 -400.41068) (xy 374.261634 -400.403314) (xy 374.246784 -400.382566) (xy 374.223148 -400.337352)
			(xy 374.207047 -400.288941) (xy 374.198894 -400.238577) (xy 374.198388 -400.213068) (xy 374.198388 -400.212814)
			(xy 374.198878 -400.187825) (xy 374.206697 -400.138462) (xy 374.222141 -400.09093) (xy 374.244831 -400.046398)
			(xy 374.274207 -400.005965) (xy 374.309547 -399.970625) (xy 374.34998 -399.941249) (xy 374.394512 -399.918559)
			(xy 374.442044 -399.903115) (xy 374.491407 -399.895296) (xy 374.541385 -399.895296) (xy 374.590748 -399.903115)
			(xy 374.63828 -399.918559) (xy 374.682812 -399.941249) (xy 374.723245 -399.970625) (xy 374.758585 -400.005965)
			(xy 374.787961 -400.046398) (xy 374.810651 -400.09093) (xy 374.826095 -400.138462) (xy 374.833914 -400.187825)
			(xy 374.834404 -400.212814) (xy 374.834404 -400.213068) (xy 374.83391 -400.238577) (xy 374.825733 -400.288936)
			(xy 374.809631 -400.337348) (xy 374.786016 -400.382572) (xy 374.771158 -400.403314) (xy 374.76557 -400.41068)
			(xy 374.76049 -400.42846) (xy 374.767348 -400.513804) (xy 374.775222 -400.530568) (xy 374.781826 -400.536918)
			(xy 374.79982 -400.554945) (xy 374.831363 -400.594937) (xy 374.857305 -400.63877) (xy 374.877186 -400.685664)
			(xy 374.890652 -400.734786) (xy 374.897463 -400.785263) (xy 374.897904 -400.81073) (xy 374.897904 -401.675346)
			(xy 374.897414 -401.703743) (xy 374.889002 -401.759911) (xy 374.872342 -401.814206) (xy 374.847804 -401.865425)
			(xy 374.815931 -401.912432) (xy 374.797066 -401.933664) (xy 374.7912 -401.940596) (xy 374.784297 -401.957377)
			(xy 374.783604 -401.96643) (xy 374.782588 -401.997418) (xy 374.782645 -402.006569) (xy 374.788512 -402.02389)
			(xy 374.794018 -402.0312) (xy 374.809355 -402.050553) (xy 374.835131 -402.092671) (xy 374.854911 -402.137916)
			(xy 374.868325 -402.185439) (xy 374.87512 -402.234349) (xy 374.875552 -402.259038) (xy 374.87505 -402.285915)
			(xy 374.867038 -402.33907) (xy 374.851194 -402.390436) (xy 374.82787 -402.438868) (xy 374.797589 -402.483282)
			(xy 374.761027 -402.522687) (xy 374.718999 -402.556203) (xy 374.672446 -402.58308) (xy 374.622407 -402.602719)
			(xy 374.57 -402.61468) (xy 374.516396 -402.618698) (xy 374.462792 -402.61468) (xy 374.410385 -402.602719)
			(xy 374.360346 -402.58308) (xy 374.313793 -402.556203) (xy 374.271765 -402.522687) (xy 374.235203 -402.483282)
			(xy 374.204922 -402.438868) (xy 374.181598 -402.390436) (xy 374.165754 -402.33907) (xy 374.157742 -402.285915)
			(xy 374.15724 -402.259038) (xy 374.157652 -402.234345) (xy 374.164408 -402.185423) (xy 374.17781 -402.13789)
			(xy 374.197605 -402.092645) (xy 374.223419 -402.050543) (xy 374.238774 -402.0312) (xy 374.244259 -402.023882)
			(xy 374.250102 -402.006564) (xy 374.250204 -401.997418) (xy 374.249188 -401.96643) (xy 374.248536 -401.957367)
			(xy 374.241625 -401.940576) (xy 374.235726 -401.933664) (xy 374.216917 -401.912392) (xy 374.185094 -401.865369)
			(xy 374.160576 -401.814156) (xy 374.143902 -401.75988) (xy 374.135439 -401.703735) (xy 374.134888 -401.675346)
			(xy 373.697998 -401.675346) (xy 373.69746 -401.703992) (xy 373.688589 -401.76162) (xy 373.671059 -401.81723)
			(xy 373.645278 -401.869527) (xy 373.611845 -401.917297) (xy 373.59209 -401.938744) (xy 373.585933 -401.945828)
			(xy 373.578775 -401.963162) (xy 373.57812 -401.972526) (xy 373.576342 -402.041106) (xy 373.576477 -402.050363)
			(xy 373.582616 -402.067817) (xy 373.58828 -402.075142) (xy 373.588788 -402.07565) (xy 373.605102 -402.095283)
			(xy 373.632575 -402.138305) (xy 373.653678 -402.184784) (xy 373.667986 -402.233783) (xy 373.67521 -402.284315)
			(xy 373.675656 -402.309838) (xy 373.675154 -402.336715) (xy 373.667142 -402.38987) (xy 373.651298 -402.441236)
			(xy 373.627974 -402.489668) (xy 373.597693 -402.534082) (xy 373.561131 -402.573487) (xy 373.519103 -402.607003)
			(xy 373.47255 -402.63388) (xy 373.422511 -402.653519) (xy 373.370104 -402.66548) (xy 373.3165 -402.669498)
			(xy 373.262896 -402.66548) (xy 373.210489 -402.653519) (xy 373.16045 -402.63388) (xy 373.113897 -402.607003)
			(xy 373.071869 -402.573487) (xy 373.035307 -402.534082) (xy 373.005026 -402.489668) (xy 372.981702 -402.441236)
			(xy 372.965858 -402.38987) (xy 372.957846 -402.336715) (xy 372.957344 -402.309838) (xy 372.957818 -402.284281)
			(xy 372.965054 -402.233682) (xy 372.979399 -402.184622) (xy 373.000562 -402.138095) (xy 373.028116 -402.095044)
			(xy 373.044466 -402.075396) (xy 373.04472 -402.075142) (xy 373.05039 -402.067825) (xy 373.056496 -402.050363)
			(xy 373.056658 -402.041106) (xy 373.054626 -401.962874) (xy 373.047514 -401.945856) (xy 373.04091 -401.938744)
			(xy 373.021176 -401.917278) (xy 372.987738 -401.869515) (xy 372.961952 -401.817222) (xy 372.944419 -401.761616)
			(xy 372.935547 -401.70399) (xy 372.934992 -401.674838) (xy 372.498112 -401.674838) (xy 372.497605 -401.702712)
			(xy 372.489498 -401.757869) (xy 372.473447 -401.811257) (xy 372.449796 -401.86174) (xy 372.419047 -401.908242)
			(xy 372.40083 -401.929346) (xy 372.394988 -401.93595) (xy 372.38813 -401.952714) (xy 372.386098 -402.027136)
			(xy 372.386216 -402.036041) (xy 372.391809 -402.052934) (xy 372.39702 -402.060156) (xy 372.397274 -402.06041)
			(xy 372.412044 -402.079584) (xy 372.436872 -402.121132) (xy 372.455908 -402.165632) (xy 372.468809 -402.212281)
			(xy 372.475343 -402.260238) (xy 372.47576 -402.284438) (xy 372.475258 -402.311334) (xy 372.46724 -402.364526)
			(xy 372.451384 -402.415929) (xy 372.428045 -402.464395) (xy 372.397742 -402.508841) (xy 372.361154 -402.548274)
			(xy 372.319097 -402.581813) (xy 372.272511 -402.608709) (xy 372.222437 -402.628362) (xy 372.169992 -402.640332)
			(xy 372.11635 -402.644352) (xy 372.062708 -402.640332) (xy 372.010263 -402.628362) (xy 371.960189 -402.608709)
			(xy 371.913603 -402.581813) (xy 371.871546 -402.548274) (xy 371.834958 -402.508841) (xy 371.804655 -402.464395)
			(xy 371.781316 -402.415929) (xy 371.76546 -402.364526) (xy 371.757442 -402.311334) (xy 371.75694 -402.284438)
			(xy 371.757355 -402.260236) (xy 371.763855 -402.212269) (xy 371.776743 -402.165611) (xy 371.795784 -402.121109)
			(xy 371.820633 -402.079569) (xy 371.835426 -402.06041) (xy 371.83568 -402.060156) (xy 371.840946 -402.052965)
			(xy 371.846535 -402.03605) (xy 371.846602 -402.027136) (xy 371.84457 -401.952714) (xy 371.837712 -401.93595)
			(xy 371.83187 -401.929346) (xy 371.813666 -401.908232) (xy 371.782921 -401.86173) (xy 371.75927 -401.811249)
			(xy 371.743215 -401.757864) (xy 371.735098 -401.702711) (xy 371.734588 -401.674838) (xy 371.298216 -401.674838)
			(xy 371.297708 -401.702712) (xy 371.289601 -401.757868) (xy 371.273551 -401.811257) (xy 371.249899 -401.86174)
			(xy 371.219151 -401.908242) (xy 371.200934 -401.929346) (xy 371.195092 -401.93595) (xy 371.188234 -401.952714)
			(xy 371.186202 -402.027136) (xy 371.186319 -402.036041) (xy 371.191913 -402.052934) (xy 371.197124 -402.060156)
			(xy 371.197378 -402.06041) (xy 371.212149 -402.079584) (xy 371.236976 -402.121132) (xy 371.256012 -402.165631)
			(xy 371.268913 -402.212281) (xy 371.275447 -402.260238) (xy 371.275864 -402.284438) (xy 371.275362 -402.311334)
			(xy 371.267344 -402.364526) (xy 371.251488 -402.415929) (xy 371.228149 -402.464395) (xy 371.197846 -402.508841)
			(xy 371.161258 -402.548274) (xy 371.119201 -402.581813) (xy 371.072615 -402.608709) (xy 371.022541 -402.628362)
			(xy 370.970096 -402.640332) (xy 370.916454 -402.644352) (xy 370.862812 -402.640332) (xy 370.810367 -402.628362)
			(xy 370.760293 -402.608709) (xy 370.713707 -402.581813) (xy 370.67165 -402.548274) (xy 370.635062 -402.508841)
			(xy 370.604759 -402.464395) (xy 370.58142 -402.415929) (xy 370.565564 -402.364526) (xy 370.557546 -402.311334)
			(xy 370.557044 -402.284438) (xy 370.557458 -402.260235) (xy 370.563958 -402.212269) (xy 370.576846 -402.165611)
			(xy 370.595887 -402.121109) (xy 370.620736 -402.079569) (xy 370.63553 -402.06041) (xy 370.635784 -402.060156)
			(xy 370.64105 -402.052965) (xy 370.646639 -402.03605) (xy 370.646706 -402.027136) (xy 370.644674 -401.952714)
			(xy 370.637816 -401.93595) (xy 370.631974 -401.929346) (xy 370.61377 -401.908232) (xy 370.583025 -401.861729)
			(xy 370.559374 -401.811249) (xy 370.543319 -401.757864) (xy 370.535202 -401.702711) (xy 370.534692 -401.674838)
			(xy 364.25886 -401.674838) (xy 364.25886 -401.83816) (xy 364.259296 -401.848224) (xy 364.267032 -401.866807)
			(xy 364.273846 -401.874228) (xy 364.938818 -402.5392) (xy 364.945673 -402.546595) (xy 364.953421 -402.565194)
			(xy 364.953804 -402.575268) (xy 364.953804 -402.763986) (xy 369.229876 -402.763986) (xy 369.229876 -402.70405)
			(xy 369.237699 -402.644628) (xy 369.253212 -402.586735) (xy 369.276148 -402.531362) (xy 369.306115 -402.479456)
			(xy 369.342602 -402.431906) (xy 369.384982 -402.389526) (xy 369.432532 -402.353039) (xy 369.484438 -402.323072)
			(xy 369.539811 -402.300136) (xy 369.597704 -402.284623) (xy 369.657126 -402.2768) (xy 369.717062 -402.2768)
			(xy 369.776484 -402.284623) (xy 369.834377 -402.300136) (xy 369.88975 -402.323072) (xy 369.941656 -402.353039)
			(xy 369.989206 -402.389526) (xy 370.031586 -402.431906) (xy 370.068073 -402.479456) (xy 370.09804 -402.531362)
			(xy 370.120976 -402.586735) (xy 370.136489 -402.644628) (xy 370.144312 -402.70405) (xy 370.144802 -402.734018)
			(xy 370.144312 -402.763986) (xy 370.136489 -402.823408) (xy 370.120976 -402.881301) (xy 370.09804 -402.936674)
			(xy 370.068073 -402.98858) (xy 370.031586 -403.03613) (xy 369.989206 -403.07851) (xy 369.941656 -403.114997)
			(xy 369.88975 -403.144964) (xy 369.834377 -403.1679) (xy 369.776484 -403.183413) (xy 369.717062 -403.191236)
			(xy 369.657126 -403.191236) (xy 369.597704 -403.183413) (xy 369.539811 -403.1679) (xy 369.484438 -403.144964)
			(xy 369.432532 -403.114997) (xy 369.384982 -403.07851) (xy 369.342602 -403.03613) (xy 369.306115 -402.98858)
			(xy 369.276148 -402.936674) (xy 369.253212 -402.881301) (xy 369.237699 -402.823408) (xy 369.229876 -402.763986)
			(xy 364.953804 -402.763986) (xy 364.953804 -403.502368) (xy 364.95424 -403.512433) (xy 364.961972 -403.531019)
			(xy 364.96879 -403.538436) (xy 366.098285 -404.667931) (xy 367.299488 -404.667931) (xy 367.299488 -404.604009)
			(xy 367.307499 -404.540591) (xy 367.323396 -404.478677) (xy 367.346928 -404.419244) (xy 367.377722 -404.363229)
			(xy 367.415295 -404.311514) (xy 367.459052 -404.264917) (xy 367.508305 -404.224172) (xy 367.562276 -404.189921)
			(xy 367.620115 -404.162704) (xy 367.680908 -404.142951) (xy 367.743698 -404.130973) (xy 367.807494 -404.12696)
			(xy 367.87129 -404.130973) (xy 367.93408 -404.142951) (xy 367.994873 -404.162704) (xy 368.052712 -404.189921)
			(xy 368.106683 -404.224172) (xy 368.155936 -404.264917) (xy 368.199693 -404.311514) (xy 368.237266 -404.363229)
			(xy 368.26806 -404.419244) (xy 368.291592 -404.478677) (xy 368.307489 -404.540591) (xy 368.3155 -404.604009)
			(xy 368.316002 -404.63597) (xy 368.3155 -404.667931) (xy 368.307489 -404.731349) (xy 368.291592 -404.793263)
			(xy 368.26806 -404.852696) (xy 368.237266 -404.908711) (xy 368.199693 -404.960426) (xy 368.155936 -405.007023)
			(xy 368.106683 -405.047768) (xy 368.052712 -405.082019) (xy 367.994873 -405.109236) (xy 367.93408 -405.128989)
			(xy 367.87129 -405.140967) (xy 367.807494 -405.144981) (xy 367.743698 -405.140967) (xy 367.680908 -405.128989)
			(xy 367.620115 -405.109236) (xy 367.562276 -405.082019) (xy 367.508305 -405.047768) (xy 367.459052 -405.007023)
			(xy 367.415295 -404.960426) (xy 367.377722 -404.908711) (xy 367.346928 -404.852696) (xy 367.323396 -404.793263)
			(xy 367.307499 -404.731349) (xy 367.299488 -404.667931) (xy 366.098285 -404.667931) (xy 367.719356 -406.289002)
			(xy 367.726681 -406.295797) (xy 367.7451 -406.303504) (xy 367.765066 -406.30355) (xy 367.774474 -406.300178)
			(xy 367.79751 -406.291248) (xy 367.845296 -406.278698) (xy 367.894297 -406.272371) (xy 367.919 -406.271984)
			(xy 367.919508 -406.271984) (xy 367.946874 -406.272475) (xy 368.00104 -406.280328) (xy 368.053532 -406.295829)
			(xy 368.103275 -406.31866) (xy 368.149252 -406.348355) (xy 368.170206 -406.365964) (xy 368.177064 -406.37206)
			(xy 368.194082 -406.37841) (xy 368.27968 -406.378664) (xy 368.296698 -406.372314) (xy 368.303556 -406.366218)
			(xy 368.324485 -406.348632) (xy 368.370425 -406.319005) (xy 368.420123 -406.296238) (xy 368.472562 -406.280796)
			(xy 368.526668 -406.272995) (xy 368.554 -406.272492) (xy 368.582165 -406.272998) (xy 368.637883 -406.281285)
			(xy 368.691775 -406.297679) (xy 368.742668 -406.321824) (xy 368.789456 -406.353193) (xy 368.831119 -406.391105)
			(xy 368.866751 -406.434733) (xy 368.895578 -406.483129) (xy 368.906806 -406.508966) (xy 368.911011 -406.518103)
			(xy 368.925188 -406.532349) (xy 368.943747 -406.540064) (xy 368.953796 -406.540462)
		)
		(stroke
			(width 0)
			(type solid)
		)
		(fill yes)
		(layer "B.Cu")
		(net "P0V9_CPU0_RT3_2A")
	)
	(gr_poly
		(pts
			(xy 65.741296 -398.1577) (xy 65.748901 -398.156186) (xy 65.762736 -398.1492) (xy 65.768474 -398.143984)
			(xy 69.204586 -394.707618) (xy 69.211421 -394.700216) (xy 69.219128 -394.681617) (xy 69.219572 -394.67155)
			(xy 69.219572 -392.710162) (xy 69.220001 -392.700094) (xy 69.227722 -392.681497) (xy 69.234558 -392.674094)
			(xy 69.32676 -392.582146) (xy 69.328792 -392.579352) (xy 69.350222 -392.552002) (xy 69.399287 -392.502807)
			(xy 69.426582 -392.481308) (xy 69.427598 -392.480546) (xy 69.432932 -392.475974) (xy 69.505576 -392.40333)
			(xy 69.512977 -392.396492) (xy 69.531576 -392.388781) (xy 69.541644 -392.388344) (xy 69.553582 -392.388344)
			(xy 69.563644 -392.387904) (xy 69.582222 -392.380163) (xy 69.58965 -392.373358) (xy 69.602096 -392.360912)
			(xy 69.608945 -392.353514) (xy 69.616684 -392.334916) (xy 69.617082 -392.324844) (xy 69.617082 -389.513572)
			(xy 69.616653 -389.503504) (xy 69.60893 -389.484909) (xy 69.602096 -389.477504) (xy 69.572886 -389.448294)
			(xy 69.565486 -389.44145) (xy 69.546889 -389.433722) (xy 69.536818 -389.433308) (xy 68.560442 -389.433308)
			(xy 68.550376 -389.432875) (xy 68.531786 -389.425146) (xy 68.524374 -389.418322) (xy 68.290186 -389.184134)
			(xy 68.281572 -389.176334) (xy 68.259613 -389.168807) (xy 68.248022 -389.169656) (xy 68.157344 -389.180832)
			(xy 68.137786 -389.193532) (xy 68.13169 -389.203438) (xy 68.117365 -389.2258) (xy 68.082752 -389.266072)
			(xy 68.04217 -389.30032) (xy 68.019676 -389.314436) (xy 68.019168 -389.31469) (xy 68.017898 -389.315452)
			(xy 68.010852 -389.320301) (xy 68.000223 -389.33369) (xy 67.994592 -389.349831) (xy 67.994276 -389.358378)
			(xy 67.994276 -389.443722) (xy 67.994702 -389.453791) (xy 68.00242 -389.472392) (xy 68.009262 -389.47979)
			(xy 68.018914 -389.489442) (xy 68.02374 -389.49249) (xy 68.043889 -389.505484) (xy 68.080558 -389.536373)
			(xy 68.112372 -389.57224) (xy 68.138664 -389.612332) (xy 68.158881 -389.655806) (xy 68.172596 -389.701746)
			(xy 68.179523 -389.749188) (xy 68.17995 -389.77316) (xy 68.179533 -389.796932) (xy 68.172715 -389.843985)
			(xy 68.159228 -389.889576) (xy 68.13935 -389.932766) (xy 68.113491 -389.972663) (xy 68.098162 -389.990838)
			(xy 68.092066 -389.997696) (xy 68.085716 -390.014714) (xy 68.085716 -390.055608) (xy 68.086098 -390.064709)
			(xy 68.09249 -390.081752) (xy 68.098162 -390.088882) (xy 68.11351 -390.107042) (xy 68.139374 -390.146938)
			(xy 68.159249 -390.190131) (xy 68.172724 -390.235728) (xy 68.179521 -390.282787) (xy 68.17995 -390.30656)
			(xy 68.179392 -390.334148) (xy 68.170227 -390.388558) (xy 68.152159 -390.440692) (xy 68.12569 -390.489105)
			(xy 68.091555 -390.532455) (xy 68.050699 -390.569539) (xy 68.027804 -390.584944) (xy 68.027296 -390.584944)
			(xy 68.019676 -390.590024) (xy 68.008754 -390.604756) (xy 67.998594 -390.640824) (xy 67.997045 -390.646733)
			(xy 67.99654 -390.658934) (xy 67.997578 -390.664954) (xy 68.000372 -390.678924) (xy 68.002658 -390.684004)
			(xy 68.011736 -390.705272) (xy 68.024517 -390.749712) (xy 68.030962 -390.795503) (xy 68.03136 -390.818624)
			(xy 68.03136 -390.819132) (xy 68.03085 -390.845119) (xy 68.02272 -390.896454) (xy 68.006659 -390.945884)
			(xy 67.983063 -390.992194) (xy 67.952513 -391.034242) (xy 67.915762 -391.070993) (xy 67.873714 -391.101543)
			(xy 67.827404 -391.125139) (xy 67.777974 -391.1412) (xy 67.726639 -391.14933) (xy 67.674665 -391.14933)
			(xy 67.62333 -391.1412) (xy 67.5739 -391.125139) (xy 67.52759 -391.101543) (xy 67.485542 -391.070993)
			(xy 67.448791 -391.034242) (xy 67.418241 -390.992194) (xy 67.394645 -390.945884) (xy 67.378584 -390.896454)
			(xy 67.370454 -390.845119) (xy 67.369944 -390.819132) (xy 67.370502 -390.791544) (xy 67.379669 -390.737135)
			(xy 67.397738 -390.685001) (xy 67.424207 -390.636589) (xy 67.458342 -390.59324) (xy 67.499198 -390.556156)
			(xy 67.52209 -390.540748) (xy 67.522598 -390.540748) (xy 67.530218 -390.535668) (xy 67.54114 -390.520936)
			(xy 67.5513 -390.484868) (xy 67.552848 -390.478959) (xy 67.553351 -390.466758) (xy 67.552316 -390.460738)
			(xy 67.549522 -390.446768) (xy 67.547236 -390.441688) (xy 67.538153 -390.420421) (xy 67.525359 -390.375982)
			(xy 67.518901 -390.33019) (xy 67.518534 -390.307068) (xy 67.518534 -390.30656) (xy 67.518949 -390.282787)
			(xy 67.525765 -390.235733) (xy 67.539249 -390.190139) (xy 67.559125 -390.146948) (xy 67.584982 -390.107048)
			(xy 67.600322 -390.088882) (xy 67.606003 -390.08176) (xy 67.612383 -390.06471) (xy 67.612768 -390.055608)
			(xy 67.612768 -390.014714) (xy 67.606418 -389.997696) (xy 67.600322 -389.990838) (xy 67.584974 -389.972678)
			(xy 67.559108 -389.932782) (xy 67.539231 -389.889589) (xy 67.525754 -389.843992) (xy 67.518956 -389.796934)
			(xy 67.518534 -389.77316) (xy 67.518973 -389.748779) (xy 67.526144 -389.700546) (xy 67.540326 -389.653891)
			(xy 67.56121 -389.609826) (xy 67.588342 -389.569309) (xy 67.621134 -389.533218) (xy 67.658873 -389.502338)
			(xy 67.67957 -389.489442) (xy 67.686941 -389.484639) (xy 67.698137 -389.471084) (xy 67.704094 -389.454544)
			(xy 67.704462 -389.445754) (xy 67.704462 -389.36041) (xy 67.70404 -389.35034) (xy 67.696324 -389.331736)
			(xy 67.689476 -389.324342) (xy 67.679824 -389.31469) (xy 67.674998 -389.311642) (xy 67.654845 -389.29865)
			(xy 67.61817 -389.267764) (xy 67.586348 -389.231898) (xy 67.560049 -389.191807) (xy 67.539826 -389.148332)
			(xy 67.526104 -389.10239) (xy 67.519173 -389.054946) (xy 67.518788 -389.030972) (xy 67.519345 -389.003351)
			(xy 67.528523 -388.948878) (xy 67.546619 -388.896684) (xy 67.573131 -388.84822) (xy 67.607323 -388.804832)
			(xy 67.648244 -388.767723) (xy 67.671188 -388.752334) (xy 67.671442 -388.75208) (xy 67.678567 -388.747045)
			(xy 67.689171 -388.733206) (xy 67.694505 -388.716607) (xy 67.694556 -388.707884) (xy 67.691508 -388.6073)
			(xy 67.677792 -388.584694) (xy 67.665854 -388.57809) (xy 67.644162 -388.565456) (xy 67.604521 -388.53466)
			(xy 67.569988 -388.498228) (xy 67.541357 -388.456996) (xy 67.519284 -388.411912) (xy 67.504276 -388.36401)
			(xy 67.496677 -388.314391) (xy 67.496182 -388.289292) (xy 67.496182 -388.288784) (xy 67.496514 -388.268373)
			(xy 67.501606 -388.227869) (xy 67.506342 -388.208012) (xy 67.506342 -388.207504) (xy 67.508374 -388.199884)
			(xy 67.509951 -388.192123) (xy 67.508799 -388.176337) (xy 67.506088 -388.168896) (xy 67.49542 -388.141972)
			(xy 67.492032 -388.134369) (xy 67.481278 -388.121677) (xy 67.474338 -388.11708) (xy 67.449001 -388.10119)
			(xy 67.402852 -388.06315) (xy 67.362769 -388.018765) (xy 67.329615 -387.968991) (xy 67.304103 -387.914899)
			(xy 67.286785 -387.857656) (xy 67.278032 -387.798495) (xy 67.277488 -387.768592) (xy 67.278006 -387.739538)
			(xy 67.286274 -387.682022) (xy 67.302639 -387.626266) (xy 67.326769 -387.573406) (xy 67.358174 -387.524516)
			(xy 67.396214 -387.480591) (xy 67.440116 -387.442524) (xy 67.488987 -387.411089) (xy 67.541832 -387.386926)
			(xy 67.597577 -387.370527) (xy 67.655089 -387.362224) (xy 67.684142 -387.361684) (xy 67.79006 -387.361684)
			(xy 67.800085 -387.361271) (xy 67.818613 -387.353608) (xy 67.832794 -387.339434) (xy 67.840467 -387.320909)
			(xy 67.84086 -387.310884) (xy 67.84086 -387.004306) (xy 67.840437 -386.994236) (xy 67.832719 -386.975634)
			(xy 67.825874 -386.968238) (xy 66.742818 -385.885436) (xy 66.73598 -385.878035) (xy 66.728266 -385.859436)
			(xy 66.727832 -385.849368) (xy 66.727832 -383.827274) (xy 66.728261 -383.817207) (xy 66.735985 -383.798612)
			(xy 66.742818 -383.791206) (xy 66.76771 -383.766314) (xy 66.774422 -383.75888) (xy 66.782049 -383.740385)
			(xy 66.782042 -383.720378) (xy 66.7744 -383.701887) (xy 66.76771 -383.694432) (xy 66.482722 -383.409698)
			(xy 66.475874 -383.4023) (xy 66.468136 -383.383702) (xy 66.467736 -383.37363) (xy 66.467736 -382.619504)
			(xy 66.468159 -382.609434) (xy 66.475877 -382.590832) (xy 66.482722 -382.583436) (xy 66.596514 -382.469898)
			(xy 66.603369 -382.462503) (xy 66.611117 -382.443905) (xy 66.6115 -382.43383) (xy 66.6115 -379.624082)
			(xy 66.611073 -379.614013) (xy 66.603354 -379.595414) (xy 66.596514 -379.588014) (xy 66.382646 -379.374146)
			(xy 66.375247 -379.367303) (xy 66.356648 -379.359581) (xy 66.346578 -379.35916) (xy 60.666122 -379.35916)
			(xy 60.656059 -379.359599) (xy 60.637481 -379.36734) (xy 60.630054 -379.374146) (xy 60.517786 -379.486414)
			(xy 60.510932 -379.493809) (xy 60.50319 -379.512408) (xy 60.5028 -379.522482) (xy 60.5028 -382.619758)
			(xy 60.502366 -382.629823) (xy 60.494637 -382.648413) (xy 60.487814 -382.655826) (xy 60.264723 -382.878917)
			(xy 60.686444 -382.878917) (xy 60.686444 -382.826943) (xy 60.694574 -382.775608) (xy 60.710635 -382.726178)
			(xy 60.734231 -382.679868) (xy 60.764781 -382.63782) (xy 60.801532 -382.601069) (xy 60.84358 -382.570519)
			(xy 60.88989 -382.546923) (xy 60.93932 -382.530862) (xy 60.990655 -382.522732) (xy 61.042629 -382.522732)
			(xy 61.093964 -382.530862) (xy 61.143394 -382.546923) (xy 61.189704 -382.570519) (xy 61.231752 -382.601069)
			(xy 61.268503 -382.63782) (xy 61.299053 -382.679868) (xy 61.322649 -382.726178) (xy 61.33871 -382.775608)
			(xy 61.34684 -382.826943) (xy 61.34735 -382.85293) (xy 61.34684 -382.878917) (xy 61.88634 -382.878917)
			(xy 61.88634 -382.826943) (xy 61.89447 -382.775608) (xy 61.910531 -382.726178) (xy 61.934127 -382.679868)
			(xy 61.964677 -382.63782) (xy 62.001428 -382.601069) (xy 62.043476 -382.570519) (xy 62.089786 -382.546923)
			(xy 62.139216 -382.530862) (xy 62.190551 -382.522732) (xy 62.242525 -382.522732) (xy 62.29386 -382.530862)
			(xy 62.34329 -382.546923) (xy 62.3896 -382.570519) (xy 62.431648 -382.601069) (xy 62.468399 -382.63782)
			(xy 62.498949 -382.679868) (xy 62.522545 -382.726178) (xy 62.538606 -382.775608) (xy 62.546736 -382.826943)
			(xy 62.547246 -382.85293) (xy 62.546736 -382.878917) (xy 63.086236 -382.878917) (xy 63.086236 -382.826943)
			(xy 63.094366 -382.775608) (xy 63.110427 -382.726178) (xy 63.134023 -382.679868) (xy 63.164573 -382.63782)
			(xy 63.201324 -382.601069) (xy 63.243372 -382.570519) (xy 63.289682 -382.546923) (xy 63.339112 -382.530862)
			(xy 63.390447 -382.522732) (xy 63.442421 -382.522732) (xy 63.493756 -382.530862) (xy 63.543186 -382.546923)
			(xy 63.589496 -382.570519) (xy 63.631544 -382.601069) (xy 63.668295 -382.63782) (xy 63.698845 -382.679868)
			(xy 63.722441 -382.726178) (xy 63.738502 -382.775608) (xy 63.746632 -382.826943) (xy 63.747142 -382.85293)
			(xy 63.746632 -382.878917) (xy 64.286386 -382.878917) (xy 64.286386 -382.826943) (xy 64.294516 -382.775608)
			(xy 64.310577 -382.726178) (xy 64.334173 -382.679868) (xy 64.364723 -382.63782) (xy 64.401474 -382.601069)
			(xy 64.443522 -382.570519) (xy 64.489832 -382.546923) (xy 64.539262 -382.530862) (xy 64.590597 -382.522732)
			(xy 64.642571 -382.522732) (xy 64.693906 -382.530862) (xy 64.743336 -382.546923) (xy 64.789646 -382.570519)
			(xy 64.831694 -382.601069) (xy 64.868445 -382.63782) (xy 64.898995 -382.679868) (xy 64.922591 -382.726178)
			(xy 64.938652 -382.775608) (xy 64.946782 -382.826943) (xy 64.947292 -382.85293) (xy 64.946782 -382.878917)
			(xy 65.486282 -382.878917) (xy 65.486282 -382.826943) (xy 65.494412 -382.775608) (xy 65.510473 -382.726178)
			(xy 65.534069 -382.679868) (xy 65.564619 -382.63782) (xy 65.60137 -382.601069) (xy 65.643418 -382.570519)
			(xy 65.689728 -382.546923) (xy 65.739158 -382.530862) (xy 65.790493 -382.522732) (xy 65.842467 -382.522732)
			(xy 65.893802 -382.530862) (xy 65.943232 -382.546923) (xy 65.989542 -382.570519) (xy 66.03159 -382.601069)
			(xy 66.068341 -382.63782) (xy 66.098891 -382.679868) (xy 66.122487 -382.726178) (xy 66.138548 -382.775608)
			(xy 66.146678 -382.826943) (xy 66.147188 -382.85293) (xy 66.146678 -382.878917) (xy 66.138548 -382.930252)
			(xy 66.122487 -382.979682) (xy 66.098891 -383.025992) (xy 66.068341 -383.06804) (xy 66.03159 -383.104791)
			(xy 65.989542 -383.135341) (xy 65.943232 -383.158937) (xy 65.893802 -383.174998) (xy 65.842467 -383.183128)
			(xy 65.790493 -383.183128) (xy 65.739158 -383.174998) (xy 65.689728 -383.158937) (xy 65.643418 -383.135341)
			(xy 65.60137 -383.104791) (xy 65.564619 -383.06804) (xy 65.534069 -383.025992) (xy 65.510473 -382.979682)
			(xy 65.494412 -382.930252) (xy 65.486282 -382.878917) (xy 64.946782 -382.878917) (xy 64.938652 -382.930252)
			(xy 64.922591 -382.979682) (xy 64.898995 -383.025992) (xy 64.868445 -383.06804) (xy 64.831694 -383.104791)
			(xy 64.789646 -383.135341) (xy 64.743336 -383.158937) (xy 64.693906 -383.174998) (xy 64.642571 -383.183128)
			(xy 64.590597 -383.183128) (xy 64.539262 -383.174998) (xy 64.489832 -383.158937) (xy 64.443522 -383.135341)
			(xy 64.401474 -383.104791) (xy 64.364723 -383.06804) (xy 64.334173 -383.025992) (xy 64.310577 -382.979682)
			(xy 64.294516 -382.930252) (xy 64.286386 -382.878917) (xy 63.746632 -382.878917) (xy 63.738502 -382.930252)
			(xy 63.722441 -382.979682) (xy 63.698845 -383.025992) (xy 63.668295 -383.06804) (xy 63.631544 -383.104791)
			(xy 63.589496 -383.135341) (xy 63.543186 -383.158937) (xy 63.493756 -383.174998) (xy 63.442421 -383.183128)
			(xy 63.390447 -383.183128) (xy 63.339112 -383.174998) (xy 63.289682 -383.158937) (xy 63.243372 -383.135341)
			(xy 63.201324 -383.104791) (xy 63.164573 -383.06804) (xy 63.134023 -383.025992) (xy 63.110427 -382.979682)
			(xy 63.094366 -382.930252) (xy 63.086236 -382.878917) (xy 62.546736 -382.878917) (xy 62.538606 -382.930252)
			(xy 62.522545 -382.979682) (xy 62.498949 -383.025992) (xy 62.468399 -383.06804) (xy 62.431648 -383.104791)
			(xy 62.3896 -383.135341) (xy 62.34329 -383.158937) (xy 62.29386 -383.174998) (xy 62.242525 -383.183128)
			(xy 62.190551 -383.183128) (xy 62.139216 -383.174998) (xy 62.089786 -383.158937) (xy 62.043476 -383.135341)
			(xy 62.001428 -383.104791) (xy 61.964677 -383.06804) (xy 61.934127 -383.025992) (xy 61.910531 -382.979682)
			(xy 61.89447 -382.930252) (xy 61.88634 -382.878917) (xy 61.34684 -382.878917) (xy 61.33871 -382.930252)
			(xy 61.322649 -382.979682) (xy 61.299053 -383.025992) (xy 61.268503 -383.06804) (xy 61.231752 -383.104791)
			(xy 61.189704 -383.135341) (xy 61.143394 -383.158937) (xy 61.093964 -383.174998) (xy 61.042629 -383.183128)
			(xy 60.990655 -383.183128) (xy 60.93932 -383.174998) (xy 60.88989 -383.158937) (xy 60.84358 -383.135341)
			(xy 60.801532 -383.104791) (xy 60.764781 -383.06804) (xy 60.734231 -383.025992) (xy 60.710635 -382.979682)
			(xy 60.694574 -382.930252) (xy 60.686444 -382.878917) (xy 60.264723 -382.878917) (xy 59.943746 -383.199894)
			(xy 59.936345 -383.206733) (xy 59.917747 -383.214448) (xy 59.907678 -383.21488) (xy 53.658262 -383.21488)
			(xy 53.648195 -383.214449) (xy 53.629603 -383.206723) (xy 53.622194 -383.199894) (xy 53.61178 -383.18948)
			(xy 53.61178 -383.18694) (xy 53.471826 -383.046986) (xy 53.464979 -383.039588) (xy 53.457246 -383.02099)
			(xy 53.45684 -383.010918) (xy 53.45684 -379.479302) (xy 53.456416 -379.469233) (xy 53.448695 -379.450634)
			(xy 53.441854 -379.443234) (xy 53.345334 -379.346714) (xy 53.341606 -379.343188) (xy 53.333037 -379.337548)
			(xy 53.328316 -379.335538) (xy 53.319172 -379.331728) (xy 46.076108 -379.331728) (xy 46.066038 -379.33215)
			(xy 46.047434 -379.339866) (xy 46.04004 -379.346714) (xy 45.910754 -379.476) (xy 45.903902 -379.483396)
			(xy 45.896159 -379.501994) (xy 45.895768 -379.512068) (xy 45.895768 -381.404368) (xy 45.89526 -381.404368)
			(xy 45.89526 -382.506728) (xy 45.895667 -382.51634) (xy 45.902708 -382.534228) (xy 45.908976 -382.541526)
			(xy 45.9232 -382.556766) (xy 45.92955 -382.563624) (xy 45.949108 -382.57353) (xy 45.955712 -382.57607)
			(xy 45.96765 -382.580134) (xy 45.971714 -382.580642) (xy 45.994464 -382.584782) (xy 46.038595 -382.598585)
			(xy 46.080372 -382.618406) (xy 46.118977 -382.643857) (xy 46.13656 -382.658874) (xy 46.143418 -382.66497)
			(xy 46.159928 -382.67132) (xy 46.226222 -382.67259) (xy 46.230877 -382.672624) (xy 46.240078 -382.671219)
			(xy 46.24451 -382.669796) (xy 46.267624 -382.661414) (xy 46.273974 -382.656588) (xy 46.295008 -382.640975)
			(xy 46.341118 -382.616126) (xy 46.390679 -382.599174) (xy 46.442348 -382.590576) (xy 46.468538 -382.59004)
			(xy 46.493521 -382.590533) (xy 46.542872 -382.598355) (xy 46.590392 -382.6138) (xy 46.634912 -382.636488)
			(xy 46.675334 -382.665861) (xy 46.710664 -382.701195) (xy 46.740032 -382.741621) (xy 46.762714 -382.786143)
			(xy 46.778154 -382.833665) (xy 46.785163 -382.877919) (xy 47.498998 -382.877919) (xy 47.498998 -382.827941)
			(xy 47.506817 -382.778578) (xy 47.522261 -382.731046) (xy 47.544951 -382.686514) (xy 47.574327 -382.646081)
			(xy 47.609667 -382.610741) (xy 47.6501 -382.581365) (xy 47.694632 -382.558675) (xy 47.742164 -382.543231)
			(xy 47.791527 -382.535412) (xy 47.841505 -382.535412) (xy 47.890868 -382.543231) (xy 47.9384 -382.558675)
			(xy 47.982932 -382.581365) (xy 48.023365 -382.610741) (xy 48.058705 -382.646081) (xy 48.088081 -382.686514)
			(xy 48.110771 -382.731046) (xy 48.126215 -382.778578) (xy 48.134034 -382.827941) (xy 48.134524 -382.85293)
			(xy 48.134034 -382.877919) (xy 48.133876 -382.878917) (xy 48.686468 -382.878917) (xy 48.686468 -382.826943)
			(xy 48.694598 -382.775608) (xy 48.710659 -382.726178) (xy 48.734255 -382.679868) (xy 48.764805 -382.63782)
			(xy 48.801556 -382.601069) (xy 48.843604 -382.570519) (xy 48.889914 -382.546923) (xy 48.939344 -382.530862)
			(xy 48.990679 -382.522732) (xy 49.042653 -382.522732) (xy 49.093988 -382.530862) (xy 49.143418 -382.546923)
			(xy 49.189728 -382.570519) (xy 49.231776 -382.601069) (xy 49.268527 -382.63782) (xy 49.299077 -382.679868)
			(xy 49.322673 -382.726178) (xy 49.338734 -382.775608) (xy 49.346864 -382.826943) (xy 49.347374 -382.85293)
			(xy 49.346864 -382.878917) (xy 49.886364 -382.878917) (xy 49.886364 -382.826943) (xy 49.894494 -382.775608)
			(xy 49.910555 -382.726178) (xy 49.934151 -382.679868) (xy 49.964701 -382.63782) (xy 50.001452 -382.601069)
			(xy 50.0435 -382.570519) (xy 50.08981 -382.546923) (xy 50.13924 -382.530862) (xy 50.190575 -382.522732)
			(xy 50.242549 -382.522732) (xy 50.293884 -382.530862) (xy 50.343314 -382.546923) (xy 50.389624 -382.570519)
			(xy 50.431672 -382.601069) (xy 50.468423 -382.63782) (xy 50.498973 -382.679868) (xy 50.522569 -382.726178)
			(xy 50.53863 -382.775608) (xy 50.54676 -382.826943) (xy 50.54727 -382.85293) (xy 50.54676 -382.878917)
			(xy 51.08626 -382.878917) (xy 51.08626 -382.826943) (xy 51.09439 -382.775608) (xy 51.110451 -382.726178)
			(xy 51.134047 -382.679868) (xy 51.164597 -382.63782) (xy 51.201348 -382.601069) (xy 51.243396 -382.570519)
			(xy 51.289706 -382.546923) (xy 51.339136 -382.530862) (xy 51.390471 -382.522732) (xy 51.442445 -382.522732)
			(xy 51.49378 -382.530862) (xy 51.54321 -382.546923) (xy 51.58952 -382.570519) (xy 51.631568 -382.601069)
			(xy 51.668319 -382.63782) (xy 51.698869 -382.679868) (xy 51.722465 -382.726178) (xy 51.738526 -382.775608)
			(xy 51.746656 -382.826943) (xy 51.747166 -382.85293) (xy 51.746656 -382.878917) (xy 52.28641 -382.878917)
			(xy 52.28641 -382.826943) (xy 52.29454 -382.775608) (xy 52.310601 -382.726178) (xy 52.334197 -382.679868)
			(xy 52.364747 -382.63782) (xy 52.401498 -382.601069) (xy 52.443546 -382.570519) (xy 52.489856 -382.546923)
			(xy 52.539286 -382.530862) (xy 52.590621 -382.522732) (xy 52.642595 -382.522732) (xy 52.69393 -382.530862)
			(xy 52.74336 -382.546923) (xy 52.78967 -382.570519) (xy 52.831718 -382.601069) (xy 52.868469 -382.63782)
			(xy 52.899019 -382.679868) (xy 52.922615 -382.726178) (xy 52.938676 -382.775608) (xy 52.946806 -382.826943)
			(xy 52.947316 -382.85293) (xy 52.946806 -382.878917) (xy 52.938676 -382.930252) (xy 52.922615 -382.979682)
			(xy 52.899019 -383.025992) (xy 52.868469 -383.06804) (xy 52.831718 -383.104791) (xy 52.78967 -383.135341)
			(xy 52.74336 -383.158937) (xy 52.69393 -383.174998) (xy 52.642595 -383.183128) (xy 52.590621 -383.183128)
			(xy 52.539286 -383.174998) (xy 52.489856 -383.158937) (xy 52.443546 -383.135341) (xy 52.401498 -383.104791)
			(xy 52.364747 -383.06804) (xy 52.334197 -383.025992) (xy 52.310601 -382.979682) (xy 52.29454 -382.930252)
			(xy 52.28641 -382.878917) (xy 51.746656 -382.878917) (xy 51.738526 -382.930252) (xy 51.722465 -382.979682)
			(xy 51.698869 -383.025992) (xy 51.668319 -383.06804) (xy 51.631568 -383.104791) (xy 51.58952 -383.135341)
			(xy 51.54321 -383.158937) (xy 51.49378 -383.174998) (xy 51.442445 -383.183128) (xy 51.390471 -383.183128)
			(xy 51.339136 -383.174998) (xy 51.289706 -383.158937) (xy 51.243396 -383.135341) (xy 51.201348 -383.104791)
			(xy 51.164597 -383.06804) (xy 51.134047 -383.025992) (xy 51.110451 -382.979682) (xy 51.09439 -382.930252)
			(xy 51.08626 -382.878917) (xy 50.54676 -382.878917) (xy 50.53863 -382.930252) (xy 50.522569 -382.979682)
			(xy 50.498973 -383.025992) (xy 50.468423 -383.06804) (xy 50.431672 -383.104791) (xy 50.389624 -383.135341)
			(xy 50.343314 -383.158937) (xy 50.293884 -383.174998) (xy 50.242549 -383.183128) (xy 50.190575 -383.183128)
			(xy 50.13924 -383.174998) (xy 50.08981 -383.158937) (xy 50.0435 -383.135341) (xy 50.001452 -383.104791)
			(xy 49.964701 -383.06804) (xy 49.934151 -383.025992) (xy 49.910555 -382.979682) (xy 49.894494 -382.930252)
			(xy 49.886364 -382.878917) (xy 49.346864 -382.878917) (xy 49.338734 -382.930252) (xy 49.322673 -382.979682)
			(xy 49.299077 -383.025992) (xy 49.268527 -383.06804) (xy 49.231776 -383.104791) (xy 49.189728 -383.135341)
			(xy 49.143418 -383.158937) (xy 49.093988 -383.174998) (xy 49.042653 -383.183128) (xy 48.990679 -383.183128)
			(xy 48.939344 -383.174998) (xy 48.889914 -383.158937) (xy 48.843604 -383.135341) (xy 48.801556 -383.104791)
			(xy 48.764805 -383.06804) (xy 48.734255 -383.025992) (xy 48.710659 -382.979682) (xy 48.694598 -382.930252)
			(xy 48.686468 -382.878917) (xy 48.133876 -382.878917) (xy 48.126215 -382.927282) (xy 48.110771 -382.974814)
			(xy 48.088081 -383.019346) (xy 48.058705 -383.059779) (xy 48.023365 -383.095119) (xy 47.982932 -383.124495)
			(xy 47.9384 -383.147185) (xy 47.890868 -383.162629) (xy 47.841505 -383.170448) (xy 47.791527 -383.170448)
			(xy 47.742164 -383.162629) (xy 47.694632 -383.147185) (xy 47.6501 -383.124495) (xy 47.609667 -383.095119)
			(xy 47.574327 -383.059779) (xy 47.544951 -383.019346) (xy 47.522261 -382.974814) (xy 47.506817 -382.927282)
			(xy 47.498998 -382.877919) (xy 46.785163 -382.877919) (xy 46.78597 -382.883016) (xy 46.78597 -382.932984)
			(xy 46.778154 -382.982335) (xy 46.762714 -383.029857) (xy 46.740031 -383.074379) (xy 46.710664 -383.114805)
			(xy 46.675334 -383.150139) (xy 46.634912 -383.179512) (xy 46.590392 -383.2022) (xy 46.542872 -383.217645)
			(xy 46.493521 -383.225467) (xy 46.468538 -383.226056) (xy 46.441211 -383.225493) (xy 46.387361 -383.216157)
			(xy 46.335898 -383.197754) (xy 46.288339 -383.170826) (xy 46.266862 -383.15392) (xy 46.260004 -383.148332)
			(xy 46.243748 -383.14249) (xy 46.233842 -383.14249) (xy 46.177708 -383.143506) (xy 46.173352 -383.143682)
			(xy 46.164794 -383.14534) (xy 46.16069 -383.146808) (xy 46.136052 -383.156206) (xy 46.129702 -383.16154)
			(xy 46.107251 -383.179393) (xy 46.057477 -383.207894) (xy 46.003541 -383.227403) (xy 45.947051 -383.237339)
			(xy 45.918374 -383.237994) (xy 45.91812 -383.237994) (xy 45.895136 -383.237584) (xy 45.849616 -383.231179)
			(xy 45.805426 -383.218518) (xy 45.784262 -383.209546) (xy 45.77472 -383.205771) (xy 45.754222 -383.205374)
			(xy 45.735213 -383.213054) (xy 45.72762 -383.21996) (xy 45.43552 -383.51206) (xy 45.43552 -383.521712)
			(xy 45.618908 -383.704592) (xy 45.635634 -383.721995) (xy 45.663998 -383.761047) (xy 45.685906 -383.804054)
			(xy 45.700821 -383.849958) (xy 45.708373 -383.897629) (xy 45.708824 -383.921762) (xy 45.708824 -384.221736)
			(xy 45.70984 -384.231134) (xy 45.711618 -384.241294) (xy 45.713396 -384.24739) (xy 45.722051 -384.273862)
			(xy 45.731374 -384.328765) (xy 45.731938 -384.35661) (xy 45.731938 -384.357372) (xy 45.73137 -384.384706)
			(xy 45.722371 -384.438629) (xy 45.704629 -384.490338) (xy 45.678629 -384.538427) (xy 45.645076 -384.581588)
			(xy 45.604884 -384.618645) (xy 45.568128 -384.642711) (xy 47.144922 -384.642711) (xy 47.144922 -384.592733)
			(xy 47.152741 -384.54337) (xy 47.168185 -384.495838) (xy 47.190875 -384.451306) (xy 47.220251 -384.410873)
			(xy 47.255591 -384.375533) (xy 47.296024 -384.346157) (xy 47.340556 -384.323467) (xy 47.388088 -384.308023)
			(xy 47.437451 -384.300204) (xy 47.487429 -384.300204) (xy 47.536792 -384.308023) (xy 47.584324 -384.323467)
			(xy 47.628856 -384.346157) (xy 47.669289 -384.375533) (xy 47.704629 -384.410873) (xy 47.734005 -384.451306)
			(xy 47.756695 -384.495838) (xy 47.772139 -384.54337) (xy 47.779958 -384.592733) (xy 47.780448 -384.617722)
			(xy 47.779958 -384.642711) (xy 47.7798 -384.643709) (xy 48.332138 -384.643709) (xy 48.332138 -384.591735)
			(xy 48.340268 -384.5404) (xy 48.356329 -384.49097) (xy 48.379925 -384.44466) (xy 48.410475 -384.402612)
			(xy 48.447226 -384.365861) (xy 48.489274 -384.335311) (xy 48.535584 -384.311715) (xy 48.585014 -384.295654)
			(xy 48.636349 -384.287524) (xy 48.688323 -384.287524) (xy 48.739658 -384.295654) (xy 48.789088 -384.311715)
			(xy 48.835398 -384.335311) (xy 48.877446 -384.365861) (xy 48.914197 -384.402612) (xy 48.944747 -384.44466)
			(xy 48.968343 -384.49097) (xy 48.984404 -384.5404) (xy 48.992534 -384.591735) (xy 48.993044 -384.617722)
			(xy 48.992534 -384.643709) (xy 49.532288 -384.643709) (xy 49.532288 -384.591735) (xy 49.540418 -384.5404)
			(xy 49.556479 -384.49097) (xy 49.580075 -384.44466) (xy 49.610625 -384.402612) (xy 49.647376 -384.365861)
			(xy 49.689424 -384.335311) (xy 49.735734 -384.311715) (xy 49.785164 -384.295654) (xy 49.836499 -384.287524)
			(xy 49.888473 -384.287524) (xy 49.939808 -384.295654) (xy 49.989238 -384.311715) (xy 50.035548 -384.335311)
			(xy 50.077596 -384.365861) (xy 50.114347 -384.402612) (xy 50.144897 -384.44466) (xy 50.168493 -384.49097)
			(xy 50.184554 -384.5404) (xy 50.192684 -384.591735) (xy 50.193194 -384.617722) (xy 50.192684 -384.643709)
			(xy 50.732184 -384.643709) (xy 50.732184 -384.591735) (xy 50.740314 -384.5404) (xy 50.756375 -384.49097)
			(xy 50.779971 -384.44466) (xy 50.810521 -384.402612) (xy 50.847272 -384.365861) (xy 50.88932 -384.335311)
			(xy 50.93563 -384.311715) (xy 50.98506 -384.295654) (xy 51.036395 -384.287524) (xy 51.088369 -384.287524)
			(xy 51.139704 -384.295654) (xy 51.189134 -384.311715) (xy 51.235444 -384.335311) (xy 51.277492 -384.365861)
			(xy 51.314243 -384.402612) (xy 51.344793 -384.44466) (xy 51.368389 -384.49097) (xy 51.38445 -384.5404)
			(xy 51.39258 -384.591735) (xy 51.39309 -384.617722) (xy 51.39258 -384.643709) (xy 51.932334 -384.643709)
			(xy 51.932334 -384.591735) (xy 51.940464 -384.5404) (xy 51.956525 -384.49097) (xy 51.980121 -384.44466)
			(xy 52.010671 -384.402612) (xy 52.047422 -384.365861) (xy 52.08947 -384.335311) (xy 52.13578 -384.311715)
			(xy 52.18521 -384.295654) (xy 52.236545 -384.287524) (xy 52.288519 -384.287524) (xy 52.339854 -384.295654)
			(xy 52.389284 -384.311715) (xy 52.435594 -384.335311) (xy 52.477642 -384.365861) (xy 52.514393 -384.402612)
			(xy 52.544943 -384.44466) (xy 52.568539 -384.49097) (xy 52.5846 -384.5404) (xy 52.59273 -384.591735)
			(xy 52.59324 -384.617722) (xy 52.59273 -384.643709) (xy 53.13223 -384.643709) (xy 53.13223 -384.591735)
			(xy 53.14036 -384.5404) (xy 53.156421 -384.49097) (xy 53.180017 -384.44466) (xy 53.210567 -384.402612)
			(xy 53.247318 -384.365861) (xy 53.289366 -384.335311) (xy 53.335676 -384.311715) (xy 53.385106 -384.295654)
			(xy 53.436441 -384.287524) (xy 53.488415 -384.287524) (xy 53.53975 -384.295654) (xy 53.58918 -384.311715)
			(xy 53.63549 -384.335311) (xy 53.677538 -384.365861) (xy 53.714289 -384.402612) (xy 53.744839 -384.44466)
			(xy 53.768435 -384.49097) (xy 53.784496 -384.5404) (xy 53.792626 -384.591735) (xy 53.793136 -384.617722)
			(xy 53.792626 -384.643709) (xy 54.332126 -384.643709) (xy 54.332126 -384.591735) (xy 54.340256 -384.5404)
			(xy 54.356317 -384.49097) (xy 54.379913 -384.44466) (xy 54.410463 -384.402612) (xy 54.447214 -384.365861)
			(xy 54.489262 -384.335311) (xy 54.535572 -384.311715) (xy 54.585002 -384.295654) (xy 54.636337 -384.287524)
			(xy 54.688311 -384.287524) (xy 54.739646 -384.295654) (xy 54.789076 -384.311715) (xy 54.835386 -384.335311)
			(xy 54.877434 -384.365861) (xy 54.914185 -384.402612) (xy 54.944735 -384.44466) (xy 54.968331 -384.49097)
			(xy 54.984392 -384.5404) (xy 54.992522 -384.591735) (xy 54.993032 -384.617722) (xy 54.992522 -384.643709)
			(xy 55.532276 -384.643709) (xy 55.532276 -384.591735) (xy 55.540406 -384.5404) (xy 55.556467 -384.49097)
			(xy 55.580063 -384.44466) (xy 55.610613 -384.402612) (xy 55.647364 -384.365861) (xy 55.689412 -384.335311)
			(xy 55.735722 -384.311715) (xy 55.785152 -384.295654) (xy 55.836487 -384.287524) (xy 55.888461 -384.287524)
			(xy 55.939796 -384.295654) (xy 55.989226 -384.311715) (xy 56.035536 -384.335311) (xy 56.077584 -384.365861)
			(xy 56.114335 -384.402612) (xy 56.144885 -384.44466) (xy 56.168481 -384.49097) (xy 56.184542 -384.5404)
			(xy 56.192672 -384.591735) (xy 56.193182 -384.617722) (xy 56.192672 -384.643709) (xy 56.732172 -384.643709)
			(xy 56.732172 -384.591735) (xy 56.740302 -384.5404) (xy 56.756363 -384.49097) (xy 56.779959 -384.44466)
			(xy 56.810509 -384.402612) (xy 56.84726 -384.365861) (xy 56.889308 -384.335311) (xy 56.935618 -384.311715)
			(xy 56.985048 -384.295654) (xy 57.036383 -384.287524) (xy 57.088357 -384.287524) (xy 57.139692 -384.295654)
			(xy 57.189122 -384.311715) (xy 57.235432 -384.335311) (xy 57.27748 -384.365861) (xy 57.314231 -384.402612)
			(xy 57.344781 -384.44466) (xy 57.368377 -384.49097) (xy 57.384438 -384.5404) (xy 57.392568 -384.591735)
			(xy 57.393078 -384.617722) (xy 57.392568 -384.643709) (xy 57.932322 -384.643709) (xy 57.932322 -384.591735)
			(xy 57.940452 -384.5404) (xy 57.956513 -384.49097) (xy 57.980109 -384.44466) (xy 58.010659 -384.402612)
			(xy 58.04741 -384.365861) (xy 58.089458 -384.335311) (xy 58.135768 -384.311715) (xy 58.185198 -384.295654)
			(xy 58.236533 -384.287524) (xy 58.288507 -384.287524) (xy 58.339842 -384.295654) (xy 58.389272 -384.311715)
			(xy 58.435582 -384.335311) (xy 58.47763 -384.365861) (xy 58.514381 -384.402612) (xy 58.544931 -384.44466)
			(xy 58.568527 -384.49097) (xy 58.584588 -384.5404) (xy 58.592718 -384.591735) (xy 58.593228 -384.617722)
			(xy 58.592718 -384.643709) (xy 59.132218 -384.643709) (xy 59.132218 -384.591735) (xy 59.140348 -384.5404)
			(xy 59.156409 -384.49097) (xy 59.180005 -384.44466) (xy 59.210555 -384.402612) (xy 59.247306 -384.365861)
			(xy 59.289354 -384.335311) (xy 59.335664 -384.311715) (xy 59.385094 -384.295654) (xy 59.436429 -384.287524)
			(xy 59.488403 -384.287524) (xy 59.539738 -384.295654) (xy 59.589168 -384.311715) (xy 59.635478 -384.335311)
			(xy 59.677526 -384.365861) (xy 59.714277 -384.402612) (xy 59.744827 -384.44466) (xy 59.768423 -384.49097)
			(xy 59.784484 -384.5404) (xy 59.792614 -384.591735) (xy 59.793124 -384.617722) (xy 59.792614 -384.643709)
			(xy 60.332114 -384.643709) (xy 60.332114 -384.591735) (xy 60.340244 -384.5404) (xy 60.356305 -384.49097)
			(xy 60.379901 -384.44466) (xy 60.410451 -384.402612) (xy 60.447202 -384.365861) (xy 60.48925 -384.335311)
			(xy 60.53556 -384.311715) (xy 60.58499 -384.295654) (xy 60.636325 -384.287524) (xy 60.688299 -384.287524)
			(xy 60.739634 -384.295654) (xy 60.789064 -384.311715) (xy 60.835374 -384.335311) (xy 60.877422 -384.365861)
			(xy 60.914173 -384.402612) (xy 60.944723 -384.44466) (xy 60.968319 -384.49097) (xy 60.98438 -384.5404)
			(xy 60.99251 -384.591735) (xy 60.99302 -384.617722) (xy 60.99251 -384.643709) (xy 61.532264 -384.643709)
			(xy 61.532264 -384.591735) (xy 61.540394 -384.5404) (xy 61.556455 -384.49097) (xy 61.580051 -384.44466)
			(xy 61.610601 -384.402612) (xy 61.647352 -384.365861) (xy 61.6894 -384.335311) (xy 61.73571 -384.311715)
			(xy 61.78514 -384.295654) (xy 61.836475 -384.287524) (xy 61.888449 -384.287524) (xy 61.939784 -384.295654)
			(xy 61.989214 -384.311715) (xy 62.035524 -384.335311) (xy 62.077572 -384.365861) (xy 62.114323 -384.402612)
			(xy 62.144873 -384.44466) (xy 62.168469 -384.49097) (xy 62.18453 -384.5404) (xy 62.19266 -384.591735)
			(xy 62.19317 -384.617722) (xy 62.19266 -384.643709) (xy 62.73216 -384.643709) (xy 62.73216 -384.591735)
			(xy 62.74029 -384.5404) (xy 62.756351 -384.49097) (xy 62.779947 -384.44466) (xy 62.810497 -384.402612)
			(xy 62.847248 -384.365861) (xy 62.889296 -384.335311) (xy 62.935606 -384.311715) (xy 62.985036 -384.295654)
			(xy 63.036371 -384.287524) (xy 63.088345 -384.287524) (xy 63.13968 -384.295654) (xy 63.18911 -384.311715)
			(xy 63.23542 -384.335311) (xy 63.277468 -384.365861) (xy 63.314219 -384.402612) (xy 63.344769 -384.44466)
			(xy 63.368365 -384.49097) (xy 63.384426 -384.5404) (xy 63.392556 -384.591735) (xy 63.393066 -384.617722)
			(xy 63.392556 -384.643709) (xy 63.93231 -384.643709) (xy 63.93231 -384.591735) (xy 63.94044 -384.5404)
			(xy 63.956501 -384.49097) (xy 63.980097 -384.44466) (xy 64.010647 -384.402612) (xy 64.047398 -384.365861)
			(xy 64.089446 -384.335311) (xy 64.135756 -384.311715) (xy 64.185186 -384.295654) (xy 64.236521 -384.287524)
			(xy 64.288495 -384.287524) (xy 64.33983 -384.295654) (xy 64.38926 -384.311715) (xy 64.43557 -384.335311)
			(xy 64.477618 -384.365861) (xy 64.514369 -384.402612) (xy 64.544919 -384.44466) (xy 64.568515 -384.49097)
			(xy 64.584576 -384.5404) (xy 64.592706 -384.591735) (xy 64.593216 -384.617722) (xy 64.592706 -384.643709)
			(xy 65.132206 -384.643709) (xy 65.132206 -384.591735) (xy 65.140336 -384.5404) (xy 65.156397 -384.49097)
			(xy 65.179993 -384.44466) (xy 65.210543 -384.402612) (xy 65.247294 -384.365861) (xy 65.289342 -384.335311)
			(xy 65.335652 -384.311715) (xy 65.385082 -384.295654) (xy 65.436417 -384.287524) (xy 65.488391 -384.287524)
			(xy 65.539726 -384.295654) (xy 65.589156 -384.311715) (xy 65.635466 -384.335311) (xy 65.677514 -384.365861)
			(xy 65.714265 -384.402612) (xy 65.744815 -384.44466) (xy 65.768411 -384.49097) (xy 65.784472 -384.5404)
			(xy 65.792602 -384.591735) (xy 65.793112 -384.617722) (xy 65.792602 -384.643709) (xy 65.784472 -384.695044)
			(xy 65.768411 -384.744474) (xy 65.744815 -384.790784) (xy 65.714265 -384.832832) (xy 65.677514 -384.869583)
			(xy 65.635466 -384.900133) (xy 65.589156 -384.923729) (xy 65.539726 -384.93979) (xy 65.488391 -384.94792)
			(xy 65.436417 -384.94792) (xy 65.385082 -384.93979) (xy 65.335652 -384.923729) (xy 65.289342 -384.900133)
			(xy 65.247294 -384.869583) (xy 65.210543 -384.832832) (xy 65.179993 -384.790784) (xy 65.156397 -384.744474)
			(xy 65.140336 -384.695044) (xy 65.132206 -384.643709) (xy 64.592706 -384.643709) (xy 64.584576 -384.695044)
			(xy 64.568515 -384.744474) (xy 64.544919 -384.790784) (xy 64.514369 -384.832832) (xy 64.477618 -384.869583)
			(xy 64.43557 -384.900133) (xy 64.38926 -384.923729) (xy 64.33983 -384.93979) (xy 64.288495 -384.94792)
			(xy 64.236521 -384.94792) (xy 64.185186 -384.93979) (xy 64.135756 -384.923729) (xy 64.089446 -384.900133)
			(xy 64.047398 -384.869583) (xy 64.010647 -384.832832) (xy 63.980097 -384.790784) (xy 63.956501 -384.744474)
			(xy 63.94044 -384.695044) (xy 63.93231 -384.643709) (xy 63.392556 -384.643709) (xy 63.384426 -384.695044)
			(xy 63.368365 -384.744474) (xy 63.344769 -384.790784) (xy 63.314219 -384.832832) (xy 63.277468 -384.869583)
			(xy 63.23542 -384.900133) (xy 63.18911 -384.923729) (xy 63.13968 -384.93979) (xy 63.088345 -384.94792)
			(xy 63.036371 -384.94792) (xy 62.985036 -384.93979) (xy 62.935606 -384.923729) (xy 62.889296 -384.900133)
			(xy 62.847248 -384.869583) (xy 62.810497 -384.832832) (xy 62.779947 -384.790784) (xy 62.756351 -384.744474)
			(xy 62.74029 -384.695044) (xy 62.73216 -384.643709) (xy 62.19266 -384.643709) (xy 62.18453 -384.695044)
			(xy 62.168469 -384.744474) (xy 62.144873 -384.790784) (xy 62.114323 -384.832832) (xy 62.077572 -384.869583)
			(xy 62.035524 -384.900133) (xy 61.989214 -384.923729) (xy 61.939784 -384.93979) (xy 61.888449 -384.94792)
			(xy 61.836475 -384.94792) (xy 61.78514 -384.93979) (xy 61.73571 -384.923729) (xy 61.6894 -384.900133)
			(xy 61.647352 -384.869583) (xy 61.610601 -384.832832) (xy 61.580051 -384.790784) (xy 61.556455 -384.744474)
			(xy 61.540394 -384.695044) (xy 61.532264 -384.643709) (xy 60.99251 -384.643709) (xy 60.98438 -384.695044)
			(xy 60.968319 -384.744474) (xy 60.944723 -384.790784) (xy 60.914173 -384.832832) (xy 60.877422 -384.869583)
			(xy 60.835374 -384.900133) (xy 60.789064 -384.923729) (xy 60.739634 -384.93979) (xy 60.688299 -384.94792)
			(xy 60.636325 -384.94792) (xy 60.58499 -384.93979) (xy 60.53556 -384.923729) (xy 60.48925 -384.900133)
			(xy 60.447202 -384.869583) (xy 60.410451 -384.832832) (xy 60.379901 -384.790784) (xy 60.356305 -384.744474)
			(xy 60.340244 -384.695044) (xy 60.332114 -384.643709) (xy 59.792614 -384.643709) (xy 59.784484 -384.695044)
			(xy 59.768423 -384.744474) (xy 59.744827 -384.790784) (xy 59.714277 -384.832832) (xy 59.677526 -384.869583)
			(xy 59.635478 -384.900133) (xy 59.589168 -384.923729) (xy 59.539738 -384.93979) (xy 59.488403 -384.94792)
			(xy 59.436429 -384.94792) (xy 59.385094 -384.93979) (xy 59.335664 -384.923729) (xy 59.289354 -384.900133)
			(xy 59.247306 -384.869583) (xy 59.210555 -384.832832) (xy 59.180005 -384.790784) (xy 59.156409 -384.744474)
			(xy 59.140348 -384.695044) (xy 59.132218 -384.643709) (xy 58.592718 -384.643709) (xy 58.584588 -384.695044)
			(xy 58.568527 -384.744474) (xy 58.544931 -384.790784) (xy 58.514381 -384.832832) (xy 58.47763 -384.869583)
			(xy 58.435582 -384.900133) (xy 58.389272 -384.923729) (xy 58.339842 -384.93979) (xy 58.288507 -384.94792)
			(xy 58.236533 -384.94792) (xy 58.185198 -384.93979) (xy 58.135768 -384.923729) (xy 58.089458 -384.900133)
			(xy 58.04741 -384.869583) (xy 58.010659 -384.832832) (xy 57.980109 -384.790784) (xy 57.956513 -384.744474)
			(xy 57.940452 -384.695044) (xy 57.932322 -384.643709) (xy 57.392568 -384.643709) (xy 57.384438 -384.695044)
			(xy 57.368377 -384.744474) (xy 57.344781 -384.790784) (xy 57.314231 -384.832832) (xy 57.27748 -384.869583)
			(xy 57.235432 -384.900133) (xy 57.189122 -384.923729) (xy 57.139692 -384.93979) (xy 57.088357 -384.94792)
			(xy 57.036383 -384.94792) (xy 56.985048 -384.93979) (xy 56.935618 -384.923729) (xy 56.889308 -384.900133)
			(xy 56.84726 -384.869583) (xy 56.810509 -384.832832) (xy 56.779959 -384.790784) (xy 56.756363 -384.744474)
			(xy 56.740302 -384.695044) (xy 56.732172 -384.643709) (xy 56.192672 -384.643709) (xy 56.184542 -384.695044)
			(xy 56.168481 -384.744474) (xy 56.144885 -384.790784) (xy 56.114335 -384.832832) (xy 56.077584 -384.869583)
			(xy 56.035536 -384.900133) (xy 55.989226 -384.923729) (xy 55.939796 -384.93979) (xy 55.888461 -384.94792)
			(xy 55.836487 -384.94792) (xy 55.785152 -384.93979) (xy 55.735722 -384.923729) (xy 55.689412 -384.900133)
			(xy 55.647364 -384.869583) (xy 55.610613 -384.832832) (xy 55.580063 -384.790784) (xy 55.556467 -384.744474)
			(xy 55.540406 -384.695044) (xy 55.532276 -384.643709) (xy 54.992522 -384.643709) (xy 54.984392 -384.695044)
			(xy 54.968331 -384.744474) (xy 54.944735 -384.790784) (xy 54.914185 -384.832832) (xy 54.877434 -384.869583)
			(xy 54.835386 -384.900133) (xy 54.789076 -384.923729) (xy 54.739646 -384.93979) (xy 54.688311 -384.94792)
			(xy 54.636337 -384.94792) (xy 54.585002 -384.93979) (xy 54.535572 -384.923729) (xy 54.489262 -384.900133)
			(xy 54.447214 -384.869583) (xy 54.410463 -384.832832) (xy 54.379913 -384.790784) (xy 54.356317 -384.744474)
			(xy 54.340256 -384.695044) (xy 54.332126 -384.643709) (xy 53.792626 -384.643709) (xy 53.784496 -384.695044)
			(xy 53.768435 -384.744474) (xy 53.744839 -384.790784) (xy 53.714289 -384.832832) (xy 53.677538 -384.869583)
			(xy 53.63549 -384.900133) (xy 53.58918 -384.923729) (xy 53.53975 -384.93979) (xy 53.488415 -384.94792)
			(xy 53.436441 -384.94792) (xy 53.385106 -384.93979) (xy 53.335676 -384.923729) (xy 53.289366 -384.900133)
			(xy 53.247318 -384.869583) (xy 53.210567 -384.832832) (xy 53.180017 -384.790784) (xy 53.156421 -384.744474)
			(xy 53.14036 -384.695044) (xy 53.13223 -384.643709) (xy 52.59273 -384.643709) (xy 52.5846 -384.695044)
			(xy 52.568539 -384.744474) (xy 52.544943 -384.790784) (xy 52.514393 -384.832832) (xy 52.477642 -384.869583)
			(xy 52.435594 -384.900133) (xy 52.389284 -384.923729) (xy 52.339854 -384.93979) (xy 52.288519 -384.94792)
			(xy 52.236545 -384.94792) (xy 52.18521 -384.93979) (xy 52.13578 -384.923729) (xy 52.08947 -384.900133)
			(xy 52.047422 -384.869583) (xy 52.010671 -384.832832) (xy 51.980121 -384.790784) (xy 51.956525 -384.744474)
			(xy 51.940464 -384.695044) (xy 51.932334 -384.643709) (xy 51.39258 -384.643709) (xy 51.38445 -384.695044)
			(xy 51.368389 -384.744474) (xy 51.344793 -384.790784) (xy 51.314243 -384.832832) (xy 51.277492 -384.869583)
			(xy 51.235444 -384.900133) (xy 51.189134 -384.923729) (xy 51.139704 -384.93979) (xy 51.088369 -384.94792)
			(xy 51.036395 -384.94792) (xy 50.98506 -384.93979) (xy 50.93563 -384.923729) (xy 50.88932 -384.900133)
			(xy 50.847272 -384.869583) (xy 50.810521 -384.832832) (xy 50.779971 -384.790784) (xy 50.756375 -384.744474)
			(xy 50.740314 -384.695044) (xy 50.732184 -384.643709) (xy 50.192684 -384.643709) (xy 50.184554 -384.695044)
			(xy 50.168493 -384.744474) (xy 50.144897 -384.790784) (xy 50.114347 -384.832832) (xy 50.077596 -384.869583)
			(xy 50.035548 -384.900133) (xy 49.989238 -384.923729) (xy 49.939808 -384.93979) (xy 49.888473 -384.94792)
			(xy 49.836499 -384.94792) (xy 49.785164 -384.93979) (xy 49.735734 -384.923729) (xy 49.689424 -384.900133)
			(xy 49.647376 -384.869583) (xy 49.610625 -384.832832) (xy 49.580075 -384.790784) (xy 49.556479 -384.744474)
			(xy 49.540418 -384.695044) (xy 49.532288 -384.643709) (xy 48.992534 -384.643709) (xy 48.984404 -384.695044)
			(xy 48.968343 -384.744474) (xy 48.944747 -384.790784) (xy 48.914197 -384.832832) (xy 48.877446 -384.869583)
			(xy 48.835398 -384.900133) (xy 48.789088 -384.923729) (xy 48.739658 -384.93979) (xy 48.688323 -384.94792)
			(xy 48.636349 -384.94792) (xy 48.585014 -384.93979) (xy 48.535584 -384.923729) (xy 48.489274 -384.900133)
			(xy 48.447226 -384.869583) (xy 48.410475 -384.832832) (xy 48.379925 -384.790784) (xy 48.356329 -384.744474)
			(xy 48.340268 -384.695044) (xy 48.332138 -384.643709) (xy 47.7798 -384.643709) (xy 47.772139 -384.692074)
			(xy 47.756695 -384.739606) (xy 47.734005 -384.784138) (xy 47.704629 -384.824571) (xy 47.669289 -384.859911)
			(xy 47.628856 -384.889287) (xy 47.584324 -384.911977) (xy 47.536792 -384.927421) (xy 47.487429 -384.93524)
			(xy 47.437451 -384.93524) (xy 47.388088 -384.927421) (xy 47.340556 -384.911977) (xy 47.296024 -384.889287)
			(xy 47.255591 -384.859911) (xy 47.220251 -384.824571) (xy 47.190875 -384.784138) (xy 47.168185 -384.739606)
			(xy 47.152741 -384.692074) (xy 47.144922 -384.642711) (xy 45.568128 -384.642711) (xy 45.559147 -384.648591)
			(xy 45.509109 -384.67061) (xy 45.482764 -384.67792) (xy 45.475144 -384.679698) (xy 45.459396 -384.689604)
			(xy 45.452267 -384.694447) (xy 45.441517 -384.707902) (xy 45.435867 -384.724171) (xy 45.43552 -384.732784)
			(xy 45.43552 -385.87553) (xy 46.834044 -385.87553) (xy 46.834604 -385.84795) (xy 46.843804 -385.793561)
			(xy 46.852332 -385.767326) (xy 46.854872 -385.759452) (xy 46.854872 -385.61518) (xy 46.85542 -385.598466)
			(xy 46.864075 -385.566177) (xy 46.880791 -385.537228) (xy 46.904428 -385.513591) (xy 46.933377 -385.496875)
			(xy 46.965666 -385.48822) (xy 46.98238 -385.487672) (xy 47.36338 -385.487672) (xy 47.373286 -385.48818)
			(xy 47.385062 -385.488533) (xy 47.406911 -385.479792) (xy 47.415196 -385.471416) (xy 47.476918 -385.402836)
			(xy 47.483268 -385.379976) (xy 47.482506 -385.376166) (xy 47.482506 -385.37515) (xy 47.477426 -385.342892)
			(xy 47.475648 -385.31038) (xy 47.476055 -385.286753) (xy 47.483118 -385.240029) (xy 47.49707 -385.19488)
			(xy 47.517597 -385.152317) (xy 47.544241 -385.11329) (xy 47.576407 -385.078672) (xy 47.613374 -385.049237)
			(xy 47.633636 -385.037076) (xy 47.657732 -385.023801) (xy 47.709431 -385.005001) (xy 47.76361 -384.995467)
			(xy 47.791116 -384.994912) (xy 47.79137 -384.994912) (xy 47.814982 -384.99537) (xy 47.861679 -385.002413)
			(xy 47.906806 -385.016332) (xy 47.949356 -385.036816) (xy 47.988382 -385.063409) (xy 48.023012 -385.095517)
			(xy 48.052474 -385.132425) (xy 48.064674 -385.152646) (xy 48.073898 -385.169158) (xy 48.088799 -385.203921)
			(xy 48.094392 -385.221988) (xy 48.0949 -385.22402) (xy 48.095916 -385.228084) (xy 48.143541 -385.31038)
			(xy 48.675544 -385.31038) (xy 48.675998 -385.285602) (xy 48.68375 -385.236656) (xy 48.699059 -385.189523)
			(xy 48.721549 -385.145364) (xy 48.750666 -385.105265) (xy 48.785695 -385.070211) (xy 48.825775 -385.041065)
			(xy 48.869918 -385.018544) (xy 48.917039 -385.003202) (xy 48.96598 -384.995416) (xy 48.990758 -384.994912)
			(xy 48.991266 -384.994912) (xy 49.01666 -384.995425) (xy 49.066794 -385.003551) (xy 49.11498 -385.019599)
			(xy 49.159976 -385.043155) (xy 49.200619 -385.073611) (xy 49.235862 -385.110181) (xy 49.264795 -385.151922)
			(xy 49.286672 -385.197757) (xy 49.294288 -385.221988) (xy 49.295812 -385.22783) (xy 49.343562 -385.31038)
			(xy 49.875948 -385.31038) (xy 49.8764 -385.285589) (xy 49.884159 -385.236618) (xy 49.899484 -385.189464)
			(xy 49.921996 -385.145287) (xy 49.951142 -385.105176) (xy 49.986204 -385.070118) (xy 50.026318 -385.040977)
			(xy 50.070497 -385.01847) (xy 50.117653 -385.003151) (xy 50.166625 -384.995397) (xy 50.191416 -384.994912)
			(xy 50.216863 -384.995415) (xy 50.267101 -385.003567) (xy 50.31538 -385.019673) (xy 50.36045 -385.043316)
			(xy 50.401142 -385.073883) (xy 50.436404 -385.110583) (xy 50.465321 -385.152465) (xy 50.487144 -385.198443)
			(xy 50.494692 -385.22275) (xy 50.496216 -385.228592) (xy 50.816002 -385.78155) (xy 50.820066 -385.785868)
			(xy 50.836224 -385.803569) (xy 50.863567 -385.842929) (xy 50.884646 -385.88597) (xy 50.898977 -385.931702)
			(xy 50.90623 -385.979075) (xy 50.90668 -386.003038) (xy 50.90668 -386.003546) (xy 50.906172 -386.023866)
			(xy 50.90541 -386.033772) (xy 50.91176 -386.052822) (xy 50.972466 -386.122164) (xy 50.990246 -386.131054)
			(xy 51.000406 -386.131816) (xy 51.025385 -386.133991) (xy 51.074243 -386.145249) (xy 51.12073 -386.164034)
			(xy 51.163694 -386.18988) (xy 51.202071 -386.222146) (xy 51.218846 -386.240782) (xy 51.221309 -386.243554)
			(xy 51.226921 -386.248401) (xy 51.230022 -386.250434) (xy 51.242061 -386.2585) (xy 51.26195 -386.279564)
			(xy 51.275956 -386.304925) (xy 51.283192 -386.332977) (xy 51.283616 -386.347462) (xy 51.283616 -386.3594)
			(xy 51.285394 -386.366004) (xy 51.290585 -386.386377) (xy 51.296196 -386.428042) (xy 51.29657 -386.449062)
			(xy 51.29619 -386.470082) (xy 51.290589 -386.511749) (xy 51.285394 -386.53212) (xy 51.283616 -386.538724)
			(xy 51.283616 -386.652262) (xy 51.283174 -386.667286) (xy 51.275404 -386.696312) (xy 51.260383 -386.722336)
			(xy 51.239136 -386.743583) (xy 51.213112 -386.758604) (xy 51.184086 -386.766374) (xy 51.169062 -386.766816)
			(xy 50.987452 -386.766816) (xy 50.986944 -386.76707) (xy 50.97018 -386.76707) (xy 50.969672 -386.766816)
			(xy 50.788062 -386.766816) (xy 50.77304 -386.766397) (xy 50.744023 -386.758611) (xy 50.718009 -386.743581)
			(xy 50.696773 -386.72233) (xy 50.681759 -386.696306) (xy 50.673993 -386.667284) (xy 50.673508 -386.652262)
			(xy 50.673508 -386.538724) (xy 50.67173 -386.53212) (xy 50.666523 -386.511751) (xy 50.660923 -386.470083)
			(xy 50.660554 -386.449062) (xy 50.661316 -386.426456) (xy 50.662078 -386.41655) (xy 50.655728 -386.397246)
			(xy 50.59553 -386.327904) (xy 50.577496 -386.31876) (xy 50.56759 -386.317998) (xy 50.543762 -386.315812)
			(xy 50.497132 -386.305082) (xy 50.452657 -386.287434) (xy 50.411356 -386.263273) (xy 50.374177 -386.233153)
			(xy 50.341972 -386.197764) (xy 50.315481 -386.157918) (xy 50.295309 -386.114529) (xy 50.28819 -386.091684)
			(xy 50.286666 -386.085842) (xy 49.966118 -385.53136) (xy 49.962054 -385.527042) (xy 49.945978 -385.509361)
			(xy 49.918787 -385.470068) (xy 49.89783 -385.427124) (xy 49.883588 -385.381511) (xy 49.876386 -385.334272)
			(xy 49.875948 -385.31038) (xy 49.343562 -385.31038) (xy 49.616106 -385.78155) (xy 49.62017 -385.785868)
			(xy 49.636329 -385.803569) (xy 49.663671 -385.842929) (xy 49.68475 -385.88597) (xy 49.699081 -385.931702)
			(xy 49.706334 -385.979075) (xy 49.706784 -386.003038) (xy 49.706784 -386.003546) (xy 49.706276 -386.023866)
			(xy 49.705514 -386.033772) (xy 49.711864 -386.052822) (xy 49.77257 -386.122164) (xy 49.79035 -386.131054)
			(xy 49.80051 -386.131816) (xy 49.825489 -386.133988) (xy 49.874348 -386.145247) (xy 49.920835 -386.164033)
			(xy 49.963798 -386.189879) (xy 50.002175 -386.222146) (xy 50.01895 -386.240782) (xy 50.021413 -386.243554)
			(xy 50.027025 -386.248401) (xy 50.030126 -386.250434) (xy 50.042166 -386.258499) (xy 50.062055 -386.279564)
			(xy 50.07606 -386.304924) (xy 50.083296 -386.332977) (xy 50.08372 -386.347462) (xy 50.08372 -386.3594)
			(xy 50.085498 -386.366004) (xy 50.090689 -386.386377) (xy 50.0963 -386.428042) (xy 50.096674 -386.449062)
			(xy 50.096294 -386.470082) (xy 50.090693 -386.511749) (xy 50.085498 -386.53212) (xy 50.08372 -386.538724)
			(xy 50.08372 -386.652262) (xy 50.083274 -386.667286) (xy 50.075504 -386.696311) (xy 50.060484 -386.722334)
			(xy 50.039238 -386.743581) (xy 50.013215 -386.758603) (xy 49.98419 -386.766374) (xy 49.969166 -386.766816)
			(xy 49.787556 -386.766816) (xy 49.787048 -386.76707) (xy 49.770284 -386.76707) (xy 49.769776 -386.766816)
			(xy 49.588166 -386.766816) (xy 49.573139 -386.766437) (xy 49.54411 -386.75865) (xy 49.518087 -386.743614)
			(xy 49.496842 -386.722356) (xy 49.481823 -386.696323) (xy 49.474053 -386.66729) (xy 49.473612 -386.652262)
			(xy 49.473612 -386.538724) (xy 49.471834 -386.53212) (xy 49.466627 -386.511751) (xy 49.461027 -386.470083)
			(xy 49.460658 -386.449062) (xy 49.46142 -386.426456) (xy 49.462182 -386.41655) (xy 49.455832 -386.397246)
			(xy 49.395634 -386.327904) (xy 49.3776 -386.31876) (xy 49.367694 -386.317998) (xy 49.343867 -386.315808)
			(xy 49.297237 -386.305079) (xy 49.252761 -386.287431) (xy 49.211461 -386.263271) (xy 49.174282 -386.233151)
			(xy 49.142077 -386.197763) (xy 49.115585 -386.157917) (xy 49.095414 -386.114529) (xy 49.088294 -386.091684)
			(xy 49.08677 -386.085842) (xy 48.766476 -385.532122) (xy 48.762412 -385.527804) (xy 48.746186 -385.510115)
			(xy 48.718764 -385.470719) (xy 48.697626 -385.427625) (xy 48.683257 -385.381826) (xy 48.675991 -385.33438)
			(xy 48.675544 -385.31038) (xy 48.143541 -385.31038) (xy 48.41621 -385.78155) (xy 48.420274 -385.785868)
			(xy 48.436433 -385.803568) (xy 48.463776 -385.842928) (xy 48.484854 -385.885969) (xy 48.499185 -385.931702)
			(xy 48.506438 -385.979075) (xy 48.506888 -386.003038) (xy 48.506888 -386.003546) (xy 48.50638 -386.023866)
			(xy 48.505618 -386.033772) (xy 48.511968 -386.052822) (xy 48.572674 -386.122164) (xy 48.590454 -386.131054)
			(xy 48.600614 -386.131816) (xy 48.625564 -386.134025) (xy 48.674365 -386.145308) (xy 48.720794 -386.164097)
			(xy 48.763707 -386.189929) (xy 48.802041 -386.222166) (xy 48.8188 -386.240782) (xy 48.821257 -386.24356)
			(xy 48.826873 -386.248403) (xy 48.829976 -386.250434) (xy 48.842054 -386.258472) (xy 48.862008 -386.279523)
			(xy 48.876078 -386.304887) (xy 48.883374 -386.33296) (xy 48.883824 -386.347462) (xy 48.883824 -386.3594)
			(xy 48.885348 -386.366004) (xy 48.89054 -386.386376) (xy 48.89615 -386.428042) (xy 48.896524 -386.449062)
			(xy 48.896142 -386.470082) (xy 48.890542 -386.511748) (xy 48.885348 -386.53212) (xy 48.883824 -386.538724)
			(xy 48.883824 -386.652262) (xy 48.883333 -386.667259) (xy 48.875588 -386.696234) (xy 48.860614 -386.722222)
			(xy 48.83943 -386.743454) (xy 48.813477 -386.758487) (xy 48.784519 -386.766299) (xy 48.769524 -386.766816)
			(xy 48.587406 -386.766816) (xy 48.586898 -386.76707) (xy 48.570134 -386.76707) (xy 48.569626 -386.766816)
			(xy 48.388016 -386.766816) (xy 48.372988 -386.766306) (xy 48.343953 -386.758542) (xy 48.317912 -386.743536)
			(xy 48.296634 -386.72231) (xy 48.281565 -386.696305) (xy 48.27373 -386.667289) (xy 48.273208 -386.652262)
			(xy 48.273208 -386.538724) (xy 48.271684 -386.53212) (xy 48.266478 -386.511751) (xy 48.260877 -386.470083)
			(xy 48.260508 -386.449062) (xy 48.26127 -386.426456) (xy 48.262032 -386.416296) (xy 48.255936 -386.3975)
			(xy 48.202342 -386.335524) (xy 48.1954 -386.328278) (xy 48.177499 -386.319256) (xy 48.167544 -386.317998)
			(xy 48.143736 -386.315769) (xy 48.097144 -386.305015) (xy 48.052709 -386.287353) (xy 48.011448 -386.263188)
			(xy 47.974305 -386.233074) (xy 47.942133 -386.1977) (xy 47.915666 -386.157875) (xy 47.895512 -386.114514)
			(xy 47.888398 -386.091684) (xy 47.886874 -386.085842) (xy 47.569374 -385.537202) (xy 47.562516 -385.527804)
			(xy 47.554134 -385.51866) (xy 47.500032 -385.549902) (xy 47.48657 -385.578604) (xy 47.48911 -385.594352)
			(xy 47.490888 -385.61518) (xy 47.490888 -385.819904) (xy 47.491396 -385.823714) (xy 47.493299 -385.83652)
			(xy 47.495337 -385.86233) (xy 47.49546 -385.875276) (xy 47.49546 -385.87553) (xy 47.495289 -385.891119)
			(xy 47.492363 -385.92216) (xy 47.489618 -385.937506) (xy 47.48911 -385.939538) (xy 47.485554 -385.956048)
			(xy 47.485046 -385.957572) (xy 47.480558 -385.974212) (xy 47.468596 -386.006536) (xy 47.46117 -386.022088)
			(xy 47.46117 -386.022342) (xy 47.45717 -386.031623) (xy 47.455976 -386.05178) (xy 47.458884 -386.061458)
			(xy 47.486824 -386.140198) (xy 47.500794 -386.155184) (xy 47.510192 -386.159502) (xy 47.530769 -386.169344)
			(xy 47.569157 -386.193978) (xy 47.60365 -386.223824) (xy 47.618904 -386.240782) (xy 47.62136 -386.24356)
			(xy 47.626977 -386.248403) (xy 47.63008 -386.250434) (xy 47.642159 -386.25847) (xy 47.662113 -386.279522)
			(xy 47.676182 -386.304887) (xy 47.683478 -386.33296) (xy 47.683928 -386.347462) (xy 47.683928 -386.3594)
			(xy 47.685452 -386.366004) (xy 47.690644 -386.386376) (xy 47.696254 -386.428042) (xy 47.696628 -386.449062)
			(xy 47.696246 -386.470082) (xy 47.690646 -386.511748) (xy 47.685452 -386.53212) (xy 47.683928 -386.538724)
			(xy 47.683928 -386.652262) (xy 47.683433 -386.667258) (xy 47.675688 -386.696233) (xy 47.660715 -386.72222)
			(xy 47.639532 -386.743453) (xy 47.61358 -386.758486) (xy 47.584623 -386.766298) (xy 47.569628 -386.766816)
			(xy 47.38751 -386.766816) (xy 47.387002 -386.76707) (xy 47.370238 -386.76707) (xy 47.36973 -386.766816)
			(xy 47.18812 -386.766816) (xy 47.173092 -386.766303) (xy 47.144058 -386.758539) (xy 47.118016 -386.743535)
			(xy 47.096738 -386.722309) (xy 47.081669 -386.696304) (xy 47.073834 -386.667288) (xy 47.073312 -386.652262)
			(xy 47.073312 -386.538724) (xy 47.071788 -386.53212) (xy 47.066582 -386.511751) (xy 47.060981 -386.470083)
			(xy 47.060612 -386.449062) (xy 47.060978 -386.428041) (xy 47.066589 -386.386375) (xy 47.071788 -386.366004)
			(xy 47.073312 -386.3594) (xy 47.073312 -386.347462) (xy 47.073608 -386.336861) (xy 47.077568 -386.316029)
			(xy 47.081186 -386.30606) (xy 47.084742 -386.296916) (xy 47.084488 -386.277612) (xy 47.050452 -386.194554)
			(xy 47.037498 -386.180838) (xy 47.028354 -386.176774) (xy 47.003884 -386.165163) (xy 46.958844 -386.135084)
			(xy 46.919308 -386.098067) (xy 46.886334 -386.055101) (xy 46.860802 -386.007336) (xy 46.843396 -385.956049)
			(xy 46.834581 -385.90261) (xy 46.834044 -385.87553) (xy 45.43552 -385.87553) (xy 45.43552 -386.88391)
			(xy 45.431456 -386.88391) (xy 45.431456 -386.995162) (xy 45.432218 -386.998972) (xy 45.433889 -387.011094)
			(xy 45.435666 -387.035503) (xy 45.435774 -387.04774) (xy 45.435685 -387.059977) (xy 45.433908 -387.084387)
			(xy 45.432218 -387.096508) (xy 45.431456 -387.100318) (xy 45.431456 -387.24078) (xy 45.430916 -387.257478)
			(xy 45.42229 -387.28974) (xy 45.405618 -387.318677) (xy 45.382033 -387.342321) (xy 45.353139 -387.359066)
			(xy 45.320899 -387.367774) (xy 45.304202 -387.368288) (xy 45.187108 -387.368288) (xy 45.181266 -387.369558)
			(xy 45.1562 -387.374993) (xy 45.105066 -387.378961) (xy 45.053932 -387.374993) (xy 45.028866 -387.369558)
			(xy 45.023024 -387.368288) (xy 44.999402 -387.368288) (xy 44.982094 -387.367707) (xy 44.94875 -387.35841)
			(xy 44.919129 -387.340498) (xy 44.895407 -387.315288) (xy 44.88688 -387.300216) (xy 44.884882 -387.296638)
			(xy 44.879905 -387.290127) (xy 44.876974 -387.287262) (xy 44.856785 -387.267193) (xy 44.822919 -387.221442)
			(xy 44.797383 -387.17057) (xy 44.788582 -387.143498) (xy 44.785026 -387.13156) (xy 44.767754 -387.11378)
			(xy 44.66463 -387.079998) (xy 44.640246 -387.084062) (xy 44.63034 -387.091428) (xy 44.60652 -387.108721)
			(xy 44.555284 -387.137701) (xy 44.500753 -387.159867) (xy 44.443829 -387.174852) (xy 44.385452 -387.182408)
			(xy 44.35602 -387.182868) (xy 44.326723 -387.182399) (xy 44.268609 -387.174923) (xy 44.211921 -387.160104)
			(xy 44.157583 -387.138183) (xy 44.10648 -387.109518) (xy 44.059447 -387.074575) (xy 44.038012 -387.054598)
			(xy 44.031154 -387.047994) (xy 44.004484 -387.036818) (xy 43.999797 -387.035021) (xy 43.989945 -387.033105)
			(xy 43.984926 -387.033008) (xy 43.734736 -387.033008) (xy 43.726608 -387.035802) (xy 43.71652 -387.039166)
			(xy 43.695582 -387.04287) (xy 43.684952 -387.043168) (xy 43.409362 -387.043168) (xy 43.404814 -387.043289)
			(xy 43.395869 -387.044946) (xy 43.391582 -387.04647) (xy 43.38066 -387.050534) (xy 43.214544 -387.216904)
			(xy 43.207137 -387.223595) (xy 43.188701 -387.231192) (xy 43.17873 -387.231636) (xy 43.013884 -387.231636)
			(xy 43.008587 -387.231778) (xy 42.99822 -387.233961) (xy 42.99331 -387.235954) (xy 42.985436 -387.23951)
			(xy 42.981626 -387.24332) (xy 41.715436 -387.24332) (xy 41.705411 -387.243734) (xy 41.686886 -387.251398)
			(xy 41.672707 -387.265572) (xy 41.665037 -387.284096) (xy 41.664636 -387.29412) (xy 41.664636 -387.789674)
			(xy 41.664218 -387.814803) (xy 41.657587 -387.864621) (xy 41.644476 -387.913139) (xy 41.635172 -387.936486)
			(xy 41.633394 -387.94055) (xy 41.632632 -387.944614) (xy 41.628822 -387.952488) (xy 41.63187 -387.981952)
			(xy 41.696894 -388.062724) (xy 41.705442 -388.072136) (xy 41.728898 -388.081865) (xy 41.741598 -388.081266)
			(xy 41.746424 -388.080758) (xy 41.74871 -388.08025) (xy 41.766569 -388.077022) (xy 41.802699 -388.073585)
			(xy 41.820846 -388.073392) (xy 41.8211 -388.073392) (xy 41.848351 -388.073878) (xy 41.902299 -388.081634)
			(xy 41.954594 -388.096989) (xy 42.004171 -388.119631) (xy 42.050021 -388.149097) (xy 42.091212 -388.184788)
			(xy 42.126903 -388.225979) (xy 42.156369 -388.271829) (xy 42.168173 -388.297674) (xy 43.808902 -388.297674)
			(xy 43.812973 -388.242052) (xy 43.825099 -388.187615) (xy 43.845022 -388.135524) (xy 43.872318 -388.086889)
			(xy 43.906404 -388.042746) (xy 43.946553 -388.004037) (xy 43.991911 -387.971586) (xy 44.041511 -387.946085)
			(xy 44.094295 -387.928078) (xy 44.149138 -387.917948) (xy 44.204872 -387.915911) (xy 44.260309 -387.922011)
			(xy 44.314266 -387.936117) (xy 44.365595 -387.957929) (xy 44.413201 -387.986983) (xy 44.456069 -388.022658)
			(xy 44.493286 -388.064195) (xy 44.524059 -388.110708) (xy 44.547731 -388.161205) (xy 44.563799 -388.214612)
			(xy 44.571919 -388.269788) (xy 44.5724 -388.29615) (xy 44.774358 -388.29615) (xy 44.774534 -388.279462)
			(xy 44.777845 -388.246251) (xy 44.780962 -388.229856) (xy 44.782232 -388.224776) (xy 44.782232 -388.189978)
			(xy 44.782818 -388.172074) (xy 44.79275 -388.137671) (xy 44.811807 -388.107355) (xy 44.838502 -388.083488)
			(xy 44.854368 -388.07517) (xy 44.858298 -388.073117) (xy 44.865456 -388.067889) (xy 44.868592 -388.064756)
			(xy 44.868846 -388.064502) (xy 44.887637 -388.046104) (xy 44.929937 -388.014865) (xy 44.97665 -387.990719)
			(xy 45.026598 -387.974275) (xy 45.07852 -387.965949) (xy 45.104812 -387.965442) (xy 45.105066 -387.965442)
			(xy 45.132887 -387.966041) (xy 45.187744 -387.975355) (xy 45.240266 -387.993725) (xy 45.288969 -388.020633)
			(xy 45.332476 -388.055319) (xy 45.351446 -388.075678) (xy 45.361098 -388.08406) (xy 45.373099 -388.092604)
			(xy 45.39318 -388.114147) (xy 45.407807 -388.139709) (xy 45.416208 -388.167936) (xy 45.417486 -388.182612)
			(xy 45.41774 -388.185914) (xy 45.419772 -388.195312) (xy 45.427193 -388.219861) (xy 45.435232 -388.27051)
			(xy 45.435774 -388.29615) (xy 45.435318 -388.321582) (xy 45.434221 -388.328662) (xy 47.200566 -388.328662)
			(xy 47.200934 -388.307641) (xy 47.206543 -388.265975) (xy 47.211742 -388.245604) (xy 47.21352 -388.239)
			(xy 47.21352 -388.125462) (xy 47.214002 -388.110446) (xy 47.221782 -388.081438) (xy 47.236803 -388.055431)
			(xy 47.25804 -388.034195) (xy 47.284049 -388.019178) (xy 47.313058 -388.011401) (xy 47.328074 -388.010908)
			(xy 47.509684 -388.010908) (xy 47.510192 -388.010654) (xy 47.526956 -388.010654) (xy 47.527464 -388.010908)
			(xy 47.709074 -388.010908) (xy 47.724087 -388.011458) (xy 47.75309 -388.019222) (xy 47.779096 -388.034228)
			(xy 47.800333 -388.055453) (xy 47.815353 -388.081451) (xy 47.823133 -388.11045) (xy 47.823628 -388.125462)
			(xy 47.823628 -388.239) (xy 47.825406 -388.245604) (xy 47.830597 -388.265977) (xy 47.836208 -388.307642)
			(xy 47.836582 -388.328662) (xy 48.400462 -388.328662) (xy 48.40083 -388.307641) (xy 48.406439 -388.265975)
			(xy 48.411638 -388.245604) (xy 48.413416 -388.239) (xy 48.413416 -388.125462) (xy 48.413902 -388.110446)
			(xy 48.421682 -388.081439) (xy 48.436702 -388.055432) (xy 48.457938 -388.034197) (xy 48.483946 -388.019179)
			(xy 48.512954 -388.011401) (xy 48.52797 -388.010908) (xy 48.70958 -388.010908) (xy 48.710088 -388.010654)
			(xy 48.726852 -388.010654) (xy 48.72736 -388.010908) (xy 48.90897 -388.010908) (xy 48.923982 -388.011462)
			(xy 48.952986 -388.019225) (xy 48.978992 -388.03423) (xy 49.000229 -388.055454) (xy 49.015249 -388.081451)
			(xy 49.023029 -388.11045) (xy 49.023524 -388.125462) (xy 49.023524 -388.239) (xy 49.025302 -388.245604)
			(xy 49.030493 -388.265977) (xy 49.036104 -388.307642) (xy 49.036478 -388.328662) (xy 49.600612 -388.328662)
			(xy 49.600978 -388.307641) (xy 49.606589 -388.265975) (xy 49.611788 -388.245604) (xy 49.613312 -388.239)
			(xy 49.613312 -388.125462) (xy 49.613799 -388.110467) (xy 49.621557 -388.081499) (xy 49.636536 -388.055518)
			(xy 49.657718 -388.034289) (xy 49.683667 -388.019253) (xy 49.712618 -388.011432) (xy 49.727612 -388.010908)
			(xy 49.90973 -388.010908) (xy 49.910238 -388.010654) (xy 49.927002 -388.010654) (xy 49.92751 -388.010908)
			(xy 50.10912 -388.010908) (xy 50.124151 -388.011363) (xy 50.153191 -388.019138) (xy 50.179235 -388.034154)
			(xy 50.200513 -388.055391) (xy 50.215578 -388.081407) (xy 50.223409 -388.110432) (xy 50.223928 -388.125462)
			(xy 50.223928 -388.239) (xy 50.225452 -388.245604) (xy 50.230644 -388.265976) (xy 50.236254 -388.307642)
			(xy 50.236628 -388.328662) (xy 50.800508 -388.328662) (xy 50.800874 -388.307641) (xy 50.806485 -388.265975)
			(xy 50.811684 -388.245604) (xy 50.813208 -388.239) (xy 50.813208 -388.125462) (xy 50.813699 -388.110468)
			(xy 50.821456 -388.081499) (xy 50.836435 -388.055519) (xy 50.857617 -388.03429) (xy 50.883564 -388.019254)
			(xy 50.912515 -388.011433) (xy 50.927508 -388.010908) (xy 51.109626 -388.010908) (xy 51.110134 -388.010654)
			(xy 51.126898 -388.010654) (xy 51.127406 -388.010908) (xy 51.309016 -388.010908) (xy 51.324047 -388.011366)
			(xy 51.353087 -388.01914) (xy 51.379131 -388.034156) (xy 51.400408 -388.055393) (xy 51.415474 -388.081407)
			(xy 51.423305 -388.110432) (xy 51.423824 -388.125462) (xy 51.423824 -388.239) (xy 51.425348 -388.245604)
			(xy 51.43054 -388.265976) (xy 51.43615 -388.307642) (xy 51.436524 -388.328662) (xy 51.436524 -388.32917)
			(xy 51.436353 -388.343795) (xy 51.433686 -388.372924) (xy 51.43119 -388.387336) (xy 51.429828 -388.39651)
			(xy 51.4331 -388.414752) (xy 51.43754 -388.422896) (xy 51.45405 -388.44982) (xy 51.459217 -388.4576)
			(xy 51.473945 -388.469061) (xy 51.482752 -388.472172) (xy 51.507642 -388.48021) (xy 51.554521 -388.503406)
			(xy 51.596931 -388.534015) (xy 51.633713 -388.5712) (xy 51.663858 -388.613943) (xy 51.686541 -388.661071)
			(xy 51.694334 -388.68604) (xy 51.695858 -388.691882) (xy 51.830732 -388.925308) (xy 51.8354 -388.932729)
			(xy 51.848754 -388.944069) (xy 51.865158 -388.950222) (xy 51.873912 -388.950708) (xy 51.961034 -388.951978)
			(xy 51.969782 -388.951789) (xy 51.986349 -388.946197) (xy 52.000052 -388.935336) (xy 52.004976 -388.928102)
			(xy 52.017167 -388.909358) (xy 52.046157 -388.875317) (xy 52.079798 -388.845865) (xy 52.117373 -388.821629)
			(xy 52.137564 -388.812024) (xy 52.262278 -388.755636) (xy 52.277772 -388.735316) (xy 52.279804 -388.72287)
			(xy 52.280566 -388.718552) (xy 52.281933 -388.709212) (xy 52.278391 -388.690681) (xy 52.273708 -388.682484)
			(xy 52.257198 -388.655814) (xy 52.252003 -388.648105) (xy 52.237272 -388.636785) (xy 52.228496 -388.633716)
			(xy 52.206924 -388.626954) (xy 52.165798 -388.608183) (xy 52.127743 -388.58378) (xy 52.093526 -388.554235)
			(xy 52.078382 -388.53745) (xy 52.075912 -388.534685) (xy 52.070305 -388.529834) (xy 52.067206 -388.527798)
			(xy 52.055062 -388.519716) (xy 52.034975 -388.498576) (xy 52.02083 -388.473075) (xy 52.013529 -388.444843)
			(xy 52.013104 -388.430262) (xy 52.013104 -388.417816) (xy 52.011326 -388.411466) (xy 52.006197 -388.391151)
			(xy 52.00072 -388.349612) (xy 52.000404 -388.328662) (xy 52.000741 -388.307714) (xy 52.006215 -388.266176)
			(xy 52.011326 -388.245858) (xy 52.013104 -388.239508) (xy 52.013104 -387.782816) (xy 52.011326 -387.776466)
			(xy 52.006197 -387.756151) (xy 52.00072 -387.714612) (xy 52.000404 -387.693662) (xy 52.000741 -387.672714)
			(xy 52.006215 -387.631176) (xy 52.011326 -387.610858) (xy 52.013104 -387.604508) (xy 52.013104 -387.592062)
			(xy 52.013609 -387.5766) (xy 52.021833 -387.546789) (xy 52.037657 -387.520219) (xy 52.059952 -387.498787)
			(xy 52.073302 -387.49097) (xy 52.076858 -387.486906) (xy 52.084209 -387.477382) (xy 52.08991 -387.454043)
			(xy 52.08778 -387.442202) (xy 52.080668 -387.410706) (xy 52.077401 -387.399192) (xy 52.062152 -387.380779)
			(xy 52.051458 -387.3754) (xy 52.029969 -387.36559) (xy 51.989906 -387.340567) (xy 51.953989 -387.309888)
			(xy 51.938174 -387.292342) (xy 51.935706 -387.289575) (xy 51.930097 -387.284725) (xy 51.926998 -387.28269)
			(xy 51.914974 -387.274603) (xy 51.895082 -387.253546) (xy 51.881073 -387.228192) (xy 51.873831 -387.200145)
			(xy 51.873404 -387.185662) (xy 51.873404 -387.173724) (xy 51.871626 -387.16712) (xy 51.866419 -387.146751)
			(xy 51.860819 -387.105083) (xy 51.86045 -387.084062) (xy 51.860818 -387.063041) (xy 51.866428 -387.021375)
			(xy 51.871626 -387.001004) (xy 51.873404 -386.9944) (xy 51.873404 -386.880862) (xy 51.874068 -386.862743)
			(xy 51.88532 -386.828298) (xy 51.895502 -386.813298) (xy 51.899973 -386.806626) (xy 51.904907 -386.791353)
			(xy 51.905154 -386.783326) (xy 51.905154 -386.749798) (xy 51.904841 -386.74178) (xy 51.899934 -386.726514)
			(xy 51.895502 -386.719826) (xy 51.885421 -386.704773) (xy 51.874162 -386.670363) (xy 51.873404 -386.652262)
			(xy 51.873404 -386.538724) (xy 51.871626 -386.53212) (xy 51.866419 -386.511751) (xy 51.860819 -386.470083)
			(xy 51.86045 -386.449062) (xy 51.861212 -386.426456) (xy 51.861974 -386.416296) (xy 51.855878 -386.3975)
			(xy 51.802284 -386.335524) (xy 51.795363 -386.328255) (xy 51.777446 -386.319246) (xy 51.767486 -386.317998)
			(xy 51.743673 -386.315816) (xy 51.69708 -386.305053) (xy 51.652644 -386.287384) (xy 51.611383 -386.263212)
			(xy 51.574242 -386.233091) (xy 51.54207 -386.197711) (xy 51.515605 -386.157882) (xy 51.495453 -386.114516)
			(xy 51.48834 -386.091684) (xy 51.486816 -386.085842) (xy 51.166522 -385.532122) (xy 51.162458 -385.527804)
			(xy 51.146307 -385.510131) (xy 51.118987 -385.470815) (xy 51.097918 -385.427825) (xy 51.083582 -385.382146)
			(xy 51.076309 -385.334825) (xy 51.075844 -385.310888) (xy 51.075844 -385.31038) (xy 51.0763 -385.285589)
			(xy 51.084059 -385.236619) (xy 51.099383 -385.189465) (xy 51.121895 -385.145288) (xy 51.151041 -385.105178)
			(xy 51.186102 -385.07012) (xy 51.226216 -385.040978) (xy 51.270394 -385.018471) (xy 51.31755 -385.003151)
			(xy 51.366521 -384.995397) (xy 51.391312 -384.994912) (xy 51.416708 -384.995385) (xy 51.466843 -385.003518)
			(xy 51.515031 -385.019573) (xy 51.560026 -385.043135) (xy 51.600669 -385.073596) (xy 51.635911 -385.110171)
			(xy 51.664843 -385.151917) (xy 51.686719 -385.197756) (xy 51.694334 -385.221988) (xy 51.695858 -385.22783)
			(xy 52.016152 -385.78155) (xy 52.020216 -385.785868) (xy 52.036417 -385.803545) (xy 52.063816 -385.842893)
			(xy 52.084948 -385.885933) (xy 52.099325 -385.931674) (xy 52.106618 -385.979064) (xy 52.107084 -386.003038)
			(xy 52.107084 -386.003546) (xy 52.106322 -386.023866) (xy 52.10556 -386.033772) (xy 52.11191 -386.052822)
			(xy 52.172616 -386.122164) (xy 52.190396 -386.131054) (xy 52.200556 -386.131816) (xy 52.225503 -386.13406)
			(xy 52.274302 -386.145334) (xy 52.320732 -386.164115) (xy 52.363645 -386.189939) (xy 52.401982 -386.222169)
			(xy 52.418742 -386.240782) (xy 52.421206 -386.243553) (xy 52.426817 -386.248401) (xy 52.429918 -386.250434)
			(xy 52.441956 -386.258501) (xy 52.461846 -386.279565) (xy 52.475851 -386.304925) (xy 52.483088 -386.332977)
			(xy 52.483512 -386.347462) (xy 52.483512 -386.3594) (xy 52.48529 -386.366004) (xy 52.490481 -386.386377)
			(xy 52.496092 -386.428042) (xy 52.496466 -386.449062) (xy 52.496086 -386.470082) (xy 52.490485 -386.511749)
			(xy 52.48529 -386.53212) (xy 52.483512 -386.538724) (xy 52.483512 -386.599176) (xy 52.48394 -386.609197)
			(xy 52.491604 -386.627716) (xy 52.505774 -386.641889) (xy 52.524291 -386.649558) (xy 52.534312 -386.649976)
			(xy 52.538376 -386.649976) (xy 52.54244 -386.649214) (xy 52.55411 -386.647465) (xy 52.577631 -386.645554)
			(xy 52.58943 -386.645404) (xy 53.0225 -386.645404) (xy 53.032507 -386.644912) (xy 53.050998 -386.637253)
			(xy 53.065151 -386.623101) (xy 53.072811 -386.604611) (xy 53.0733 -386.594604) (xy 53.0733 -386.538724)
			(xy 53.071776 -386.53212) (xy 53.06657 -386.511751) (xy 53.060969 -386.470083) (xy 53.0606 -386.449062)
			(xy 53.061362 -386.426456) (xy 53.062124 -386.41655) (xy 53.055774 -386.397246) (xy 52.995576 -386.327904)
			(xy 52.977542 -386.31876) (xy 52.967636 -386.317998) (xy 52.943812 -386.315774) (xy 52.897183 -386.305051)
			(xy 52.852708 -386.287409) (xy 52.811407 -386.263254) (xy 52.774228 -386.233139) (xy 52.742022 -386.197755)
			(xy 52.715529 -386.157913) (xy 52.695356 -386.114527) (xy 52.688236 -386.091684) (xy 52.686712 -386.085842)
			(xy 52.366418 -385.532122) (xy 52.362354 -385.527804) (xy 52.346202 -385.510131) (xy 52.318882 -385.470815)
			(xy 52.297813 -385.427825) (xy 52.283478 -385.382146) (xy 52.276205 -385.334825) (xy 52.27574 -385.310888)
			(xy 52.27574 -385.31038) (xy 52.2762 -385.285589) (xy 52.283959 -385.236619) (xy 52.299283 -385.189465)
			(xy 52.321794 -385.14529) (xy 52.350939 -385.105179) (xy 52.386 -385.070121) (xy 52.426113 -385.04098)
			(xy 52.470291 -385.018472) (xy 52.517446 -385.003152) (xy 52.566417 -384.995397) (xy 52.591208 -384.994912)
			(xy 52.616603 -384.995388) (xy 52.666739 -385.003521) (xy 52.714926 -385.019575) (xy 52.759922 -385.043136)
			(xy 52.800565 -385.073597) (xy 52.835807 -385.110172) (xy 52.864739 -385.151917) (xy 52.886615 -385.197756)
			(xy 52.89423 -385.221988) (xy 52.895754 -385.22783) (xy 53.216048 -385.78155) (xy 53.220112 -385.785868)
			(xy 53.236313 -385.803545) (xy 53.263712 -385.842893) (xy 53.284844 -385.885933) (xy 53.299221 -385.931675)
			(xy 53.306514 -385.979064) (xy 53.30698 -386.003038) (xy 53.30698 -386.003546) (xy 53.306218 -386.023866)
			(xy 53.305456 -386.033772) (xy 53.311806 -386.052822) (xy 53.372512 -386.122164) (xy 53.390292 -386.131054)
			(xy 53.400452 -386.131816) (xy 53.425427 -386.134023) (xy 53.474285 -386.145274) (xy 53.520772 -386.164051)
			(xy 53.563737 -386.189889) (xy 53.602116 -386.222149) (xy 53.618892 -386.240782) (xy 53.62135 -386.243559)
			(xy 53.626965 -386.248402) (xy 53.630068 -386.250434) (xy 53.642145 -386.258474) (xy 53.662099 -386.279524)
			(xy 53.67617 -386.304888) (xy 53.683466 -386.33296) (xy 53.683916 -386.347462) (xy 53.683916 -386.3594)
			(xy 53.68544 -386.366004) (xy 53.690632 -386.386376) (xy 53.696242 -386.428042) (xy 53.696616 -386.449062)
			(xy 53.696234 -386.470082) (xy 53.690634 -386.511748) (xy 53.68544 -386.53212) (xy 53.683916 -386.538724)
			(xy 53.683916 -386.594604) (xy 53.684317 -386.604628) (xy 53.691991 -386.623148) (xy 53.706169 -386.63732)
			(xy 53.724692 -386.644987) (xy 53.734716 -386.645404) (xy 53.811424 -386.645404) (xy 53.840884 -386.646137)
			(xy 53.898695 -386.657516) (xy 53.926232 -386.66801) (xy 53.93563 -386.67182) (xy 54.237128 -386.67182)
			(xy 54.243423 -386.67164) (xy 54.25563 -386.668551) (xy 54.261258 -386.665724) (xy 54.273196 -386.659628)
			(xy 54.273196 -386.538724) (xy 54.271672 -386.53212) (xy 54.266466 -386.511751) (xy 54.260865 -386.470083)
			(xy 54.260496 -386.449062) (xy 54.261258 -386.426456) (xy 54.26202 -386.416296) (xy 54.255924 -386.3975)
			(xy 54.20233 -386.335524) (xy 54.195392 -386.328274) (xy 54.177488 -386.319254) (xy 54.167532 -386.317998)
			(xy 54.143723 -386.315779) (xy 54.097131 -386.305023) (xy 54.052695 -386.28736) (xy 54.011434 -386.263193)
			(xy 53.974292 -386.233078) (xy 53.942119 -386.197702) (xy 53.915653 -386.157877) (xy 53.8955 -386.114514)
			(xy 53.888386 -386.091684) (xy 53.886862 -386.085842) (xy 53.566568 -385.532122) (xy 53.562504 -385.527804)
			(xy 53.546277 -385.510116) (xy 53.518856 -385.47072) (xy 53.497717 -385.427625) (xy 53.483349 -385.381827)
			(xy 53.476083 -385.33438) (xy 53.475636 -385.31038) (xy 53.476098 -385.285602) (xy 53.48385 -385.236657)
			(xy 53.499158 -385.189525) (xy 53.521647 -385.145367) (xy 53.550764 -385.105267) (xy 53.585792 -385.070213)
			(xy 53.62587 -385.041067) (xy 53.670012 -385.018546) (xy 53.717133 -385.003203) (xy 53.766073 -384.995417)
			(xy 53.79085 -384.994912) (xy 53.791358 -384.994912) (xy 53.816752 -384.995432) (xy 53.866886 -385.003557)
			(xy 53.915072 -385.019604) (xy 53.960067 -385.043159) (xy 54.00071 -385.073614) (xy 54.035954 -385.110183)
			(xy 54.064887 -385.151923) (xy 54.086764 -385.197758) (xy 54.09438 -385.221988) (xy 54.095904 -385.22783)
			(xy 54.416198 -385.78155) (xy 54.420262 -385.785868) (xy 54.436419 -385.80357) (xy 54.463762 -385.84293)
			(xy 54.484842 -385.88597) (xy 54.499173 -385.931702) (xy 54.506426 -385.979075) (xy 54.506876 -386.003038)
			(xy 54.506876 -386.003546) (xy 54.506368 -386.023866) (xy 54.505606 -386.033772) (xy 54.511956 -386.052822)
			(xy 54.572662 -386.122164) (xy 54.590442 -386.131054) (xy 54.600602 -386.131816) (xy 54.625552 -386.134032)
			(xy 54.674352 -386.145313) (xy 54.720781 -386.164101) (xy 54.763694 -386.189931) (xy 54.802029 -386.222167)
			(xy 54.818788 -386.240782) (xy 54.821246 -386.243558) (xy 54.826862 -386.248402) (xy 54.829964 -386.250434)
			(xy 54.84204 -386.258475) (xy 54.861995 -386.279525) (xy 54.876065 -386.304888) (xy 54.883362 -386.33296)
			(xy 54.883812 -386.347462) (xy 54.883812 -386.3594) (xy 54.885336 -386.366004) (xy 54.890528 -386.386376)
			(xy 54.896138 -386.428042) (xy 54.896512 -386.449062) (xy 54.89613 -386.470082) (xy 54.89053 -386.511748)
			(xy 54.885336 -386.53212) (xy 54.883812 -386.538724) (xy 54.883812 -386.576824) (xy 54.884269 -386.586835)
			(xy 54.891938 -386.605329) (xy 54.906101 -386.619482) (xy 54.924601 -386.627139) (xy 54.934612 -386.627624)
			(xy 55.4228 -386.627624) (xy 55.432805 -386.627112) (xy 55.451292 -386.619457) (xy 55.465444 -386.605312)
			(xy 55.473108 -386.586828) (xy 55.4736 -386.576824) (xy 55.4736 -386.538724) (xy 55.471822 -386.53212)
			(xy 55.466615 -386.511751) (xy 55.461015 -386.470083) (xy 55.460646 -386.449062) (xy 55.461408 -386.426456)
			(xy 55.46217 -386.41655) (xy 55.45582 -386.397246) (xy 55.395622 -386.327904) (xy 55.377588 -386.31876)
			(xy 55.367682 -386.317998) (xy 55.343854 -386.315818) (xy 55.297223 -386.305087) (xy 55.252748 -386.287438)
			(xy 55.211447 -386.263276) (xy 55.174268 -386.233155) (xy 55.142064 -386.197765) (xy 55.115572 -386.157919)
			(xy 55.095401 -386.114529) (xy 55.088282 -386.091684) (xy 55.086758 -386.085842) (xy 54.766464 -385.532122)
			(xy 54.7624 -385.527804) (xy 54.746172 -385.510117) (xy 54.718751 -385.47072) (xy 54.697613 -385.427626)
			(xy 54.683245 -385.381827) (xy 54.675979 -385.33438) (xy 54.675532 -385.31038) (xy 54.675998 -385.285603)
			(xy 54.683749 -385.236657) (xy 54.699058 -385.189526) (xy 54.721546 -385.145368) (xy 54.750663 -385.105269)
			(xy 54.78569 -385.070215) (xy 54.825768 -385.041069) (xy 54.86991 -385.018547) (xy 54.91703 -385.003204)
			(xy 54.965969 -384.995417) (xy 54.990746 -384.994912) (xy 54.991254 -384.994912) (xy 55.016648 -384.995436)
			(xy 55.066781 -385.00356) (xy 55.114967 -385.019606) (xy 55.159963 -385.04316) (xy 55.200606 -385.073615)
			(xy 55.235849 -385.110184) (xy 55.264783 -385.151924) (xy 55.28666 -385.197758) (xy 55.294276 -385.221988)
			(xy 55.2958 -385.22783) (xy 55.616094 -385.78155) (xy 55.620158 -385.785868) (xy 55.636315 -385.80357)
			(xy 55.663658 -385.84293) (xy 55.684737 -385.88597) (xy 55.699069 -385.931702) (xy 55.706322 -385.979076)
			(xy 55.706772 -386.003038) (xy 55.706772 -386.003546) (xy 55.706264 -386.023866) (xy 55.705502 -386.033772)
			(xy 55.711852 -386.052822) (xy 55.772558 -386.122164) (xy 55.790338 -386.131054) (xy 55.800498 -386.131816)
			(xy 55.825476 -386.133996) (xy 55.874335 -386.145253) (xy 55.920822 -386.164036) (xy 55.963786 -386.189881)
			(xy 56.002163 -386.222147) (xy 56.018938 -386.240782) (xy 56.021402 -386.243553) (xy 56.027013 -386.2484)
			(xy 56.030114 -386.250434) (xy 56.042151 -386.258502) (xy 56.062041 -386.279566) (xy 56.076047 -386.304925)
			(xy 56.083284 -386.332977) (xy 56.083708 -386.347462) (xy 56.083708 -386.3594) (xy 56.085486 -386.366004)
			(xy 56.090679 -386.386376) (xy 56.096288 -386.428042) (xy 56.096662 -386.449062) (xy 56.096279 -386.470082)
			(xy 56.090679 -386.511748) (xy 56.085486 -386.53212) (xy 56.083708 -386.538724) (xy 56.083708 -386.576824)
			(xy 56.084168 -386.586834) (xy 56.091837 -386.605328) (xy 56.105999 -386.619481) (xy 56.124497 -386.627138)
			(xy 56.134508 -386.627624) (xy 56.622696 -386.627624) (xy 56.6327 -386.627109) (xy 56.651187 -386.619455)
			(xy 56.66534 -386.605311) (xy 56.673004 -386.586828) (xy 56.673496 -386.576824) (xy 56.673496 -386.538724)
			(xy 56.671718 -386.53212) (xy 56.666511 -386.511751) (xy 56.660911 -386.470083) (xy 56.660542 -386.449062)
			(xy 56.661304 -386.426456) (xy 56.662066 -386.41655) (xy 56.655716 -386.397246) (xy 56.595518 -386.327904)
			(xy 56.577484 -386.31876) (xy 56.567578 -386.317998) (xy 56.543749 -386.315821) (xy 56.497119 -386.30509)
			(xy 56.452643 -386.28744) (xy 56.411343 -386.263278) (xy 56.374164 -386.233156) (xy 56.34196 -386.197766)
			(xy 56.315468 -386.157919) (xy 56.295297 -386.114529) (xy 56.288178 -386.091684) (xy 56.286654 -386.085842)
			(xy 55.966106 -385.53136) (xy 55.962042 -385.527042) (xy 55.945964 -385.509363) (xy 55.918773 -385.470069)
			(xy 55.897817 -385.427124) (xy 55.883576 -385.381511) (xy 55.876374 -385.334272) (xy 55.875936 -385.31038)
			(xy 55.8764 -385.28559) (xy 55.884159 -385.23662) (xy 55.899482 -385.189466) (xy 55.921994 -385.145291)
			(xy 55.951138 -385.10518) (xy 55.986199 -385.070123) (xy 56.026311 -385.040981) (xy 56.070489 -385.018473)
			(xy 56.117643 -385.003153) (xy 56.166614 -384.995398) (xy 56.191404 -384.994912) (xy 56.216851 -384.995426)
			(xy 56.267088 -385.003576) (xy 56.315367 -385.01968) (xy 56.360437 -385.043321) (xy 56.401129 -385.073887)
			(xy 56.436391 -385.110586) (xy 56.465309 -385.152466) (xy 56.487132 -385.198443) (xy 56.49468 -385.22275)
			(xy 56.496204 -385.228592) (xy 56.81599 -385.78155) (xy 56.820054 -385.785868) (xy 56.83621 -385.803571)
			(xy 56.863554 -385.84293) (xy 56.884633 -385.88597) (xy 56.898965 -385.931703) (xy 56.906218 -385.979076)
			(xy 56.906668 -386.003038) (xy 56.906668 -386.003546) (xy 56.90616 -386.023866) (xy 56.905398 -386.033772)
			(xy 56.911748 -386.052822) (xy 56.972454 -386.122164) (xy 56.990234 -386.131054) (xy 57.000394 -386.131816)
			(xy 57.025372 -386.133998) (xy 57.07423 -386.145255) (xy 57.120717 -386.164038) (xy 57.163682 -386.189882)
			(xy 57.202059 -386.222147) (xy 57.218834 -386.240782) (xy 57.221299 -386.243552) (xy 57.22691 -386.2484)
			(xy 57.23001 -386.250434) (xy 57.242046 -386.258503) (xy 57.261937 -386.279566) (xy 57.275943 -386.304925)
			(xy 57.28318 -386.332977) (xy 57.283604 -386.347462) (xy 57.283604 -386.3594) (xy 57.285382 -386.366004)
			(xy 57.290575 -386.386376) (xy 57.296184 -386.428042) (xy 57.296558 -386.449062) (xy 57.296175 -386.470082)
			(xy 57.290575 -386.511748) (xy 57.285382 -386.53212) (xy 57.283604 -386.538724) (xy 57.283604 -386.576824)
			(xy 57.284068 -386.586834) (xy 57.291737 -386.605327) (xy 57.305897 -386.619479) (xy 57.324394 -386.627137)
			(xy 57.334404 -386.627624) (xy 57.835292 -386.627624) (xy 57.844841 -386.627685) (xy 57.863904 -386.628828)
			(xy 57.873392 -386.62991) (xy 57.873392 -386.538724) (xy 57.871614 -386.53212) (xy 57.866407 -386.511751)
			(xy 57.860807 -386.470083) (xy 57.860438 -386.449062) (xy 57.8612 -386.426456) (xy 57.861962 -386.416296)
			(xy 57.855866 -386.3975) (xy 57.802272 -386.335524) (xy 57.795355 -386.32825) (xy 57.777435 -386.319244)
			(xy 57.767474 -386.317998) (xy 57.74366 -386.315826) (xy 57.697066 -386.305061) (xy 57.652631 -386.28739)
			(xy 57.61137 -386.263217) (xy 57.574229 -386.233094) (xy 57.542057 -386.197713) (xy 57.515593 -386.157883)
			(xy 57.495441 -386.114516) (xy 57.488328 -386.091684) (xy 57.486804 -386.085842) (xy 57.16651 -385.532122)
			(xy 57.162446 -385.527804) (xy 57.146293 -385.510132) (xy 57.118974 -385.470816) (xy 57.097905 -385.427825)
			(xy 57.08357 -385.382146) (xy 57.076297 -385.334826) (xy 57.075832 -385.310888) (xy 57.075832 -385.31038)
			(xy 57.0763 -385.28559) (xy 57.084058 -385.23662) (xy 57.099382 -385.189467) (xy 57.121893 -385.145292)
			(xy 57.151037 -385.105182) (xy 57.186097 -385.070124) (xy 57.226209 -385.040983) (xy 57.270386 -385.018474)
			(xy 57.31754 -385.003154) (xy 57.36651 -384.995398) (xy 57.3913 -384.994912) (xy 57.416695 -384.995395)
			(xy 57.466831 -385.003527) (xy 57.515018 -385.01958) (xy 57.560013 -385.04314) (xy 57.600656 -385.0736)
			(xy 57.635898 -385.110174) (xy 57.664831 -385.151918) (xy 57.686707 -385.197756) (xy 57.694322 -385.221988)
			(xy 57.695846 -385.22783) (xy 58.01614 -385.78155) (xy 58.020204 -385.785868) (xy 58.036403 -385.803546)
			(xy 58.063803 -385.842894) (xy 58.084935 -385.885934) (xy 58.099313 -385.931675) (xy 58.106606 -385.979065)
			(xy 58.107072 -386.003038) (xy 58.107072 -386.003546) (xy 58.10631 -386.023866) (xy 58.105548 -386.033772)
			(xy 58.111898 -386.052822) (xy 58.172604 -386.122164) (xy 58.190384 -386.131054) (xy 58.200544 -386.131816)
			(xy 58.225496 -386.134007) (xy 58.274297 -386.145294) (xy 58.320727 -386.164088) (xy 58.363638 -386.189924)
			(xy 58.401972 -386.222164) (xy 58.41873 -386.240782) (xy 58.421195 -386.243552) (xy 58.426806 -386.2484)
			(xy 58.429906 -386.250434) (xy 58.441942 -386.258505) (xy 58.461832 -386.279567) (xy 58.475839 -386.304926)
			(xy 58.483076 -386.332977) (xy 58.4835 -386.347462) (xy 58.4835 -386.3594) (xy 58.485278 -386.366004)
			(xy 58.49047 -386.386376) (xy 58.49608 -386.428042) (xy 58.496454 -386.449062) (xy 58.496071 -386.470082)
			(xy 58.490471 -386.511748) (xy 58.485278 -386.53212) (xy 58.4835 -386.538724) (xy 58.4835 -386.62102)
			(xy 58.483972 -386.631029) (xy 58.491638 -386.649521) (xy 58.505796 -386.663674) (xy 58.524291 -386.671332)
			(xy 58.5343 -386.67182) (xy 58.873898 -386.67182) (xy 58.886344 -386.668518) (xy 58.891932 -386.66547)
			(xy 58.918867 -386.651327) (xy 58.976837 -386.632907) (xy 59.006994 -386.628894) (xy 59.015906 -386.627637)
			(xy 59.03204 -386.619679) (xy 59.03849 -386.6134) (xy 59.059318 -386.591302) (xy 59.065678 -386.583968)
			(xy 59.072859 -386.565948) (xy 59.073288 -386.55625) (xy 59.073288 -386.538724) (xy 59.071764 -386.53212)
			(xy 59.066558 -386.511751) (xy 59.060957 -386.470083) (xy 59.060588 -386.449062) (xy 59.06135 -386.426456)
			(xy 59.062112 -386.41655) (xy 59.055762 -386.397246) (xy 58.995564 -386.327904) (xy 58.97753 -386.31876)
			(xy 58.967624 -386.317998) (xy 58.943799 -386.315784) (xy 58.89717 -386.305059) (xy 58.852695 -386.287416)
			(xy 58.811394 -386.263259) (xy 58.774214 -386.233142) (xy 58.742009 -386.197757) (xy 58.715516 -386.157914)
			(xy 58.695344 -386.114528) (xy 58.688224 -386.091684) (xy 58.6867 -386.085842) (xy 58.366406 -385.532122)
			(xy 58.362342 -385.527804) (xy 58.346188 -385.510133) (xy 58.318869 -385.470816) (xy 58.297801 -385.427825)
			(xy 58.283466 -385.382146) (xy 58.276193 -385.334826) (xy 58.275728 -385.310888) (xy 58.275728 -385.31038)
			(xy 58.2762 -385.28559) (xy 58.283958 -385.236621) (xy 58.299282 -385.189468) (xy 58.321792 -385.145293)
			(xy 58.350936 -385.105183) (xy 58.385995 -385.070126) (xy 58.426107 -385.040984) (xy 58.470283 -385.018475)
			(xy 58.517436 -385.003155) (xy 58.566406 -384.995398) (xy 58.591196 -384.994912) (xy 58.616591 -384.995399)
			(xy 58.666726 -385.00353) (xy 58.714913 -385.019582) (xy 58.759908 -385.043142) (xy 58.800552 -385.073601)
			(xy 58.835794 -385.110175) (xy 58.864727 -385.151919) (xy 58.886603 -385.197756) (xy 58.894218 -385.221988)
			(xy 58.895742 -385.22783) (xy 58.943492 -385.31038) (xy 59.475624 -385.31038) (xy 59.476098 -385.285603)
			(xy 59.483849 -385.236659) (xy 59.499157 -385.189528) (xy 59.521645 -385.14537) (xy 59.55076 -385.105271)
			(xy 59.585787 -385.070218) (xy 59.625864 -385.041072) (xy 59.670004 -385.01855) (xy 59.717123 -385.003206)
			(xy 59.766061 -384.995418) (xy 59.790838 -384.994912) (xy 59.791346 -384.994912) (xy 59.816743 -384.995355)
			(xy 59.86688 -385.003493) (xy 59.915068 -385.019553) (xy 59.960063 -385.043119) (xy 60.000706 -385.073585)
			(xy 60.035947 -385.110164) (xy 60.064878 -385.151913) (xy 60.086753 -385.197754) (xy 60.094368 -385.221988)
			(xy 60.095892 -385.22783) (xy 60.143642 -385.31038) (xy 60.67552 -385.31038) (xy 60.675998 -385.285603)
			(xy 60.683749 -385.236659) (xy 60.699056 -385.189529) (xy 60.721544 -385.145371) (xy 60.750659 -385.105273)
			(xy 60.785685 -385.070219) (xy 60.825761 -385.041073) (xy 60.869901 -385.018551) (xy 60.91702 -385.003207)
			(xy 60.965957 -384.995418) (xy 60.990734 -384.994912) (xy 60.991242 -384.994912) (xy 61.016639 -384.995358)
			(xy 61.066776 -385.003496) (xy 61.114963 -385.019555) (xy 61.159959 -385.043121) (xy 61.200601 -385.073586)
			(xy 61.235843 -385.110165) (xy 61.264774 -385.151913) (xy 61.286649 -385.197755) (xy 61.294264 -385.221988)
			(xy 61.295788 -385.22783) (xy 61.343538 -385.31038) (xy 61.875924 -385.31038) (xy 61.8764 -385.28559)
			(xy 61.884158 -385.236621) (xy 61.899481 -385.189469) (xy 61.921992 -385.145294) (xy 61.951135 -385.105184)
			(xy 61.986194 -385.070127) (xy 62.026305 -385.040985) (xy 62.07048 -385.018477) (xy 62.117633 -385.003155)
			(xy 62.166602 -384.995399) (xy 62.191392 -384.994912) (xy 62.216839 -384.995436) (xy 62.267075 -385.003584)
			(xy 62.315354 -385.019687) (xy 62.360423 -385.043326) (xy 62.401116 -385.073891) (xy 62.436379 -385.110588)
			(xy 62.465296 -385.152467) (xy 62.48712 -385.198444) (xy 62.494668 -385.22275) (xy 62.496192 -385.228592)
			(xy 62.543785 -385.310888) (xy 63.07582 -385.310888) (xy 63.07582 -385.31038) (xy 63.076299 -385.28559)
			(xy 63.084058 -385.236622) (xy 63.099381 -385.18947) (xy 63.121891 -385.145295) (xy 63.151034 -385.105186)
			(xy 63.186092 -385.070128) (xy 63.226202 -385.040987) (xy 63.270378 -385.018478) (xy 63.31753 -385.003156)
			(xy 63.366498 -384.995399) (xy 63.391288 -384.994912) (xy 63.416683 -384.995406) (xy 63.466818 -385.003535)
			(xy 63.515004 -385.019587) (xy 63.56 -385.043145) (xy 63.600643 -385.073604) (xy 63.635885 -385.110177)
			(xy 63.664818 -385.15192) (xy 63.686695 -385.197757) (xy 63.69431 -385.221988) (xy 63.695834 -385.22783)
			(xy 63.743584 -385.31038) (xy 64.275716 -385.31038) (xy 64.276198 -385.285603) (xy 64.283949 -385.23666)
			(xy 64.299256 -385.18953) (xy 64.321743 -385.145373) (xy 64.350858 -385.105274) (xy 64.385884 -385.070221)
			(xy 64.425959 -385.041074) (xy 64.470098 -385.018552) (xy 64.517216 -385.003207) (xy 64.566154 -384.995418)
			(xy 64.59093 -384.994912) (xy 64.591438 -384.994912) (xy 64.616886 -384.995396) (xy 64.667125 -385.003551)
			(xy 64.715404 -385.01966) (xy 64.760474 -385.043306) (xy 64.801166 -385.073876) (xy 64.836428 -385.110578)
			(xy 64.865344 -385.152462) (xy 64.887167 -385.198442) (xy 64.894714 -385.22275) (xy 64.896238 -385.228592)
			(xy 64.943538 -385.31038) (xy 65.475612 -385.31038) (xy 65.476098 -385.285604) (xy 65.483849 -385.23666)
			(xy 65.499156 -385.189531) (xy 65.521643 -385.145374) (xy 65.550757 -385.105275) (xy 65.585782 -385.070222)
			(xy 65.625857 -385.041076) (xy 65.669996 -385.018553) (xy 65.717113 -385.003208) (xy 65.76605 -384.995418)
			(xy 65.790826 -384.994912) (xy 65.791334 -384.994912) (xy 65.81673 -384.995365) (xy 65.866867 -385.003502)
			(xy 65.915055 -385.01956) (xy 65.96005 -385.043125) (xy 66.000693 -385.073589) (xy 66.035934 -385.110167)
			(xy 66.064866 -385.151914) (xy 66.086741 -385.197755) (xy 66.094356 -385.221988) (xy 66.09588 -385.22783)
			(xy 66.416174 -385.78155) (xy 66.420238 -385.785868) (xy 66.436391 -385.803573) (xy 66.463736 -385.842932)
			(xy 66.484816 -385.885971) (xy 66.499148 -385.931703) (xy 66.506402 -385.979076) (xy 66.506852 -386.003038)
			(xy 66.506852 -386.003546) (xy 66.506344 -386.023612) (xy 66.506175 -386.03366) (xy 66.512704 -386.052647)
			(xy 66.519044 -386.060442) (xy 66.573654 -386.122164) (xy 66.591688 -386.131054) (xy 66.601848 -386.131562)
			(xy 66.627229 -386.133504) (xy 66.676936 -386.144461) (xy 66.724265 -386.163192) (xy 66.768008 -386.18922)
			(xy 66.807048 -386.22188) (xy 66.824098 -386.240782) (xy 66.826555 -386.24356) (xy 66.832171 -386.248403)
			(xy 66.835274 -386.250434) (xy 66.847303 -386.258515) (xy 66.867196 -386.279572) (xy 66.881205 -386.304928)
			(xy 66.888443 -386.332978) (xy 66.888868 -386.347462) (xy 66.888868 -386.3594) (xy 66.890646 -386.366004)
			(xy 66.895838 -386.386376) (xy 66.901448 -386.428042) (xy 66.901822 -386.449062) (xy 66.90144 -386.470082)
			(xy 66.89584 -386.511748) (xy 66.890646 -386.53212) (xy 66.888868 -386.538724) (xy 66.888868 -386.652262)
			(xy 66.888375 -386.667282) (xy 66.880609 -386.6963) (xy 66.865596 -386.722318) (xy 66.84436 -386.743564)
			(xy 66.818348 -386.758589) (xy 66.789334 -386.766368) (xy 66.774314 -386.766816) (xy 66.592704 -386.766816)
			(xy 66.592196 -386.76707) (xy 66.575432 -386.76707) (xy 66.574924 -386.766816) (xy 66.393314 -386.766816)
			(xy 66.378289 -386.766395) (xy 66.349262 -386.758619) (xy 66.323239 -386.743593) (xy 66.301992 -386.722342)
			(xy 66.286972 -386.696315) (xy 66.279202 -386.667287) (xy 66.27876 -386.652262) (xy 66.27876 -386.538724)
			(xy 66.276982 -386.53212) (xy 66.271776 -386.511751) (xy 66.266175 -386.470083) (xy 66.265806 -386.449062)
			(xy 66.266568 -386.42671) (xy 66.26733 -386.41655) (xy 66.26098 -386.3975) (xy 66.199766 -386.32765)
			(xy 66.181732 -386.31876) (xy 66.171572 -386.318252) (xy 66.147488 -386.316269) (xy 66.100283 -386.305943)
			(xy 66.055205 -386.288537) (xy 66.013309 -386.264461) (xy 65.975576 -386.234277) (xy 65.942887 -386.19869)
			(xy 65.916007 -386.158535) (xy 65.895567 -386.11475) (xy 65.888362 -386.091684) (xy 65.886838 -386.085842)
			(xy 65.566544 -385.532122) (xy 65.56248 -385.527804) (xy 65.546249 -385.51012) (xy 65.518829 -385.470722)
			(xy 65.497692 -385.427627) (xy 65.483324 -385.381827) (xy 65.476059 -385.33438) (xy 65.475612 -385.31038)
			(xy 64.943538 -385.31038) (xy 65.216024 -385.78155) (xy 65.220088 -385.785868) (xy 65.236285 -385.803549)
			(xy 65.263685 -385.842895) (xy 65.284818 -385.885934) (xy 65.299197 -385.931675) (xy 65.30649 -385.979065)
			(xy 65.306956 -386.003038) (xy 65.306956 -386.003546) (xy 65.306194 -386.023866) (xy 65.305432 -386.033772)
			(xy 65.311782 -386.052822) (xy 65.372488 -386.122164) (xy 65.390268 -386.131054) (xy 65.400428 -386.131816)
			(xy 65.425402 -386.134038) (xy 65.474259 -386.145284) (xy 65.520746 -386.164058) (xy 65.563712 -386.189893)
			(xy 65.602091 -386.22215) (xy 65.618868 -386.240782) (xy 65.621329 -386.243556) (xy 65.626942 -386.248402)
			(xy 65.630044 -386.250434) (xy 65.642116 -386.258481) (xy 65.662072 -386.279528) (xy 65.676145 -386.30489)
			(xy 65.683442 -386.332961) (xy 65.683892 -386.347462) (xy 65.683892 -386.3594) (xy 65.685416 -386.366004)
			(xy 65.690607 -386.386377) (xy 65.696218 -386.428042) (xy 65.696592 -386.449062) (xy 65.696211 -386.470082)
			(xy 65.69061 -386.511748) (xy 65.685416 -386.53212) (xy 65.683892 -386.538724) (xy 65.683892 -386.652262)
			(xy 65.683334 -386.667253) (xy 65.675595 -386.696218) (xy 65.660632 -386.722199) (xy 65.639462 -386.74343)
			(xy 65.613524 -386.758468) (xy 65.584581 -386.766291) (xy 65.569592 -386.766816) (xy 65.387474 -386.766816)
			(xy 65.386966 -386.76707) (xy 65.370202 -386.76707) (xy 65.369694 -386.766816) (xy 65.188084 -386.766816)
			(xy 65.173055 -386.766334) (xy 65.144019 -386.758562) (xy 65.117977 -386.74355) (xy 65.0967 -386.722319)
			(xy 65.081633 -386.69631) (xy 65.073798 -386.66729) (xy 65.073276 -386.652262) (xy 65.073276 -386.538724)
			(xy 65.071752 -386.53212) (xy 65.066546 -386.511751) (xy 65.060945 -386.470083) (xy 65.060576 -386.449062)
			(xy 65.061338 -386.426456) (xy 65.0621 -386.41655) (xy 65.05575 -386.397246) (xy 64.995552 -386.327904)
			(xy 64.977518 -386.31876) (xy 64.967612 -386.317998) (xy 64.943786 -386.315793) (xy 64.897157 -386.305067)
			(xy 64.852681 -386.287422) (xy 64.811381 -386.263264) (xy 64.774201 -386.233146) (xy 64.741996 -386.197759)
			(xy 64.715504 -386.157915) (xy 64.695332 -386.114528) (xy 64.688212 -386.091684) (xy 64.686688 -386.085842)
			(xy 64.36614 -385.53136) (xy 64.362076 -385.527042) (xy 64.345952 -385.50939) (xy 64.318706 -385.470107)
			(xy 64.297699 -385.427162) (xy 64.283411 -385.381539) (xy 64.276171 -385.334283) (xy 64.275716 -385.31038)
			(xy 63.743584 -385.31038) (xy 64.016128 -385.78155) (xy 64.020192 -385.785868) (xy 64.036389 -385.803548)
			(xy 64.06379 -385.842895) (xy 64.084923 -385.885934) (xy 64.099301 -385.931675) (xy 64.106594 -385.979065)
			(xy 64.10706 -386.003038) (xy 64.10706 -386.003546) (xy 64.106298 -386.023866) (xy 64.105536 -386.033772)
			(xy 64.111886 -386.052822) (xy 64.172592 -386.122164) (xy 64.190372 -386.131054) (xy 64.200532 -386.131816)
			(xy 64.225506 -386.134036) (xy 64.274363 -386.145283) (xy 64.32085 -386.164057) (xy 64.363816 -386.189893)
			(xy 64.402195 -386.22215) (xy 64.418972 -386.240782) (xy 64.421432 -386.243556) (xy 64.427046 -386.248402)
			(xy 64.430148 -386.250434) (xy 64.44222 -386.25848) (xy 64.462177 -386.279527) (xy 64.476249 -386.304889)
			(xy 64.483546 -386.332961) (xy 64.483996 -386.347462) (xy 64.483996 -386.3594) (xy 64.48552 -386.366004)
			(xy 64.490711 -386.386377) (xy 64.496322 -386.428042) (xy 64.496696 -386.449062) (xy 64.496315 -386.470082)
			(xy 64.490714 -386.511748) (xy 64.48552 -386.53212) (xy 64.483996 -386.538724) (xy 64.483996 -386.652262)
			(xy 64.483434 -386.667253) (xy 64.475695 -386.696217) (xy 64.460733 -386.722198) (xy 64.439564 -386.743429)
			(xy 64.413627 -386.758467) (xy 64.384685 -386.76629) (xy 64.369696 -386.766816) (xy 64.187578 -386.766816)
			(xy 64.18707 -386.76707) (xy 64.170306 -386.76707) (xy 64.169798 -386.766816) (xy 63.988188 -386.766816)
			(xy 63.973159 -386.766331) (xy 63.944123 -386.75856) (xy 63.918082 -386.743549) (xy 63.896804 -386.722318)
			(xy 63.881737 -386.696309) (xy 63.873902 -386.66729) (xy 63.87338 -386.652262) (xy 63.87338 -386.538724)
			(xy 63.871856 -386.53212) (xy 63.86665 -386.511751) (xy 63.861049 -386.470083) (xy 63.86068 -386.449062)
			(xy 63.861442 -386.426456) (xy 63.862204 -386.41655) (xy 63.855854 -386.397246) (xy 63.795656 -386.327904)
			(xy 63.777622 -386.31876) (xy 63.767716 -386.317998) (xy 63.743891 -386.31579) (xy 63.697261 -386.305064)
			(xy 63.652786 -386.28742) (xy 63.611485 -386.263262) (xy 63.574306 -386.233145) (xy 63.542101 -386.197759)
			(xy 63.515608 -386.157915) (xy 63.495436 -386.114528) (xy 63.488316 -386.091684) (xy 63.486792 -386.085842)
			(xy 63.166498 -385.532122) (xy 63.162434 -385.527804) (xy 63.146279 -385.510134) (xy 63.11896 -385.470817)
			(xy 63.097892 -385.427826) (xy 63.083558 -385.382146) (xy 63.076285 -385.334826) (xy 63.07582 -385.310888)
			(xy 62.543785 -385.310888) (xy 62.815978 -385.78155) (xy 62.820042 -385.785868) (xy 62.836196 -385.803573)
			(xy 62.86354 -385.842931) (xy 62.88462 -385.885971) (xy 62.898952 -385.931703) (xy 62.906206 -385.979076)
			(xy 62.906656 -386.003038) (xy 62.906656 -386.003546) (xy 62.906148 -386.023866) (xy 62.905386 -386.033772)
			(xy 62.911736 -386.052822) (xy 62.972442 -386.122164) (xy 62.990222 -386.131054) (xy 63.000382 -386.131816)
			(xy 63.025359 -386.134005) (xy 63.074217 -386.14526) (xy 63.120704 -386.164041) (xy 63.163669 -386.189884)
			(xy 63.202046 -386.222147) (xy 63.218822 -386.240782) (xy 63.221288 -386.243551) (xy 63.226898 -386.2484)
			(xy 63.229998 -386.250434) (xy 63.242032 -386.258507) (xy 63.261923 -386.279568) (xy 63.27593 -386.304926)
			(xy 63.283168 -386.332977) (xy 63.283592 -386.347462) (xy 63.283592 -386.3594) (xy 63.28537 -386.366004)
			(xy 63.290562 -386.386376) (xy 63.296172 -386.428042) (xy 63.296546 -386.449062) (xy 63.296163 -386.470082)
			(xy 63.290564 -386.511748) (xy 63.28537 -386.53212) (xy 63.283592 -386.538724) (xy 63.283592 -386.652262)
			(xy 63.283031 -386.667274) (xy 63.27527 -386.696277) (xy 63.260267 -386.722283) (xy 63.239044 -386.74352)
			(xy 63.213048 -386.758541) (xy 63.18405 -386.766321) (xy 63.169038 -386.766816) (xy 62.987428 -386.766816)
			(xy 62.98692 -386.76707) (xy 62.970156 -386.76707) (xy 62.969648 -386.766816) (xy 62.788038 -386.766816)
			(xy 62.773014 -386.766374) (xy 62.743988 -386.758604) (xy 62.717964 -386.743583) (xy 62.696717 -386.722336)
			(xy 62.681696 -386.696312) (xy 62.673926 -386.667286) (xy 62.673484 -386.652262) (xy 62.673484 -386.538724)
			(xy 62.671706 -386.53212) (xy 62.666501 -386.511751) (xy 62.660899 -386.470083) (xy 62.66053 -386.449062)
			(xy 62.661292 -386.426456) (xy 62.662054 -386.41655) (xy 62.655704 -386.397246) (xy 62.595506 -386.327904)
			(xy 62.577472 -386.31876) (xy 62.567566 -386.317998) (xy 62.543745 -386.31575) (xy 62.497117 -386.305031)
			(xy 62.452642 -386.287394) (xy 62.411341 -386.263242) (xy 62.37416 -386.23313) (xy 62.341954 -386.197749)
			(xy 62.31546 -386.15791) (xy 62.295287 -386.114526) (xy 62.288166 -386.091684) (xy 62.286642 -386.085842)
			(xy 61.966094 -385.53136) (xy 61.96203 -385.527042) (xy 61.94595 -385.509365) (xy 61.91876 -385.47007)
			(xy 61.897805 -385.427125) (xy 61.883564 -385.381512) (xy 61.876362 -385.334272) (xy 61.875924 -385.31038)
			(xy 61.343538 -385.31038) (xy 61.616082 -385.78155) (xy 61.620146 -385.785868) (xy 61.636301 -385.803572)
			(xy 61.663645 -385.842931) (xy 61.684725 -385.885971) (xy 61.699056 -385.931703) (xy 61.70631 -385.979076)
			(xy 61.70676 -386.003038) (xy 61.70676 -386.003546) (xy 61.706252 -386.023866) (xy 61.70549 -386.033772)
			(xy 61.71184 -386.052822) (xy 61.772546 -386.122164) (xy 61.790326 -386.131054) (xy 61.800486 -386.131816)
			(xy 61.825464 -386.134003) (xy 61.874322 -386.145258) (xy 61.920809 -386.16404) (xy 61.963773 -386.189883)
			(xy 62.002151 -386.222147) (xy 62.018926 -386.240782) (xy 62.021392 -386.243551) (xy 62.027002 -386.2484)
			(xy 62.030102 -386.250434) (xy 62.042137 -386.258506) (xy 62.062028 -386.279568) (xy 62.076035 -386.304926)
			(xy 62.083272 -386.332977) (xy 62.083696 -386.347462) (xy 62.083696 -386.3594) (xy 62.085474 -386.366004)
			(xy 62.090666 -386.386376) (xy 62.096276 -386.428042) (xy 62.09665 -386.449062) (xy 62.096267 -386.470082)
			(xy 62.090667 -386.511748) (xy 62.085474 -386.53212) (xy 62.083696 -386.538724) (xy 62.083696 -386.652262)
			(xy 62.083131 -386.667274) (xy 62.07537 -386.696276) (xy 62.060368 -386.722282) (xy 62.039146 -386.743519)
			(xy 62.01315 -386.75854) (xy 61.984153 -386.766321) (xy 61.969142 -386.766816) (xy 61.787532 -386.766816)
			(xy 61.787024 -386.76707) (xy 61.77026 -386.76707) (xy 61.769752 -386.766816) (xy 61.588142 -386.766816)
			(xy 61.573118 -386.766371) (xy 61.544092 -386.758601) (xy 61.518069 -386.743581) (xy 61.496821 -386.722335)
			(xy 61.4818 -386.696311) (xy 61.47403 -386.667286) (xy 61.473588 -386.652262) (xy 61.473588 -386.538724)
			(xy 61.47181 -386.53212) (xy 61.466605 -386.511751) (xy 61.461003 -386.470083) (xy 61.460634 -386.449062)
			(xy 61.461396 -386.426456) (xy 61.462158 -386.41655) (xy 61.455808 -386.397246) (xy 61.39561 -386.327904)
			(xy 61.377576 -386.31876) (xy 61.36767 -386.317998) (xy 61.343849 -386.315747) (xy 61.297221 -386.305029)
			(xy 61.252746 -386.287392) (xy 61.211445 -386.263241) (xy 61.174265 -386.233129) (xy 61.142058 -386.197748)
			(xy 61.115564 -386.157909) (xy 61.095391 -386.114526) (xy 61.08827 -386.091684) (xy 61.086746 -386.085842)
			(xy 60.766452 -385.532122) (xy 60.762388 -385.527804) (xy 60.746158 -385.510119) (xy 60.718738 -385.470722)
			(xy 60.6976 -385.427626) (xy 60.683233 -385.381827) (xy 60.675967 -385.33438) (xy 60.67552 -385.31038)
			(xy 60.143642 -385.31038) (xy 60.416186 -385.78155) (xy 60.42025 -385.785868) (xy 60.436405 -385.803572)
			(xy 60.463749 -385.842931) (xy 60.484829 -385.885971) (xy 60.49916 -385.931703) (xy 60.506414 -385.979076)
			(xy 60.506864 -386.003038) (xy 60.506864 -386.003546) (xy 60.506356 -386.023866) (xy 60.505594 -386.033772)
			(xy 60.511944 -386.052822) (xy 60.57265 -386.122164) (xy 60.59043 -386.131054) (xy 60.60059 -386.131816)
			(xy 60.625539 -386.134039) (xy 60.674339 -386.145318) (xy 60.720768 -386.164104) (xy 60.763681 -386.189933)
			(xy 60.802017 -386.222167) (xy 60.818776 -386.240782) (xy 60.821236 -386.243557) (xy 60.82685 -386.248402)
			(xy 60.829952 -386.250434) (xy 60.842025 -386.258479) (xy 60.861981 -386.279527) (xy 60.876053 -386.304889)
			(xy 60.88335 -386.332961) (xy 60.8838 -386.347462) (xy 60.8838 -386.3594) (xy 60.885324 -386.366004)
			(xy 60.890515 -386.386377) (xy 60.896126 -386.428042) (xy 60.8965 -386.449062) (xy 60.896119 -386.470082)
			(xy 60.890518 -386.511748) (xy 60.885324 -386.53212) (xy 60.8838 -386.538724) (xy 60.8838 -386.652262)
			(xy 60.883145 -386.670381) (xy 60.871887 -386.704827) (xy 60.861702 -386.719826) (xy 60.857191 -386.726488)
			(xy 60.852153 -386.74176) (xy 60.851796 -386.749798) (xy 60.851796 -386.783326) (xy 60.852082 -386.791375)
			(xy 60.85714 -386.806659) (xy 60.861702 -386.813298) (xy 60.871793 -386.828345) (xy 60.883046 -386.86276)
			(xy 60.8838 -386.880862) (xy 60.8838 -386.9944) (xy 60.885324 -387.001004) (xy 60.890515 -387.021377)
			(xy 60.896126 -387.063042) (xy 60.8965 -387.084062) (xy 60.896119 -387.105082) (xy 60.890518 -387.146748)
			(xy 60.885324 -387.16712) (xy 60.8838 -387.173724) (xy 60.8838 -387.185662) (xy 60.883274 -387.201046)
			(xy 60.87507 -387.230703) (xy 60.859317 -387.257136) (xy 60.837136 -387.278463) (xy 60.823856 -387.286246)
			(xy 60.820046 -387.290818) (xy 60.812739 -387.300286) (xy 60.807052 -387.323487) (xy 60.809124 -387.335268)
			(xy 60.816236 -387.367018) (xy 60.819537 -387.37852) (xy 60.834761 -387.396939) (xy 60.845446 -387.402324)
			(xy 60.86687 -387.412067) (xy 60.906823 -387.436941) (xy 60.942674 -387.467432) (xy 60.958476 -387.484874)
			(xy 60.960937 -387.487648) (xy 60.96655 -387.492493) (xy 60.969652 -387.494526) (xy 60.981798 -387.502605)
			(xy 61.001888 -387.523744) (xy 61.016034 -387.549246) (xy 61.023332 -387.577481) (xy 61.023754 -387.592062)
			(xy 61.023754 -387.604508) (xy 61.025532 -387.610858) (xy 61.030665 -387.631172) (xy 61.03614 -387.672712)
			(xy 61.036454 -387.693662) (xy 61.036123 -387.714611) (xy 61.030645 -387.756148) (xy 61.025532 -387.776466)
			(xy 61.023754 -387.782816) (xy 61.023754 -388.239508) (xy 61.025532 -388.245858) (xy 61.030665 -388.266172)
			(xy 61.03614 -388.307712) (xy 61.036454 -388.328662) (xy 61.600588 -388.328662) (xy 61.600955 -388.307641)
			(xy 61.606565 -388.265975) (xy 61.611764 -388.245604) (xy 61.613288 -388.239) (xy 61.613288 -388.125462)
			(xy 61.6137 -388.110461) (xy 61.621464 -388.081481) (xy 61.636455 -388.055492) (xy 61.657654 -388.034262)
			(xy 61.68362 -388.019231) (xy 61.712588 -388.011423) (xy 61.727588 -388.010908) (xy 61.909706 -388.010908)
			(xy 61.910214 -388.010654) (xy 61.926978 -388.010654) (xy 61.927486 -388.010908) (xy 62.109096 -388.010908)
			(xy 62.124126 -388.011384) (xy 62.153165 -388.019153) (xy 62.179209 -388.034165) (xy 62.200487 -388.055398)
			(xy 62.215554 -388.08141) (xy 62.223384 -388.110433) (xy 62.223904 -388.125462) (xy 62.223904 -388.239)
			(xy 62.225428 -388.245604) (xy 62.230619 -388.265976) (xy 62.23623 -388.307642) (xy 62.236604 -388.328662)
			(xy 62.800484 -388.328662) (xy 62.800851 -388.307641) (xy 62.806461 -388.265975) (xy 62.81166 -388.245604)
			(xy 62.813184 -388.239) (xy 62.813184 -388.125462) (xy 62.8136 -388.110461) (xy 62.821364 -388.081482)
			(xy 62.836354 -388.055494) (xy 62.857552 -388.034263) (xy 62.883517 -388.019232) (xy 62.912484 -388.011424)
			(xy 62.927484 -388.010908) (xy 63.109602 -388.010908) (xy 63.11011 -388.010654) (xy 63.126874 -388.010654)
			(xy 63.127382 -388.010908) (xy 63.308992 -388.010908) (xy 63.324022 -388.011387) (xy 63.353061 -388.019155)
			(xy 63.379105 -388.034166) (xy 63.400383 -388.055399) (xy 63.41545 -388.081411) (xy 63.42328 -388.110433)
			(xy 63.4238 -388.125462) (xy 63.4238 -388.239) (xy 63.425324 -388.245604) (xy 63.430515 -388.265977)
			(xy 63.436126 -388.307642) (xy 63.4365 -388.328662) (xy 64.000634 -388.328662) (xy 64.000999 -388.307641)
			(xy 64.00661 -388.265975) (xy 64.01181 -388.245604) (xy 64.013588 -388.239) (xy 64.013588 -388.125462)
			(xy 64.013959 -388.110434) (xy 64.021748 -388.081405) (xy 64.036785 -388.055381) (xy 64.058045 -388.034136)
			(xy 64.08408 -388.019118) (xy 64.113114 -388.011349) (xy 64.128142 -388.010908) (xy 64.309752 -388.010908)
			(xy 64.31026 -388.010654) (xy 64.327024 -388.010654) (xy 64.327532 -388.010908) (xy 64.509142 -388.010908)
			(xy 64.524158 -388.011399) (xy 64.553164 -388.019179) (xy 64.57917 -388.034198) (xy 64.600405 -388.055434)
			(xy 64.615423 -388.08144) (xy 64.623202 -388.110446) (xy 64.623696 -388.125462) (xy 64.623696 -388.239)
			(xy 64.625474 -388.245604) (xy 64.630666 -388.265976) (xy 64.636276 -388.307642) (xy 64.63665 -388.328662)
			(xy 65.20053 -388.328662) (xy 65.200896 -388.307641) (xy 65.206506 -388.265975) (xy 65.211706 -388.245604)
			(xy 65.213484 -388.239) (xy 65.213484 -388.125462) (xy 65.213903 -388.11044) (xy 65.221689 -388.081423)
			(xy 65.236719 -388.055409) (xy 65.25797 -388.034173) (xy 65.283994 -388.019159) (xy 65.313016 -388.011393)
			(xy 65.328038 -388.010908) (xy 65.509648 -388.010908) (xy 65.510156 -388.010654) (xy 65.52692 -388.010654)
			(xy 65.527428 -388.010908) (xy 65.709038 -388.010908) (xy 65.724053 -388.011402) (xy 65.753059 -388.019181)
			(xy 65.779065 -388.0342) (xy 65.8003 -388.055435) (xy 65.815319 -388.081441) (xy 65.823098 -388.110447)
			(xy 65.823592 -388.125462) (xy 65.823592 -388.239) (xy 65.82537 -388.245604) (xy 65.830562 -388.265976)
			(xy 65.836172 -388.307642) (xy 65.836546 -388.328662) (xy 65.836546 -388.32917) (xy 65.836376 -388.343795)
			(xy 65.833709 -388.372924) (xy 65.831212 -388.387336) (xy 65.829847 -388.39651) (xy 65.83312 -388.414752)
			(xy 65.837562 -388.422896) (xy 65.854072 -388.44982) (xy 65.859231 -388.457606) (xy 65.873965 -388.469064)
			(xy 65.882774 -388.472172) (xy 65.907649 -388.480254) (xy 65.954529 -388.503438) (xy 65.996942 -388.534038)
			(xy 66.033727 -388.571215) (xy 66.063875 -388.613951) (xy 66.086561 -388.661074) (xy 66.094356 -388.68604)
			(xy 66.09588 -388.691882) (xy 66.416174 -389.245602) (xy 66.420238 -389.24992) (xy 66.4364 -389.267584)
			(xy 66.463719 -389.306902) (xy 66.484786 -389.349895) (xy 66.499119 -389.395576) (xy 66.506389 -389.442898)
			(xy 66.506852 -389.466836) (xy 66.506852 -389.467344) (xy 66.506423 -389.492136) (xy 66.49866 -389.541108)
			(xy 66.483332 -389.588262) (xy 66.460816 -389.632439) (xy 66.431668 -389.672549) (xy 66.396604 -389.707607)
			(xy 66.356488 -389.736748) (xy 66.312307 -389.759255) (xy 66.265149 -389.774574) (xy 66.216176 -389.782327)
			(xy 66.191384 -389.782812) (xy 66.165989 -389.782326) (xy 66.115855 -389.774193) (xy 66.067669 -389.758139)
			(xy 66.022675 -389.734578) (xy 65.982032 -389.704119) (xy 65.94679 -389.667546) (xy 65.917856 -389.625803)
			(xy 65.895978 -389.579967) (xy 65.888362 -389.555736) (xy 65.886838 -389.549894) (xy 65.566544 -388.996174)
			(xy 65.56248 -388.991856) (xy 65.546273 -388.97415) (xy 65.51885 -388.934759) (xy 65.497708 -388.891668)
			(xy 65.483335 -388.845874) (xy 65.476062 -388.798431) (xy 65.475612 -388.774432) (xy 65.475791 -388.760384)
			(xy 65.478334 -388.732402) (xy 65.480692 -388.718552) (xy 65.481983 -388.709296) (xy 65.478585 -388.690932)
			(xy 65.474088 -388.682738) (xy 65.457324 -388.655814) (xy 65.452119 -388.648113) (xy 65.437396 -388.636788)
			(xy 65.428622 -388.633716) (xy 65.406992 -388.626927) (xy 65.365778 -388.608041) (xy 65.327659 -388.583503)
			(xy 65.293405 -388.553807) (xy 65.278254 -388.536942) (xy 65.275788 -388.534173) (xy 65.270178 -388.529324)
			(xy 65.267078 -388.52729) (xy 65.25505 -388.519209) (xy 65.23516 -388.498149) (xy 65.221152 -388.472794)
			(xy 65.213911 -388.444746) (xy 65.213484 -388.430262) (xy 65.213484 -388.418324) (xy 65.211706 -388.41172)
			(xy 65.206501 -388.391351) (xy 65.200899 -388.349683) (xy 65.20053 -388.328662) (xy 64.63665 -388.328662)
			(xy 64.63665 -388.32917) (xy 64.63648 -388.343795) (xy 64.633813 -388.372924) (xy 64.631316 -388.387336)
			(xy 64.629951 -388.39651) (xy 64.633224 -388.414752) (xy 64.637666 -388.422896) (xy 64.654176 -388.44982)
			(xy 64.659334 -388.457607) (xy 64.674068 -388.469065) (xy 64.682878 -388.472172) (xy 64.707812 -388.480277)
			(xy 64.754777 -388.503578) (xy 64.797255 -388.534307) (xy 64.834082 -388.571621) (xy 64.86425 -388.614498)
			(xy 64.886932 -388.661765) (xy 64.894714 -388.686802) (xy 64.896238 -388.692644) (xy 65.216024 -389.245602)
			(xy 65.220088 -389.24992) (xy 65.236278 -389.26764) (xy 65.263704 -389.307028) (xy 65.28485 -389.350114)
			(xy 65.299227 -389.395906) (xy 65.306504 -389.443346) (xy 65.306956 -389.467344) (xy 65.306453 -389.492806)
			(xy 65.298255 -389.543065) (xy 65.282096 -389.591356) (xy 65.258394 -389.636428) (xy 65.227764 -389.677109)
			(xy 65.191 -389.712347) (xy 65.170304 -389.727186) (xy 65.161795 -389.733655) (xy 65.1506 -389.751837)
			(xy 65.147762 -389.772999) (xy 65.15377 -389.793488) (xy 65.167587 -389.809766) (xy 65.186827 -389.819024)
			(xy 65.197482 -389.819896) (xy 65.207134 -389.819388) (xy 65.215647 -389.818092) (xy 65.232813 -389.816695)
			(xy 65.241424 -389.816594) (xy 65.241678 -389.816848) (xy 65.54089 -389.816848) (xy 65.541144 -389.816594)
			(xy 65.562205 -389.817013) (xy 65.603564 -389.824965) (xy 65.642562 -389.840867) (xy 65.677688 -389.864102)
			(xy 65.70758 -389.893771) (xy 65.731078 -389.928721) (xy 65.747272 -389.967599) (xy 65.755534 -390.008896)
			(xy 65.756028 -390.029954) (xy 65.756028 -390.233916) (xy 66.380868 -390.233916) (xy 66.380868 -390.029954)
			(xy 66.381367 -390.009506) (xy 66.389177 -389.969363) (xy 66.404483 -389.93144) (xy 66.426726 -389.897122)
			(xy 66.455092 -389.867664) (xy 66.488546 -389.844142) (xy 66.525865 -389.827415) (xy 66.565685 -389.818096)
			(xy 66.5861 -389.816848) (xy 66.586608 -389.816848) (xy 66.596006 -389.816594) (xy 66.59626 -389.816848)
			(xy 66.894456 -389.816848) (xy 66.89471 -389.816594) (xy 66.904108 -389.816848) (xy 66.904616 -389.816848)
			(xy 66.925035 -389.818124) (xy 66.964873 -389.827404) (xy 67.002213 -389.844107) (xy 67.035685 -389.867619)
			(xy 67.064064 -389.897079) (xy 67.086308 -389.931406) (xy 67.101603 -389.969344) (xy 67.109388 -390.009501)
			(xy 67.109848 -390.029954) (xy 67.109848 -390.284716) (xy 67.097148 -390.284716) (xy 67.088055 -390.285721)
			(xy 67.071421 -390.293303) (xy 67.058496 -390.306231) (xy 67.050917 -390.322868) (xy 67.049904 -390.33196)
			(xy 67.049904 -390.499092) (xy 67.049474 -390.509112) (xy 67.041808 -390.527628) (xy 67.027638 -390.541801)
			(xy 67.009124 -390.549472) (xy 66.999104 -390.549892) (xy 66.491612 -390.549892) (xy 66.48159 -390.549471)
			(xy 66.463072 -390.541803) (xy 66.448899 -390.527631) (xy 66.44123 -390.509114) (xy 66.440812 -390.499092)
			(xy 66.440812 -390.284716) (xy 66.431668 -390.284716) (xy 66.42166 -390.284239) (xy 66.403171 -390.276571)
			(xy 66.38902 -390.262416) (xy 66.381358 -390.243924) (xy 66.380868 -390.233916) (xy 65.756028 -390.233916)
			(xy 65.756028 -390.284716) (xy 65.746884 -390.284716) (xy 65.736873 -390.285175) (xy 65.718378 -390.292843)
			(xy 65.704225 -390.307005) (xy 65.696569 -390.325505) (xy 65.696084 -390.335516) (xy 65.696084 -390.499092)
			(xy 65.695674 -390.509115) (xy 65.688003 -390.527635) (xy 65.673828 -390.541808) (xy 65.655307 -390.549475)
			(xy 65.645284 -390.549892) (xy 65.137284 -390.549892) (xy 65.127274 -390.549425) (xy 65.108781 -390.541759)
			(xy 65.094628 -390.527599) (xy 65.08697 -390.509102) (xy 65.086484 -390.499092) (xy 65.086484 -390.284716)
			(xy 65.07734 -390.284716) (xy 65.067323 -390.284248) (xy 65.04881 -390.276594) (xy 65.034637 -390.262437)
			(xy 65.026963 -390.243932) (xy 65.02654 -390.233916) (xy 65.02654 -390.029954) (xy 65.026882 -390.012721)
			(xy 65.032454 -389.978708) (xy 65.043427 -389.946035) (xy 65.051178 -389.93064) (xy 65.05702 -389.91921)
			(xy 65.056766 -389.89381) (xy 65.003172 -389.796782) (xy 64.981582 -389.783066) (xy 64.968628 -389.78205)
			(xy 64.944732 -389.779929) (xy 64.897945 -389.769328) (xy 64.853304 -389.751762) (xy 64.81184 -389.727635)
			(xy 64.774509 -389.697504) (xy 64.742175 -389.662065) (xy 64.715584 -389.622137) (xy 64.695348 -389.578641)
			(xy 64.688212 -389.555736) (xy 64.686688 -389.549894) (xy 64.36614 -388.995412) (xy 64.362076 -388.991094)
			(xy 64.345977 -388.973421) (xy 64.318727 -388.934143) (xy 64.297715 -388.891204) (xy 64.283422 -388.845586)
			(xy 64.276175 -388.798334) (xy 64.275716 -388.774432) (xy 64.275895 -388.760384) (xy 64.278438 -388.732402)
			(xy 64.280796 -388.718552) (xy 64.282086 -388.709296) (xy 64.278688 -388.690932) (xy 64.274192 -388.682738)
			(xy 64.257428 -388.655814) (xy 64.252222 -388.648114) (xy 64.237499 -388.636789) (xy 64.228726 -388.633716)
			(xy 64.207097 -388.626925) (xy 64.165883 -388.60804) (xy 64.127764 -388.583502) (xy 64.093509 -388.553807)
			(xy 64.078358 -388.536942) (xy 64.075891 -388.534173) (xy 64.070282 -388.529325) (xy 64.067182 -388.52729)
			(xy 64.055155 -388.519208) (xy 64.035264 -388.498149) (xy 64.021256 -388.472794) (xy 64.014015 -388.444746)
			(xy 64.013588 -388.430262) (xy 64.013588 -388.418324) (xy 64.01181 -388.41172) (xy 64.006605 -388.391351)
			(xy 64.001003 -388.349683) (xy 64.000634 -388.328662) (xy 63.4365 -388.328662) (xy 63.4365 -388.32917)
			(xy 63.43633 -388.343795) (xy 63.433663 -388.372924) (xy 63.431166 -388.387336) (xy 63.429807 -388.39651)
			(xy 63.433078 -388.414752) (xy 63.437516 -388.422896) (xy 63.454026 -388.44982) (xy 63.459202 -388.457593)
			(xy 63.473924 -388.469058) (xy 63.482728 -388.472172) (xy 63.507614 -388.480223) (xy 63.554493 -388.503416)
			(xy 63.596904 -388.534022) (xy 63.633687 -388.571205) (xy 63.663833 -388.613945) (xy 63.686517 -388.661072)
			(xy 63.69431 -388.68604) (xy 63.695834 -388.691882) (xy 64.016128 -389.245602) (xy 64.020192 -389.24992)
			(xy 64.036382 -389.26764) (xy 64.063809 -389.307027) (xy 64.084954 -389.350114) (xy 64.099331 -389.395906)
			(xy 64.106608 -389.443346) (xy 64.10706 -389.467344) (xy 64.106555 -389.492805) (xy 64.098358 -389.543065)
			(xy 64.082198 -389.591356) (xy 64.058497 -389.636427) (xy 64.027867 -389.677109) (xy 63.991104 -389.712346)
			(xy 63.970408 -389.727186) (xy 63.961897 -389.733653) (xy 63.950701 -389.751836) (xy 63.947862 -389.772999)
			(xy 63.95387 -389.793489) (xy 63.967689 -389.809768) (xy 63.986931 -389.819024) (xy 63.997586 -389.819896)
			(xy 64.007238 -389.819388) (xy 64.015751 -389.818092) (xy 64.032917 -389.816694) (xy 64.041528 -389.816594)
			(xy 64.041782 -389.816848) (xy 64.340994 -389.816848) (xy 64.341248 -389.816594) (xy 64.36231 -389.81701)
			(xy 64.403668 -389.824962) (xy 64.442666 -389.840864) (xy 64.477792 -389.864101) (xy 64.507684 -389.893769)
			(xy 64.531182 -389.92872) (xy 64.547377 -389.967598) (xy 64.555638 -390.008896) (xy 64.556132 -390.029954)
			(xy 64.556132 -390.284716) (xy 64.546988 -390.284716) (xy 64.536964 -390.28511) (xy 64.518444 -390.292787)
			(xy 64.504271 -390.306967) (xy 64.496605 -390.325492) (xy 64.496188 -390.335516) (xy 64.496188 -390.499092)
			(xy 64.495774 -390.509114) (xy 64.488104 -390.527633) (xy 64.47393 -390.541806) (xy 64.45541 -390.549475)
			(xy 64.445388 -390.549892) (xy 63.937388 -390.549892) (xy 63.927379 -390.549421) (xy 63.908885 -390.541756)
			(xy 63.894732 -390.527598) (xy 63.887075 -390.509102) (xy 63.886588 -390.499092) (xy 63.886588 -390.284716)
			(xy 63.877444 -390.284716) (xy 63.867428 -390.284245) (xy 63.848915 -390.276592) (xy 63.834741 -390.262436)
			(xy 63.827067 -390.243932) (xy 63.826644 -390.233916) (xy 63.826644 -390.029954) (xy 63.826986 -390.012721)
			(xy 63.832557 -389.978708) (xy 63.843531 -389.946035) (xy 63.851282 -389.93064) (xy 63.857124 -389.91921)
			(xy 63.85687 -389.89381) (xy 63.803276 -389.796782) (xy 63.781686 -389.783066) (xy 63.768732 -389.78205)
			(xy 63.744836 -389.779926) (xy 63.698049 -389.769326) (xy 63.653408 -389.75176) (xy 63.611944 -389.727633)
			(xy 63.574614 -389.697503) (xy 63.54228 -389.662065) (xy 63.515688 -389.622137) (xy 63.495452 -389.57864)
			(xy 63.488316 -389.555736) (xy 63.486792 -389.549894) (xy 63.166498 -388.996174) (xy 63.162434 -388.991856)
			(xy 63.146271 -388.974125) (xy 63.118904 -388.934722) (xy 63.097815 -388.891631) (xy 63.083488 -388.845846)
			(xy 63.076254 -388.79842) (xy 63.07582 -388.774432) (xy 63.076002 -388.760384) (xy 63.078542 -388.732402)
			(xy 63.0809 -388.718552) (xy 63.082222 -388.709272) (xy 63.078695 -388.690875) (xy 63.074042 -388.682738)
			(xy 63.057278 -388.655814) (xy 63.05209 -388.6481) (xy 63.037355 -388.636782) (xy 63.028576 -388.633716)
			(xy 63.006953 -388.626906) (xy 62.965738 -388.608027) (xy 62.927617 -388.583495) (xy 62.89336 -388.553804)
			(xy 62.878208 -388.536942) (xy 62.875748 -388.534167) (xy 62.870134 -388.529322) (xy 62.867032 -388.52729)
			(xy 62.854966 -388.519235) (xy 62.835011 -388.49819) (xy 62.820938 -388.472831) (xy 62.813637 -388.444762)
			(xy 62.813184 -388.430262) (xy 62.813184 -388.418324) (xy 62.81166 -388.41172) (xy 62.806454 -388.391351)
			(xy 62.800853 -388.349683) (xy 62.800484 -388.328662) (xy 62.236604 -388.328662) (xy 62.236604 -388.32917)
			(xy 62.236433 -388.343795) (xy 62.233767 -388.372924) (xy 62.23127 -388.387336) (xy 62.229911 -388.39651)
			(xy 62.233181 -388.414752) (xy 62.23762 -388.422896) (xy 62.25413 -388.44982) (xy 62.259305 -388.457594)
			(xy 62.274027 -388.469058) (xy 62.282832 -388.472172) (xy 62.307757 -388.480303) (xy 62.354723 -388.503597)
			(xy 62.397202 -388.53432) (xy 62.434031 -388.571629) (xy 62.464201 -388.614503) (xy 62.486885 -388.661766)
			(xy 62.494668 -388.686802) (xy 62.496192 -388.692644) (xy 62.815978 -389.245602) (xy 62.820042 -389.24992)
			(xy 62.836205 -389.267583) (xy 62.863523 -389.306902) (xy 62.88459 -389.349895) (xy 62.898923 -389.395576)
			(xy 62.906193 -389.442898) (xy 62.906656 -389.466836) (xy 62.906656 -389.467344) (xy 62.906153 -389.492792)
			(xy 62.897983 -389.543029) (xy 62.881859 -389.591305) (xy 62.858202 -389.636369) (xy 62.827622 -389.677055)
			(xy 62.790912 -389.71231) (xy 62.770258 -389.727186) (xy 62.761659 -389.73357) (xy 62.750428 -389.75179)
			(xy 62.747578 -389.773002) (xy 62.753602 -389.79354) (xy 62.767459 -389.809851) (xy 62.786753 -389.819117)
			(xy 62.797436 -389.819896) (xy 62.807088 -389.819388) (xy 62.815602 -389.818098) (xy 62.832767 -389.816696)
			(xy 62.841378 -389.816594) (xy 62.841632 -389.816848) (xy 63.140844 -389.816848) (xy 63.141098 -389.816594)
			(xy 63.162143 -389.817035) (xy 63.203462 -389.825024) (xy 63.242417 -389.840948) (xy 63.277499 -389.864193)
			(xy 63.307351 -389.893856) (xy 63.330816 -389.928791) (xy 63.346986 -389.967645) (xy 63.355236 -390.008912)
			(xy 63.355728 -390.029954) (xy 63.355728 -390.284716) (xy 63.346584 -390.284716) (xy 63.336573 -390.285175)
			(xy 63.318078 -390.292843) (xy 63.303925 -390.307005) (xy 63.296269 -390.325505) (xy 63.295784 -390.335516)
			(xy 63.295784 -390.499092) (xy 63.295374 -390.509115) (xy 63.287703 -390.527635) (xy 63.273528 -390.541808)
			(xy 63.255007 -390.549475) (xy 63.244984 -390.549892) (xy 62.737492 -390.549892) (xy 62.727483 -390.549418)
			(xy 62.708989 -390.541754) (xy 62.694837 -390.527597) (xy 62.687179 -390.509101) (xy 62.686692 -390.499092)
			(xy 62.686692 -390.335516) (xy 62.686267 -390.325495) (xy 62.678601 -390.306977) (xy 62.66443 -390.292803)
			(xy 62.645913 -390.285134) (xy 62.635892 -390.284716) (xy 62.626748 -390.284716) (xy 62.626748 -390.029446)
			(xy 62.627529 -390.003723) (xy 62.639864 -389.953777) (xy 62.651132 -389.93064) (xy 62.656974 -389.91921)
			(xy 62.65672 -389.89381) (xy 62.603126 -389.796782) (xy 62.581536 -389.783066) (xy 62.568582 -389.78205)
			(xy 62.544682 -389.779966) (xy 62.497894 -389.769359) (xy 62.453252 -389.751786) (xy 62.411789 -389.727653)
			(xy 62.374459 -389.697517) (xy 62.342126 -389.662074) (xy 62.315536 -389.622142) (xy 62.295302 -389.578642)
			(xy 62.288166 -389.555736) (xy 62.286642 -389.549894) (xy 61.966094 -388.995412) (xy 61.96203 -388.991094)
			(xy 61.945927 -388.973437) (xy 61.91874 -388.934136) (xy 61.897789 -388.891186) (xy 61.883554 -388.845569)
			(xy 61.876359 -388.798326) (xy 61.875924 -388.774432) (xy 61.876106 -388.760384) (xy 61.878646 -388.732402)
			(xy 61.881004 -388.718552) (xy 61.882326 -388.709272) (xy 61.878799 -388.690875) (xy 61.874146 -388.682738)
			(xy 61.857382 -388.655814) (xy 61.852192 -388.648101) (xy 61.837458 -388.636782) (xy 61.82868 -388.633716)
			(xy 61.807058 -388.626904) (xy 61.765843 -388.608026) (xy 61.727722 -388.583494) (xy 61.693465 -388.553804)
			(xy 61.678312 -388.536942) (xy 61.675851 -388.534168) (xy 61.670238 -388.529322) (xy 61.667136 -388.52729)
			(xy 61.655071 -388.519234) (xy 61.635115 -388.498189) (xy 61.621042 -388.47283) (xy 61.613741 -388.444762)
			(xy 61.613288 -388.430262) (xy 61.613288 -388.418324) (xy 61.611764 -388.41172) (xy 61.606558 -388.391351)
			(xy 61.600957 -388.349683) (xy 61.600588 -388.328662) (xy 61.036454 -388.328662) (xy 61.036314 -388.343415)
			(xy 61.033638 -388.372799) (xy 61.03112 -388.387336) (xy 61.029754 -388.39651) (xy 61.033028 -388.414752)
			(xy 61.03747 -388.422896) (xy 61.05398 -388.44982) (xy 61.059136 -388.457608) (xy 61.073872 -388.469065)
			(xy 61.082682 -388.472172) (xy 61.107559 -388.480249) (xy 61.154438 -388.503435) (xy 61.196851 -388.534036)
			(xy 61.233636 -388.571214) (xy 61.263784 -388.61395) (xy 61.28647 -388.661073) (xy 61.294264 -388.68604)
			(xy 61.295788 -388.691882) (xy 61.616082 -389.245602) (xy 61.620146 -389.24992) (xy 61.636309 -389.267583)
			(xy 61.663627 -389.306901) (xy 61.684694 -389.349894) (xy 61.699027 -389.395576) (xy 61.706297 -389.442898)
			(xy 61.70676 -389.466836) (xy 61.70676 -389.467344) (xy 61.706256 -389.492792) (xy 61.698085 -389.543029)
			(xy 61.681962 -389.591304) (xy 61.658305 -389.636369) (xy 61.627725 -389.677055) (xy 61.591016 -389.71231)
			(xy 61.570362 -389.727186) (xy 61.561761 -389.733569) (xy 61.550528 -389.751788) (xy 61.547678 -389.773002)
			(xy 61.553702 -389.79354) (xy 61.567561 -389.809853) (xy 61.586856 -389.819117) (xy 61.59754 -389.819896)
			(xy 61.607192 -389.819388) (xy 61.615706 -389.818097) (xy 61.632871 -389.816696) (xy 61.641482 -389.816594)
			(xy 61.641736 -389.816848) (xy 61.940948 -389.816848) (xy 61.941202 -389.816594) (xy 61.962247 -389.817032)
			(xy 62.003566 -389.825021) (xy 62.042521 -389.840946) (xy 62.077603 -389.864191) (xy 62.107455 -389.893855)
			(xy 62.13092 -389.92879) (xy 62.14709 -389.967644) (xy 62.15534 -390.008912) (xy 62.155832 -390.029954)
			(xy 62.155832 -390.284716) (xy 62.146688 -390.284716) (xy 62.136664 -390.28511) (xy 62.118144 -390.292787)
			(xy 62.103971 -390.306967) (xy 62.096305 -390.325492) (xy 62.095888 -390.335516) (xy 62.095888 -390.499092)
			(xy 62.095474 -390.509114) (xy 62.087804 -390.527633) (xy 62.07363 -390.541806) (xy 62.05511 -390.549475)
			(xy 62.045088 -390.549892) (xy 61.537596 -390.549892) (xy 61.527573 -390.549484) (xy 61.509055 -390.541811)
			(xy 61.494883 -390.527635) (xy 61.487214 -390.509115) (xy 61.486796 -390.499092) (xy 61.486796 -390.284716)
			(xy 61.477652 -390.284716) (xy 61.467643 -390.284252) (xy 61.449154 -390.276579) (xy 61.435003 -390.26242)
			(xy 61.427342 -390.243925) (xy 61.426852 -390.233916) (xy 61.426852 -390.029446) (xy 61.427633 -390.003723)
			(xy 61.439968 -389.953777) (xy 61.451236 -389.93064) (xy 61.457078 -389.91921) (xy 61.456824 -389.89381)
			(xy 61.40323 -389.796782) (xy 61.38164 -389.783066) (xy 61.368686 -389.78205) (xy 61.344786 -389.779963)
			(xy 61.297998 -389.769356) (xy 61.253357 -389.751784) (xy 61.211893 -389.727652) (xy 61.174564 -389.697516)
			(xy 61.14223 -389.662074) (xy 61.11564 -389.622142) (xy 61.095406 -389.578642) (xy 61.08827 -389.555736)
			(xy 61.086746 -389.549894) (xy 60.766452 -388.996174) (xy 60.762388 -388.991856) (xy 60.746183 -388.974149)
			(xy 60.718759 -388.934758) (xy 60.697617 -388.891668) (xy 60.683243 -388.845874) (xy 60.67597 -388.798431)
			(xy 60.67552 -388.774432) (xy 60.675699 -388.760384) (xy 60.678242 -388.732402) (xy 60.6806 -388.718552)
			(xy 60.68189 -388.709296) (xy 60.678492 -388.690932) (xy 60.673996 -388.682738) (xy 60.657232 -388.655814)
			(xy 60.652025 -388.648114) (xy 60.637303 -388.636789) (xy 60.62853 -388.633716) (xy 60.606949 -388.62698)
			(xy 60.565825 -388.6082) (xy 60.527773 -388.583789) (xy 60.493558 -388.554238) (xy 60.478416 -388.53745)
			(xy 60.475954 -388.534677) (xy 60.470341 -388.529831) (xy 60.46724 -388.527798) (xy 60.455103 -388.519706)
			(xy 60.435014 -388.498571) (xy 60.420865 -388.473073) (xy 60.413563 -388.444842) (xy 60.413138 -388.430262)
			(xy 60.413138 -388.417816) (xy 60.41136 -388.411466) (xy 60.406231 -388.391151) (xy 60.400754 -388.349612)
			(xy 60.400438 -388.328662) (xy 60.400774 -388.307714) (xy 60.406248 -388.266176) (xy 60.41136 -388.245858)
			(xy 60.413138 -388.239508) (xy 60.413138 -387.782816) (xy 60.41136 -387.776466) (xy 60.406231 -387.756151)
			(xy 60.400754 -387.714612) (xy 60.400438 -387.693662) (xy 60.400774 -387.672714) (xy 60.406248 -387.631176)
			(xy 60.41136 -387.610858) (xy 60.413138 -387.604508) (xy 60.413138 -387.592062) (xy 60.413626 -387.576599)
			(xy 60.421853 -387.546785) (xy 60.437682 -387.520214) (xy 60.459983 -387.498785) (xy 60.473336 -387.49097)
			(xy 60.476892 -387.486906) (xy 60.484246 -387.477384) (xy 60.489943 -387.454044) (xy 60.487814 -387.442202)
			(xy 60.480702 -387.410706) (xy 60.477419 -387.399198) (xy 60.46218 -387.380784) (xy 60.451492 -387.3754)
			(xy 60.430008 -387.365581) (xy 60.389943 -387.340562) (xy 60.354024 -387.309887) (xy 60.338208 -387.292342)
			(xy 60.335748 -387.289567) (xy 60.330134 -387.284722) (xy 60.327032 -387.28269) (xy 60.314966 -387.274635)
			(xy 60.295011 -387.25359) (xy 60.280938 -387.228231) (xy 60.273637 -387.200162) (xy 60.273184 -387.185662)
			(xy 60.273184 -387.173724) (xy 60.27166 -387.16712) (xy 60.266454 -387.146751) (xy 60.260853 -387.105083)
			(xy 60.260484 -387.084062) (xy 60.260851 -387.063041) (xy 60.266461 -387.021375) (xy 60.27166 -387.001004)
			(xy 60.273184 -386.9944) (xy 60.273184 -386.880862) (xy 60.273852 -386.862744) (xy 60.285101 -386.828299)
			(xy 60.295282 -386.813298) (xy 60.299782 -386.806629) (xy 60.304826 -386.791363) (xy 60.305188 -386.783326)
			(xy 60.305188 -386.749798) (xy 60.304876 -386.741751) (xy 60.299834 -386.726468) (xy 60.295282 -386.719826)
			(xy 60.285199 -386.704775) (xy 60.273941 -386.670363) (xy 60.273184 -386.652262) (xy 60.273184 -386.538724)
			(xy 60.27166 -386.53212) (xy 60.266454 -386.511751) (xy 60.260853 -386.470083) (xy 60.260484 -386.449062)
			(xy 60.261246 -386.426456) (xy 60.262008 -386.416296) (xy 60.255912 -386.3975) (xy 60.202318 -386.335524)
			(xy 60.195384 -386.328269) (xy 60.177477 -386.319252) (xy 60.16752 -386.317998) (xy 60.14371 -386.315789)
			(xy 60.097118 -386.305031) (xy 60.052682 -386.287366) (xy 60.011421 -386.263198) (xy 59.974279 -386.233081)
			(xy 59.942107 -386.197704) (xy 59.915641 -386.157878) (xy 59.895487 -386.114515) (xy 59.888374 -386.091684)
			(xy 59.88685 -386.085842) (xy 59.566556 -385.532122) (xy 59.562492 -385.527804) (xy 59.546263 -385.510118)
			(xy 59.518842 -385.470721) (xy 59.497704 -385.427626) (xy 59.483337 -385.381827) (xy 59.476071 -385.33438)
			(xy 59.475624 -385.31038) (xy 58.943492 -385.31038) (xy 59.216036 -385.78155) (xy 59.2201 -385.785868)
			(xy 59.236299 -385.803547) (xy 59.263699 -385.842894) (xy 59.284831 -385.885934) (xy 59.299209 -385.931675)
			(xy 59.306502 -385.979065) (xy 59.306968 -386.003038) (xy 59.306968 -386.003546) (xy 59.306206 -386.023866)
			(xy 59.305444 -386.033772) (xy 59.311794 -386.052822) (xy 59.3725 -386.122164) (xy 59.39028 -386.131054)
			(xy 59.40044 -386.131816) (xy 59.425415 -386.134031) (xy 59.474272 -386.145279) (xy 59.520759 -386.164054)
			(xy 59.563724 -386.189891) (xy 59.602104 -386.22215) (xy 59.61888 -386.240782) (xy 59.621339 -386.243557)
			(xy 59.626954 -386.248402) (xy 59.630056 -386.250434) (xy 59.64213 -386.258478) (xy 59.662086 -386.279526)
			(xy 59.676157 -386.304889) (xy 59.683454 -386.332961) (xy 59.683904 -386.347462) (xy 59.683904 -386.3594)
			(xy 59.685428 -386.366004) (xy 59.690619 -386.386376) (xy 59.69623 -386.428042) (xy 59.696604 -386.449062)
			(xy 59.696223 -386.470082) (xy 59.690622 -386.511748) (xy 59.685428 -386.53212) (xy 59.683904 -386.538724)
			(xy 59.683904 -386.597398) (xy 59.713622 -386.627116) (xy 59.726068 -386.627116) (xy 59.736136 -386.627554)
			(xy 59.754734 -386.635265) (xy 59.762136 -386.642102) (xy 59.791854 -386.67182) (xy 59.80684 -386.67182)
			(xy 59.9948 -386.85978) (xy 59.9948 -386.874766) (xy 59.997594 -386.87756) (xy 60.005468 -386.896102)
			(xy 60.005468 -388.330948) (xy 60.005903 -388.341017) (xy 60.013615 -388.359615) (xy 60.020454 -388.367016)
			(xy 60.087002 -388.433564) (xy 60.093819 -388.440982) (xy 60.101552 -388.459568) (xy 60.101988 -388.469632)
			(xy 60.101988 -388.688326) (xy 60.102241 -388.694985) (xy 60.105707 -388.707848) (xy 60.108846 -388.713726)
			(xy 60.416186 -389.245602) (xy 60.42025 -389.24992) (xy 60.436414 -389.267582) (xy 60.463732 -389.306901)
			(xy 60.484799 -389.349894) (xy 60.499131 -389.395576) (xy 60.506401 -389.442898) (xy 60.506864 -389.466836)
			(xy 60.506864 -389.467344) (xy 60.50633 -389.492059) (xy 60.498622 -389.540885) (xy 60.483401 -389.587914)
			(xy 60.461039 -389.631997) (xy 60.432082 -389.672058) (xy 60.397236 -389.707118) (xy 60.377578 -389.722106)
			(xy 60.368388 -389.729747) (xy 60.357655 -389.751067) (xy 60.357004 -389.763) (xy 60.357004 -389.767826)
			(xy 60.357467 -389.777836) (xy 60.365136 -389.796329) (xy 60.379296 -389.810481) (xy 60.397794 -389.818139)
			(xy 60.407804 -389.818626) (xy 60.410852 -389.818626) (xy 60.4139 -389.818372) (xy 60.441332 -389.816594)
			(xy 60.441586 -389.816848) (xy 60.740798 -389.816848) (xy 60.741052 -389.816594) (xy 60.762114 -389.817006)
			(xy 60.803472 -389.824959) (xy 60.84247 -389.840862) (xy 60.877596 -389.864099) (xy 60.907488 -389.893768)
			(xy 60.930987 -389.92872) (xy 60.947181 -389.967598) (xy 60.955442 -390.008896) (xy 60.955936 -390.029954)
			(xy 60.955936 -390.284716) (xy 60.946792 -390.284716) (xy 60.936768 -390.285113) (xy 60.918248 -390.292789)
			(xy 60.904076 -390.306968) (xy 60.896409 -390.325492) (xy 60.895992 -390.335516) (xy 60.895992 -390.499092)
			(xy 60.895574 -390.509114) (xy 60.887905 -390.527632) (xy 60.873732 -390.541805) (xy 60.855214 -390.549474)
			(xy 60.845192 -390.549892) (xy 60.391548 -390.549892) (xy 60.381531 -390.550359) (xy 60.363016 -390.558011)
			(xy 60.348843 -390.572169) (xy 60.34117 -390.590675) (xy 60.340748 -390.600692) (xy 60.340748 -393.292838)
			(xy 60.63488 -393.292838) (xy 60.63488 -392.429238) (xy 60.635293 -392.403717) (xy 60.642084 -392.35313)
			(xy 60.655562 -392.303901) (xy 60.675488 -392.25691) (xy 60.701504 -392.212997) (xy 60.733145 -392.172947)
			(xy 60.751212 -392.154918) (xy 60.757816 -392.148568) (xy 60.76569 -392.131804) (xy 60.772548 -392.04646)
			(xy 60.767468 -392.02868) (xy 60.76188 -392.021314) (xy 60.747023 -392.00057) (xy 60.723391 -391.955354)
			(xy 60.707291 -391.906942) (xy 60.699139 -391.856578) (xy 60.698634 -391.831068) (xy 60.698634 -391.830814)
			(xy 60.699124 -391.805825) (xy 60.706943 -391.756462) (xy 60.722387 -391.70893) (xy 60.745077 -391.664398)
			(xy 60.774453 -391.623965) (xy 60.809793 -391.588625) (xy 60.850226 -391.559249) (xy 60.894758 -391.536559)
			(xy 60.94229 -391.521115) (xy 60.991653 -391.513296) (xy 61.041631 -391.513296) (xy 61.090994 -391.521115)
			(xy 61.138526 -391.536559) (xy 61.183058 -391.559249) (xy 61.223491 -391.588625) (xy 61.258831 -391.623965)
			(xy 61.288207 -391.664398) (xy 61.310897 -391.70893) (xy 61.326341 -391.756462) (xy 61.33416 -391.805825)
			(xy 61.33465 -391.830814) (xy 61.33465 -391.831068) (xy 61.334147 -391.856577) (xy 61.325971 -391.906935)
			(xy 61.309872 -391.955346) (xy 61.28626 -392.000571) (xy 61.271404 -392.021314) (xy 61.265816 -392.02868)
			(xy 61.260736 -392.04646) (xy 61.267594 -392.131804) (xy 61.275468 -392.148568) (xy 61.282072 -392.154918)
			(xy 61.300109 -392.172974) (xy 61.331739 -392.213026) (xy 61.357749 -392.256936) (xy 61.377676 -392.30392)
			(xy 61.391165 -392.353141) (xy 61.397974 -392.40372) (xy 61.398404 -392.429238) (xy 61.398404 -393.292838)
			(xy 61.834776 -393.292838) (xy 61.834776 -392.429238) (xy 61.83519 -392.403717) (xy 61.841981 -392.35313)
			(xy 61.855459 -392.303901) (xy 61.875384 -392.25691) (xy 61.9014 -392.212997) (xy 61.933041 -392.172947)
			(xy 61.951108 -392.154918) (xy 61.957712 -392.148568) (xy 61.965586 -392.131804) (xy 61.972444 -392.04646)
			(xy 61.967364 -392.02868) (xy 61.961776 -392.021314) (xy 61.946931 -392.000562) (xy 61.923293 -391.95535)
			(xy 61.90719 -391.90694) (xy 61.899036 -391.856577) (xy 61.89853 -391.831068) (xy 61.89853 -391.830814)
			(xy 61.89902 -391.805825) (xy 61.906839 -391.756462) (xy 61.922283 -391.70893) (xy 61.944973 -391.664398)
			(xy 61.974349 -391.623965) (xy 62.009689 -391.588625) (xy 62.050122 -391.559249) (xy 62.094654 -391.536559)
			(xy 62.142186 -391.521115) (xy 62.191549 -391.513296) (xy 62.241527 -391.513296) (xy 62.29089 -391.521115)
			(xy 62.338422 -391.536559) (xy 62.382954 -391.559249) (xy 62.423387 -391.588625) (xy 62.458727 -391.623965)
			(xy 62.488103 -391.664398) (xy 62.510793 -391.70893) (xy 62.526237 -391.756462) (xy 62.534056 -391.805825)
			(xy 62.534546 -391.830814) (xy 62.534546 -391.831068) (xy 62.534044 -391.856577) (xy 62.525868 -391.906935)
			(xy 62.509768 -391.955346) (xy 62.486156 -392.000572) (xy 62.4713 -392.021314) (xy 62.465712 -392.02868)
			(xy 62.460632 -392.04646) (xy 62.46749 -392.131804) (xy 62.475364 -392.148568) (xy 62.481968 -392.154918)
			(xy 62.500005 -392.172974) (xy 62.531635 -392.213026) (xy 62.557645 -392.256936) (xy 62.577572 -392.30392)
			(xy 62.591061 -392.353141) (xy 62.59787 -392.40372) (xy 62.5983 -392.429238) (xy 62.5983 -393.292838)
			(xy 63.034672 -393.292838) (xy 63.034672 -392.429238) (xy 63.035088 -392.403717) (xy 63.041878 -392.35313)
			(xy 63.055356 -392.303901) (xy 63.075281 -392.25691) (xy 63.101297 -392.212997) (xy 63.132937 -392.172947)
			(xy 63.151004 -392.154918) (xy 63.157608 -392.148568) (xy 63.165482 -392.131804) (xy 63.17234 -392.04646)
			(xy 63.16726 -392.02868) (xy 63.161672 -392.021314) (xy 63.146827 -392.000562) (xy 63.123189 -391.95535)
			(xy 63.107086 -391.90694) (xy 63.098932 -391.856577) (xy 63.098426 -391.831068) (xy 63.098426 -391.830814)
			(xy 63.098916 -391.805825) (xy 63.106735 -391.756462) (xy 63.122179 -391.70893) (xy 63.144869 -391.664398)
			(xy 63.174245 -391.623965) (xy 63.209585 -391.588625) (xy 63.250018 -391.559249) (xy 63.29455 -391.536559)
			(xy 63.342082 -391.521115) (xy 63.391445 -391.513296) (xy 63.441423 -391.513296) (xy 63.490786 -391.521115)
			(xy 63.538318 -391.536559) (xy 63.58285 -391.559249) (xy 63.623283 -391.588625) (xy 63.658623 -391.623965)
			(xy 63.687999 -391.664398) (xy 63.710689 -391.70893) (xy 63.726133 -391.756462) (xy 63.733952 -391.805825)
			(xy 63.734442 -391.830814) (xy 63.734442 -391.831068) (xy 63.733941 -391.856577) (xy 63.725765 -391.906935)
			(xy 63.709665 -391.955346) (xy 63.686053 -392.000572) (xy 63.671196 -392.021314) (xy 63.665608 -392.02868)
			(xy 63.660528 -392.04646) (xy 63.667386 -392.131804) (xy 63.67526 -392.148568) (xy 63.681864 -392.154918)
			(xy 63.6999 -392.172975) (xy 63.73153 -392.213027) (xy 63.757541 -392.256936) (xy 63.777468 -392.303921)
			(xy 63.790957 -392.353141) (xy 63.797766 -392.40372) (xy 63.798196 -392.429238) (xy 63.798196 -393.292838)
			(xy 64.235076 -393.292838) (xy 64.235076 -392.42873) (xy 64.235523 -392.403263) (xy 64.242325 -392.352783)
			(xy 64.255785 -392.303659) (xy 64.275664 -392.256763) (xy 64.301607 -392.21293) (xy 64.333154 -392.17294)
			(xy 64.351154 -392.154918) (xy 64.357758 -392.148568) (xy 64.365632 -392.131804) (xy 64.37249 -392.04646)
			(xy 64.36741 -392.02868) (xy 64.361822 -392.021314) (xy 64.34697 -392.000567) (xy 64.323335 -391.955353)
			(xy 64.307234 -391.906941) (xy 64.299082 -391.856578) (xy 64.298576 -391.831068) (xy 64.298576 -391.830814)
			(xy 64.299066 -391.805825) (xy 64.306885 -391.756462) (xy 64.322329 -391.70893) (xy 64.345019 -391.664398)
			(xy 64.374395 -391.623965) (xy 64.409735 -391.588625) (xy 64.450168 -391.559249) (xy 64.4947 -391.536559)
			(xy 64.542232 -391.521115) (xy 64.591595 -391.513296) (xy 64.641573 -391.513296) (xy 64.690936 -391.521115)
			(xy 64.738468 -391.536559) (xy 64.783 -391.559249) (xy 64.823433 -391.588625) (xy 64.858773 -391.623965)
			(xy 64.888149 -391.664398) (xy 64.910839 -391.70893) (xy 64.926283 -391.756462) (xy 64.934102 -391.805825)
			(xy 64.934592 -391.830814) (xy 64.934592 -391.831068) (xy 64.934101 -391.856577) (xy 64.925923 -391.906937)
			(xy 64.909821 -391.955348) (xy 64.886205 -392.000572) (xy 64.871346 -392.021314) (xy 64.865758 -392.02868)
			(xy 64.860678 -392.04646) (xy 64.867536 -392.131804) (xy 64.87541 -392.148568) (xy 64.882014 -392.154918)
			(xy 64.900024 -392.172929) (xy 64.931562 -392.212927) (xy 64.9575 -392.256763) (xy 64.977378 -392.30366)
			(xy 64.990841 -392.352784) (xy 64.997651 -392.403262) (xy 64.998092 -392.42873) (xy 64.998092 -393.292838)
			(xy 64.998083 -393.293346) (xy 65.434972 -393.293346) (xy 65.434972 -392.42873) (xy 65.43542 -392.403263)
			(xy 65.442222 -392.352784) (xy 65.455682 -392.303659) (xy 65.475561 -392.256763) (xy 65.501504 -392.21293)
			(xy 65.53305 -392.17294) (xy 65.55105 -392.154918) (xy 65.557654 -392.148568) (xy 65.565528 -392.131804)
			(xy 65.572386 -392.04646) (xy 65.567306 -392.02868) (xy 65.561718 -392.021314) (xy 65.546866 -392.000567)
			(xy 65.523231 -391.955353) (xy 65.50713 -391.906941) (xy 65.498978 -391.856578) (xy 65.498472 -391.831068)
			(xy 65.498472 -391.830814) (xy 65.498962 -391.805825) (xy 65.506781 -391.756462) (xy 65.522225 -391.70893)
			(xy 65.544915 -391.664398) (xy 65.574291 -391.623965) (xy 65.609631 -391.588625) (xy 65.650064 -391.559249)
			(xy 65.694596 -391.536559) (xy 65.742128 -391.521115) (xy 65.791491 -391.513296) (xy 65.841469 -391.513296)
			(xy 65.890832 -391.521115) (xy 65.938364 -391.536559) (xy 65.982896 -391.559249) (xy 66.023329 -391.588625)
			(xy 66.058669 -391.623965) (xy 66.088045 -391.664398) (xy 66.110735 -391.70893) (xy 66.126179 -391.756462)
			(xy 66.133998 -391.805825) (xy 66.134488 -391.830814) (xy 66.134488 -391.831068) (xy 66.133978 -391.856576)
			(xy 66.125803 -391.906934) (xy 66.109705 -391.955345) (xy 66.086097 -392.000571) (xy 66.071242 -392.021314)
			(xy 66.065654 -392.02868) (xy 66.060574 -392.04646) (xy 66.067432 -392.131804) (xy 66.075306 -392.148568)
			(xy 66.08191 -392.154918) (xy 66.09992 -392.17293) (xy 66.131458 -392.212927) (xy 66.157396 -392.256763)
			(xy 66.177274 -392.30366) (xy 66.190737 -392.352784) (xy 66.197547 -392.403263) (xy 66.197988 -392.42873)
			(xy 66.197988 -392.714226) (xy 67.51142 -392.714226) (xy 67.515491 -392.658604) (xy 67.527617 -392.604167)
			(xy 67.54754 -392.552076) (xy 67.574836 -392.503441) (xy 67.608922 -392.459298) (xy 67.649071 -392.420589)
			(xy 67.694429 -392.388138) (xy 67.744029 -392.362637) (xy 67.796813 -392.34463) (xy 67.851656 -392.3345)
			(xy 67.90739 -392.332463) (xy 67.962827 -392.338563) (xy 68.016784 -392.352669) (xy 68.068113 -392.374481)
			(xy 68.115719 -392.403535) (xy 68.158587 -392.43921) (xy 68.195804 -392.480747) (xy 68.226577 -392.52726)
			(xy 68.250249 -392.577757) (xy 68.266317 -392.631164) (xy 68.274437 -392.68634) (xy 68.274946 -392.714226)
			(xy 68.274437 -392.742112) (xy 68.266317 -392.797288) (xy 68.250249 -392.850695) (xy 68.226577 -392.901192)
			(xy 68.195804 -392.947705) (xy 68.158587 -392.989242) (xy 68.115719 -393.024917) (xy 68.068113 -393.053971)
			(xy 68.016784 -393.075783) (xy 67.962827 -393.089889) (xy 67.90739 -393.095989) (xy 67.851656 -393.093952)
			(xy 67.796813 -393.083822) (xy 67.744029 -393.065815) (xy 67.694429 -393.040314) (xy 67.649071 -393.007863)
			(xy 67.608922 -392.969154) (xy 67.574836 -392.925011) (xy 67.54754 -392.876376) (xy 67.527617 -392.824285)
			(xy 67.515491 -392.769848) (xy 67.51142 -392.714226) (xy 66.197988 -392.714226) (xy 66.197988 -393.292838)
			(xy 66.197226 -393.317476) (xy 66.197226 -393.31773) (xy 66.197177 -393.329926) (xy 66.199411 -393.335002)
			(xy 68.233288 -393.335002) (xy 68.237359 -393.27938) (xy 68.249485 -393.224943) (xy 68.269408 -393.172852)
			(xy 68.296704 -393.124217) (xy 68.33079 -393.080074) (xy 68.370939 -393.041365) (xy 68.416297 -393.008914)
			(xy 68.465897 -392.983413) (xy 68.518681 -392.965406) (xy 68.573524 -392.955276) (xy 68.629258 -392.953239)
			(xy 68.684695 -392.959339) (xy 68.738652 -392.973445) (xy 68.789981 -392.995257) (xy 68.837587 -393.024311)
			(xy 68.880455 -393.059986) (xy 68.917672 -393.101523) (xy 68.948445 -393.148036) (xy 68.972117 -393.198533)
			(xy 68.988185 -393.25194) (xy 68.996305 -393.307116) (xy 68.996814 -393.335002) (xy 68.996305 -393.362888)
			(xy 68.988185 -393.418064) (xy 68.972117 -393.471471) (xy 68.948445 -393.521968) (xy 68.917672 -393.568481)
			(xy 68.880455 -393.610018) (xy 68.837587 -393.645693) (xy 68.789981 -393.674747) (xy 68.738652 -393.696559)
			(xy 68.684695 -393.710665) (xy 68.629258 -393.716765) (xy 68.573524 -393.714728) (xy 68.518681 -393.704598)
			(xy 68.465897 -393.686591) (xy 68.416297 -393.66109) (xy 68.370939 -393.628639) (xy 68.33079 -393.58993)
			(xy 68.296704 -393.545787) (xy 68.269408 -393.497152) (xy 68.249485 -393.445061) (xy 68.237359 -393.390624)
			(xy 68.233288 -393.335002) (xy 66.199411 -393.335002) (xy 66.206987 -393.352212) (xy 66.216022 -393.360402)
			(xy 66.290444 -393.420346) (xy 66.314828 -393.425172) (xy 66.326766 -393.421616) (xy 66.351511 -393.414981)
			(xy 66.402243 -393.407846) (xy 66.427858 -393.407392) (xy 66.42862 -393.407392) (xy 66.456219 -393.407909)
			(xy 66.510799 -393.416139) (xy 66.563544 -393.432411) (xy 66.613274 -393.456362) (xy 66.658879 -393.487457)
			(xy 66.699341 -393.525002) (xy 66.733755 -393.568158) (xy 66.761353 -393.615961) (xy 66.781518 -393.667343)
			(xy 66.7938 -393.721157) (xy 66.797925 -393.7762) (xy 66.7938 -393.831243) (xy 66.781518 -393.885057)
			(xy 66.761353 -393.936439) (xy 66.733755 -393.984242) (xy 66.699341 -394.027398) (xy 66.658879 -394.064943)
			(xy 66.613274 -394.096038) (xy 66.563544 -394.119989) (xy 66.510799 -394.136261) (xy 66.456219 -394.144491)
			(xy 66.42862 -394.145008) (xy 66.428366 -394.145008) (xy 66.403328 -394.144606) (xy 66.353714 -394.137825)
			(xy 66.305477 -394.124379) (xy 66.259509 -394.104517) (xy 66.237866 -394.091922) (xy 66.229628 -394.087363)
			(xy 66.211098 -394.084099) (xy 66.201798 -394.085572) (xy 66.125598 -394.10005) (xy 66.109596 -394.11021)
			(xy 66.104008 -394.11783) (xy 66.086944 -394.139781) (xy 66.047158 -394.178615) (xy 66.001869 -394.210865)
			(xy 65.952158 -394.23576) (xy 65.899207 -394.252709) (xy 65.844278 -394.261308) (xy 65.81648 -394.261848)
			(xy 65.790811 -394.261438) (xy 65.739998 -394.254126) (xy 65.690743 -394.239654) (xy 65.64405 -394.218316)
			(xy 65.60087 -394.190549) (xy 65.562085 -394.156916) (xy 65.528482 -394.118103) (xy 65.500748 -394.074902)
			(xy 65.479447 -394.028193) (xy 65.465014 -393.978926) (xy 65.457742 -393.928107) (xy 65.457324 -393.902438)
			(xy 65.457698 -393.878244) (xy 65.464162 -393.83029) (xy 65.477006 -393.783638) (xy 65.495997 -393.739133)
			(xy 65.520791 -393.69758) (xy 65.535556 -393.67841) (xy 65.53581 -393.678156) (xy 65.541079 -393.670967)
			(xy 65.546665 -393.65405) (xy 65.546732 -393.645136) (xy 65.5447 -393.570714) (xy 65.537842 -393.55395)
			(xy 65.532 -393.547346) (xy 65.513875 -393.526245) (xy 65.483229 -393.479825) (xy 65.459645 -393.429449)
			(xy 65.443623 -393.376184) (xy 65.4355 -393.321157) (xy 65.434972 -393.293346) (xy 64.998083 -393.293346)
			(xy 64.997548 -393.321992) (xy 64.988677 -393.379621) (xy 64.971146 -393.43523) (xy 64.945364 -393.487528)
			(xy 64.91193 -393.535298) (xy 64.892174 -393.556744) (xy 64.886015 -393.563826) (xy 64.878858 -393.581162)
			(xy 64.878204 -393.590526) (xy 64.876426 -393.659106) (xy 64.876564 -393.668363) (xy 64.882701 -393.685817)
			(xy 64.888364 -393.693142) (xy 64.888872 -393.69365) (xy 64.905183 -393.713285) (xy 64.932657 -393.756306)
			(xy 64.953761 -393.802785) (xy 64.96807 -393.851784) (xy 64.975294 -393.902315) (xy 64.97574 -393.927838)
			(xy 64.975238 -393.954715) (xy 64.967226 -394.00787) (xy 64.951382 -394.059236) (xy 64.928058 -394.107668)
			(xy 64.897777 -394.152082) (xy 64.861215 -394.191487) (xy 64.819187 -394.225003) (xy 64.772634 -394.25188)
			(xy 64.722595 -394.271519) (xy 64.670188 -394.28348) (xy 64.616584 -394.287498) (xy 64.56298 -394.28348)
			(xy 64.510573 -394.271519) (xy 64.460534 -394.25188) (xy 64.413981 -394.225003) (xy 64.371953 -394.191487)
			(xy 64.335391 -394.152082) (xy 64.30511 -394.107668) (xy 64.281786 -394.059236) (xy 64.265942 -394.00787)
			(xy 64.25793 -393.954715) (xy 64.257428 -393.927838) (xy 64.257906 -393.902281) (xy 64.265141 -393.851682)
			(xy 64.279486 -393.802623) (xy 64.300648 -393.756096) (xy 64.3282 -393.713044) (xy 64.34455 -393.693396)
			(xy 64.344804 -393.693142) (xy 64.350472 -393.685824) (xy 64.356579 -393.668362) (xy 64.356742 -393.659106)
			(xy 64.35471 -393.580874) (xy 64.347598 -393.563856) (xy 64.340994 -393.556744) (xy 64.321258 -393.535281)
			(xy 64.28782 -393.487516) (xy 64.262035 -393.435223) (xy 64.244503 -393.379616) (xy 64.235631 -393.32199)
			(xy 64.235076 -393.292838) (xy 63.798196 -393.292838) (xy 63.797624 -393.322001) (xy 63.788704 -393.379642)
			(xy 63.771123 -393.435256) (xy 63.745289 -393.487549) (xy 63.711804 -393.535307) (xy 63.692024 -393.556744)
			(xy 63.685858 -393.563821) (xy 63.678707 -393.581161) (xy 63.678054 -393.590526) (xy 63.676276 -393.659106)
			(xy 63.676425 -393.668362) (xy 63.682556 -393.685815) (xy 63.688214 -393.693142) (xy 63.688722 -393.69365)
			(xy 63.705075 -393.713264) (xy 63.732607 -393.756273) (xy 63.753765 -393.80275) (xy 63.76812 -393.851757)
			(xy 63.775383 -393.902305) (xy 63.775844 -393.927838) (xy 63.775342 -393.954734) (xy 63.767324 -394.007926)
			(xy 63.751468 -394.059329) (xy 63.728129 -394.107795) (xy 63.697826 -394.152241) (xy 63.661238 -394.191674)
			(xy 63.619181 -394.225213) (xy 63.572595 -394.252109) (xy 63.522521 -394.271762) (xy 63.470076 -394.283732)
			(xy 63.416434 -394.287752) (xy 63.362792 -394.283732) (xy 63.310347 -394.271762) (xy 63.260273 -394.252109)
			(xy 63.213687 -394.225213) (xy 63.17163 -394.191674) (xy 63.135042 -394.152241) (xy 63.104739 -394.107795)
			(xy 63.0814 -394.059329) (xy 63.065544 -394.007926) (xy 63.057526 -393.954734) (xy 63.057024 -393.927838)
			(xy 63.057507 -393.902271) (xy 63.064783 -393.851656) (xy 63.079177 -393.802589) (xy 63.100399 -393.756065)
			(xy 63.128017 -393.71303) (xy 63.1444 -393.693396) (xy 63.144654 -393.693142) (xy 63.150316 -393.68582)
			(xy 63.156428 -393.668362) (xy 63.156592 -393.659106) (xy 63.15456 -393.580874) (xy 63.147448 -393.563856)
			(xy 63.140844 -393.556744) (xy 63.121065 -393.535304) (xy 63.087571 -393.487552) (xy 63.061734 -393.43526)
			(xy 63.044155 -393.379644) (xy 63.035243 -393.322001) (xy 63.034672 -393.292838) (xy 62.5983 -393.292838)
			(xy 62.597768 -393.32129) (xy 62.58932 -393.377565) (xy 62.572619 -393.431963) (xy 62.548032 -393.483282)
			(xy 62.516104 -393.530386) (xy 62.497208 -393.551664) (xy 62.491307 -393.558648) (xy 62.484405 -393.575565)
			(xy 62.483746 -393.584684) (xy 62.48273 -393.615418) (xy 62.482873 -393.624588) (xy 62.488854 -393.641908)
			(xy 62.494414 -393.6492) (xy 62.50979 -393.668527) (xy 62.5356 -393.710634) (xy 62.555392 -393.755884)
			(xy 62.568792 -393.803419) (xy 62.575546 -393.852344) (xy 62.575948 -393.877038) (xy 62.575446 -393.903934)
			(xy 62.567428 -393.957126) (xy 62.551572 -394.008529) (xy 62.528233 -394.056995) (xy 62.49793 -394.101441)
			(xy 62.461342 -394.140874) (xy 62.419285 -394.174413) (xy 62.372699 -394.201309) (xy 62.322625 -394.220962)
			(xy 62.27018 -394.232932) (xy 62.216538 -394.236952) (xy 62.162896 -394.232932) (xy 62.110451 -394.220962)
			(xy 62.060377 -394.201309) (xy 62.013791 -394.174413) (xy 61.971734 -394.140874) (xy 61.935146 -394.101441)
			(xy 61.904843 -394.056995) (xy 61.881504 -394.008529) (xy 61.865648 -393.957126) (xy 61.85763 -393.903934)
			(xy 61.857128 -393.877038) (xy 61.857585 -393.852349) (xy 61.86437 -393.80344) (xy 61.877777 -393.755917)
			(xy 61.897555 -393.710673) (xy 61.923331 -393.668557) (xy 61.938662 -393.6492) (xy 61.944184 -393.641884)
			(xy 61.950182 -393.624581) (xy 61.950346 -393.615418) (xy 61.94933 -393.584684) (xy 61.948684 -393.57556)
			(xy 61.941793 -393.558632) (xy 61.935868 -393.551664) (xy 61.916939 -393.53041) (xy 61.88498 -393.483317)
			(xy 61.860381 -393.431994) (xy 61.84369 -393.377583) (xy 61.835278 -393.321295) (xy 61.834776 -393.292838)
			(xy 61.398404 -393.292838) (xy 61.39783 -393.322001) (xy 61.38891 -393.379641) (xy 61.371329 -393.435255)
			(xy 61.345496 -393.487549) (xy 61.312012 -393.535307) (xy 61.292232 -393.556744) (xy 61.286067 -393.563822)
			(xy 61.278915 -393.581161) (xy 61.278262 -393.590526) (xy 61.276484 -393.659106) (xy 61.276631 -393.668362)
			(xy 61.282763 -393.685815) (xy 61.288422 -393.693142) (xy 61.28893 -393.69365) (xy 61.305284 -393.713263)
			(xy 61.332816 -393.756272) (xy 61.353974 -393.80275) (xy 61.368328 -393.851757) (xy 61.375591 -393.902305)
			(xy 61.376052 -393.927838) (xy 61.37555 -393.954734) (xy 61.367532 -394.007926) (xy 61.351676 -394.059329)
			(xy 61.328337 -394.107795) (xy 61.298034 -394.152241) (xy 61.261446 -394.191674) (xy 61.219389 -394.225213)
			(xy 61.172803 -394.252109) (xy 61.122729 -394.271762) (xy 61.070284 -394.283732) (xy 61.016642 -394.287752)
			(xy 60.963 -394.283732) (xy 60.910555 -394.271762) (xy 60.860481 -394.252109) (xy 60.813895 -394.225213)
			(xy 60.771838 -394.191674) (xy 60.73525 -394.152241) (xy 60.704947 -394.107795) (xy 60.681608 -394.059329)
			(xy 60.665752 -394.007926) (xy 60.657734 -393.954734) (xy 60.657232 -393.927838) (xy 60.657713 -393.90227)
			(xy 60.664989 -393.851656) (xy 60.679384 -393.802588) (xy 60.700606 -393.756065) (xy 60.728224 -393.71303)
			(xy 60.744608 -393.693396) (xy 60.744862 -393.693142) (xy 60.750525 -393.68582) (xy 60.756637 -393.668362)
			(xy 60.7568 -393.659106) (xy 60.754768 -393.580874) (xy 60.747656 -393.563856) (xy 60.741052 -393.556744)
			(xy 60.721275 -393.535303) (xy 60.68778 -393.487552) (xy 60.661942 -393.435259) (xy 60.644363 -393.379644)
			(xy 60.635451 -393.322001) (xy 60.63488 -393.292838) (xy 60.340748 -393.292838) (xy 60.340748 -394.428218)
			(xy 60.340346 -394.43829) (xy 60.33261 -394.456889) (xy 60.325762 -394.464286) (xy 60.040012 -394.750036)
			(xy 60.032606 -394.756868) (xy 60.014011 -394.764592) (xy 60.003944 -394.765022) (xy 53.187092 -394.765022)
			(xy 53.17702 -394.764621) (xy 53.158421 -394.756885) (xy 53.151024 -394.750036) (xy 52.850796 -394.449808)
			(xy 52.850796 -394.449554) (xy 52.753768 -394.352526) (xy 52.743169 -394.341709) (xy 52.723956 -394.318296)
			(xy 52.715414 -394.30579) (xy 52.709808 -394.29807) (xy 52.694177 -394.287155) (xy 52.675631 -394.28274)
			(xy 52.666138 -394.283692) (xy 52.65382 -394.285327) (xy 52.629033 -394.287105) (xy 52.616608 -394.287248)
			(xy 52.590965 -394.286792) (xy 52.5402 -394.279497) (xy 52.490989 -394.265055) (xy 52.444332 -394.243759)
			(xy 52.40118 -394.216043) (xy 52.36241 -394.18247) (xy 52.328809 -394.143723) (xy 52.301063 -394.100591)
			(xy 52.279734 -394.05395) (xy 52.265257 -394.004749) (xy 52.257927 -393.953989) (xy 52.257452 -393.928346)
			(xy 52.257452 -393.927838) (xy 52.257924 -393.902281) (xy 52.26516 -393.851681) (xy 52.279505 -393.802622)
			(xy 52.300669 -393.756095) (xy 52.328223 -393.713044) (xy 52.344574 -393.693396) (xy 52.344828 -393.693142)
			(xy 52.350499 -393.685826) (xy 52.356604 -393.668363) (xy 52.356766 -393.659106) (xy 52.354734 -393.580874)
			(xy 52.347622 -393.563856) (xy 52.341018 -393.556744) (xy 52.321286 -393.535277) (xy 52.287847 -393.487514)
			(xy 52.262061 -393.435222) (xy 52.244527 -393.379616) (xy 52.235655 -393.32199) (xy 52.2351 -393.292838)
			(xy 52.2351 -392.42873) (xy 52.23554 -392.403262) (xy 52.242342 -392.352783) (xy 52.255803 -392.303658)
			(xy 52.275683 -392.256761) (xy 52.301628 -392.212929) (xy 52.333177 -392.172939) (xy 52.351178 -392.154918)
			(xy 52.357782 -392.148568) (xy 52.365656 -392.131804) (xy 52.372514 -392.04646) (xy 52.367434 -392.02868)
			(xy 52.361846 -392.021314) (xy 52.346997 -392.000565) (xy 52.323361 -391.955351) (xy 52.307259 -391.90694)
			(xy 52.299106 -391.856577) (xy 52.2986 -391.831068) (xy 52.2986 -391.830814) (xy 52.299144 -391.804185)
			(xy 52.308023 -391.751673) (xy 52.325517 -391.70137) (xy 52.351139 -391.654681) (xy 52.384174 -391.612907)
			(xy 52.423701 -391.577214) (xy 52.468617 -391.548598) (xy 52.51767 -391.527856) (xy 52.543456 -391.521188)
			(xy 52.560728 -391.517124) (xy 52.582572 -391.489692) (xy 52.582572 -390.783826) (xy 52.582141 -390.773757)
			(xy 52.574425 -390.755159) (xy 52.567586 -390.747758) (xy 52.384706 -390.564878) (xy 52.377301 -390.558045)
			(xy 52.358705 -390.550322) (xy 52.348638 -390.549892) (xy 51.937412 -390.549892) (xy 51.92739 -390.549471)
			(xy 51.908872 -390.541803) (xy 51.894699 -390.527631) (xy 51.88703 -390.509114) (xy 51.886612 -390.499092)
			(xy 51.886612 -390.284716) (xy 51.877468 -390.284716) (xy 51.86746 -390.284239) (xy 51.848971 -390.276571)
			(xy 51.83482 -390.262416) (xy 51.827158 -390.243924) (xy 51.826668 -390.233916) (xy 51.826668 -390.029954)
			(xy 51.827018 -390.012722) (xy 51.832588 -389.978709) (xy 51.843557 -389.946036) (xy 51.851306 -389.93064)
			(xy 51.857148 -389.91921) (xy 51.856894 -389.89381) (xy 51.8033 -389.796782) (xy 51.78171 -389.783066)
			(xy 51.768756 -389.78205) (xy 51.744862 -389.779906) (xy 51.698076 -389.76931) (xy 51.653435 -389.751747)
			(xy 51.611971 -389.727624) (xy 51.57464 -389.697496) (xy 51.542305 -389.66206) (xy 51.515713 -389.622134)
			(xy 51.495477 -389.57864) (xy 51.48834 -389.555736) (xy 51.486816 -389.549894) (xy 51.166522 -388.996174)
			(xy 51.162458 -388.991856) (xy 51.146299 -388.974121) (xy 51.118931 -388.93472) (xy 51.09784 -388.89163)
			(xy 51.083512 -388.845845) (xy 51.076278 -388.798419) (xy 51.075844 -388.774432) (xy 51.076026 -388.760384)
			(xy 51.078566 -388.732402) (xy 51.080924 -388.718552) (xy 51.082243 -388.709272) (xy 51.078717 -388.690876)
			(xy 51.074066 -388.682738) (xy 51.057302 -388.655814) (xy 51.052105 -388.648106) (xy 51.037376 -388.636785)
			(xy 51.0286 -388.633716) (xy 51.00698 -388.626896) (xy 50.965765 -388.608021) (xy 50.927643 -388.583491)
			(xy 50.893385 -388.553803) (xy 50.878232 -388.536942) (xy 50.875769 -388.53417) (xy 50.870157 -388.529323)
			(xy 50.867056 -388.52729) (xy 50.854995 -388.519228) (xy 50.835038 -388.498186) (xy 50.820963 -388.472829)
			(xy 50.813661 -388.444762) (xy 50.813208 -388.430262) (xy 50.813208 -388.418324) (xy 50.811684 -388.41172)
			(xy 50.806478 -388.391351) (xy 50.800877 -388.349683) (xy 50.800508 -388.328662) (xy 50.236628 -388.328662)
			(xy 50.236628 -388.32917) (xy 50.236457 -388.343795) (xy 50.23379 -388.372924) (xy 50.231294 -388.387336)
			(xy 50.229931 -388.39651) (xy 50.233203 -388.414752) (xy 50.237644 -388.422896) (xy 50.254154 -388.44982)
			(xy 50.25932 -388.457601) (xy 50.274049 -388.469062) (xy 50.282856 -388.472172) (xy 50.307786 -388.480289)
			(xy 50.354751 -388.503587) (xy 50.39723 -388.534313) (xy 50.434058 -388.571625) (xy 50.464227 -388.614501)
			(xy 50.486909 -388.661766) (xy 50.494692 -388.686802) (xy 50.496216 -388.692644) (xy 50.816002 -389.245602)
			(xy 50.820066 -389.24992) (xy 50.836233 -389.26758) (xy 50.86355 -389.3069) (xy 50.884615 -389.349893)
			(xy 50.898947 -389.395575) (xy 50.906217 -389.442898) (xy 50.90668 -389.466836) (xy 50.90668 -389.467344)
			(xy 50.906167 -389.492792) (xy 50.897997 -389.543028) (xy 50.881875 -389.591303) (xy 50.858219 -389.636367)
			(xy 50.827642 -389.677053) (xy 50.790935 -389.712309) (xy 50.770282 -389.727186) (xy 50.761784 -389.733666)
			(xy 50.750597 -389.751845) (xy 50.747761 -389.773001) (xy 50.753767 -389.793484) (xy 50.767577 -389.80976)
			(xy 50.786809 -389.81902) (xy 50.79746 -389.819896) (xy 50.807112 -389.819388) (xy 50.815626 -389.818095)
			(xy 50.832791 -389.816695) (xy 50.841402 -389.816594) (xy 50.841656 -389.816848) (xy 51.140868 -389.816848)
			(xy 51.141122 -389.816594) (xy 51.162168 -389.817013) (xy 51.203487 -389.825006) (xy 51.242442 -389.840935)
			(xy 51.277525 -389.864183) (xy 51.307376 -389.893849) (xy 51.330841 -389.928787) (xy 51.347011 -389.967642)
			(xy 51.35526 -390.008911) (xy 51.355752 -390.029954) (xy 51.355752 -390.284716) (xy 51.346608 -390.284716)
			(xy 51.336585 -390.285126) (xy 51.318065 -390.292797) (xy 51.303892 -390.306972) (xy 51.296225 -390.325493)
			(xy 51.295808 -390.335516) (xy 51.295808 -390.499092) (xy 51.295306 -390.509098) (xy 51.28765 -390.527588)
			(xy 51.273502 -390.541741) (xy 51.255014 -390.549402) (xy 51.245008 -390.549892) (xy 50.737516 -390.549892)
			(xy 50.727495 -390.549467) (xy 50.708977 -390.541801) (xy 50.694803 -390.52763) (xy 50.687134 -390.509113)
			(xy 50.686716 -390.499092) (xy 50.686716 -390.335516) (xy 50.686199 -390.325511) (xy 50.678548 -390.307023)
			(xy 50.664404 -390.29287) (xy 50.64592 -390.285207) (xy 50.635916 -390.284716) (xy 50.626772 -390.284716)
			(xy 50.626772 -390.029446) (xy 50.627551 -390.003723) (xy 50.639887 -389.953777) (xy 50.651156 -389.93064)
			(xy 50.656998 -389.91921) (xy 50.656744 -389.89381) (xy 50.60315 -389.796782) (xy 50.58156 -389.783066)
			(xy 50.568606 -389.78205) (xy 50.544708 -389.779947) (xy 50.49792 -389.769343) (xy 50.453279 -389.751774)
			(xy 50.411815 -389.727644) (xy 50.374485 -389.69751) (xy 50.342152 -389.66207) (xy 50.315561 -389.622139)
			(xy 50.295326 -389.578641) (xy 50.28819 -389.555736) (xy 50.286666 -389.549894) (xy 49.966118 -388.995412)
			(xy 49.962054 -388.991094) (xy 49.945955 -388.973433) (xy 49.918767 -388.934134) (xy 49.897815 -388.891185)
			(xy 49.883578 -388.845568) (xy 49.876383 -388.798326) (xy 49.875948 -388.774432) (xy 49.876129 -388.760384)
			(xy 49.87867 -388.732402) (xy 49.881028 -388.718552) (xy 49.882346 -388.709272) (xy 49.878821 -388.690876)
			(xy 49.87417 -388.682738) (xy 49.857406 -388.655814) (xy 49.852208 -388.648107) (xy 49.83748 -388.636786)
			(xy 49.828704 -388.633716) (xy 49.807085 -388.626895) (xy 49.765869 -388.60802) (xy 49.727747 -388.583491)
			(xy 49.693489 -388.553803) (xy 49.678336 -388.536942) (xy 49.675872 -388.534171) (xy 49.670261 -388.529324)
			(xy 49.66716 -388.52729) (xy 49.6551 -388.519227) (xy 49.635142 -388.498185) (xy 49.621067 -388.472829)
			(xy 49.613765 -388.444762) (xy 49.613312 -388.430262) (xy 49.613312 -388.418324) (xy 49.611788 -388.41172)
			(xy 49.606582 -388.391351) (xy 49.600981 -388.349683) (xy 49.600612 -388.328662) (xy 49.036478 -388.328662)
			(xy 49.036478 -388.32917) (xy 49.036308 -388.343795) (xy 49.033641 -388.372924) (xy 49.031144 -388.387336)
			(xy 49.029775 -388.39651) (xy 49.03305 -388.414753) (xy 49.037494 -388.422896) (xy 49.054004 -388.44982)
			(xy 49.059152 -388.457615) (xy 49.073893 -388.469068) (xy 49.082706 -388.472172) (xy 49.107587 -388.480236)
			(xy 49.154467 -388.503425) (xy 49.196879 -388.534029) (xy 49.233662 -388.571209) (xy 49.263809 -388.613947)
			(xy 49.286494 -388.661073) (xy 49.294288 -388.68604) (xy 49.295812 -388.691882) (xy 49.616106 -389.245602)
			(xy 49.62017 -389.24992) (xy 49.636337 -389.267579) (xy 49.663654 -389.306899) (xy 49.68472 -389.349893)
			(xy 49.699052 -389.395575) (xy 49.706321 -389.442898) (xy 49.706784 -389.466836) (xy 49.706784 -389.467344)
			(xy 49.706269 -389.492792) (xy 49.698099 -389.543027) (xy 49.681978 -389.591302) (xy 49.658322 -389.636366)
			(xy 49.627745 -389.677053) (xy 49.591038 -389.712309) (xy 49.570386 -389.727186) (xy 49.561886 -389.733664)
			(xy 49.550698 -389.751843) (xy 49.547862 -389.773) (xy 49.553867 -389.793485) (xy 49.567679 -389.809761)
			(xy 49.586912 -389.81902) (xy 49.597564 -389.819896) (xy 49.607216 -389.819388) (xy 49.61573 -389.818094)
			(xy 49.632895 -389.816695) (xy 49.641506 -389.816594) (xy 49.64176 -389.816848) (xy 49.940972 -389.816848)
			(xy 49.941226 -389.816594) (xy 49.962272 -389.81701) (xy 50.003592 -389.825003) (xy 50.042547 -389.840933)
			(xy 50.077629 -389.864181) (xy 50.10748 -389.893848) (xy 50.130945 -389.928786) (xy 50.147115 -389.967641)
			(xy 50.155364 -390.008911) (xy 50.155856 -390.029954) (xy 50.155856 -390.284716) (xy 50.146712 -390.284716)
			(xy 50.136689 -390.28513) (xy 50.11817 -390.292799) (xy 50.103996 -390.306973) (xy 50.096329 -390.325493)
			(xy 50.095912 -390.335516) (xy 50.095912 -390.499092) (xy 50.095406 -390.509098) (xy 50.087751 -390.527587)
			(xy 50.073604 -390.54174) (xy 50.055117 -390.549402) (xy 50.045112 -390.549892) (xy 49.53762 -390.549892)
			(xy 49.527599 -390.549464) (xy 49.509081 -390.541799) (xy 49.494908 -390.527629) (xy 49.487239 -390.509113)
			(xy 49.48682 -390.499092) (xy 49.48682 -390.335516) (xy 49.486299 -390.325512) (xy 49.478649 -390.307024)
			(xy 49.464506 -390.292871) (xy 49.446024 -390.285208) (xy 49.43602 -390.284716) (xy 49.426876 -390.284716)
			(xy 49.426876 -390.029446) (xy 49.427664 -390.003724) (xy 49.439995 -389.953778) (xy 49.45126 -389.93064)
			(xy 49.457102 -389.91921) (xy 49.456848 -389.89381) (xy 49.403254 -389.796782) (xy 49.381664 -389.783066)
			(xy 49.36871 -389.78205) (xy 49.344812 -389.779943) (xy 49.298025 -389.76934) (xy 49.253384 -389.751771)
			(xy 49.21192 -389.727642) (xy 49.17459 -389.697509) (xy 49.142256 -389.662069) (xy 49.115665 -389.622139)
			(xy 49.09543 -389.578641) (xy 49.088294 -389.555736) (xy 49.08677 -389.549894) (xy 48.766476 -388.996174)
			(xy 48.762412 -388.991856) (xy 48.746211 -388.974145) (xy 48.718786 -388.934756) (xy 48.697642 -388.891667)
			(xy 48.683268 -388.845873) (xy 48.675994 -388.79843) (xy 48.675544 -388.774432) (xy 48.675722 -388.760384)
			(xy 48.678266 -388.732402) (xy 48.680624 -388.718552) (xy 48.68191 -388.709296) (xy 48.678514 -388.690932)
			(xy 48.67402 -388.682738) (xy 48.657256 -388.655814) (xy 48.65204 -388.648121) (xy 48.637325 -388.636792)
			(xy 48.628554 -388.633716) (xy 48.606928 -388.626915) (xy 48.565714 -388.608033) (xy 48.527593 -388.583498)
			(xy 48.493338 -388.553805) (xy 48.478186 -388.536942) (xy 48.475716 -388.534176) (xy 48.470109 -388.529326)
			(xy 48.46701 -388.52729) (xy 48.454989 -388.5192) (xy 48.435096 -388.498144) (xy 48.421085 -388.472792)
			(xy 48.413843 -388.444745) (xy 48.413416 -388.430262) (xy 48.413416 -388.418324) (xy 48.411638 -388.41172)
			(xy 48.406431 -388.391351) (xy 48.400831 -388.349683) (xy 48.400462 -388.328662) (xy 47.836582 -388.328662)
			(xy 47.836582 -388.32917) (xy 47.836412 -388.343795) (xy 47.833745 -388.372924) (xy 47.831248 -388.387336)
			(xy 47.829878 -388.39651) (xy 47.833154 -388.414753) (xy 47.837598 -388.422896) (xy 47.854108 -388.44982)
			(xy 47.859291 -388.457588) (xy 47.874008 -388.469056) (xy 47.88281 -388.472172) (xy 47.907692 -388.480234)
			(xy 47.954571 -388.503423) (xy 47.996983 -388.534028) (xy 48.033767 -388.571209) (xy 48.063913 -388.613947)
			(xy 48.086598 -388.661073) (xy 48.094392 -388.68604) (xy 48.095916 -388.691882) (xy 48.41621 -389.245602)
			(xy 48.420274 -389.24992) (xy 48.436442 -389.267579) (xy 48.463758 -389.306899) (xy 48.484824 -389.349893)
			(xy 48.499156 -389.395575) (xy 48.506425 -389.442898) (xy 48.506888 -389.466836) (xy 48.506888 -389.467344)
			(xy 48.506372 -389.492792) (xy 48.498202 -389.543027) (xy 48.48208 -389.591302) (xy 48.458425 -389.636366)
			(xy 48.427849 -389.677053) (xy 48.391142 -389.712309) (xy 48.37049 -389.727186) (xy 48.361996 -389.73364)
			(xy 48.350811 -389.751778) (xy 48.347945 -389.772894) (xy 48.353889 -389.793358) (xy 48.367623 -389.809651)
			(xy 48.386785 -389.818973) (xy 48.397414 -389.819896) (xy 48.40732 -389.819388) (xy 48.415771 -389.818102)
			(xy 48.432809 -389.816703) (xy 48.441356 -389.816594) (xy 48.44161 -389.816848) (xy 48.740822 -389.816848)
			(xy 48.741076 -389.816594) (xy 48.762138 -389.816984) (xy 48.803498 -389.824942) (xy 48.842496 -389.840849)
			(xy 48.877622 -389.864089) (xy 48.907513 -389.893761) (xy 48.931011 -389.928715) (xy 48.947205 -389.967595)
			(xy 48.955466 -390.008895) (xy 48.95596 -390.029954) (xy 48.95596 -390.284716) (xy 48.946816 -390.284716)
			(xy 48.936794 -390.285133) (xy 48.918274 -390.292801) (xy 48.904101 -390.306974) (xy 48.896433 -390.325494)
			(xy 48.896016 -390.335516) (xy 48.896016 -390.499092) (xy 48.895506 -390.509097) (xy 48.887852 -390.527586)
			(xy 48.873706 -390.541738) (xy 48.855221 -390.549401) (xy 48.845216 -390.549892) (xy 48.337216 -390.549892)
			(xy 48.327195 -390.549467) (xy 48.308677 -390.541801) (xy 48.294503 -390.52763) (xy 48.286834 -390.509113)
			(xy 48.286416 -390.499092) (xy 48.286416 -390.284716) (xy 48.277272 -390.284716) (xy 48.267265 -390.284235)
			(xy 48.248775 -390.27657) (xy 48.234624 -390.262415) (xy 48.226962 -390.243924) (xy 48.226472 -390.233916)
			(xy 48.226472 -390.029954) (xy 48.226822 -390.012721) (xy 48.232391 -389.978709) (xy 48.243361 -389.946036)
			(xy 48.25111 -389.93064) (xy 48.256952 -389.91921) (xy 48.256698 -389.89381) (xy 48.2092 -389.808212)
			(xy 48.202461 -389.797447) (xy 48.18115 -389.783702) (xy 48.16856 -389.78205) (xy 48.14469 -389.779835)
			(xy 48.097947 -389.769211) (xy 48.05335 -389.751634) (xy 48.011929 -389.727509) (xy 47.974636 -389.697392)
			(xy 47.942332 -389.661977) (xy 47.91576 -389.62208) (xy 47.895534 -389.578621) (xy 47.888398 -389.555736)
			(xy 47.886874 -389.549894) (xy 47.56658 -388.996174) (xy 47.562516 -388.991856) (xy 47.546316 -388.974145)
			(xy 47.51889 -388.934755) (xy 47.497746 -388.891667) (xy 47.483372 -388.845873) (xy 47.476098 -388.79843)
			(xy 47.475648 -388.774432) (xy 47.475826 -388.760384) (xy 47.47837 -388.732402) (xy 47.480728 -388.718552)
			(xy 47.482014 -388.709296) (xy 47.478618 -388.690932) (xy 47.474124 -388.682738) (xy 47.45736 -388.655814)
			(xy 47.452143 -388.648122) (xy 47.437428 -388.636792) (xy 47.428658 -388.633716) (xy 47.407033 -388.626913)
			(xy 47.365818 -388.608032) (xy 47.327698 -388.583498) (xy 47.293442 -388.553805) (xy 47.27829 -388.536942)
			(xy 47.27582 -388.534177) (xy 47.270213 -388.529326) (xy 47.267114 -388.52729) (xy 47.255094 -388.519199)
			(xy 47.2352 -388.498144) (xy 47.221189 -388.472791) (xy 47.213947 -388.444745) (xy 47.21352 -388.430262)
			(xy 47.21352 -388.418324) (xy 47.211742 -388.41172) (xy 47.206535 -388.391351) (xy 47.200935 -388.349683)
			(xy 47.200566 -388.328662) (xy 45.434221 -388.328662) (xy 45.42753 -388.371845) (xy 45.42028 -388.396226)
			(xy 45.41774 -388.403846) (xy 45.41774 -388.494778) (xy 45.417239 -388.511466) (xy 45.408605 -388.543706)
			(xy 45.391919 -388.572612) (xy 45.368319 -388.596214) (xy 45.339414 -388.612901) (xy 45.307174 -388.621538)
			(xy 45.290486 -388.622032) (xy 45.161708 -388.622032) (xy 45.157644 -388.622794) (xy 45.144648 -388.624711)
			(xy 45.118456 -388.626746) (xy 45.10532 -388.626858) (xy 45.104812 -388.626858) (xy 45.091676 -388.626756)
			(xy 45.065482 -388.624726) (xy 45.052488 -388.622794) (xy 45.048424 -388.622032) (xy 44.909486 -388.622032)
			(xy 44.892795 -388.621571) (xy 44.860553 -388.612927) (xy 44.831646 -388.596233) (xy 44.808045 -388.572625)
			(xy 44.791359 -388.543714) (xy 44.782725 -388.511469) (xy 44.782232 -388.494778) (xy 44.782232 -388.367524)
			(xy 44.780962 -388.362444) (xy 44.777854 -388.346047) (xy 44.774543 -388.312838) (xy 44.774358 -388.29615)
			(xy 44.5724 -388.29615) (xy 44.572428 -388.297674) (xy 44.571919 -388.32556) (xy 44.563799 -388.380736)
			(xy 44.547731 -388.434143) (xy 44.524059 -388.48464) (xy 44.493286 -388.531153) (xy 44.456069 -388.57269)
			(xy 44.413201 -388.608365) (xy 44.365595 -388.637419) (xy 44.314266 -388.659231) (xy 44.260309 -388.673337)
			(xy 44.204872 -388.679437) (xy 44.149138 -388.6774) (xy 44.094295 -388.66727) (xy 44.041511 -388.649263)
			(xy 43.991911 -388.623762) (xy 43.946553 -388.591311) (xy 43.906404 -388.552602) (xy 43.872318 -388.508459)
			(xy 43.845022 -388.459824) (xy 43.825099 -388.407733) (xy 43.812973 -388.353296) (xy 43.808902 -388.297674)
			(xy 42.168173 -388.297674) (xy 42.179011 -388.321406) (xy 42.194366 -388.373701) (xy 42.202122 -388.427649)
			(xy 42.202122 -388.482151) (xy 42.194366 -388.536099) (xy 42.179011 -388.588394) (xy 42.156369 -388.637971)
			(xy 42.126903 -388.683821) (xy 42.091212 -388.725012) (xy 42.050021 -388.760703) (xy 42.004171 -388.790169)
			(xy 41.954594 -388.812811) (xy 41.902299 -388.828166) (xy 41.848351 -388.835922) (xy 41.793849 -388.835922)
			(xy 41.739901 -388.828166) (xy 41.687606 -388.812811) (xy 41.638029 -388.790169) (xy 41.592179 -388.760703)
			(xy 41.550988 -388.725012) (xy 41.515297 -388.683821) (xy 41.485831 -388.637971) (xy 41.463189 -388.588394)
			(xy 41.447834 -388.536099) (xy 41.440078 -388.482151) (xy 41.439592 -388.4549) (xy 41.440055 -388.429075)
			(xy 41.447095 -388.377904) (xy 41.460978 -388.328153) (xy 41.470834 -388.304278) (xy 41.470834 -388.30377)
			(xy 41.473315 -388.297344) (xy 41.47513 -388.283694) (xy 41.47439 -388.276846) (xy 41.47439 -388.276084)
			(xy 41.473222 -388.269284) (xy 41.467681 -388.256655) (xy 41.463468 -388.251192) (xy 41.406826 -388.181596)
			(xy 41.400547 -388.174567) (xy 41.384188 -388.165241) (xy 41.365565 -388.162449) (xy 41.35628 -388.16407)
			(xy 41.352978 -388.164832) (xy 41.335613 -388.167891) (xy 41.300505 -388.171197) (xy 41.282874 -388.171436)
			(xy 41.255607 -388.170948) (xy 41.201627 -388.163183) (xy 41.149302 -388.147815) (xy 41.099697 -388.125157)
			(xy 41.053821 -388.09567) (xy 41.012609 -388.059954) (xy 40.976899 -388.018737) (xy 40.947418 -387.972857)
			(xy 40.924767 -387.923249) (xy 40.909406 -387.870922) (xy 40.901649 -387.816942) (xy 40.901112 -387.789674)
			(xy 40.901112 -387.679438) (xy 40.900699 -387.669411) (xy 40.893036 -387.650879) (xy 40.878863 -387.636692)
			(xy 40.860339 -387.629011) (xy 40.850312 -387.628638) (xy 40.835072 -387.628638) (xy 40.809926 -387.644894)
			(xy 40.80383 -387.65861) (xy 40.790501 -387.687099) (xy 40.757181 -387.740445) (xy 40.716876 -387.788729)
			(xy 40.670342 -387.831045) (xy 40.618457 -387.866596) (xy 40.562195 -387.894713) (xy 40.532558 -387.905244)
			(xy 40.523594 -387.908687) (xy 40.50892 -387.921049) (xy 40.499799 -387.93793) (xy 40.498268 -387.947408)
			(xy 40.49776 -387.951726) (xy 40.49776 -389.609076) (xy 40.498199 -389.619139) (xy 40.505939 -389.637717)
			(xy 40.512746 -389.645144) (xy 40.70223 -389.834374) (xy 40.724252 -389.85709) (xy 40.762771 -389.907281)
			(xy 40.794407 -389.962073) (xy 40.818616 -390.020527) (xy 40.834986 -390.081641) (xy 40.843234 -390.14437)
			(xy 40.843708 -390.176004) (xy 40.843708 -390.626092) (xy 44.762674 -390.626092) (xy 44.763091 -390.602859)
			(xy 44.769584 -390.556849) (xy 44.782457 -390.512202) (xy 44.801454 -390.469797) (xy 44.826202 -390.43047)
			(xy 44.840906 -390.412478) (xy 44.846748 -390.40562) (xy 44.849796 -390.397238) (xy 44.852336 -390.38403)
			(xy 44.853098 -390.374886) (xy 44.853098 -390.313926) (xy 44.852965 -390.309379) (xy 44.851312 -390.300435)
			(xy 44.849796 -390.296146) (xy 44.846748 -390.287764) (xy 44.840906 -390.280906) (xy 44.826187 -390.262925)
			(xy 44.801442 -390.223593) (xy 44.782444 -390.181186) (xy 44.769568 -390.136537) (xy 44.763067 -390.090526)
			(xy 44.762674 -390.067292) (xy 44.763184 -390.041305) (xy 44.771314 -389.98997) (xy 44.787375 -389.94054)
			(xy 44.810971 -389.89423) (xy 44.841521 -389.852182) (xy 44.878272 -389.815431) (xy 44.92032 -389.784881)
			(xy 44.96663 -389.761285) (xy 45.01606 -389.745224) (xy 45.067395 -389.737094) (xy 45.119369 -389.737094)
			(xy 45.170704 -389.745224) (xy 45.220134 -389.761285) (xy 45.266444 -389.784881) (xy 45.308492 -389.815431)
			(xy 45.345243 -389.852182) (xy 45.375793 -389.89423) (xy 45.399389 -389.94054) (xy 45.41545 -389.98997)
			(xy 45.42358 -390.041305) (xy 45.42409 -390.067292) (xy 45.42373 -390.090527) (xy 45.417224 -390.13654)
			(xy 45.404339 -390.181188) (xy 45.385329 -390.223592) (xy 45.378829 -390.233916) (xy 47.026576 -390.233916)
			(xy 47.026576 -390.029954) (xy 47.027131 -390.008472) (xy 47.035743 -389.966381) (xy 47.052591 -389.926858)
			(xy 47.076996 -389.891498) (xy 47.107972 -389.861727) (xy 47.144272 -389.838744) (xy 47.184432 -389.823477)
			(xy 47.226832 -389.816541) (xy 47.248318 -389.816848) (xy 47.25035 -389.816848) (xy 47.533814 -389.816848)
			(xy 47.555306 -389.81649) (xy 47.597725 -389.823403) (xy 47.637905 -389.83866) (xy 47.674221 -389.861645)
			(xy 47.705207 -389.891428) (xy 47.72961 -389.926807) (xy 47.746444 -389.966352) (xy 47.755029 -390.008465)
			(xy 47.755556 -390.029954) (xy 47.755556 -390.284716) (xy 47.746412 -390.284716) (xy 47.736389 -390.28513)
			(xy 47.71787 -390.292799) (xy 47.703696 -390.306973) (xy 47.696029 -390.325493) (xy 47.695612 -390.335516)
			(xy 47.695612 -390.499092) (xy 47.695106 -390.509098) (xy 47.687451 -390.527587) (xy 47.673304 -390.54174)
			(xy 47.654817 -390.549402) (xy 47.644812 -390.549892) (xy 47.13732 -390.549892) (xy 47.127299 -390.549464)
			(xy 47.108781 -390.541799) (xy 47.094608 -390.527629) (xy 47.086939 -390.509113) (xy 47.08652 -390.499092)
			(xy 47.08652 -390.311386) (xy 47.070264 -390.28624) (xy 47.056548 -390.280144) (xy 47.047821 -390.275787)
			(xy 47.034306 -390.261741) (xy 47.027018 -390.243662) (xy 47.026576 -390.233916) (xy 45.378829 -390.233916)
			(xy 45.360569 -390.262917) (xy 45.345858 -390.280906) (xy 45.340016 -390.287764) (xy 45.336968 -390.296146)
			(xy 45.334428 -390.309354) (xy 45.333666 -390.318498) (xy 45.333666 -390.379458) (xy 45.333773 -390.384007)
			(xy 45.335443 -390.392951) (xy 45.336968 -390.397238) (xy 45.340016 -390.40562) (xy 45.345858 -390.412478)
			(xy 45.360564 -390.430469) (xy 45.385312 -390.469797) (xy 45.404313 -390.512202) (xy 45.417192 -390.556849)
			(xy 45.423696 -390.602858) (xy 45.42409 -390.626092) (xy 45.42409 -390.626346) (xy 45.423662 -390.650396)
			(xy 45.416671 -390.697986) (xy 45.402871 -390.744065) (xy 45.393102 -390.766046) (xy 45.387768 -390.777476)
			(xy 45.389038 -390.802622) (xy 45.445426 -390.896602) (xy 45.467016 -390.909556) (xy 45.479462 -390.910318)
			(xy 45.504458 -390.912162) (xy 45.553503 -390.922494) (xy 45.600427 -390.940108) (xy 45.644155 -390.964601)
			(xy 45.683688 -390.995411) (xy 45.718119 -391.031834) (xy 45.746659 -391.073035) (xy 45.768657 -391.118071)
			(xy 45.783606 -391.16591) (xy 45.791166 -391.215458) (xy 45.791628 -391.240518) (xy 45.791118 -391.266505)
			(xy 45.782988 -391.31784) (xy 45.766927 -391.36727) (xy 45.743331 -391.41358) (xy 45.712781 -391.455628)
			(xy 45.67603 -391.492379) (xy 45.633982 -391.522929) (xy 45.587672 -391.546525) (xy 45.538242 -391.562586)
			(xy 45.486907 -391.570716) (xy 45.434933 -391.570716) (xy 45.383598 -391.562586) (xy 45.334168 -391.546525)
			(xy 45.287858 -391.522929) (xy 45.24581 -391.492379) (xy 45.209059 -391.455628) (xy 45.178509 -391.41358)
			(xy 45.154913 -391.36727) (xy 45.138852 -391.31784) (xy 45.130722 -391.266505) (xy 45.130212 -391.240518)
			(xy 45.130212 -391.240264) (xy 45.130643 -391.216214) (xy 45.137633 -391.168624) (xy 45.151431 -391.122545)
			(xy 45.1612 -391.100564) (xy 45.166534 -391.089134) (xy 45.165264 -391.063988) (xy 45.108876 -390.970008)
			(xy 45.087286 -390.957054) (xy 45.07484 -390.956292) (xy 45.049845 -390.954436) (xy 45.000801 -390.944105)
			(xy 44.953878 -390.926492) (xy 44.91015 -390.902001) (xy 44.870618 -390.871191) (xy 44.836187 -390.83477)
			(xy 44.807646 -390.79357) (xy 44.785648 -390.748536) (xy 44.770698 -390.700698) (xy 44.763136 -390.651152)
			(xy 44.762674 -390.626092) (xy 40.843708 -390.626092) (xy 40.843708 -391.2235) (xy 41.439082 -391.2235)
			(xy 41.443153 -391.167878) (xy 41.455279 -391.113441) (xy 41.475202 -391.06135) (xy 41.502498 -391.012715)
			(xy 41.536584 -390.968572) (xy 41.576733 -390.929863) (xy 41.622091 -390.897412) (xy 41.671691 -390.871911)
			(xy 41.724475 -390.853904) (xy 41.779318 -390.843774) (xy 41.835052 -390.841737) (xy 41.890489 -390.847837)
			(xy 41.944446 -390.861943) (xy 41.995775 -390.883755) (xy 42.043381 -390.912809) (xy 42.086249 -390.948484)
			(xy 42.123466 -390.990021) (xy 42.154239 -391.036534) (xy 42.177911 -391.087031) (xy 42.193979 -391.140438)
			(xy 42.202099 -391.195614) (xy 42.202608 -391.2235) (xy 42.202099 -391.251386) (xy 42.193979 -391.306562)
			(xy 42.177911 -391.359969) (xy 42.154239 -391.410466) (xy 42.123466 -391.456979) (xy 42.086249 -391.498516)
			(xy 42.043381 -391.534191) (xy 41.995775 -391.563245) (xy 41.944446 -391.585057) (xy 41.890489 -391.599163)
			(xy 41.835052 -391.605263) (xy 41.779318 -391.603226) (xy 41.724475 -391.593096) (xy 41.671691 -391.575089)
			(xy 41.622091 -391.549588) (xy 41.576733 -391.517137) (xy 41.536584 -391.478428) (xy 41.502498 -391.434285)
			(xy 41.475202 -391.38565) (xy 41.455279 -391.333559) (xy 41.443153 -391.279122) (xy 41.439082 -391.2235)
			(xy 40.843708 -391.2235) (xy 40.843708 -391.939051) (xy 42.857395 -391.939051) (xy 42.857395 -391.884549)
			(xy 42.865152 -391.830602) (xy 42.880507 -391.778308) (xy 42.903149 -391.728732) (xy 42.932616 -391.682883)
			(xy 42.968308 -391.641694) (xy 43.009499 -391.606004) (xy 43.055349 -391.576539) (xy 43.104927 -391.5539)
			(xy 43.157222 -391.538548) (xy 43.211169 -391.530794) (xy 43.23842 -391.530332) (xy 43.267535 -391.530871)
			(xy 43.325091 -391.539704) (xy 43.380637 -391.557177) (xy 43.432885 -391.582885) (xy 43.480621 -391.616231)
			(xy 43.522739 -391.65644) (xy 43.540934 -391.679176) (xy 43.550639 -391.690819) (xy 43.575361 -391.708326)
			(xy 43.604129 -391.717815) (xy 43.634415 -391.718452) (xy 43.663558 -391.710183) (xy 43.688995 -391.693733)
			(xy 43.708492 -391.670548) (xy 43.714924 -391.656824) (xy 43.726242 -391.631265) (xy 43.755266 -391.583495)
			(xy 43.790949 -391.540469) (xy 43.832525 -391.503108) (xy 43.879107 -391.472212) (xy 43.929697 -391.44844)
			(xy 43.983214 -391.432302) (xy 44.038512 -391.424143) (xy 44.06646 -391.423652) (xy 44.093712 -391.424193)
			(xy 44.147661 -391.431944) (xy 44.199959 -391.447295) (xy 44.249539 -391.469933) (xy 44.295392 -391.499397)
			(xy 44.336585 -391.535087) (xy 44.372279 -391.576276) (xy 44.401748 -391.622126) (xy 44.424391 -391.671704)
			(xy 44.439747 -391.723999) (xy 44.447505 -391.777948) (xy 44.447505 -391.832452) (xy 44.441969 -391.870946)
			(xy 46.122844 -391.870946) (xy 46.122844 -391.616184) (xy 46.131988 -391.616184) (xy 46.142011 -391.61577)
			(xy 46.16053 -391.608101) (xy 46.174704 -391.593927) (xy 46.182371 -391.575407) (xy 46.182788 -391.565384)
			(xy 46.182788 -391.401808) (xy 46.183294 -391.391802) (xy 46.190949 -391.373313) (xy 46.205096 -391.35916)
			(xy 46.223583 -391.351498) (xy 46.233588 -391.351008) (xy 46.74108 -391.351008) (xy 46.751101 -391.351436)
			(xy 46.769619 -391.359101) (xy 46.783792 -391.373271) (xy 46.791461 -391.391787) (xy 46.79188 -391.401808)
			(xy 46.79188 -391.589514) (xy 46.808136 -391.61466) (xy 46.821852 -391.620756) (xy 46.830579 -391.625113)
			(xy 46.844094 -391.639159) (xy 46.851382 -391.657238) (xy 46.851824 -391.666984) (xy 46.851824 -391.870946)
			(xy 46.85128 -391.893539) (xy 46.841814 -391.937721) (xy 46.823273 -391.978927) (xy 46.796484 -392.015314)
			(xy 46.779942 -392.030712) (xy 46.779688 -392.030966) (xy 46.773182 -392.037191) (xy 46.764737 -392.053084)
			(xy 46.763178 -392.061954) (xy 46.762416 -392.068304) (xy 46.761908 -392.074908) (xy 46.761908 -392.154664)
			(xy 46.765464 -392.167872) (xy 46.76902 -392.173714) (xy 46.782767 -392.198309) (xy 46.802349 -392.251134)
			(xy 46.812327 -392.306582) (xy 46.812962 -392.33475) (xy 46.812472 -392.359739) (xy 46.804653 -392.409102)
			(xy 46.789209 -392.456634) (xy 46.766519 -392.501166) (xy 46.737143 -392.541599) (xy 46.701803 -392.576939)
			(xy 46.66137 -392.606315) (xy 46.616838 -392.629005) (xy 46.569306 -392.644449) (xy 46.519943 -392.652268)
			(xy 46.469965 -392.652268) (xy 46.420602 -392.644449) (xy 46.37307 -392.629005) (xy 46.328538 -392.606315)
			(xy 46.288105 -392.576939) (xy 46.252765 -392.541599) (xy 46.223389 -392.501166) (xy 46.200699 -392.456634)
			(xy 46.185255 -392.409102) (xy 46.177436 -392.359739) (xy 46.176946 -392.33475) (xy 46.177619 -392.305549)
			(xy 46.188269 -392.248126) (xy 46.209223 -392.193612) (xy 46.223936 -392.16838) (xy 46.228453 -392.160331)
			(xy 46.23197 -392.142228) (xy 46.230794 -392.133074) (xy 46.219364 -392.067034) (xy 46.217458 -392.058187)
			(xy 46.208351 -392.042563) (xy 46.201584 -392.036554) (xy 46.201584 -392.0363) (xy 46.20133 -392.0363)
			(xy 46.186938 -392.023997) (xy 46.162286 -391.995266) (xy 46.143086 -391.962639) (xy 46.129938 -391.927138)
			(xy 46.123256 -391.889875) (xy 46.122844 -391.870946) (xy 44.441969 -391.870946) (xy 44.439747 -391.886401)
			(xy 44.424391 -391.938696) (xy 44.401748 -391.988274) (xy 44.372279 -392.034124) (xy 44.336585 -392.075313)
			(xy 44.295392 -392.111003) (xy 44.249539 -392.140467) (xy 44.199959 -392.163105) (xy 44.147661 -392.178456)
			(xy 44.093712 -392.186207) (xy 44.06646 -392.186668) (xy 44.037344 -392.186143) (xy 43.979788 -392.177307)
			(xy 43.924241 -392.159831) (xy 43.871994 -392.134121) (xy 43.824258 -392.100773) (xy 43.782141 -392.060561)
			(xy 43.763946 -392.037824) (xy 43.754266 -392.026159) (xy 43.729537 -392.008653) (xy 43.700763 -391.999165)
			(xy 43.670472 -391.998531) (xy 43.641326 -392.006804) (xy 43.615886 -392.023259) (xy 43.596388 -392.046449)
			(xy 43.589956 -392.060176) (xy 43.578654 -392.085742) (xy 43.549628 -392.133513) (xy 43.513943 -392.176539)
			(xy 43.472364 -392.2139) (xy 43.42578 -392.244795) (xy 43.375188 -392.268565) (xy 43.321669 -392.284701)
			(xy 43.266369 -392.292858) (xy 43.23842 -392.293348) (xy 43.211169 -392.292806) (xy 43.157222 -392.285052)
			(xy 43.104927 -392.2697) (xy 43.055349 -392.247061) (xy 43.009499 -392.217596) (xy 42.968308 -392.181906)
			(xy 42.932616 -392.140717) (xy 42.903149 -392.094868) (xy 42.880507 -392.045292) (xy 42.865152 -391.992998)
			(xy 42.857395 -391.939051) (xy 40.843708 -391.939051) (xy 40.843708 -393.293346) (xy 47.435008 -393.293346)
			(xy 47.435008 -392.42873) (xy 47.435446 -392.403262) (xy 47.442248 -392.352782) (xy 47.455709 -392.303657)
			(xy 47.47559 -392.256761) (xy 47.501535 -392.212928) (xy 47.533085 -392.172939) (xy 47.551086 -392.154918)
			(xy 47.55769 -392.148568) (xy 47.565564 -392.131804) (xy 47.572422 -392.04646) (xy 47.567342 -392.02868)
			(xy 47.561754 -392.021314) (xy 47.546906 -392.000564) (xy 47.52327 -391.955351) (xy 47.507167 -391.90694)
			(xy 47.499014 -391.856577) (xy 47.498508 -391.831068) (xy 47.498508 -391.830814) (xy 47.498998 -391.805825)
			(xy 47.506817 -391.756462) (xy 47.522261 -391.70893) (xy 47.544951 -391.664398) (xy 47.574327 -391.623965)
			(xy 47.609667 -391.588625) (xy 47.6501 -391.559249) (xy 47.694632 -391.536559) (xy 47.742164 -391.521115)
			(xy 47.791527 -391.513296) (xy 47.841505 -391.513296) (xy 47.890868 -391.521115) (xy 47.9384 -391.536559)
			(xy 47.982932 -391.559249) (xy 48.023365 -391.588625) (xy 48.058705 -391.623965) (xy 48.088081 -391.664398)
			(xy 48.110771 -391.70893) (xy 48.126215 -391.756462) (xy 48.134034 -391.805825) (xy 48.134524 -391.830814)
			(xy 48.134524 -391.831068) (xy 48.134026 -391.856577) (xy 48.12585 -391.906936) (xy 48.109749 -391.955347)
			(xy 48.086135 -392.000572) (xy 48.071278 -392.021314) (xy 48.06569 -392.02868) (xy 48.06061 -392.04646)
			(xy 48.067468 -392.131804) (xy 48.075342 -392.148568) (xy 48.081946 -392.154918) (xy 48.099944 -392.172941)
			(xy 48.131485 -392.212935) (xy 48.157427 -392.256768) (xy 48.177307 -392.303663) (xy 48.190772 -392.352786)
			(xy 48.197583 -392.403263) (xy 48.198024 -392.42873) (xy 48.198024 -393.293346) (xy 48.634904 -393.293346)
			(xy 48.634904 -392.42873) (xy 48.635343 -392.403262) (xy 48.642145 -392.352782) (xy 48.655606 -392.303657)
			(xy 48.675486 -392.256761) (xy 48.701432 -392.212928) (xy 48.732981 -392.172939) (xy 48.750982 -392.154918)
			(xy 48.75784 -392.148568) (xy 48.765714 -392.131804) (xy 48.77181 -392.05535) (xy 48.772155 -392.046285)
			(xy 48.767214 -392.028845) (xy 48.762158 -392.021314) (xy 48.761904 -392.02106) (xy 48.747045 -392.000319)
			(xy 48.723418 -391.9551) (xy 48.707321 -391.906687) (xy 48.699166 -391.856324) (xy 48.698658 -391.830814)
			(xy 48.699148 -391.805825) (xy 48.706967 -391.756462) (xy 48.722411 -391.70893) (xy 48.745101 -391.664398)
			(xy 48.774477 -391.623965) (xy 48.809817 -391.588625) (xy 48.85025 -391.559249) (xy 48.894782 -391.536559)
			(xy 48.942314 -391.521115) (xy 48.991677 -391.513296) (xy 49.041655 -391.513296) (xy 49.091018 -391.521115)
			(xy 49.13855 -391.536559) (xy 49.183082 -391.559249) (xy 49.223515 -391.588625) (xy 49.258855 -391.623965)
			(xy 49.288231 -391.664398) (xy 49.310921 -391.70893) (xy 49.326365 -391.756462) (xy 49.334184 -391.805825)
			(xy 49.334674 -391.830814) (xy 49.334155 -391.856366) (xy 49.325969 -391.906811) (xy 49.309809 -391.955294)
			(xy 49.286094 -392.000564) (xy 49.271174 -392.021314) (xy 49.265586 -392.02868) (xy 49.260506 -392.04646)
			(xy 49.266602 -392.122914) (xy 49.267703 -392.131912) (xy 49.275373 -392.14832) (xy 49.281588 -392.154918)
			(xy 49.281842 -392.155172) (xy 49.299831 -392.173233) (xy 49.331397 -392.213258) (xy 49.357353 -392.257129)
			(xy 49.377238 -392.304066) (xy 49.390697 -392.353231) (xy 49.397492 -392.403751) (xy 49.39792 -392.429238)
			(xy 49.39792 -393.292838) (xy 49.8348 -393.292838) (xy 49.8348 -392.429238) (xy 49.835237 -392.403718)
			(xy 49.842026 -392.353133) (xy 49.855502 -392.303905) (xy 49.875423 -392.256915) (xy 49.901433 -392.213001)
			(xy 49.933068 -392.172949) (xy 49.951132 -392.154918) (xy 49.957736 -392.148568) (xy 49.96561 -392.131804)
			(xy 49.972468 -392.04646) (xy 49.967388 -392.02868) (xy 49.9618 -392.021314) (xy 49.946946 -392.000569)
			(xy 49.923312 -391.955354) (xy 49.907212 -391.906941) (xy 49.89906 -391.856578) (xy 49.898554 -391.831068)
			(xy 49.898554 -391.830814) (xy 49.899044 -391.805825) (xy 49.906863 -391.756462) (xy 49.922307 -391.70893)
			(xy 49.944997 -391.664398) (xy 49.974373 -391.623965) (xy 50.009713 -391.588625) (xy 50.050146 -391.559249)
			(xy 50.094678 -391.536559) (xy 50.14221 -391.521115) (xy 50.191573 -391.513296) (xy 50.241551 -391.513296)
			(xy 50.290914 -391.521115) (xy 50.338446 -391.536559) (xy 50.382978 -391.559249) (xy 50.423411 -391.588625)
			(xy 50.458751 -391.623965) (xy 50.488127 -391.664398) (xy 50.510817 -391.70893) (xy 50.526261 -391.756462)
			(xy 50.53408 -391.805825) (xy 50.53457 -391.830814) (xy 50.53457 -391.831068) (xy 50.534063 -391.856576)
			(xy 50.525888 -391.906935) (xy 50.509789 -391.955346) (xy 50.486179 -392.000571) (xy 50.471324 -392.021314)
			(xy 50.465736 -392.02868) (xy 50.460656 -392.04646) (xy 50.467514 -392.131804) (xy 50.475388 -392.148568)
			(xy 50.481992 -392.154918) (xy 50.500033 -392.17297) (xy 50.531662 -392.213023) (xy 50.557671 -392.256934)
			(xy 50.577597 -392.303919) (xy 50.591085 -392.353141) (xy 50.597894 -392.40372) (xy 50.598324 -392.429238)
			(xy 50.598324 -393.292838) (xy 51.034696 -393.292838) (xy 51.034696 -392.429238) (xy 51.035135 -392.403718)
			(xy 51.041924 -392.353133) (xy 51.055399 -392.303906) (xy 51.07532 -392.256915) (xy 51.10133 -392.213001)
			(xy 51.132965 -392.172949) (xy 51.151028 -392.154918) (xy 51.157632 -392.148568) (xy 51.165506 -392.131804)
			(xy 51.172364 -392.04646) (xy 51.167284 -392.02868) (xy 51.161696 -392.021314) (xy 51.146841 -392.000569)
			(xy 51.123208 -391.955354) (xy 51.107108 -391.906941) (xy 51.098956 -391.856578) (xy 51.09845 -391.831068)
			(xy 51.09845 -391.830814) (xy 51.09894 -391.805825) (xy 51.106759 -391.756462) (xy 51.122203 -391.70893)
			(xy 51.144893 -391.664398) (xy 51.174269 -391.623965) (xy 51.209609 -391.588625) (xy 51.250042 -391.559249)
			(xy 51.294574 -391.536559) (xy 51.342106 -391.521115) (xy 51.391469 -391.513296) (xy 51.441447 -391.513296)
			(xy 51.49081 -391.521115) (xy 51.538342 -391.536559) (xy 51.582874 -391.559249) (xy 51.623307 -391.588625)
			(xy 51.658647 -391.623965) (xy 51.688023 -391.664398) (xy 51.710713 -391.70893) (xy 51.726157 -391.756462)
			(xy 51.733976 -391.805825) (xy 51.734466 -391.830814) (xy 51.734466 -391.831068) (xy 51.73396 -391.856576)
			(xy 51.725785 -391.906935) (xy 51.709686 -391.955346) (xy 51.686076 -392.000571) (xy 51.67122 -392.021314)
			(xy 51.665632 -392.02868) (xy 51.660552 -392.04646) (xy 51.66741 -392.131804) (xy 51.675284 -392.148568)
			(xy 51.681888 -392.154918) (xy 51.699928 -392.172971) (xy 51.731557 -392.213024) (xy 51.757567 -392.256935)
			(xy 51.777493 -392.30392) (xy 51.790981 -392.353141) (xy 51.79779 -392.40372) (xy 51.79822 -392.429238)
			(xy 51.79822 -393.292838) (xy 51.797709 -393.321291) (xy 51.789259 -393.377567) (xy 51.772554 -393.431967)
			(xy 51.747962 -393.483286) (xy 51.716027 -393.530388) (xy 51.697128 -393.551664) (xy 51.69123 -393.55865)
			(xy 51.684326 -393.575565) (xy 51.683666 -393.584684) (xy 51.68265 -393.615418) (xy 51.682788 -393.624588)
			(xy 51.688772 -393.641908) (xy 51.694334 -393.6492) (xy 51.709698 -393.668536) (xy 51.735513 -393.71064)
			(xy 51.755308 -393.755887) (xy 51.76871 -393.803421) (xy 51.775466 -393.852344) (xy 51.775868 -393.877038)
			(xy 51.775366 -393.903934) (xy 51.767348 -393.957126) (xy 51.751492 -394.008529) (xy 51.728153 -394.056995)
			(xy 51.69785 -394.101441) (xy 51.661262 -394.140874) (xy 51.619205 -394.174413) (xy 51.572619 -394.201309)
			(xy 51.522545 -394.220962) (xy 51.4701 -394.232932) (xy 51.416458 -394.236952) (xy 51.362816 -394.232932)
			(xy 51.310371 -394.220962) (xy 51.260297 -394.201309) (xy 51.213711 -394.174413) (xy 51.171654 -394.140874)
			(xy 51.135066 -394.101441) (xy 51.104763 -394.056995) (xy 51.081424 -394.008529) (xy 51.065568 -393.957126)
			(xy 51.05755 -393.903934) (xy 51.057048 -393.877038) (xy 51.0575 -393.852349) (xy 51.064286 -393.803439)
			(xy 51.077694 -393.755916) (xy 51.097472 -393.710672) (xy 51.12325 -393.668556) (xy 51.138582 -393.6492)
			(xy 51.144106 -393.641886) (xy 51.150102 -393.624581) (xy 51.150266 -393.615418) (xy 51.14925 -393.584684)
			(xy 51.148599 -393.57556) (xy 51.141711 -393.558633) (xy 51.135788 -393.551664) (xy 51.116862 -393.530407)
			(xy 51.084902 -393.483315) (xy 51.060302 -393.431993) (xy 51.04361 -393.377583) (xy 51.035198 -393.321295)
			(xy 51.034696 -393.292838) (xy 50.598324 -393.292838) (xy 50.597772 -393.322002) (xy 50.58885 -393.379644)
			(xy 50.571265 -393.435259) (xy 50.545427 -393.487553) (xy 50.511936 -393.535309) (xy 50.492152 -393.556744)
			(xy 50.48599 -393.563824) (xy 50.478835 -393.581162) (xy 50.478182 -393.590526) (xy 50.476404 -393.659106)
			(xy 50.476547 -393.668363) (xy 50.482681 -393.685816) (xy 50.488342 -393.693142) (xy 50.48885 -393.69365)
			(xy 50.505207 -393.713261) (xy 50.532738 -393.756271) (xy 50.553895 -393.802749) (xy 50.568249 -393.851757)
			(xy 50.575511 -393.902305) (xy 50.575972 -393.927838) (xy 50.57547 -393.954734) (xy 50.567452 -394.007926)
			(xy 50.551596 -394.059329) (xy 50.528257 -394.107795) (xy 50.497954 -394.152241) (xy 50.461366 -394.191674)
			(xy 50.419309 -394.225213) (xy 50.372723 -394.252109) (xy 50.322649 -394.271762) (xy 50.270204 -394.283732)
			(xy 50.216562 -394.287752) (xy 50.16292 -394.283732) (xy 50.110475 -394.271762) (xy 50.060401 -394.252109)
			(xy 50.013815 -394.225213) (xy 49.971758 -394.191674) (xy 49.93517 -394.152241) (xy 49.904867 -394.107795)
			(xy 49.881528 -394.059329) (xy 49.865672 -394.007926) (xy 49.857654 -393.954734) (xy 49.857152 -393.927838)
			(xy 49.857628 -393.90227) (xy 49.864904 -393.851655) (xy 49.8793 -393.802588) (xy 49.900524 -393.756064)
			(xy 49.928143 -393.713029) (xy 49.944528 -393.693396) (xy 49.944782 -393.693142) (xy 49.950447 -393.685822)
			(xy 49.956557 -393.668362) (xy 49.95672 -393.659106) (xy 49.954688 -393.580874) (xy 49.947576 -393.563856)
			(xy 49.940972 -393.556744) (xy 49.921198 -393.5353) (xy 49.887702 -393.48755) (xy 49.861864 -393.435258)
			(xy 49.844283 -393.379644) (xy 49.835371 -393.322001) (xy 49.8348 -393.292838) (xy 49.39792 -393.292838)
			(xy 49.39792 -393.293346) (xy 49.397414 -393.321161) (xy 49.38931 -393.376196) (xy 49.373295 -393.429471)
			(xy 49.34971 -393.479853) (xy 49.319054 -393.526273) (xy 49.300892 -393.547346) (xy 49.29505 -393.55395)
			(xy 49.288192 -393.570714) (xy 49.28616 -393.645136) (xy 49.286266 -393.654042) (xy 49.291866 -393.670936)
			(xy 49.297082 -393.678156) (xy 49.297336 -393.67841) (xy 49.312066 -393.697542) (xy 49.33682 -393.739)
			(xy 49.355796 -393.7834) (xy 49.368653 -393.829942) (xy 49.375158 -393.877788) (xy 49.375568 -393.90193)
			(xy 49.375568 -393.902438) (xy 49.375066 -393.929315) (xy 49.367054 -393.98247) (xy 49.35121 -394.033836)
			(xy 49.327886 -394.082268) (xy 49.297605 -394.126682) (xy 49.261043 -394.166087) (xy 49.219015 -394.199603)
			(xy 49.172462 -394.22648) (xy 49.122423 -394.246119) (xy 49.070016 -394.25808) (xy 49.016412 -394.262098)
			(xy 48.962808 -394.25808) (xy 48.910401 -394.246119) (xy 48.860362 -394.22648) (xy 48.813809 -394.199603)
			(xy 48.771781 -394.166087) (xy 48.735219 -394.126682) (xy 48.704938 -394.082268) (xy 48.681614 -394.033836)
			(xy 48.66577 -393.98247) (xy 48.657758 -393.929315) (xy 48.657256 -393.902438) (xy 48.657256 -393.90193)
			(xy 48.657654 -393.877787) (xy 48.664159 -393.82994) (xy 48.677017 -393.783397) (xy 48.695995 -393.738996)
			(xy 48.720751 -393.697538) (xy 48.735488 -393.67841) (xy 48.735742 -393.678156) (xy 48.741015 -393.670969)
			(xy 48.746598 -393.65405) (xy 48.746664 -393.645136) (xy 48.744632 -393.570714) (xy 48.737774 -393.55395)
			(xy 48.731932 -393.547346) (xy 48.713796 -393.526254) (xy 48.683154 -393.479831) (xy 48.659574 -393.429452)
			(xy 48.643553 -393.376185) (xy 48.635432 -393.321158) (xy 48.634904 -393.293346) (xy 48.198024 -393.293346)
			(xy 48.197517 -393.32116) (xy 48.189413 -393.376196) (xy 48.173399 -393.429471) (xy 48.149813 -393.479853)
			(xy 48.119158 -393.526273) (xy 48.100996 -393.547346) (xy 48.095154 -393.55395) (xy 48.088296 -393.570714)
			(xy 48.086264 -393.645136) (xy 48.086369 -393.654042) (xy 48.091969 -393.670936) (xy 48.097186 -393.678156)
			(xy 48.09744 -393.67841) (xy 48.112171 -393.697542) (xy 48.136924 -393.739) (xy 48.1559 -393.7834)
			(xy 48.168757 -393.829942) (xy 48.175262 -393.877788) (xy 48.175672 -393.90193) (xy 48.175672 -393.902438)
			(xy 48.17517 -393.929315) (xy 48.167158 -393.98247) (xy 48.151314 -394.033836) (xy 48.12799 -394.082268)
			(xy 48.097709 -394.126682) (xy 48.061147 -394.166087) (xy 48.019119 -394.199603) (xy 47.972566 -394.22648)
			(xy 47.922527 -394.246119) (xy 47.87012 -394.25808) (xy 47.816516 -394.262098) (xy 47.762912 -394.25808)
			(xy 47.710505 -394.246119) (xy 47.660466 -394.22648) (xy 47.613913 -394.199603) (xy 47.571885 -394.166087)
			(xy 47.535323 -394.126682) (xy 47.505042 -394.082268) (xy 47.481718 -394.033836) (xy 47.465874 -393.98247)
			(xy 47.457862 -393.929315) (xy 47.45736 -393.902438) (xy 47.45736 -393.90193) (xy 47.457757 -393.877787)
			(xy 47.464262 -393.82994) (xy 47.47712 -393.783397) (xy 47.496099 -393.738996) (xy 47.520855 -393.697538)
			(xy 47.535592 -393.67841) (xy 47.535846 -393.678156) (xy 47.541119 -393.670969) (xy 47.546702 -393.65405)
			(xy 47.546768 -393.645136) (xy 47.544736 -393.570714) (xy 47.537878 -393.55395) (xy 47.532036 -393.547346)
			(xy 47.513901 -393.526254) (xy 47.483259 -393.47983) (xy 47.459678 -393.429452) (xy 47.443657 -393.376185)
			(xy 47.435536 -393.321158) (xy 47.435008 -393.293346) (xy 40.843708 -393.293346) (xy 40.843708 -393.799314)
			(xy 40.84319 -393.830946) (xy 40.834934 -393.893668) (xy 40.818565 -393.954777) (xy 40.794362 -394.013227)
			(xy 40.76274 -394.06802) (xy 40.724239 -394.118219) (xy 40.70223 -394.140944) (xy 40.512746 -394.330174)
			(xy 40.505906 -394.337574) (xy 40.498191 -394.356173) (xy 40.49776 -394.366242) (xy 40.49776 -395.760194)
			(xy 40.498184 -395.770263) (xy 40.505903 -395.788864) (xy 40.512746 -395.796262) (xy 40.914574 -396.19809)
			(xy 40.921976 -396.204926) (xy 40.940574 -396.212635) (xy 40.950642 -396.213076) (xy 43.610784 -396.213076)
			(xy 43.620834 -396.213582) (xy 43.639394 -396.221305) (xy 43.646852 -396.228062) (xy 43.785282 -396.366492)
			(xy 48.627536 -396.366492) (xy 48.631607 -396.31087) (xy 48.643733 -396.256433) (xy 48.663656 -396.204342)
			(xy 48.690952 -396.155707) (xy 48.725038 -396.111564) (xy 48.765187 -396.072855) (xy 48.810545 -396.040404)
			(xy 48.860145 -396.014903) (xy 48.912929 -395.996896) (xy 48.967772 -395.986766) (xy 49.023506 -395.984729)
			(xy 49.078943 -395.990829) (xy 49.1329 -396.004935) (xy 49.184229 -396.026747) (xy 49.231835 -396.055801)
			(xy 49.274703 -396.091476) (xy 49.31192 -396.133013) (xy 49.342693 -396.179526) (xy 49.366365 -396.230023)
			(xy 49.382433 -396.28343) (xy 49.390553 -396.338606) (xy 49.391062 -396.366492) (xy 49.390553 -396.394378)
			(xy 49.382433 -396.449554) (xy 49.366365 -396.502961) (xy 49.342693 -396.553458) (xy 49.31192 -396.599971)
			(xy 49.274703 -396.641508) (xy 49.231835 -396.677183) (xy 49.184229 -396.706237) (xy 49.1329 -396.728049)
			(xy 49.078943 -396.742155) (xy 49.023506 -396.748255) (xy 48.967772 -396.746218) (xy 48.912929 -396.736088)
			(xy 48.860145 -396.718081) (xy 48.810545 -396.69258) (xy 48.765187 -396.660129) (xy 48.725038 -396.62142)
			(xy 48.690952 -396.577277) (xy 48.663656 -396.528642) (xy 48.643733 -396.476551) (xy 48.631607 -396.422114)
			(xy 48.627536 -396.366492) (xy 43.785282 -396.366492) (xy 44.16679 -396.748) (xy 44.173637 -396.755398)
			(xy 44.181373 -396.773996) (xy 44.181776 -396.784068) (xy 44.181776 -397.96466) (xy 44.182209 -397.974726)
			(xy 44.189936 -397.993317) (xy 44.196762 -398.000728) (xy 44.33951 -398.143476) (xy 44.346908 -398.150323)
			(xy 44.365506 -398.158058) (xy 44.375578 -398.158462) (xy 65.732914 -398.158462)
		)
		(stroke
			(width 0)
			(type solid)
		)
		(fill yes)
		(layer "B.Cu")
		(net "P0V9_CPU1_RT0_2A")
	)
	(gr_poly
		(pts
			(xy 377.519184 -293.036752) (xy 377.528232 -293.036391) (xy 377.545203 -293.030113) (xy 377.558938 -293.018331)
			(xy 377.563634 -293.01059) (xy 377.612402 -292.92296) (xy 377.611894 -292.895274) (xy 377.604528 -292.88359)
			(xy 377.589593 -292.8582) (xy 377.568295 -292.803288) (xy 377.557448 -292.745398) (xy 377.556776 -292.71595)
			(xy 377.557266 -292.690961) (xy 377.565085 -292.641598) (xy 377.580529 -292.594066) (xy 377.603219 -292.549534)
			(xy 377.632595 -292.509101) (xy 377.667935 -292.473761) (xy 377.708368 -292.444385) (xy 377.7529 -292.421695)
			(xy 377.800432 -292.406251) (xy 377.849795 -292.398432) (xy 377.899773 -292.398432) (xy 377.949136 -292.406251)
			(xy 377.996668 -292.421695) (xy 378.0412 -292.444385) (xy 378.081633 -292.473761) (xy 378.116973 -292.509101)
			(xy 378.146349 -292.549534) (xy 378.169039 -292.594066) (xy 378.184483 -292.641598) (xy 378.192302 -292.690961)
			(xy 378.192792 -292.71595) (xy 378.192156 -292.745403) (xy 378.181324 -292.803305) (xy 378.160022 -292.858224)
			(xy 378.14504 -292.88359) (xy 378.137674 -292.895274) (xy 378.137166 -292.92296) (xy 378.185934 -293.01059)
			(xy 378.190639 -293.018324) (xy 378.204368 -293.030106) (xy 378.221338 -293.036373) (xy 378.230384 -293.036752)
			(xy 379.399292 -293.036752) (xy 379.408339 -293.03639) (xy 379.425308 -293.03011) (xy 379.439041 -293.018328)
			(xy 379.443742 -293.01059) (xy 379.49251 -292.92296) (xy 379.492002 -292.895274) (xy 379.484636 -292.88359)
			(xy 379.469701 -292.8582) (xy 379.448402 -292.803289) (xy 379.437554 -292.745399) (xy 379.436884 -292.71595)
			(xy 379.437374 -292.690961) (xy 379.445193 -292.641598) (xy 379.460637 -292.594066) (xy 379.483327 -292.549534)
			(xy 379.512703 -292.509101) (xy 379.548043 -292.473761) (xy 379.588476 -292.444385) (xy 379.633008 -292.421695)
			(xy 379.68054 -292.406251) (xy 379.729903 -292.398432) (xy 379.779881 -292.398432) (xy 379.829244 -292.406251)
			(xy 379.876776 -292.421695) (xy 379.921308 -292.444385) (xy 379.961741 -292.473761) (xy 379.997081 -292.509101)
			(xy 380.026457 -292.549534) (xy 380.049147 -292.594066) (xy 380.064591 -292.641598) (xy 380.07241 -292.690961)
			(xy 380.0729 -292.71595) (xy 380.072264 -292.745403) (xy 380.061433 -292.803305) (xy 380.040131 -292.858225)
			(xy 380.025148 -292.88359) (xy 380.017782 -292.895274) (xy 380.017274 -292.92296) (xy 380.066042 -293.01059)
			(xy 380.070748 -293.018323) (xy 380.084476 -293.030103) (xy 380.101446 -293.036368) (xy 380.110492 -293.036752)
			(xy 380.339346 -293.036752) (xy 380.348388 -293.036381) (xy 380.365343 -293.030089) (xy 380.379061 -293.018304)
			(xy 380.383796 -293.01059) (xy 380.432564 -292.92296) (xy 380.432056 -292.895274) (xy 380.42469 -292.88359)
			(xy 380.409753 -292.858201) (xy 380.388451 -292.80329) (xy 380.377601 -292.745399) (xy 380.376938 -292.71595)
			(xy 380.377399 -292.690958) (xy 380.385212 -292.641587) (xy 380.400654 -292.594047) (xy 380.423343 -292.549509)
			(xy 380.452722 -292.50907) (xy 380.488067 -292.473725) (xy 380.528506 -292.444346) (xy 380.573044 -292.421655)
			(xy 380.620583 -292.406213) (xy 380.669954 -292.3984) (xy 380.694946 -292.397942) (xy 380.719544 -292.398404)
			(xy 380.768153 -292.405984) (xy 380.815015 -292.420956) (xy 380.859015 -292.442962) (xy 380.899103 -292.47148)
			(xy 380.934323 -292.505828) (xy 380.963836 -292.545188) (xy 380.986939 -292.588621) (xy 381.003082 -292.635094)
			(xy 381.011878 -292.683497) (xy 381.012954 -292.708076) (xy 381.013462 -292.72357) (xy 381.03048 -292.748208)
			(xy 381.129286 -292.787832) (xy 381.13866 -292.791117) (xy 381.158503 -292.791005) (xy 381.17681 -292.783348)
			(xy 381.18415 -292.776656) (xy 381.32766 -292.633146) (xy 381.330454 -292.623494) (xy 381.330454 -292.319202)
			(xy 381.329916 -292.308182) (xy 381.320704 -292.288159) (xy 381.312674 -292.280594) (xy 381.246888 -292.22446)
			(xy 381.225552 -292.218364) (xy 381.21463 -292.220142) (xy 381.202264 -292.221948) (xy 381.177343 -292.223858)
			(xy 381.164846 -292.223952) (xy 381.139849 -292.223491) (xy 381.09047 -292.215677) (xy 381.042921 -292.200233)
			(xy 380.998373 -292.177541) (xy 380.957925 -292.148159) (xy 380.922571 -292.11281) (xy 380.893183 -292.072366)
			(xy 380.870485 -292.027822) (xy 380.855034 -291.980275) (xy 380.847213 -291.930897) (xy 380.847213 -291.880903)
			(xy 380.855034 -291.831525) (xy 380.870485 -291.783978) (xy 380.893183 -291.739434) (xy 380.922571 -291.69899)
			(xy 380.957925 -291.663641) (xy 380.998373 -291.634259) (xy 381.042921 -291.611567) (xy 381.09047 -291.596123)
			(xy 381.139849 -291.588309) (xy 381.164846 -291.587936) (xy 381.177343 -291.588024) (xy 381.202265 -291.589928)
			(xy 381.21463 -291.591746) (xy 381.225552 -291.593524) (xy 381.246888 -291.587428) (xy 381.312674 -291.531294)
			(xy 381.3207 -291.523723) (xy 381.329923 -291.503706) (xy 381.330454 -291.492686) (xy 381.330454 -291.188648)
			(xy 381.328676 -291.18179) (xy 381.323114 -291.160764) (xy 381.317129 -291.117684) (xy 381.316738 -291.095938)
			(xy 381.317146 -291.074193) (xy 381.323137 -291.031117) (xy 381.328676 -291.010086) (xy 381.330454 -291.003228)
			(xy 381.330454 -290.69919) (xy 381.329913 -290.688171) (xy 381.320699 -290.668152) (xy 381.312674 -290.660582)
			(xy 381.246888 -290.604448) (xy 381.225552 -290.598352) (xy 381.21463 -290.60013) (xy 381.202264 -290.601936)
			(xy 381.177343 -290.603846) (xy 381.164846 -290.60394) (xy 381.13985 -290.603479) (xy 381.090472 -290.595665)
			(xy 381.042925 -290.580222) (xy 380.99838 -290.557531) (xy 380.957933 -290.528149) (xy 380.92258 -290.492802)
			(xy 380.893194 -290.45236) (xy 380.870496 -290.407817) (xy 380.855046 -290.360272) (xy 380.847225 -290.310896)
			(xy 380.847225 -290.260904) (xy 380.855046 -290.211528) (xy 380.870496 -290.163983) (xy 380.893194 -290.11944)
			(xy 380.92258 -290.078998) (xy 380.957933 -290.043651) (xy 380.99838 -290.014269) (xy 381.042925 -289.991578)
			(xy 381.090472 -289.976135) (xy 381.13985 -289.968321) (xy 381.164846 -289.967924) (xy 381.177343 -289.968012)
			(xy 381.202265 -289.969916) (xy 381.21463 -289.971734) (xy 381.225552 -289.973512) (xy 381.246888 -289.967416)
			(xy 381.312674 -289.911282) (xy 381.320698 -289.903711) (xy 381.329916 -289.883693) (xy 381.330454 -289.872674)
			(xy 381.330454 -289.568636) (xy 381.328676 -289.561778) (xy 381.323115 -289.540752) (xy 381.317131 -289.497672)
			(xy 381.316738 -289.475926) (xy 381.317147 -289.454181) (xy 381.323139 -289.411106) (xy 381.328676 -289.390074)
			(xy 381.330454 -289.383216) (xy 381.330454 -289.079178) (xy 381.329911 -289.06816) (xy 381.320693 -289.048145)
			(xy 381.312674 -289.04057) (xy 381.246888 -288.984436) (xy 381.225552 -288.97834) (xy 381.21463 -288.980118)
			(xy 381.202264 -288.981924) (xy 381.177343 -288.983833) (xy 381.164846 -288.983928) (xy 381.139851 -288.983467)
			(xy 381.090475 -288.975653) (xy 381.04293 -288.960211) (xy 380.998386 -288.93752) (xy 380.957941 -288.90814)
			(xy 380.92259 -288.872795) (xy 380.893204 -288.832353) (xy 380.870507 -288.787813) (xy 380.855058 -288.74027)
			(xy 380.847237 -288.690895) (xy 380.847237 -288.640905) (xy 380.855058 -288.59153) (xy 380.870507 -288.543987)
			(xy 380.893204 -288.499447) (xy 380.92259 -288.459005) (xy 380.957941 -288.42366) (xy 380.998386 -288.39428)
			(xy 381.04293 -288.371589) (xy 381.090475 -288.356147) (xy 381.139851 -288.348333) (xy 381.164846 -288.347912)
			(xy 381.177343 -288.348) (xy 381.202265 -288.349904) (xy 381.21463 -288.351722) (xy 381.225552 -288.3535)
			(xy 381.246888 -288.347404) (xy 381.312674 -288.29127) (xy 381.320696 -288.283698) (xy 381.32991 -288.26368)
			(xy 381.330454 -288.252662) (xy 381.330454 -287.948878) (xy 381.328676 -287.94202) (xy 381.323112 -287.920994)
			(xy 381.317122 -287.877914) (xy 381.316738 -287.856168) (xy 381.317144 -287.834423) (xy 381.323131 -287.791346)
			(xy 381.328676 -287.770316) (xy 381.330454 -287.763458) (xy 381.330454 -287.459166) (xy 381.329909 -287.448149)
			(xy 381.320688 -287.428138) (xy 381.312674 -287.420558) (xy 381.246888 -287.364424) (xy 381.225552 -287.358328)
			(xy 381.21463 -287.360106) (xy 381.202264 -287.361912) (xy 381.177343 -287.363822) (xy 381.164846 -287.363916)
			(xy 381.139852 -287.363455) (xy 381.090478 -287.355642) (xy 381.042934 -287.3402) (xy 380.998392 -287.31751)
			(xy 380.957948 -287.288131) (xy 380.922599 -287.252787) (xy 380.893214 -287.212347) (xy 380.870518 -287.167808)
			(xy 380.855069 -287.120267) (xy 380.847249 -287.070894) (xy 380.847249 -287.020906) (xy 380.855069 -286.971533)
			(xy 380.870518 -286.923992) (xy 380.893214 -286.879453) (xy 380.922599 -286.839013) (xy 380.957948 -286.803669)
			(xy 380.998392 -286.77429) (xy 381.042934 -286.7516) (xy 381.090478 -286.736158) (xy 381.139852 -286.728345)
			(xy 381.164846 -286.7279) (xy 381.177343 -286.727987) (xy 381.202265 -286.729891) (xy 381.21463 -286.73171)
			(xy 381.225552 -286.733488) (xy 381.246888 -286.727392) (xy 381.312674 -286.671258) (xy 381.320694 -286.663685)
			(xy 381.329903 -286.643668) (xy 381.330454 -286.63265) (xy 381.330454 -286.328866) (xy 381.328676 -286.322008)
			(xy 381.323113 -286.300982) (xy 381.317125 -286.257902) (xy 381.316738 -286.236156) (xy 381.317145 -286.214411)
			(xy 381.323133 -286.171334) (xy 381.328676 -286.150304) (xy 381.330454 -286.143446) (xy 381.330454 -285.839408)
			(xy 381.329917 -285.828387) (xy 381.320707 -285.808363) (xy 381.312674 -285.8008) (xy 381.246888 -285.744666)
			(xy 381.225552 -285.73857) (xy 381.21463 -285.740348) (xy 381.202264 -285.742154) (xy 381.177343 -285.744064)
			(xy 381.164846 -285.744158) (xy 381.139848 -285.743697) (xy 381.090468 -285.735882) (xy 381.042918 -285.720439)
			(xy 380.99837 -285.697746) (xy 380.957921 -285.668363) (xy 380.922567 -285.633014) (xy 380.893178 -285.592569)
			(xy 380.870479 -285.548024) (xy 380.855028 -285.500477) (xy 380.847207 -285.451097) (xy 380.847207 -285.401103)
			(xy 380.855028 -285.351723) (xy 380.870479 -285.304176) (xy 380.893178 -285.259631) (xy 380.922567 -285.219186)
			(xy 380.957921 -285.183837) (xy 380.99837 -285.154454) (xy 381.042918 -285.131761) (xy 381.090468 -285.116318)
			(xy 381.139849 -285.108503) (xy 381.164846 -285.108142) (xy 381.177343 -285.10823) (xy 381.202265 -285.110134)
			(xy 381.21463 -285.111952) (xy 381.225552 -285.11373) (xy 381.246888 -285.107634) (xy 381.312674 -285.0515)
			(xy 381.320701 -285.04393) (xy 381.329926 -285.023913) (xy 381.330454 -285.012892) (xy 381.330454 -284.708854)
			(xy 381.328676 -284.701996) (xy 381.323114 -284.68097) (xy 381.317127 -284.63789) (xy 381.316738 -284.616144)
			(xy 381.317145 -284.594399) (xy 381.323135 -284.551323) (xy 381.328676 -284.530292) (xy 381.330454 -284.523434)
			(xy 381.330454 -284.219396) (xy 381.329915 -284.208377) (xy 381.320701 -284.188356) (xy 381.312674 -284.180788)
			(xy 381.246888 -284.124654) (xy 381.225552 -284.118558) (xy 381.21463 -284.120336) (xy 381.202264 -284.122142)
			(xy 381.177343 -284.124052) (xy 381.164846 -284.124146) (xy 381.139849 -284.123685) (xy 381.090471 -284.115871)
			(xy 381.042923 -284.100428) (xy 380.998377 -284.077736) (xy 380.957929 -284.048354) (xy 380.922576 -284.013006)
			(xy 380.893188 -283.972563) (xy 380.87049 -283.92802) (xy 380.85504 -283.880474) (xy 380.847219 -283.831096)
			(xy 380.847219 -283.781103) (xy 380.85504 -283.731726) (xy 380.87049 -283.68418) (xy 380.893188 -283.639637)
			(xy 380.922576 -283.599194) (xy 380.957929 -283.563846) (xy 380.998377 -283.534464) (xy 381.042923 -283.511772)
			(xy 381.090471 -283.496329) (xy 381.139849 -283.488515) (xy 381.164846 -283.48813) (xy 381.177343 -283.488218)
			(xy 381.202265 -283.490122) (xy 381.21463 -283.49194) (xy 381.225552 -283.493718) (xy 381.246888 -283.487622)
			(xy 381.312674 -283.431488) (xy 381.320699 -283.423917) (xy 381.329919 -283.4039) (xy 381.330454 -283.39288)
			(xy 381.330454 -283.088842) (xy 381.328676 -283.081984) (xy 381.323114 -283.060958) (xy 381.31713 -283.017878)
			(xy 381.316738 -282.996132) (xy 381.317146 -282.974387) (xy 381.323138 -282.931312) (xy 381.328676 -282.91028)
			(xy 381.330454 -282.903422) (xy 381.330454 -282.599384) (xy 381.329912 -282.588366) (xy 381.320696 -282.568348)
			(xy 381.312674 -282.560776) (xy 381.246888 -282.504642) (xy 381.225552 -282.498546) (xy 381.21463 -282.500324)
			(xy 381.202264 -282.50213) (xy 381.177343 -282.50404) (xy 381.164846 -282.504134) (xy 381.13985 -282.503673)
			(xy 381.090474 -282.495859) (xy 381.042928 -282.480416) (xy 380.998383 -282.457725) (xy 380.957937 -282.428345)
			(xy 380.922585 -282.392998) (xy 380.893199 -282.352556) (xy 380.870501 -282.308015) (xy 380.855052 -282.260471)
			(xy 380.847231 -282.211096) (xy 380.847231 -282.161104) (xy 380.855052 -282.111729) (xy 380.870501 -282.064185)
			(xy 380.893199 -282.019644) (xy 380.922585 -281.979202) (xy 380.957937 -281.943855) (xy 380.998383 -281.914475)
			(xy 381.042928 -281.891784) (xy 381.090474 -281.876341) (xy 381.13985 -281.868527) (xy 381.164846 -281.868118)
			(xy 381.177343 -281.868206) (xy 381.202265 -281.87011) (xy 381.21463 -281.871928) (xy 381.225552 -281.873706)
			(xy 381.246888 -281.86761) (xy 381.312674 -281.811476) (xy 381.320697 -281.803904) (xy 381.329913 -281.783887)
			(xy 381.330454 -281.772868) (xy 381.330454 -281.46883) (xy 381.328676 -281.461972) (xy 381.323109 -281.440946)
			(xy 381.317112 -281.397867) (xy 381.316738 -281.37612) (xy 381.317147 -281.354376) (xy 381.32314 -281.3113)
			(xy 381.328676 -281.290268) (xy 381.330454 -281.28341) (xy 381.330454 -280.979372) (xy 381.32991 -280.968355)
			(xy 381.320691 -280.948341) (xy 381.312674 -280.940764) (xy 381.246888 -280.88463) (xy 381.225552 -280.878534)
			(xy 381.21463 -280.880312) (xy 381.202264 -280.882118) (xy 381.177343 -280.884028) (xy 381.164846 -280.884122)
			(xy 381.139851 -280.883661) (xy 381.090477 -280.875847) (xy 381.042932 -280.860405) (xy 380.998389 -280.837715)
			(xy 380.957944 -280.808336) (xy 380.922594 -280.772991) (xy 380.893209 -280.73255) (xy 380.870512 -280.68801)
			(xy 380.855063 -280.640468) (xy 380.847243 -280.591095) (xy 380.847243 -280.541105) (xy 380.855063 -280.491732)
			(xy 380.870512 -280.44419) (xy 380.893209 -280.39965) (xy 380.922594 -280.359209) (xy 380.957944 -280.323864)
			(xy 380.998389 -280.294485) (xy 381.042932 -280.271795) (xy 381.090477 -280.256353) (xy 381.139851 -280.248539)
			(xy 381.164846 -280.248106) (xy 381.177343 -280.248194) (xy 381.202265 -280.250098) (xy 381.21463 -280.251916)
			(xy 381.225552 -280.253694) (xy 381.246888 -280.247598) (xy 381.312674 -280.191464) (xy 381.320695 -280.183892)
			(xy 381.329906 -280.163874) (xy 381.330454 -280.152856) (xy 381.330454 -279.848818) (xy 381.328676 -279.84196)
			(xy 381.323109 -279.820934) (xy 381.317114 -279.777855) (xy 381.316738 -279.756108) (xy 381.317148 -279.734364)
			(xy 381.323143 -279.691289) (xy 381.328676 -279.670256) (xy 381.330454 -279.663398) (xy 381.330454 -279.35936)
			(xy 381.329907 -279.348344) (xy 381.320685 -279.328334) (xy 381.312674 -279.320752) (xy 381.246888 -279.264618)
			(xy 381.225552 -279.258522) (xy 381.21463 -279.2603) (xy 381.202264 -279.262106) (xy 381.177343 -279.264016)
			(xy 381.164846 -279.26411) (xy 381.139852 -279.263649) (xy 381.090479 -279.255836) (xy 381.042937 -279.240394)
			(xy 380.998395 -279.217705) (xy 380.957952 -279.188327) (xy 380.922603 -279.152983) (xy 380.893219 -279.112544)
			(xy 380.870523 -279.068006) (xy 380.855075 -279.020465) (xy 380.847255 -278.971094) (xy 380.847255 -278.921106)
			(xy 380.855075 -278.871735) (xy 380.870523 -278.824194) (xy 380.893219 -278.779656) (xy 380.922603 -278.739217)
			(xy 380.957952 -278.703873) (xy 380.998395 -278.674495) (xy 381.042937 -278.651806) (xy 381.090479 -278.636364)
			(xy 381.139852 -278.628551) (xy 381.164846 -278.628094) (xy 381.177343 -278.628181) (xy 381.202265 -278.630085)
			(xy 381.21463 -278.631904) (xy 381.225552 -278.633682) (xy 381.246888 -278.627586) (xy 381.312674 -278.571452)
			(xy 381.320693 -278.563879) (xy 381.3299 -278.543861) (xy 381.330454 -278.532844) (xy 381.330454 -278.228806)
			(xy 381.328676 -278.221948) (xy 381.32311 -278.200922) (xy 381.317117 -278.157843) (xy 381.316738 -278.136096)
			(xy 381.317142 -278.114351) (xy 381.323125 -278.071273) (xy 381.328676 -278.050244) (xy 381.330454 -278.043386)
			(xy 381.330454 -277.739348) (xy 381.329905 -277.728333) (xy 381.32068 -277.708327) (xy 381.312674 -277.70074)
			(xy 381.246888 -277.644606) (xy 381.225552 -277.63851) (xy 381.21463 -277.640288) (xy 381.202264 -277.642094)
			(xy 381.177343 -277.644004) (xy 381.164846 -277.644098) (xy 381.139853 -277.643637) (xy 381.090482 -277.635824)
			(xy 381.042941 -277.620383) (xy 380.998402 -277.597695) (xy 380.95796 -277.568318) (xy 380.922612 -277.532975)
			(xy 380.893229 -277.492538) (xy 380.870534 -277.448001) (xy 380.855087 -277.400463) (xy 380.847267 -277.351093)
			(xy 380.847267 -277.301107) (xy 380.855087 -277.251737) (xy 380.870534 -277.204199) (xy 380.893229 -277.159662)
			(xy 380.922612 -277.119225) (xy 380.95796 -277.083882) (xy 380.998402 -277.054505) (xy 381.042941 -277.031817)
			(xy 381.090482 -277.016376) (xy 381.139853 -277.008563) (xy 381.164846 -277.008082) (xy 381.177344 -277.008169)
			(xy 381.202265 -277.010073) (xy 381.21463 -277.011892) (xy 381.225552 -277.01367) (xy 381.246888 -277.007574)
			(xy 381.312674 -276.95144) (xy 381.320708 -276.943872) (xy 381.329948 -276.923855) (xy 381.330454 -276.912832)
			(xy 381.330454 -276.608794) (xy 381.328676 -276.601936) (xy 381.323111 -276.58091) (xy 381.317119 -276.537831)
			(xy 381.316738 -276.516084) (xy 381.317143 -276.494339) (xy 381.323128 -276.451261) (xy 381.328676 -276.430232)
			(xy 381.330454 -276.423374) (xy 381.330454 -276.119336) (xy 381.329922 -276.108313) (xy 381.320719 -276.088279)
			(xy 381.312674 -276.080728) (xy 381.246888 -276.024594) (xy 381.225552 -276.018498) (xy 381.21463 -276.020276)
			(xy 381.202264 -276.022082) (xy 381.177343 -276.023992) (xy 381.164846 -276.024086) (xy 381.139854 -276.023625)
			(xy 381.090485 -276.015812) (xy 381.042946 -276.000372) (xy 380.998408 -275.977684) (xy 380.957968 -275.948308)
			(xy 380.922622 -275.912967) (xy 380.89324 -275.872531) (xy 380.870546 -275.827996) (xy 380.855099 -275.78046)
			(xy 380.847279 -275.731092) (xy 380.847279 -275.681108) (xy 380.855099 -275.63174) (xy 380.870546 -275.584204)
			(xy 380.89324 -275.539669) (xy 380.922622 -275.499233) (xy 380.957968 -275.463892) (xy 380.998408 -275.434516)
			(xy 381.042946 -275.411828) (xy 381.090485 -275.396388) (xy 381.139854 -275.388575) (xy 381.164846 -275.38807)
			(xy 381.177344 -275.388157) (xy 381.202265 -275.390061) (xy 381.21463 -275.39188) (xy 381.225552 -275.393658)
			(xy 381.246888 -275.387562) (xy 381.312674 -275.331428) (xy 381.320706 -275.32386) (xy 381.329942 -275.303842)
			(xy 381.330454 -275.29282) (xy 381.330454 -274.988782) (xy 381.328676 -274.981924) (xy 381.323112 -274.960898)
			(xy 381.317122 -274.917819) (xy 381.316738 -274.896072) (xy 381.317143 -274.874327) (xy 381.32313 -274.83125)
			(xy 381.328676 -274.81022) (xy 381.330454 -274.803362) (xy 381.330454 -274.499324) (xy 381.32992 -274.488302)
			(xy 381.320714 -274.468272) (xy 381.312674 -274.460716) (xy 381.246888 -274.404582) (xy 381.225552 -274.398486)
			(xy 381.21463 -274.400264) (xy 381.202264 -274.40207) (xy 381.177343 -274.40398) (xy 381.164846 -274.404074)
			(xy 381.139855 -274.403613) (xy 381.090488 -274.3958) (xy 381.042951 -274.380361) (xy 380.998414 -274.357674)
			(xy 380.957976 -274.328299) (xy 380.922631 -274.292959) (xy 380.89325 -274.252525) (xy 380.870557 -274.207992)
			(xy 380.855111 -274.160457) (xy 380.847291 -274.111091) (xy 380.847291 -274.061109) (xy 380.855111 -274.011743)
			(xy 380.870557 -273.964208) (xy 380.89325 -273.919675) (xy 380.922631 -273.879241) (xy 380.957976 -273.843901)
			(xy 380.998414 -273.814526) (xy 381.042951 -273.791839) (xy 381.090488 -273.7764) (xy 381.139855 -273.768587)
			(xy 381.164846 -273.768058) (xy 381.177343 -273.768146) (xy 381.202265 -273.77005) (xy 381.21463 -273.771868)
			(xy 381.225552 -273.773646) (xy 381.246888 -273.76755) (xy 381.312674 -273.711416) (xy 381.320704 -273.703847)
			(xy 381.329935 -273.68383) (xy 381.330454 -273.672808) (xy 381.330454 -273.36877) (xy 381.328676 -273.361912)
			(xy 381.323112 -273.340886) (xy 381.317124 -273.297806) (xy 381.316738 -273.27606) (xy 381.317144 -273.254315)
			(xy 381.323132 -273.211238) (xy 381.328676 -273.190208) (xy 381.330454 -273.18335) (xy 381.330454 -272.879312)
			(xy 381.329918 -272.868291) (xy 381.320709 -272.848265) (xy 381.312674 -272.840704) (xy 381.246888 -272.78457)
			(xy 381.225552 -272.778474) (xy 381.21463 -272.780252) (xy 381.202264 -272.782058) (xy 381.177343 -272.783968)
			(xy 381.164846 -272.784062) (xy 381.139856 -272.783601) (xy 381.090491 -272.775789) (xy 381.042955 -272.760349)
			(xy 380.998421 -272.737664) (xy 380.957984 -272.70829) (xy 380.92264 -272.672951) (xy 380.89326 -272.632519)
			(xy 380.870568 -272.587987) (xy 380.855122 -272.540454) (xy 380.847303 -272.49109) (xy 380.847303 -272.44111)
			(xy 380.855122 -272.391746) (xy 380.870568 -272.344213) (xy 380.89326 -272.299681) (xy 380.92264 -272.259249)
			(xy 380.957984 -272.22391) (xy 380.998421 -272.194536) (xy 381.042955 -272.171851) (xy 381.090491 -272.156411)
			(xy 381.139856 -272.148599) (xy 381.164846 -272.148046) (xy 381.177343 -272.148134) (xy 381.202265 -272.150038)
			(xy 381.21463 -272.151856) (xy 381.225552 -272.153634) (xy 381.246888 -272.147538) (xy 381.312674 -272.091404)
			(xy 381.320702 -272.083834) (xy 381.329929 -272.063817) (xy 381.330454 -272.052796) (xy 381.330454 -271.748758)
			(xy 381.328676 -271.7419) (xy 381.323113 -271.720874) (xy 381.317126 -271.677794) (xy 381.316738 -271.656048)
			(xy 381.317145 -271.634303) (xy 381.323135 -271.591227) (xy 381.328676 -271.570196) (xy 381.330454 -271.563338)
			(xy 381.330454 -271.2593) (xy 381.329915 -271.24828) (xy 381.320703 -271.228258) (xy 381.312674 -271.220692)
			(xy 381.246888 -271.164558) (xy 381.225552 -271.158462) (xy 381.21463 -271.16024) (xy 381.202264 -271.162046)
			(xy 381.177343 -271.163956) (xy 381.164846 -271.16405) (xy 381.139849 -271.163589) (xy 381.09047 -271.155775)
			(xy 381.042921 -271.140331) (xy 380.998374 -271.117639) (xy 380.957926 -271.088257) (xy 380.922573 -271.052909)
			(xy 380.893185 -271.012465) (xy 380.870486 -270.967921) (xy 380.855036 -270.920375) (xy 380.847215 -270.870997)
			(xy 380.847215 -270.821003) (xy 380.855036 -270.771625) (xy 380.870486 -270.724079) (xy 380.893185 -270.679535)
			(xy 380.922573 -270.639091) (xy 380.957926 -270.603743) (xy 380.998374 -270.574361) (xy 381.042921 -270.551669)
			(xy 381.09047 -270.536225) (xy 381.139849 -270.528411) (xy 381.164846 -270.528034) (xy 381.177343 -270.528122)
			(xy 381.202265 -270.530026) (xy 381.21463 -270.531844) (xy 381.225552 -270.533622) (xy 381.246888 -270.527526)
			(xy 381.312674 -270.471392) (xy 381.3207 -270.463821) (xy 381.329922 -270.443804) (xy 381.330454 -270.432784)
			(xy 381.330454 -270.128746) (xy 381.328676 -270.121888) (xy 381.323114 -270.100862) (xy 381.317129 -270.057782)
			(xy 381.316738 -270.036036) (xy 381.317146 -270.014291) (xy 381.323137 -269.971215) (xy 381.328676 -269.950184)
			(xy 381.330454 -269.943326) (xy 381.330454 -269.639288) (xy 381.329913 -269.628269) (xy 381.320698 -269.608251)
			(xy 381.312674 -269.60068) (xy 381.246888 -269.544546) (xy 381.225552 -269.53845) (xy 381.21463 -269.540228)
			(xy 381.202264 -269.542034) (xy 381.177343 -269.543944) (xy 381.164846 -269.544038) (xy 381.13985 -269.543577)
			(xy 381.090473 -269.535763) (xy 381.042926 -269.52032) (xy 380.998381 -269.497629) (xy 380.957934 -269.468248)
			(xy 380.922582 -269.432901) (xy 380.893195 -269.392459) (xy 380.870497 -269.347917) (xy 380.855048 -269.300372)
			(xy 380.847227 -269.250996) (xy 380.847227 -269.201004) (xy 380.855048 -269.151628) (xy 380.870498 -269.104083)
			(xy 380.893195 -269.059541) (xy 380.922582 -269.019099) (xy 380.957934 -268.983752) (xy 380.998381 -268.954371)
			(xy 381.042926 -268.93168) (xy 381.090473 -268.916237) (xy 381.13985 -268.908423) (xy 381.164846 -268.908022)
			(xy 381.177343 -268.90811) (xy 381.202265 -268.910014) (xy 381.21463 -268.911832) (xy 381.225552 -268.91361)
			(xy 381.246888 -268.907514) (xy 381.312674 -268.85138) (xy 381.320698 -268.843809) (xy 381.329915 -268.823791)
			(xy 381.330454 -268.812772) (xy 381.330454 -268.508734) (xy 381.328676 -268.501876) (xy 381.323115 -268.48085)
			(xy 381.317131 -268.43777) (xy 381.316738 -268.416024) (xy 381.317147 -268.394279) (xy 381.323139 -268.351204)
			(xy 381.328676 -268.330172) (xy 381.330454 -268.323314) (xy 381.330454 -268.019276) (xy 381.329911 -268.008258)
			(xy 381.320692 -267.988244) (xy 381.312674 -267.980668) (xy 381.246888 -267.924534) (xy 381.225552 -267.918438)
			(xy 381.21463 -267.920216) (xy 381.202264 -267.922022) (xy 381.177343 -267.923932) (xy 381.164846 -267.924026)
			(xy 381.139851 -267.923565) (xy 381.090476 -267.915751) (xy 381.042931 -267.900309) (xy 380.998387 -267.877619)
			(xy 380.957942 -267.848239) (xy 380.922591 -267.812893) (xy 380.893205 -267.772452) (xy 380.870509 -267.727912)
			(xy 380.855059 -267.680369) (xy 380.847239 -267.630995) (xy 380.847239 -267.581005) (xy 380.855059 -267.531631)
			(xy 380.870509 -267.484088) (xy 380.893205 -267.439548) (xy 380.922591 -267.399107) (xy 380.957942 -267.363761)
			(xy 380.998387 -267.334381) (xy 381.042931 -267.311691) (xy 381.090476 -267.296249) (xy 381.139851 -267.288435)
			(xy 381.164846 -267.28801) (xy 381.177343 -267.288098) (xy 381.202265 -267.290002) (xy 381.21463 -267.29182)
			(xy 381.225552 -267.293598) (xy 381.246888 -267.287502) (xy 381.312674 -267.231368) (xy 381.320696 -267.223796)
			(xy 381.329909 -267.203778) (xy 381.330454 -267.19276) (xy 381.330454 -266.888722) (xy 381.328676 -266.881864)
			(xy 381.323109 -266.860838) (xy 381.317114 -266.817759) (xy 381.316738 -266.796012) (xy 381.317148 -266.774268)
			(xy 381.323142 -266.731192) (xy 381.328676 -266.71016) (xy 381.330454 -266.703302) (xy 381.330454 -266.399264)
			(xy 381.329908 -266.388248) (xy 381.320687 -266.368236) (xy 381.312674 -266.360656) (xy 381.246888 -266.304522)
			(xy 381.225552 -266.298426) (xy 381.21463 -266.300204) (xy 381.202264 -266.30201) (xy 381.177343 -266.30392)
			(xy 381.164846 -266.304014) (xy 381.139852 -266.303553) (xy 381.090478 -266.29574) (xy 381.042935 -266.280298)
			(xy 380.998393 -266.257608) (xy 380.95795 -266.22823) (xy 380.9226 -266.192885) (xy 380.893216 -266.152446)
			(xy 380.87052 -266.107907) (xy 380.855071 -266.060366) (xy 380.847251 -266.010994) (xy 380.847251 -265.961006)
			(xy 380.855071 -265.911634) (xy 380.87052 -265.864093) (xy 380.893216 -265.819554) (xy 380.9226 -265.779115)
			(xy 380.95795 -265.74377) (xy 380.998393 -265.714392) (xy 381.042935 -265.691702) (xy 381.090478 -265.67626)
			(xy 381.139852 -265.668447) (xy 381.164846 -265.667998) (xy 381.177343 -265.668085) (xy 381.202265 -265.669989)
			(xy 381.21463 -265.671808) (xy 381.225552 -265.673586) (xy 381.246888 -265.66749) (xy 381.312674 -265.611356)
			(xy 381.320694 -265.603783) (xy 381.329902 -265.583766) (xy 381.330454 -265.572748) (xy 381.330454 -265.26871)
			(xy 381.328676 -265.261852) (xy 381.32311 -265.240826) (xy 381.317116 -265.197747) (xy 381.316738 -265.176)
			(xy 381.317148 -265.154256) (xy 381.323144 -265.111181) (xy 381.328676 -265.090148) (xy 381.330454 -265.08329)
			(xy 381.330454 -264.779252) (xy 381.329906 -264.768237) (xy 381.320682 -264.748229) (xy 381.312674 -264.740644)
			(xy 381.246888 -264.68451) (xy 381.225552 -264.678414) (xy 381.21463 -264.680192) (xy 381.202264 -264.681998)
			(xy 381.177343 -264.683908) (xy 381.164846 -264.684002) (xy 381.139516 -264.683514) (xy 381.089495 -264.675486)
			(xy 381.04138 -264.659627) (xy 380.99639 -264.636338) (xy 380.955663 -264.606209) (xy 380.920229 -264.570001)
			(xy 380.890987 -264.528633) (xy 380.868675 -264.48315) (xy 380.853859 -264.434704) (xy 380.849886 -264.409682)
			(xy 380.848108 -264.397236) (xy 380.846149 -264.372643) (xy 380.848941 -264.323389) (xy 380.8593 -264.275155)
			(xy 380.876979 -264.229099) (xy 380.901554 -264.186322) (xy 380.932435 -264.14785) (xy 380.968884 -264.114604)
			(xy 381.010027 -264.087382) (xy 381.054878 -264.066835) (xy 381.078486 -264.05967) (xy 381.091694 -264.056114)
			(xy 381.11049 -264.03681) (xy 381.13589 -263.94156) (xy 381.13716 -263.93394) (xy 381.137824 -263.922915)
			(xy 381.130831 -263.901989) (xy 381.123698 -263.893554) (xy 381.122682 -263.892538) (xy 381.028448 -263.798304)
			(xy 381.011176 -263.790938) (xy 381.001524 -263.79043) (xy 380.934468 -263.787636) (xy 380.925128 -263.787629)
			(xy 380.907408 -263.79348) (xy 380.899924 -263.799066) (xy 380.89967 -263.79932) (xy 380.878009 -263.816792)
			(xy 380.829844 -263.844662) (xy 380.777567 -263.863731) (xy 380.722769 -263.873417) (xy 380.694946 -263.873996)
			(xy 380.669953 -263.873535) (xy 380.620581 -263.865722) (xy 380.573039 -263.85028) (xy 380.528499 -263.827591)
			(xy 380.488057 -263.798213) (xy 380.45271 -263.762869) (xy 380.423327 -263.72243) (xy 380.400633 -263.677892)
			(xy 380.385186 -263.630352) (xy 380.377368 -263.580981) (xy 380.376938 -263.555988) (xy 380.376938 -263.555734)
			(xy 380.377332 -263.533198) (xy 380.383712 -263.48858) (xy 380.389638 -263.466834) (xy 380.39294 -263.45515)
			(xy 380.388876 -263.432036) (xy 380.334012 -263.35863) (xy 380.326408 -263.349528) (xy 380.305217 -263.338942)
			(xy 380.293372 -263.33831) (xy 380.156466 -263.33831) (xy 380.144624 -263.338937) (xy 380.123446 -263.349542)
			(xy 380.115826 -263.35863) (xy 380.060962 -263.432036) (xy 380.056898 -263.45515) (xy 380.0602 -263.466834)
			(xy 380.066119 -263.488581) (xy 380.072486 -263.533199) (xy 380.0729 -263.555734) (xy 380.0729 -263.555988)
			(xy 380.07241 -263.580977) (xy 380.064591 -263.63034) (xy 380.049147 -263.677872) (xy 380.026457 -263.722404)
			(xy 379.997081 -263.762837) (xy 379.961741 -263.798177) (xy 379.921308 -263.827553) (xy 379.876776 -263.850243)
			(xy 379.829244 -263.865687) (xy 379.779881 -263.873506) (xy 379.729903 -263.873506) (xy 379.68054 -263.865687)
			(xy 379.633008 -263.850243) (xy 379.588476 -263.827553) (xy 379.548043 -263.798177) (xy 379.512703 -263.762837)
			(xy 379.483327 -263.722404) (xy 379.460637 -263.677872) (xy 379.445193 -263.63034) (xy 379.437374 -263.580977)
			(xy 379.436884 -263.555988) (xy 379.436884 -263.555734) (xy 379.437278 -263.533198) (xy 379.443657 -263.48858)
			(xy 379.449584 -263.466834) (xy 379.452886 -263.45515) (xy 379.448822 -263.432036) (xy 379.393958 -263.35863)
			(xy 379.386357 -263.34952) (xy 379.365166 -263.338915) (xy 379.353318 -263.33831) (xy 378.276358 -263.33831)
			(xy 378.264517 -263.338938) (xy 378.243342 -263.349545) (xy 378.235718 -263.35863) (xy 378.180854 -263.432036)
			(xy 378.17679 -263.45515) (xy 378.180092 -263.466834) (xy 378.186011 -263.488581) (xy 378.192379 -263.533199)
			(xy 378.192792 -263.555734) (xy 378.192792 -263.555988) (xy 378.192302 -263.580977) (xy 378.184483 -263.63034)
			(xy 378.169039 -263.677872) (xy 378.146349 -263.722404) (xy 378.116973 -263.762837) (xy 378.081633 -263.798177)
			(xy 378.0412 -263.827553) (xy 377.996668 -263.850243) (xy 377.949136 -263.865687) (xy 377.899773 -263.873506)
			(xy 377.849795 -263.873506) (xy 377.800432 -263.865687) (xy 377.7529 -263.850243) (xy 377.708368 -263.827553)
			(xy 377.667935 -263.798177) (xy 377.632595 -263.762837) (xy 377.603219 -263.722404) (xy 377.580529 -263.677872)
			(xy 377.565085 -263.63034) (xy 377.557266 -263.580977) (xy 377.556776 -263.555988) (xy 377.556776 -263.555734)
			(xy 377.55717 -263.533198) (xy 377.563548 -263.48858) (xy 377.569476 -263.466834) (xy 377.572778 -263.45515)
			(xy 377.568714 -263.432036) (xy 377.51385 -263.35863) (xy 377.506248 -263.349522) (xy 377.485057 -263.33892)
			(xy 377.47321 -263.33831) (xy 377.336304 -263.33831) (xy 377.324458 -263.338929) (xy 377.303267 -263.349524)
			(xy 377.295664 -263.35863) (xy 377.2408 -263.432036) (xy 377.236736 -263.45515) (xy 377.240038 -263.466834)
			(xy 377.245972 -263.488643) (xy 377.25234 -263.533389) (xy 377.252738 -263.555988) (xy 377.252738 -263.563354)
			(xy 377.251706 -263.587965) (xy 377.242989 -263.636444) (xy 377.226903 -263.682999) (xy 377.203832 -263.726518)
			(xy 377.174329 -263.765961) (xy 377.139099 -263.800385) (xy 377.098983 -263.828967) (xy 377.054941 -263.851023)
			(xy 377.008026 -263.866027) (xy 376.959358 -263.87362) (xy 376.910102 -263.87362) (xy 376.861434 -263.866027)
			(xy 376.814519 -263.851023) (xy 376.770477 -263.828967) (xy 376.730361 -263.800385) (xy 376.695131 -263.765961)
			(xy 376.665628 -263.726518) (xy 376.642557 -263.682999) (xy 376.626471 -263.636444) (xy 376.617754 -263.587965)
			(xy 376.616722 -263.563354) (xy 376.616722 -263.55929) (xy 376.616722 -263.555988) (xy 376.617102 -263.533388)
			(xy 376.623482 -263.488642) (xy 376.629422 -263.466834) (xy 376.632724 -263.45515) (xy 376.62866 -263.432036)
			(xy 376.573796 -263.35863) (xy 376.566191 -263.349531) (xy 376.544999 -263.338951) (xy 376.533156 -263.33831)
			(xy 376.396504 -263.33831) (xy 376.384658 -263.338929) (xy 376.363467 -263.349524) (xy 376.355864 -263.35863)
			(xy 376.301 -263.432036) (xy 376.296936 -263.45515) (xy 376.300238 -263.466834) (xy 376.306158 -263.488581)
			(xy 376.312527 -263.533199) (xy 376.312938 -263.555734) (xy 376.312938 -263.555988) (xy 376.312448 -263.580977)
			(xy 376.304629 -263.63034) (xy 376.289185 -263.677872) (xy 376.266495 -263.722404) (xy 376.237119 -263.762837)
			(xy 376.201779 -263.798177) (xy 376.161346 -263.827553) (xy 376.116814 -263.850243) (xy 376.069282 -263.865687)
			(xy 376.019919 -263.873506) (xy 375.969941 -263.873506) (xy 375.920578 -263.865687) (xy 375.873046 -263.850243)
			(xy 375.828514 -263.827553) (xy 375.788081 -263.798177) (xy 375.752741 -263.762837) (xy 375.723365 -263.722404)
			(xy 375.700675 -263.677872) (xy 375.685231 -263.63034) (xy 375.677412 -263.580977) (xy 375.676922 -263.555988)
			(xy 375.676922 -263.555734) (xy 375.677316 -263.533198) (xy 375.683695 -263.48858) (xy 375.689622 -263.466834)
			(xy 375.692924 -263.45515) (xy 375.68886 -263.432036) (xy 375.633996 -263.35863) (xy 375.626391 -263.349531)
			(xy 375.605199 -263.338951) (xy 375.593356 -263.33831) (xy 375.45645 -263.33831) (xy 375.44461 -263.33894)
			(xy 375.423438 -263.349549) (xy 375.41581 -263.35863) (xy 375.360946 -263.432036) (xy 375.356882 -263.45515)
			(xy 375.360184 -263.466834) (xy 375.366117 -263.488643) (xy 375.372484 -263.533389) (xy 375.372884 -263.555988)
			(xy 375.372884 -263.563354) (xy 375.371852 -263.587965) (xy 375.363135 -263.636444) (xy 375.347049 -263.682999)
			(xy 375.323978 -263.726518) (xy 375.294475 -263.765961) (xy 375.259245 -263.800385) (xy 375.219129 -263.828967)
			(xy 375.175087 -263.851023) (xy 375.128172 -263.866027) (xy 375.079504 -263.87362) (xy 375.030248 -263.87362)
			(xy 374.98158 -263.866027) (xy 374.934665 -263.851023) (xy 374.890623 -263.828967) (xy 374.850507 -263.800385)
			(xy 374.815277 -263.765961) (xy 374.785774 -263.726518) (xy 374.762703 -263.682999) (xy 374.746617 -263.636444)
			(xy 374.7379 -263.587965) (xy 374.736868 -263.563354) (xy 374.736868 -263.55929) (xy 374.736868 -263.555988)
			(xy 374.737248 -263.533388) (xy 374.743627 -263.488642) (xy 374.749568 -263.466834) (xy 374.75287 -263.45515)
			(xy 374.748806 -263.432036) (xy 374.693942 -263.35863) (xy 374.68634 -263.349523) (xy 374.665149 -263.338924)
			(xy 374.653302 -263.33831) (xy 373.576342 -263.33831) (xy 373.564492 -263.338921) (xy 373.543288 -263.349507)
			(xy 373.535702 -263.35863) (xy 373.480838 -263.432036) (xy 373.476774 -263.45515) (xy 373.480076 -263.466834)
			(xy 373.486009 -263.488643) (xy 373.492377 -263.533389) (xy 373.492776 -263.555988) (xy 373.492776 -263.563354)
			(xy 373.491744 -263.587965) (xy 373.483027 -263.636444) (xy 373.466941 -263.682999) (xy 373.44387 -263.726518)
			(xy 373.414367 -263.765961) (xy 373.379137 -263.800385) (xy 373.339021 -263.828967) (xy 373.294979 -263.851023)
			(xy 373.248064 -263.866027) (xy 373.199396 -263.87362) (xy 373.15014 -263.87362) (xy 373.101472 -263.866027)
			(xy 373.054557 -263.851023) (xy 373.010515 -263.828967) (xy 372.970399 -263.800385) (xy 372.935169 -263.765961)
			(xy 372.905666 -263.726518) (xy 372.882595 -263.682999) (xy 372.866509 -263.636444) (xy 372.857792 -263.587965)
			(xy 372.85676 -263.563354) (xy 372.85676 -263.55929) (xy 372.85676 -263.555988) (xy 372.85714 -263.533388)
			(xy 372.863518 -263.488642) (xy 372.86946 -263.466834) (xy 372.872762 -263.45515) (xy 372.868698 -263.432036)
			(xy 372.813834 -263.35863) (xy 372.806231 -263.349524) (xy 372.78504 -263.338929) (xy 372.773194 -263.33831)
			(xy 371.696488 -263.33831) (xy 371.684644 -263.338932) (xy 371.663458 -263.349532) (xy 371.655848 -263.35863)
			(xy 371.600984 -263.432036) (xy 371.59692 -263.45515) (xy 371.600222 -263.466834) (xy 371.606154 -263.488643)
			(xy 371.612521 -263.53339) (xy 371.612922 -263.555988) (xy 371.612922 -263.563354) (xy 371.61189 -263.587965)
			(xy 371.603173 -263.636444) (xy 371.587087 -263.682999) (xy 371.564016 -263.726518) (xy 371.534513 -263.765961)
			(xy 371.499283 -263.800385) (xy 371.459167 -263.828967) (xy 371.415125 -263.851023) (xy 371.36821 -263.866027)
			(xy 371.319542 -263.87362) (xy 371.270286 -263.87362) (xy 371.221618 -263.866027) (xy 371.174703 -263.851023)
			(xy 371.130661 -263.828967) (xy 371.090545 -263.800385) (xy 371.055315 -263.765961) (xy 371.025812 -263.726518)
			(xy 371.002741 -263.682999) (xy 370.986655 -263.636444) (xy 370.977938 -263.587965) (xy 370.976906 -263.563354)
			(xy 370.976906 -263.55929) (xy 370.976906 -263.555988) (xy 370.977286 -263.533388) (xy 370.983665 -263.488642)
			(xy 370.989606 -263.466834) (xy 370.992908 -263.45515) (xy 370.988844 -263.432036) (xy 370.93398 -263.35863)
			(xy 370.92638 -263.349516) (xy 370.90519 -263.338902) (xy 370.89334 -263.33831) (xy 370.877592 -263.33831)
			(xy 370.867749 -263.337786) (xy 370.849571 -263.330216) (xy 370.842286 -263.323578) (xy 370.736114 -263.217406)
			(xy 370.729002 -263.21004) (xy 370.710206 -263.20242) (xy 370.166392 -263.20242) (xy 370.156549 -263.201896)
			(xy 370.13837 -263.194327) (xy 370.131086 -263.187688) (xy 370.010944 -263.067546) (xy 370.004524 -263.061668)
			(xy 369.988782 -263.054269) (xy 369.971468 -263.052597) (xy 369.962938 -263.054338) (xy 369.962684 -263.054338)
			(xy 369.93195 -263.060434) (xy 369.931442 -263.060688) (xy 369.919504 -263.062212) (xy 369.910285 -263.063633)
			(xy 369.893704 -263.072145) (xy 369.881266 -263.086026) (xy 369.874618 -263.103439) (xy 369.874292 -263.112758)
			(xy 369.874292 -263.719056) (xy 369.873911 -263.729094) (xy 369.866278 -263.747659) (xy 369.852089 -263.761858)
			(xy 369.83353 -263.769504) (xy 369.823492 -263.769856) (xy 369.6716 -263.769856) (xy 369.661721 -263.770312)
			(xy 369.643414 -263.777746) (xy 369.63604 -263.784334) (xy 369.609624 -263.807448) (xy 369.587018 -263.8298)
			(xy 369.576858 -263.8298) (xy 369.565428 -263.835896) (xy 369.542135 -263.847844) (xy 369.49261 -263.864802)
			(xy 369.440979 -263.873431) (xy 369.414806 -263.873996) (xy 369.389815 -263.873532) (xy 369.340448 -263.865714)
			(xy 369.292912 -263.850269) (xy 369.248377 -263.827577) (xy 369.20794 -263.798198) (xy 369.172598 -263.762855)
			(xy 369.14322 -263.722418) (xy 369.120529 -263.677883) (xy 369.105085 -263.630346) (xy 369.097267 -263.580979)
			(xy 369.096798 -263.555988) (xy 369.097292 -263.529631) (xy 369.105943 -263.477632) (xy 369.123055 -263.427773)
			(xy 369.135152 -263.40435) (xy 369.138454 -263.398762) (xy 369.141248 -263.386824) (xy 369.141248 -263.31545)
			(xy 369.141612 -263.294403) (xy 369.149612 -263.25308) (xy 369.165549 -263.214124) (xy 369.188805 -263.179043)
			(xy 369.21848 -263.149194) (xy 369.253425 -263.125734) (xy 369.292288 -263.109571) (xy 369.333563 -263.101331)
			(xy 369.354608 -263.10082) (xy 369.558824 -263.10082) (xy 369.568827 -263.101312) (xy 369.587307 -263.108977)
			(xy 369.601448 -263.12313) (xy 369.609096 -263.141617) (xy 369.609624 -263.15162) (xy 369.609624 -263.160764)
			(xy 369.777772 -263.160764) (xy 369.787269 -263.160377) (xy 369.804959 -263.153457) (xy 369.818904 -263.140561)
			(xy 369.827184 -263.123466) (xy 369.828318 -263.114028) (xy 369.829334 -263.10336) (xy 369.829704 -263.091756)
			(xy 369.821252 -263.070157) (xy 369.804202 -263.054433) (xy 369.793266 -263.050528) (xy 369.76917 -263.042777)
			(xy 369.723615 -263.020719) (xy 369.682128 -262.991726) (xy 369.645756 -262.956528) (xy 369.615417 -262.916014)
			(xy 369.591877 -262.871208) (xy 369.575729 -262.823238) (xy 369.567382 -262.773317) (xy 369.566698 -262.748014)
			(xy 369.566698 -262.745728) (xy 369.567004 -262.726155) (xy 369.57185 -262.687309) (xy 369.57635 -262.668258)
			(xy 369.57635 -262.66775) (xy 369.578083 -262.659227) (xy 369.576361 -262.641931) (xy 369.568974 -262.626198)
			(xy 369.563142 -262.619744) (xy 369.395248 -262.45185) (xy 369.391692 -262.448548) (xy 369.384682 -262.443136)
			(xy 369.368031 -262.437136) (xy 369.35918 -262.436864) (xy 366.687862 -262.436864) (xy 366.677982 -262.436424)
			(xy 366.659685 -262.428967) (xy 366.652302 -262.422386) (xy 366.059212 -261.829296) (xy 366.0521 -261.82193)
			(xy 366.033304 -261.81431) (xy 365.876332 -261.81431) (xy 365.866307 -261.814724) (xy 365.847781 -261.822389)
			(xy 365.833601 -261.836562) (xy 365.825928 -261.855085) (xy 365.825532 -261.86511) (xy 365.825532 -262.458708)
			(xy 365.825532 -262.480044) (xy 365.79556 -262.509508) (xy 365.605568 -262.509508) (xy 365.596356 -262.510813)
			(xy 365.579786 -262.519246) (xy 365.567386 -262.5331) (xy 365.560836 -262.550501) (xy 365.56061 -262.5598)
			(xy 365.56061 -262.569452) (xy 365.514636 -262.569452) (xy 365.305594 -262.569452) (xy 365.285286 -262.56897)
			(xy 365.245402 -262.561289) (xy 365.20769 -262.546205) (xy 365.17351 -262.524262) (xy 365.144096 -262.496252)
			(xy 365.120509 -262.463186) (xy 365.103599 -262.426257) (xy 365.09833 -262.406638) (xy 365.097314 -262.40232)
			(xy 365.089948 -262.385556) (xy 365.087154 -262.381492) (xy 365.072397 -262.359143) (xy 365.049045 -262.310948)
			(xy 365.033179 -262.259798) (xy 365.025158 -262.206847) (xy 365.02467 -262.18007) (xy 365.02467 -262.172958)
			(xy 365.024924 -262.166862) (xy 365.026442 -262.139663) (xy 365.036717 -262.086169) (xy 365.05503 -262.034868)
			(xy 365.080953 -261.98696) (xy 365.113878 -261.943565) (xy 365.133128 -261.924292) (xy 365.144304 -261.91337)
			(xy 365.150654 -261.883398) (xy 365.135668 -261.846314) (xy 365.131536 -261.837078) (xy 365.117406 -261.822618)
			(xy 365.098785 -261.814741) (xy 365.088678 -261.81431) (xy 353.940872 -261.81431) (xy 353.930869 -261.814803)
			(xy 353.912388 -261.822468) (xy 353.898247 -261.83662) (xy 353.890596 -261.855106) (xy 353.890072 -261.86511)
			(xy 353.890072 -262.458708) (xy 353.890072 -262.480044) (xy 353.8601 -262.509508) (xy 353.670108 -262.509508)
			(xy 353.660904 -262.510822) (xy 353.644352 -262.519264) (xy 353.631969 -262.533116) (xy 353.625429 -262.550507)
			(xy 353.62515 -262.5598) (xy 353.62515 -262.569452) (xy 353.624896 -262.569452) (xy 353.370134 -262.569452)
			(xy 353.348526 -262.56891) (xy 353.306193 -262.560222) (xy 353.266474 -262.543195) (xy 353.230992 -262.518526)
			(xy 353.201198 -262.487222) (xy 353.178312 -262.450564) (xy 353.170236 -262.430514) (xy 353.168712 -262.426196)
			(xy 353.159822 -262.41121) (xy 353.157282 -262.408162) (xy 353.147891 -262.39661) (xy 353.130852 -262.372193)
			(xy 353.123246 -262.359394) (xy 353.117363 -262.350501) (xy 353.100032 -262.338125) (xy 353.07917 -262.333843)
			(xy 353.068636 -262.335518) (xy 353.049586 -262.339582) (xy 353.038393 -262.342531) (xy 353.02017 -262.356766)
			(xy 353.010036 -262.37755) (xy 353.009454 -262.389112) (xy 353.009454 -263.444736) (xy 353.008925 -263.454577)
			(xy 353.001353 -263.472752) (xy 352.994722 -263.480042) (xy 352.643186 -263.831578) (xy 352.635949 -263.838294)
			(xy 352.617744 -263.845893) (xy 352.607951 -263.846307) (xy 359.161537 -263.846307) (xy 359.165838 -263.791081)
			(xy 359.178637 -263.737187) (xy 359.199628 -263.685925) (xy 359.228303 -263.638531) (xy 359.26397 -263.596149)
			(xy 359.284524 -263.577578) (xy 359.292144 -263.569196) (xy 359.304386 -263.553305) (xy 359.333693 -263.525925)
			(xy 359.367596 -263.504498) (xy 359.404903 -263.489777) (xy 359.444303 -263.482281) (xy 359.464356 -263.48182)
			(xy 359.719372 -263.48182) (xy 359.719372 -263.490964) (xy 359.719848 -263.50098) (xy 359.727501 -263.51949)
			(xy 359.741656 -263.533663) (xy 359.760157 -263.541339) (xy 359.770172 -263.541764) (xy 359.93324 -263.541764)
			(xy 359.94324 -263.54227) (xy 359.961709 -263.54995) (xy 359.975852 -263.564095) (xy 359.983531 -263.582564)
			(xy 359.98404 -263.592564) (xy 359.98404 -264.100056) (xy 359.983674 -264.110094) (xy 359.976037 -264.128655)
			(xy 359.961842 -264.142846) (xy 359.943278 -264.150477) (xy 359.93324 -264.150856) (xy 359.719372 -264.150856)
			(xy 359.719372 -264.16) (xy 359.71898 -264.170025) (xy 359.711305 -264.188547) (xy 359.697124 -264.20272)
			(xy 359.678597 -264.210385) (xy 359.668572 -264.2108) (xy 359.464356 -264.2108) (xy 359.4443 -264.210342)
			(xy 359.404893 -264.202859) (xy 359.367577 -264.188147) (xy 359.333666 -264.166723) (xy 359.304354 -264.139341)
			(xy 359.292144 -264.123424) (xy 359.284524 -264.115042) (xy 359.263979 -264.09646) (xy 359.22831 -264.054079)
			(xy 359.199634 -264.006687) (xy 359.178642 -263.955426) (xy 359.16584 -263.901532) (xy 359.161537 -263.846307)
			(xy 352.607951 -263.846307) (xy 352.60788 -263.84631) (xy 350.75114 -263.84631) (xy 350.741996 -263.85012)
			(xy 350.71886 -263.859115) (xy 350.670577 -263.870624) (xy 350.621092 -263.874492) (xy 350.571607 -263.870624)
			(xy 350.523324 -263.859115) (xy 350.500188 -263.85012) (xy 350.491044 -263.84631) (xy 349.811086 -263.84631)
			(xy 349.801942 -263.85012) (xy 349.778806 -263.859115) (xy 349.730523 -263.870624) (xy 349.681038 -263.874492)
			(xy 349.631553 -263.870624) (xy 349.58327 -263.859115) (xy 349.560134 -263.85012) (xy 349.55099 -263.84631)
			(xy 349.347028 -263.84631) (xy 349.337191 -263.846847) (xy 349.319031 -263.854435) (xy 349.311722 -263.861042)
			(xy 348.960186 -264.212578) (xy 348.953468 -264.219814) (xy 348.945861 -264.238019) (xy 348.945454 -264.247884)
			(xy 348.945454 -264.365994) (xy 349.833184 -264.365994) (xy 349.833733 -264.339719) (xy 349.842422 -264.287892)
			(xy 349.850456 -264.26287) (xy 349.852996 -264.254742) (xy 349.852996 -264.20445) (xy 349.853388 -264.183403)
			(xy 349.861386 -264.142082) (xy 349.87732 -264.103127) (xy 349.900571 -264.068045) (xy 349.930242 -264.038194)
			(xy 349.965182 -264.01473) (xy 350.00404 -263.998561) (xy 350.045312 -263.990312) (xy 350.066356 -263.98982)
			(xy 350.321372 -263.98982) (xy 350.321372 -263.998964) (xy 350.321848 -264.00898) (xy 350.329501 -264.02749)
			(xy 350.343656 -264.041663) (xy 350.362157 -264.049339) (xy 350.372172 -264.049764) (xy 350.53524 -264.049764)
			(xy 350.54524 -264.05027) (xy 350.563709 -264.05795) (xy 350.577852 -264.072095) (xy 350.585531 -264.090564)
			(xy 350.58604 -264.100564) (xy 350.58604 -264.368026) (xy 351.70999 -264.368026) (xy 351.710591 -264.340445)
			(xy 351.720151 -264.286118) (xy 351.738939 -264.234254) (xy 351.752154 -264.210038) (xy 351.7549 -264.204968)
			(xy 351.758236 -264.193936) (xy 351.758758 -264.188194) (xy 351.760607 -264.168264) (xy 351.770811 -264.129565)
			(xy 351.788046 -264.093444) (xy 351.811708 -264.061168) (xy 351.840971 -264.033865) (xy 351.874807 -264.012492)
			(xy 351.912033 -263.997797) (xy 351.951346 -263.990296) (xy 351.971356 -263.98982) (xy 352.226372 -263.98982)
			(xy 352.226372 -263.998964) (xy 352.226848 -264.00898) (xy 352.234501 -264.02749) (xy 352.248656 -264.041663)
			(xy 352.267157 -264.049339) (xy 352.277172 -264.049764) (xy 352.44024 -264.049764) (xy 352.45024 -264.05027)
			(xy 352.468709 -264.05795) (xy 352.482852 -264.072095) (xy 352.490531 -264.090564) (xy 352.49104 -264.100564)
			(xy 352.49104 -264.368026) (xy 353.590098 -264.368026) (xy 353.590648 -264.341065) (xy 353.599759 -264.287919)
			(xy 353.617708 -264.237072) (xy 353.643979 -264.189983) (xy 353.660456 -264.168636) (xy 353.663669 -264.164349)
			(xy 353.668413 -264.154746) (xy 353.669854 -264.149586) (xy 353.675329 -264.130255) (xy 353.692507 -264.093941)
			(xy 353.716175 -264.061482) (xy 353.745499 -264.034024) (xy 353.779442 -264.012538) (xy 353.816805 -263.997781)
			(xy 353.85627 -263.990275) (xy 353.876356 -263.98982) (xy 354.131372 -263.98982) (xy 354.131372 -263.998964)
			(xy 354.131848 -264.00898) (xy 354.139501 -264.02749) (xy 354.153656 -264.041663) (xy 354.172157 -264.049339)
			(xy 354.182172 -264.049764) (xy 354.34524 -264.049764) (xy 354.35524 -264.05027) (xy 354.373709 -264.05795)
			(xy 354.387852 -264.072095) (xy 354.395531 -264.090564) (xy 354.39604 -264.100564) (xy 354.39604 -264.368026)
			(xy 355.469952 -264.368026) (xy 355.470512 -264.341417) (xy 355.47936 -264.28894) (xy 355.496832 -264.238671)
			(xy 355.522436 -264.192018) (xy 355.555458 -264.150284) (xy 355.574854 -264.13206) (xy 355.578636 -264.128454)
			(xy 355.584782 -264.120005) (xy 355.587046 -264.115296) (xy 355.595862 -264.096902) (xy 355.619389 -264.063588)
			(xy 355.648819 -264.035353) (xy 355.68308 -264.013227) (xy 355.720921 -263.998016) (xy 355.760964 -263.990275)
			(xy 355.781356 -263.98982) (xy 356.036372 -263.98982) (xy 356.036372 -263.998964) (xy 356.036848 -264.00898)
			(xy 356.044501 -264.02749) (xy 356.058656 -264.041663) (xy 356.077157 -264.049339) (xy 356.087172 -264.049764)
			(xy 356.25024 -264.049764) (xy 356.26024 -264.05027) (xy 356.278709 -264.05795) (xy 356.292852 -264.072095)
			(xy 356.300531 -264.090564) (xy 356.30104 -264.100564) (xy 356.30104 -264.368026) (xy 362.989876 -264.368026)
			(xy 362.990408 -264.341516) (xy 362.999211 -264.28923) (xy 363.01656 -264.239128) (xy 363.041975 -264.192595)
			(xy 363.057948 -264.17143) (xy 363.061159 -264.167072) (xy 363.065898 -264.157342) (xy 363.067346 -264.152126)
			(xy 363.072688 -264.13258) (xy 363.089648 -264.095788) (xy 363.113237 -264.062851) (xy 363.142609 -264.034947)
			(xy 363.176712 -264.013077) (xy 363.214325 -263.998024) (xy 363.2541 -263.990327) (xy 363.274356 -263.98982)
			(xy 363.529372 -263.98982) (xy 363.529372 -263.998964) (xy 363.529848 -264.00898) (xy 363.537501 -264.02749)
			(xy 363.551656 -264.041663) (xy 363.570157 -264.049339) (xy 363.580172 -264.049764) (xy 363.74324 -264.049764)
			(xy 363.75324 -264.05027) (xy 363.771709 -264.05795) (xy 363.785852 -264.072095) (xy 363.793531 -264.090564)
			(xy 363.79404 -264.100564) (xy 363.79404 -264.368026) (xy 364.869984 -264.368026) (xy 364.870535 -264.341832)
			(xy 364.879112 -264.290152) (xy 364.896054 -264.240579) (xy 364.920902 -264.194459) (xy 364.952981 -264.153043)
			(xy 364.971838 -264.134854) (xy 364.975626 -264.131181) (xy 364.981765 -264.122602) (xy 364.98403 -264.117836)
			(xy 364.992675 -264.099119) (xy 365.01612 -264.06521) (xy 365.045633 -264.036425) (xy 365.080117 -264.013833)
			(xy 365.118293 -263.998273) (xy 365.158744 -263.990322) (xy 365.179356 -263.98982) (xy 365.434372 -263.98982)
			(xy 365.434372 -263.998964) (xy 365.434848 -264.00898) (xy 365.442501 -264.02749) (xy 365.456656 -264.041663)
			(xy 365.475157 -264.049339) (xy 365.485172 -264.049764) (xy 365.64824 -264.049764) (xy 365.65824 -264.05027)
			(xy 365.676709 -264.05795) (xy 365.690852 -264.072095) (xy 365.698531 -264.090564) (xy 365.69904 -264.100564)
			(xy 365.69904 -264.368026) (xy 366.749838 -264.368026) (xy 366.750309 -264.342211) (xy 366.75864 -264.291258)
			(xy 366.775104 -264.242323) (xy 366.799266 -264.196696) (xy 366.830491 -264.155578) (xy 366.867955 -264.120053)
			(xy 366.88903 -264.105136) (xy 366.893311 -264.102013) (xy 366.900607 -264.09433) (xy 366.903508 -264.089896)
			(xy 366.915454 -264.071899) (xy 366.945272 -264.040658) (xy 366.980754 -264.016039) (xy 367.020457 -263.999044)
			(xy 367.062763 -263.990366) (xy 367.084356 -263.98982) (xy 367.339372 -263.98982) (xy 367.339372 -263.998964)
			(xy 367.339848 -264.00898) (xy 367.347501 -264.02749) (xy 367.361656 -264.041663) (xy 367.380157 -264.049339)
			(xy 367.390172 -264.049764) (xy 367.55324 -264.049764) (xy 367.56324 -264.05027) (xy 367.581709 -264.05795)
			(xy 367.595852 -264.072095) (xy 367.603531 -264.090564) (xy 367.60404 -264.100564) (xy 367.60404 -264.368026)
			(xy 368.62766 -264.368026) (xy 368.62824 -264.340743) (xy 368.63756 -264.286977) (xy 368.646202 -264.261092)
			(xy 368.648996 -264.252964) (xy 368.648996 -264.20445) (xy 368.649388 -264.183403) (xy 368.657386 -264.142082)
			(xy 368.67332 -264.103127) (xy 368.696571 -264.068045) (xy 368.726242 -264.038194) (xy 368.761182 -264.01473)
			(xy 368.80004 -263.998561) (xy 368.841312 -263.990312) (xy 368.862356 -263.98982) (xy 369.117372 -263.98982)
			(xy 369.117372 -263.998964) (xy 369.117848 -264.00898) (xy 369.125501 -264.02749) (xy 369.139656 -264.041663)
			(xy 369.158157 -264.049339) (xy 369.168172 -264.049764) (xy 369.33124 -264.049764) (xy 369.34124 -264.05027)
			(xy 369.359709 -264.05795) (xy 369.373852 -264.072095) (xy 369.381531 -264.090564) (xy 369.38204 -264.100564)
			(xy 369.38204 -264.365994) (xy 370.506752 -264.365994) (xy 370.507316 -264.338616) (xy 370.516685 -264.284668)
			(xy 370.535145 -264.233119) (xy 370.548154 -264.209022) (xy 370.550806 -264.204049) (xy 370.554147 -264.193288)
			(xy 370.554758 -264.187686) (xy 370.5567 -264.167798) (xy 370.566979 -264.12919) (xy 370.584256 -264.093166)
			(xy 370.607929 -264.060981) (xy 370.637173 -264.033759) (xy 370.670968 -264.012449) (xy 370.708136 -263.997792)
			(xy 370.74738 -263.990301) (xy 370.767356 -263.98982) (xy 371.022372 -263.98982) (xy 371.022372 -263.998964)
			(xy 371.022848 -264.00898) (xy 371.030501 -264.02749) (xy 371.044656 -264.041663) (xy 371.063157 -264.049339)
			(xy 371.073172 -264.049764) (xy 371.23624 -264.049764) (xy 371.24624 -264.05027) (xy 371.264709 -264.05795)
			(xy 371.278852 -264.072095) (xy 371.286531 -264.090564) (xy 371.28704 -264.100564) (xy 371.28704 -264.50417)
			(xy 372.331996 -264.50417) (xy 372.331996 -264.204704) (xy 372.331996 -264.20445) (xy 372.332388 -264.183403)
			(xy 372.340386 -264.142082) (xy 372.35632 -264.103127) (xy 372.379571 -264.068045) (xy 372.409242 -264.038194)
			(xy 372.444182 -264.01473) (xy 372.48304 -263.998561) (xy 372.524312 -263.990312) (xy 372.545356 -263.98982)
			(xy 372.800372 -263.98982) (xy 372.800372 -263.998964) (xy 372.800848 -264.00898) (xy 372.808501 -264.02749)
			(xy 372.822656 -264.041663) (xy 372.841157 -264.049339) (xy 372.851172 -264.049764) (xy 373.01424 -264.049764)
			(xy 373.02424 -264.05027) (xy 373.042709 -264.05795) (xy 373.056852 -264.072095) (xy 373.064531 -264.090564)
			(xy 373.06504 -264.100564) (xy 373.06504 -264.390983) (xy 374.267204 -264.390983) (xy 374.267204 -264.341005)
			(xy 374.275023 -264.291642) (xy 374.290467 -264.24411) (xy 374.313157 -264.199578) (xy 374.342533 -264.159145)
			(xy 374.377873 -264.123805) (xy 374.418306 -264.094429) (xy 374.462838 -264.071739) (xy 374.51037 -264.056295)
			(xy 374.559733 -264.048476) (xy 374.609711 -264.048476) (xy 374.659074 -264.056295) (xy 374.706606 -264.071739)
			(xy 374.751138 -264.094429) (xy 374.791571 -264.123805) (xy 374.826911 -264.159145) (xy 374.856287 -264.199578)
			(xy 374.878977 -264.24411) (xy 374.894421 -264.291642) (xy 374.90224 -264.341005) (xy 374.90273 -264.365994)
			(xy 376.148595 -264.365994) (xy 376.15269 -264.315266) (xy 376.164869 -264.265852) (xy 376.184817 -264.219032)
			(xy 376.212018 -264.176018) (xy 376.245766 -264.137924) (xy 376.285188 -264.105737) (xy 376.329262 -264.080291)
			(xy 376.376848 -264.062244) (xy 376.426712 -264.052064) (xy 376.477564 -264.050015) (xy 376.528085 -264.056149)
			(xy 376.576969 -264.070309) (xy 376.622948 -264.092126) (xy 376.664832 -264.121036) (xy 376.701536 -264.156291)
			(xy 376.732109 -264.196977) (xy 376.75576 -264.24204) (xy 376.771876 -264.290314) (xy 376.78004 -264.340548)
			(xy 376.780552 -264.365994) (xy 377.088649 -264.365994) (xy 377.092744 -264.315266) (xy 377.104923 -264.265852)
			(xy 377.124871 -264.219032) (xy 377.152072 -264.176018) (xy 377.18582 -264.137924) (xy 377.225242 -264.105737)
			(xy 377.269316 -264.080291) (xy 377.316902 -264.062244) (xy 377.366766 -264.052064) (xy 377.417618 -264.050015)
			(xy 377.468139 -264.056149) (xy 377.517023 -264.070309) (xy 377.563002 -264.092126) (xy 377.604886 -264.121036)
			(xy 377.64159 -264.156291) (xy 377.672163 -264.196977) (xy 377.695814 -264.24204) (xy 377.71193 -264.290314)
			(xy 377.720094 -264.340548) (xy 377.720606 -264.365994) (xy 377.720103 -264.390983) (xy 378.02742 -264.390983)
			(xy 378.02742 -264.341005) (xy 378.035239 -264.291642) (xy 378.050683 -264.24411) (xy 378.073373 -264.199578)
			(xy 378.102749 -264.159145) (xy 378.138089 -264.123805) (xy 378.178522 -264.094429) (xy 378.223054 -264.071739)
			(xy 378.270586 -264.056295) (xy 378.319949 -264.048476) (xy 378.369927 -264.048476) (xy 378.41929 -264.056295)
			(xy 378.466822 -264.071739) (xy 378.511354 -264.094429) (xy 378.551787 -264.123805) (xy 378.587127 -264.159145)
			(xy 378.616503 -264.199578) (xy 378.639193 -264.24411) (xy 378.654637 -264.291642) (xy 378.662456 -264.341005)
			(xy 378.662946 -264.365994) (xy 378.968503 -264.365994) (xy 378.972598 -264.315266) (xy 378.984777 -264.265852)
			(xy 379.004725 -264.219032) (xy 379.031926 -264.176018) (xy 379.065674 -264.137924) (xy 379.105096 -264.105737)
			(xy 379.14917 -264.080291) (xy 379.196756 -264.062244) (xy 379.24662 -264.052064) (xy 379.297472 -264.050015)
			(xy 379.347993 -264.056149) (xy 379.396877 -264.070309) (xy 379.442856 -264.092126) (xy 379.48474 -264.121036)
			(xy 379.521444 -264.156291) (xy 379.552017 -264.196977) (xy 379.575668 -264.24204) (xy 379.591784 -264.290314)
			(xy 379.599948 -264.340548) (xy 379.60046 -264.365994) (xy 379.599957 -264.390983) (xy 379.907274 -264.390983)
			(xy 379.907274 -264.341005) (xy 379.915093 -264.291642) (xy 379.930537 -264.24411) (xy 379.953227 -264.199578)
			(xy 379.982603 -264.159145) (xy 380.017943 -264.123805) (xy 380.058376 -264.094429) (xy 380.102908 -264.071739)
			(xy 380.15044 -264.056295) (xy 380.199803 -264.048476) (xy 380.249781 -264.048476) (xy 380.299144 -264.056295)
			(xy 380.346676 -264.071739) (xy 380.391208 -264.094429) (xy 380.431641 -264.123805) (xy 380.466981 -264.159145)
			(xy 380.496357 -264.199578) (xy 380.519047 -264.24411) (xy 380.534491 -264.291642) (xy 380.54231 -264.341005)
			(xy 380.5428 -264.365994) (xy 380.54231 -264.390983) (xy 380.534491 -264.440346) (xy 380.519047 -264.487878)
			(xy 380.496357 -264.53241) (xy 380.466981 -264.572843) (xy 380.431641 -264.608183) (xy 380.391208 -264.637559)
			(xy 380.346676 -264.660249) (xy 380.299144 -264.675693) (xy 380.249781 -264.683512) (xy 380.199803 -264.683512)
			(xy 380.15044 -264.675693) (xy 380.102908 -264.660249) (xy 380.058376 -264.637559) (xy 380.017943 -264.608183)
			(xy 379.982603 -264.572843) (xy 379.953227 -264.53241) (xy 379.930537 -264.487878) (xy 379.915093 -264.440346)
			(xy 379.907274 -264.390983) (xy 379.599957 -264.390983) (xy 379.599948 -264.39144) (xy 379.591784 -264.441674)
			(xy 379.575668 -264.489948) (xy 379.552017 -264.535011) (xy 379.521444 -264.575697) (xy 379.48474 -264.610952)
			(xy 379.442856 -264.639862) (xy 379.396877 -264.661679) (xy 379.347993 -264.675839) (xy 379.297472 -264.681973)
			(xy 379.24662 -264.679924) (xy 379.196756 -264.669744) (xy 379.14917 -264.651697) (xy 379.105096 -264.626251)
			(xy 379.065674 -264.594064) (xy 379.031926 -264.55597) (xy 379.004725 -264.512956) (xy 378.984777 -264.466136)
			(xy 378.972598 -264.416722) (xy 378.968503 -264.365994) (xy 378.662946 -264.365994) (xy 378.662456 -264.390983)
			(xy 378.654637 -264.440346) (xy 378.639193 -264.487878) (xy 378.616503 -264.53241) (xy 378.587127 -264.572843)
			(xy 378.551787 -264.608183) (xy 378.511354 -264.637559) (xy 378.466822 -264.660249) (xy 378.41929 -264.675693)
			(xy 378.369927 -264.683512) (xy 378.319949 -264.683512) (xy 378.270586 -264.675693) (xy 378.223054 -264.660249)
			(xy 378.178522 -264.637559) (xy 378.138089 -264.608183) (xy 378.102749 -264.572843) (xy 378.073373 -264.53241)
			(xy 378.050683 -264.487878) (xy 378.035239 -264.440346) (xy 378.02742 -264.390983) (xy 377.720103 -264.390983)
			(xy 377.720094 -264.39144) (xy 377.71193 -264.441674) (xy 377.695814 -264.489948) (xy 377.672163 -264.535011)
			(xy 377.64159 -264.575697) (xy 377.604886 -264.610952) (xy 377.563002 -264.639862) (xy 377.517023 -264.661679)
			(xy 377.468139 -264.675839) (xy 377.417618 -264.681973) (xy 377.366766 -264.679924) (xy 377.316902 -264.669744)
			(xy 377.269316 -264.651697) (xy 377.225242 -264.626251) (xy 377.18582 -264.594064) (xy 377.152072 -264.55597)
			(xy 377.124871 -264.512956) (xy 377.104923 -264.466136) (xy 377.092744 -264.416722) (xy 377.088649 -264.365994)
			(xy 376.780552 -264.365994) (xy 376.78004 -264.39144) (xy 376.771876 -264.441674) (xy 376.75576 -264.489948)
			(xy 376.732109 -264.535011) (xy 376.701536 -264.575697) (xy 376.664832 -264.610952) (xy 376.622948 -264.639862)
			(xy 376.576969 -264.661679) (xy 376.528085 -264.675839) (xy 376.477564 -264.681973) (xy 376.426712 -264.679924)
			(xy 376.376848 -264.669744) (xy 376.329262 -264.651697) (xy 376.285188 -264.626251) (xy 376.245766 -264.594064)
			(xy 376.212018 -264.55597) (xy 376.184817 -264.512956) (xy 376.164869 -264.466136) (xy 376.15269 -264.416722)
			(xy 376.148595 -264.365994) (xy 374.90273 -264.365994) (xy 374.90224 -264.390983) (xy 374.894421 -264.440346)
			(xy 374.878977 -264.487878) (xy 374.856287 -264.53241) (xy 374.826911 -264.572843) (xy 374.791571 -264.608183)
			(xy 374.751138 -264.637559) (xy 374.706606 -264.660249) (xy 374.659074 -264.675693) (xy 374.609711 -264.683512)
			(xy 374.559733 -264.683512) (xy 374.51037 -264.675693) (xy 374.462838 -264.660249) (xy 374.418306 -264.637559)
			(xy 374.377873 -264.608183) (xy 374.342533 -264.572843) (xy 374.313157 -264.53241) (xy 374.290467 -264.487878)
			(xy 374.275023 -264.440346) (xy 374.267204 -264.390983) (xy 373.06504 -264.390983) (xy 373.06504 -264.608056)
			(xy 373.064674 -264.618094) (xy 373.057037 -264.636655) (xy 373.042842 -264.650846) (xy 373.024278 -264.658477)
			(xy 373.01424 -264.658856) (xy 372.838472 -264.658856) (xy 372.833718 -264.658943) (xy 372.824382 -264.66074)
			(xy 372.81993 -264.662412) (xy 372.800372 -264.66927) (xy 372.800372 -264.689336) (xy 372.7704 -264.7188)
			(xy 372.545356 -264.7188) (xy 372.524311 -264.718316) (xy 372.483036 -264.710067) (xy 372.444174 -264.693898)
			(xy 372.409231 -264.670433) (xy 372.379557 -264.640582) (xy 372.356301 -264.605498) (xy 372.340364 -264.566541)
			(xy 372.332362 -264.525218) (xy 372.331996 -264.50417) (xy 371.28704 -264.50417) (xy 371.28704 -264.608056)
			(xy 371.286674 -264.618094) (xy 371.279037 -264.636655) (xy 371.264842 -264.650846) (xy 371.246278 -264.658477)
			(xy 371.23624 -264.658856) (xy 371.022372 -264.658856) (xy 371.022372 -264.668) (xy 371.02198 -264.678025)
			(xy 371.014305 -264.696547) (xy 371.000124 -264.71072) (xy 370.981597 -264.718385) (xy 370.971572 -264.7188)
			(xy 370.767356 -264.7188) (xy 370.746265 -264.718354) (xy 370.704906 -264.710052) (xy 370.66598 -264.693798)
			(xy 370.630998 -264.670225) (xy 370.601319 -264.640249) (xy 370.578097 -264.605033) (xy 370.562233 -264.565946)
			(xy 370.557806 -264.545318) (xy 370.556918 -264.540982) (xy 370.553861 -264.532676) (xy 370.55171 -264.528808)
			(xy 370.537638 -264.504003) (xy 370.517613 -264.45061) (xy 370.507411 -264.394506) (xy 370.506752 -264.365994)
			(xy 369.38204 -264.365994) (xy 369.38204 -264.608056) (xy 369.381674 -264.618094) (xy 369.374037 -264.636655)
			(xy 369.359842 -264.650846) (xy 369.341278 -264.658477) (xy 369.33124 -264.658856) (xy 369.117372 -264.658856)
			(xy 369.117372 -264.668) (xy 369.11698 -264.678025) (xy 369.109305 -264.696547) (xy 369.095124 -264.71072)
			(xy 369.076597 -264.718385) (xy 369.066572 -264.7188) (xy 368.862356 -264.7188) (xy 368.841311 -264.718316)
			(xy 368.800036 -264.710067) (xy 368.761174 -264.693898) (xy 368.726231 -264.670433) (xy 368.696557 -264.640582)
			(xy 368.673301 -264.605498) (xy 368.657364 -264.566541) (xy 368.649362 -264.525218) (xy 368.648996 -264.50417)
			(xy 368.648996 -264.483088) (xy 368.646202 -264.47496) (xy 368.637543 -264.449079) (xy 368.628221 -264.395311)
			(xy 368.62766 -264.368026) (xy 367.60404 -264.368026) (xy 367.60404 -264.608056) (xy 367.603674 -264.618094)
			(xy 367.596037 -264.636655) (xy 367.581842 -264.650846) (xy 367.563278 -264.658477) (xy 367.55324 -264.658856)
			(xy 367.339372 -264.658856) (xy 367.339372 -264.668) (xy 367.33898 -264.678025) (xy 367.331305 -264.696547)
			(xy 367.317124 -264.71072) (xy 367.298597 -264.718385) (xy 367.288572 -264.7188) (xy 367.084356 -264.7188)
			(xy 367.064318 -264.718325) (xy 367.024948 -264.710828) (xy 366.987666 -264.696126) (xy 366.953777 -264.674732)
			(xy 366.938814 -264.661396) (xy 366.936052 -264.658912) (xy 366.929931 -264.654702) (xy 366.926622 -264.653014)
			(xy 366.904216 -264.641371) (xy 366.863096 -264.612071) (xy 366.827118 -264.576645) (xy 366.797188 -264.535981)
			(xy 366.774056 -264.4911) (xy 366.758303 -264.443129) (xy 366.750324 -264.393272) (xy 366.749838 -264.368026)
			(xy 365.69904 -264.368026) (xy 365.69904 -264.608056) (xy 365.698674 -264.618094) (xy 365.691037 -264.636655)
			(xy 365.676842 -264.650846) (xy 365.658278 -264.658477) (xy 365.64824 -264.658856) (xy 365.434372 -264.658856)
			(xy 365.434372 -264.668) (xy 365.43398 -264.678025) (xy 365.426305 -264.696547) (xy 365.412124 -264.71072)
			(xy 365.393597 -264.718385) (xy 365.383572 -264.7188) (xy 365.179356 -264.7188) (xy 365.159596 -264.718327)
			(xy 365.120754 -264.711035) (xy 365.083914 -264.696727) (xy 365.050333 -264.67589) (xy 365.021155 -264.649235)
			(xy 365.008922 -264.63371) (xy 365.006648 -264.630853) (xy 365.001422 -264.625751) (xy 364.998508 -264.62355)
			(xy 364.978933 -264.608424) (xy 364.944261 -264.573142) (xy 364.915464 -264.532921) (xy 364.893236 -264.488729)
			(xy 364.878111 -264.441631) (xy 364.870455 -264.39276) (xy 364.869984 -264.368026) (xy 363.79404 -264.368026)
			(xy 363.79404 -264.608056) (xy 363.793674 -264.618094) (xy 363.786037 -264.636655) (xy 363.771842 -264.650846)
			(xy 363.753278 -264.658477) (xy 363.74324 -264.658856) (xy 363.529372 -264.658856) (xy 363.529372 -264.668)
			(xy 363.52898 -264.678025) (xy 363.521305 -264.696547) (xy 363.507124 -264.71072) (xy 363.488597 -264.718385)
			(xy 363.478572 -264.7188) (xy 363.274356 -264.7188) (xy 363.254032 -264.718315) (xy 363.214119 -264.710616)
			(xy 363.176383 -264.695506) (xy 363.142188 -264.673529) (xy 363.112768 -264.64548) (xy 363.089185 -264.612372)
			(xy 363.0803 -264.594086) (xy 363.078657 -264.590576) (xy 363.074448 -264.584068) (xy 363.071918 -264.581132)
			(xy 363.056562 -264.563512) (xy 363.030636 -264.524624) (xy 363.010686 -264.482359) (xy 362.99714 -264.437628)
			(xy 362.990291 -264.391395) (xy 362.989876 -264.368026) (xy 356.30104 -264.368026) (xy 356.30104 -264.608056)
			(xy 356.300674 -264.618094) (xy 356.293037 -264.636655) (xy 356.278842 -264.650846) (xy 356.260278 -264.658477)
			(xy 356.25024 -264.658856) (xy 356.036372 -264.658856) (xy 356.036372 -264.668) (xy 356.03598 -264.678025)
			(xy 356.028305 -264.696547) (xy 356.014124 -264.71072) (xy 355.995597 -264.718385) (xy 355.985572 -264.7188)
			(xy 355.781356 -264.7188) (xy 355.761936 -264.718359) (xy 355.723732 -264.711354) (xy 355.687428 -264.697549)
			(xy 355.654224 -264.677398) (xy 355.625217 -264.651568) (xy 355.612954 -264.636504) (xy 355.610689 -264.633639)
			(xy 355.605457 -264.628542) (xy 355.60254 -264.626344) (xy 355.582373 -264.61132) (xy 355.546637 -264.575939)
			(xy 355.516919 -264.535371) (xy 355.493959 -264.490631) (xy 355.478331 -264.442833) (xy 355.470424 -264.39317)
			(xy 355.469952 -264.368026) (xy 354.39604 -264.368026) (xy 354.39604 -264.608056) (xy 354.395674 -264.618094)
			(xy 354.388037 -264.636655) (xy 354.373842 -264.650846) (xy 354.355278 -264.658477) (xy 354.34524 -264.658856)
			(xy 354.131372 -264.658856) (xy 354.131372 -264.668) (xy 354.13098 -264.678025) (xy 354.123305 -264.696547)
			(xy 354.109124 -264.71072) (xy 354.090597 -264.718385) (xy 354.080572 -264.7188) (xy 353.876356 -264.7188)
			(xy 353.856333 -264.71836) (xy 353.816989 -264.710887) (xy 353.779728 -264.696212) (xy 353.745855 -264.674849)
			(xy 353.716558 -264.647546) (xy 353.692864 -264.61526) (xy 353.683824 -264.597388) (xy 353.682126 -264.593865)
			(xy 353.677782 -264.587361) (xy 353.675188 -264.584434) (xy 353.659295 -264.566688) (xy 353.632416 -264.527359)
			(xy 353.61171 -264.484458) (xy 353.597641 -264.438946) (xy 353.590525 -264.391844) (xy 353.590098 -264.368026)
			(xy 352.49104 -264.368026) (xy 352.49104 -264.608056) (xy 352.490674 -264.618094) (xy 352.483037 -264.636655)
			(xy 352.468842 -264.650846) (xy 352.450278 -264.658477) (xy 352.44024 -264.658856) (xy 352.226372 -264.658856)
			(xy 352.226372 -264.668) (xy 352.22598 -264.678025) (xy 352.218305 -264.696547) (xy 352.204124 -264.71072)
			(xy 352.185597 -264.718385) (xy 352.175572 -264.7188) (xy 351.971356 -264.7188) (xy 351.950561 -264.718312)
			(xy 351.909759 -264.710257) (xy 351.871286 -264.694459) (xy 351.836598 -264.671515) (xy 351.807004 -264.642293)
			(xy 351.783623 -264.607898) (xy 351.76734 -264.569628) (xy 351.762568 -264.549382) (xy 351.761592 -264.545165)
			(xy 351.758401 -264.537118) (xy 351.756218 -264.53338) (xy 351.741711 -264.508264) (xy 351.721074 -264.454066)
			(xy 351.710607 -264.397024) (xy 351.70999 -264.368026) (xy 350.58604 -264.368026) (xy 350.58604 -264.608056)
			(xy 350.585674 -264.618094) (xy 350.578037 -264.636655) (xy 350.563842 -264.650846) (xy 350.545278 -264.658477)
			(xy 350.53524 -264.658856) (xy 350.321372 -264.658856) (xy 350.321372 -264.668) (xy 350.32098 -264.678025)
			(xy 350.313305 -264.696547) (xy 350.299124 -264.71072) (xy 350.280597 -264.718385) (xy 350.270572 -264.7188)
			(xy 350.066356 -264.7188) (xy 350.045311 -264.718316) (xy 350.004036 -264.710067) (xy 349.965174 -264.693898)
			(xy 349.930231 -264.670433) (xy 349.900557 -264.640582) (xy 349.877301 -264.605498) (xy 349.861364 -264.566541)
			(xy 349.853362 -264.525218) (xy 349.852996 -264.50417) (xy 349.852996 -264.477246) (xy 349.850456 -264.469118)
			(xy 349.842435 -264.444092) (xy 349.833749 -264.392267) (xy 349.833184 -264.365994) (xy 348.945454 -264.365994)
			(xy 348.945454 -264.805922) (xy 348.945914 -264.8158) (xy 348.953353 -264.834101) (xy 348.959932 -264.841482)
			(xy 348.960186 -264.841736) (xy 349.04553 -264.92708) (xy 349.052246 -264.934317) (xy 349.059849 -264.952522)
			(xy 349.060262 -264.962386) (xy 349.060262 -265.200989) (xy 349.36352 -265.200989) (xy 349.36352 -265.151011)
			(xy 349.371339 -265.101648) (xy 349.386783 -265.054116) (xy 349.409473 -265.009584) (xy 349.438849 -264.969151)
			(xy 349.474189 -264.933811) (xy 349.514622 -264.904435) (xy 349.559154 -264.881745) (xy 349.606686 -264.866301)
			(xy 349.656049 -264.858482) (xy 349.706027 -264.858482) (xy 349.730175 -264.862307) (xy 359.161537 -264.862307)
			(xy 359.165838 -264.807081) (xy 359.178637 -264.753187) (xy 359.199628 -264.701925) (xy 359.228303 -264.654531)
			(xy 359.26397 -264.612149) (xy 359.284524 -264.593578) (xy 359.292144 -264.585196) (xy 359.304386 -264.569305)
			(xy 359.333693 -264.541925) (xy 359.367596 -264.520498) (xy 359.404903 -264.505777) (xy 359.444303 -264.498281)
			(xy 359.464356 -264.49782) (xy 359.719372 -264.49782) (xy 359.719372 -264.506964) (xy 359.719848 -264.51698)
			(xy 359.727501 -264.53549) (xy 359.741656 -264.549663) (xy 359.760157 -264.557339) (xy 359.770172 -264.557764)
			(xy 359.93324 -264.557764) (xy 359.94324 -264.55827) (xy 359.961709 -264.56595) (xy 359.975852 -264.580095)
			(xy 359.983531 -264.598564) (xy 359.98404 -264.608564) (xy 359.98404 -265.116056) (xy 359.983674 -265.126094)
			(xy 359.976037 -265.144655) (xy 359.961842 -265.158846) (xy 359.943278 -265.166477) (xy 359.93324 -265.166856)
			(xy 359.719372 -265.166856) (xy 359.719372 -265.176) (xy 359.71898 -265.186025) (xy 359.712779 -265.200989)
			(xy 369.097288 -265.200989) (xy 369.097288 -265.151011) (xy 369.105107 -265.101648) (xy 369.120551 -265.054116)
			(xy 369.143241 -265.009584) (xy 369.172617 -264.969151) (xy 369.207957 -264.933811) (xy 369.24839 -264.904435)
			(xy 369.292922 -264.881745) (xy 369.340454 -264.866301) (xy 369.389817 -264.858482) (xy 369.439795 -264.858482)
			(xy 369.489158 -264.866301) (xy 369.53669 -264.881745) (xy 369.581222 -264.904435) (xy 369.621655 -264.933811)
			(xy 369.656995 -264.969151) (xy 369.686371 -265.009584) (xy 369.709061 -265.054116) (xy 369.724505 -265.101648)
			(xy 369.732324 -265.151011) (xy 369.732814 -265.176) (xy 369.732324 -265.200989) (xy 370.977396 -265.200989)
			(xy 370.977396 -265.151011) (xy 370.985215 -265.101648) (xy 371.000659 -265.054116) (xy 371.023349 -265.009584)
			(xy 371.052725 -264.969151) (xy 371.088065 -264.933811) (xy 371.128498 -264.904435) (xy 371.17303 -264.881745)
			(xy 371.220562 -264.866301) (xy 371.269925 -264.858482) (xy 371.319903 -264.858482) (xy 371.369266 -264.866301)
			(xy 371.416798 -264.881745) (xy 371.46133 -264.904435) (xy 371.501763 -264.933811) (xy 371.537103 -264.969151)
			(xy 371.566479 -265.009584) (xy 371.589169 -265.054116) (xy 371.604613 -265.101648) (xy 371.612432 -265.151011)
			(xy 371.612922 -265.176) (xy 371.612432 -265.200989) (xy 372.85725 -265.200989) (xy 372.85725 -265.151011)
			(xy 372.865069 -265.101648) (xy 372.880513 -265.054116) (xy 372.903203 -265.009584) (xy 372.932579 -264.969151)
			(xy 372.967919 -264.933811) (xy 373.008352 -264.904435) (xy 373.052884 -264.881745) (xy 373.100416 -264.866301)
			(xy 373.149779 -264.858482) (xy 373.199757 -264.858482) (xy 373.24912 -264.866301) (xy 373.296652 -264.881745)
			(xy 373.341184 -264.904435) (xy 373.381617 -264.933811) (xy 373.416957 -264.969151) (xy 373.446333 -265.009584)
			(xy 373.469023 -265.054116) (xy 373.484467 -265.101648) (xy 373.492286 -265.151011) (xy 373.492776 -265.176)
			(xy 373.492286 -265.200989) (xy 374.737358 -265.200989) (xy 374.737358 -265.151011) (xy 374.745177 -265.101648)
			(xy 374.760621 -265.054116) (xy 374.783311 -265.009584) (xy 374.812687 -264.969151) (xy 374.848027 -264.933811)
			(xy 374.88846 -264.904435) (xy 374.932992 -264.881745) (xy 374.980524 -264.866301) (xy 375.029887 -264.858482)
			(xy 375.079865 -264.858482) (xy 375.129228 -264.866301) (xy 375.17676 -264.881745) (xy 375.221292 -264.904435)
			(xy 375.261725 -264.933811) (xy 375.297065 -264.969151) (xy 375.326441 -265.009584) (xy 375.349131 -265.054116)
			(xy 375.364575 -265.101648) (xy 375.372394 -265.151011) (xy 375.372884 -265.176) (xy 375.678695 -265.176)
			(xy 375.68279 -265.125272) (xy 375.694969 -265.075858) (xy 375.714917 -265.029038) (xy 375.742118 -264.986024)
			(xy 375.775866 -264.94793) (xy 375.815288 -264.915743) (xy 375.859362 -264.890297) (xy 375.906948 -264.87225)
			(xy 375.956812 -264.86207) (xy 376.007664 -264.860021) (xy 376.058185 -264.866155) (xy 376.107069 -264.880315)
			(xy 376.153048 -264.902132) (xy 376.194932 -264.931042) (xy 376.231636 -264.966297) (xy 376.262209 -265.006983)
			(xy 376.28586 -265.052046) (xy 376.301976 -265.10032) (xy 376.31014 -265.150554) (xy 376.310652 -265.176)
			(xy 376.310149 -265.200989) (xy 376.617212 -265.200989) (xy 376.617212 -265.151011) (xy 376.625031 -265.101648)
			(xy 376.640475 -265.054116) (xy 376.663165 -265.009584) (xy 376.692541 -264.969151) (xy 376.727881 -264.933811)
			(xy 376.768314 -264.904435) (xy 376.812846 -264.881745) (xy 376.860378 -264.866301) (xy 376.909741 -264.858482)
			(xy 376.959719 -264.858482) (xy 377.009082 -264.866301) (xy 377.056614 -264.881745) (xy 377.101146 -264.904435)
			(xy 377.141579 -264.933811) (xy 377.176919 -264.969151) (xy 377.206295 -265.009584) (xy 377.228985 -265.054116)
			(xy 377.244429 -265.101648) (xy 377.252248 -265.151011) (xy 377.252738 -265.176) (xy 377.252248 -265.200989)
			(xy 377.557266 -265.200989) (xy 377.557266 -265.151011) (xy 377.565085 -265.101648) (xy 377.580529 -265.054116)
			(xy 377.603219 -265.009584) (xy 377.632595 -264.969151) (xy 377.667935 -264.933811) (xy 377.708368 -264.904435)
			(xy 377.7529 -264.881745) (xy 377.800432 -264.866301) (xy 377.849795 -264.858482) (xy 377.899773 -264.858482)
			(xy 377.949136 -264.866301) (xy 377.996668 -264.881745) (xy 378.0412 -264.904435) (xy 378.081633 -264.933811)
			(xy 378.116973 -264.969151) (xy 378.146349 -265.009584) (xy 378.169039 -265.054116) (xy 378.184483 -265.101648)
			(xy 378.192302 -265.151011) (xy 378.192792 -265.176) (xy 378.192302 -265.200989) (xy 378.49732 -265.200989)
			(xy 378.49732 -265.151011) (xy 378.505139 -265.101648) (xy 378.520583 -265.054116) (xy 378.543273 -265.009584)
			(xy 378.572649 -264.969151) (xy 378.607989 -264.933811) (xy 378.648422 -264.904435) (xy 378.692954 -264.881745)
			(xy 378.740486 -264.866301) (xy 378.789849 -264.858482) (xy 378.839827 -264.858482) (xy 378.88919 -264.866301)
			(xy 378.936722 -264.881745) (xy 378.981254 -264.904435) (xy 379.021687 -264.933811) (xy 379.057027 -264.969151)
			(xy 379.086403 -265.009584) (xy 379.109093 -265.054116) (xy 379.124537 -265.101648) (xy 379.132356 -265.151011)
			(xy 379.132846 -265.176) (xy 379.438657 -265.176) (xy 379.442752 -265.125272) (xy 379.454931 -265.075858)
			(xy 379.474879 -265.029038) (xy 379.50208 -264.986024) (xy 379.535828 -264.94793) (xy 379.57525 -264.915743)
			(xy 379.619324 -264.890297) (xy 379.66691 -264.87225) (xy 379.716774 -264.86207) (xy 379.767626 -264.860021)
			(xy 379.818147 -264.866155) (xy 379.867031 -264.880315) (xy 379.91301 -264.902132) (xy 379.954894 -264.931042)
			(xy 379.991598 -264.966297) (xy 380.022171 -265.006983) (xy 380.045822 -265.052046) (xy 380.061938 -265.10032)
			(xy 380.070102 -265.150554) (xy 380.070614 -265.176) (xy 380.070111 -265.200989) (xy 380.377174 -265.200989)
			(xy 380.377174 -265.151011) (xy 380.384993 -265.101648) (xy 380.400437 -265.054116) (xy 380.423127 -265.009584)
			(xy 380.452503 -264.969151) (xy 380.487843 -264.933811) (xy 380.528276 -264.904435) (xy 380.572808 -264.881745)
			(xy 380.62034 -264.866301) (xy 380.669703 -264.858482) (xy 380.719681 -264.858482) (xy 380.769044 -264.866301)
			(xy 380.816576 -264.881745) (xy 380.861108 -264.904435) (xy 380.901541 -264.933811) (xy 380.936881 -264.969151)
			(xy 380.966257 -265.009584) (xy 380.988947 -265.054116) (xy 381.004391 -265.101648) (xy 381.01221 -265.151011)
			(xy 381.0127 -265.176) (xy 381.01221 -265.200989) (xy 381.004391 -265.250352) (xy 380.988947 -265.297884)
			(xy 380.966257 -265.342416) (xy 380.936881 -265.382849) (xy 380.901541 -265.418189) (xy 380.861108 -265.447565)
			(xy 380.816576 -265.470255) (xy 380.769044 -265.485699) (xy 380.719681 -265.493518) (xy 380.669703 -265.493518)
			(xy 380.62034 -265.485699) (xy 380.572808 -265.470255) (xy 380.528276 -265.447565) (xy 380.487843 -265.418189)
			(xy 380.452503 -265.382849) (xy 380.423127 -265.342416) (xy 380.400437 -265.297884) (xy 380.384993 -265.250352)
			(xy 380.377174 -265.200989) (xy 380.070111 -265.200989) (xy 380.070102 -265.201446) (xy 380.061938 -265.25168)
			(xy 380.045822 -265.299954) (xy 380.022171 -265.345017) (xy 379.991598 -265.385703) (xy 379.954894 -265.420958)
			(xy 379.91301 -265.449868) (xy 379.867031 -265.471685) (xy 379.818147 -265.485845) (xy 379.767626 -265.491979)
			(xy 379.716774 -265.48993) (xy 379.66691 -265.47975) (xy 379.619324 -265.461703) (xy 379.57525 -265.436257)
			(xy 379.535828 -265.40407) (xy 379.50208 -265.365976) (xy 379.474879 -265.322962) (xy 379.454931 -265.276142)
			(xy 379.442752 -265.226728) (xy 379.438657 -265.176) (xy 379.132846 -265.176) (xy 379.132356 -265.200989)
			(xy 379.124537 -265.250352) (xy 379.109093 -265.297884) (xy 379.086403 -265.342416) (xy 379.057027 -265.382849)
			(xy 379.021687 -265.418189) (xy 378.981254 -265.447565) (xy 378.936722 -265.470255) (xy 378.88919 -265.485699)
			(xy 378.839827 -265.493518) (xy 378.789849 -265.493518) (xy 378.740486 -265.485699) (xy 378.692954 -265.470255)
			(xy 378.648422 -265.447565) (xy 378.607989 -265.418189) (xy 378.572649 -265.382849) (xy 378.543273 -265.342416)
			(xy 378.520583 -265.297884) (xy 378.505139 -265.250352) (xy 378.49732 -265.200989) (xy 378.192302 -265.200989)
			(xy 378.184483 -265.250352) (xy 378.169039 -265.297884) (xy 378.146349 -265.342416) (xy 378.116973 -265.382849)
			(xy 378.081633 -265.418189) (xy 378.0412 -265.447565) (xy 377.996668 -265.470255) (xy 377.949136 -265.485699)
			(xy 377.899773 -265.493518) (xy 377.849795 -265.493518) (xy 377.800432 -265.485699) (xy 377.7529 -265.470255)
			(xy 377.708368 -265.447565) (xy 377.667935 -265.418189) (xy 377.632595 -265.382849) (xy 377.603219 -265.342416)
			(xy 377.580529 -265.297884) (xy 377.565085 -265.250352) (xy 377.557266 -265.200989) (xy 377.252248 -265.200989)
			(xy 377.244429 -265.250352) (xy 377.228985 -265.297884) (xy 377.206295 -265.342416) (xy 377.176919 -265.382849)
			(xy 377.141579 -265.418189) (xy 377.101146 -265.447565) (xy 377.056614 -265.470255) (xy 377.009082 -265.485699)
			(xy 376.959719 -265.493518) (xy 376.909741 -265.493518) (xy 376.860378 -265.485699) (xy 376.812846 -265.470255)
			(xy 376.768314 -265.447565) (xy 376.727881 -265.418189) (xy 376.692541 -265.382849) (xy 376.663165 -265.342416)
			(xy 376.640475 -265.297884) (xy 376.625031 -265.250352) (xy 376.617212 -265.200989) (xy 376.310149 -265.200989)
			(xy 376.31014 -265.201446) (xy 376.301976 -265.25168) (xy 376.28586 -265.299954) (xy 376.262209 -265.345017)
			(xy 376.231636 -265.385703) (xy 376.194932 -265.420958) (xy 376.153048 -265.449868) (xy 376.107069 -265.471685)
			(xy 376.058185 -265.485845) (xy 376.007664 -265.491979) (xy 375.956812 -265.48993) (xy 375.906948 -265.47975)
			(xy 375.859362 -265.461703) (xy 375.815288 -265.436257) (xy 375.775866 -265.40407) (xy 375.742118 -265.365976)
			(xy 375.714917 -265.322962) (xy 375.694969 -265.276142) (xy 375.68279 -265.226728) (xy 375.678695 -265.176)
			(xy 375.372884 -265.176) (xy 375.372394 -265.200989) (xy 375.364575 -265.250352) (xy 375.349131 -265.297884)
			(xy 375.326441 -265.342416) (xy 375.297065 -265.382849) (xy 375.261725 -265.418189) (xy 375.221292 -265.447565)
			(xy 375.17676 -265.470255) (xy 375.129228 -265.485699) (xy 375.079865 -265.493518) (xy 375.029887 -265.493518)
			(xy 374.980524 -265.485699) (xy 374.932992 -265.470255) (xy 374.88846 -265.447565) (xy 374.848027 -265.418189)
			(xy 374.812687 -265.382849) (xy 374.783311 -265.342416) (xy 374.760621 -265.297884) (xy 374.745177 -265.250352)
			(xy 374.737358 -265.200989) (xy 373.492286 -265.200989) (xy 373.484467 -265.250352) (xy 373.469023 -265.297884)
			(xy 373.446333 -265.342416) (xy 373.416957 -265.382849) (xy 373.381617 -265.418189) (xy 373.341184 -265.447565)
			(xy 373.296652 -265.470255) (xy 373.24912 -265.485699) (xy 373.199757 -265.493518) (xy 373.149779 -265.493518)
			(xy 373.100416 -265.485699) (xy 373.052884 -265.470255) (xy 373.008352 -265.447565) (xy 372.967919 -265.418189)
			(xy 372.932579 -265.382849) (xy 372.903203 -265.342416) (xy 372.880513 -265.297884) (xy 372.865069 -265.250352)
			(xy 372.85725 -265.200989) (xy 371.612432 -265.200989) (xy 371.604613 -265.250352) (xy 371.589169 -265.297884)
			(xy 371.566479 -265.342416) (xy 371.537103 -265.382849) (xy 371.501763 -265.418189) (xy 371.46133 -265.447565)
			(xy 371.416798 -265.470255) (xy 371.369266 -265.485699) (xy 371.319903 -265.493518) (xy 371.269925 -265.493518)
			(xy 371.220562 -265.485699) (xy 371.17303 -265.470255) (xy 371.128498 -265.447565) (xy 371.088065 -265.418189)
			(xy 371.052725 -265.382849) (xy 371.023349 -265.342416) (xy 371.000659 -265.297884) (xy 370.985215 -265.250352)
			(xy 370.977396 -265.200989) (xy 369.732324 -265.200989) (xy 369.724505 -265.250352) (xy 369.709061 -265.297884)
			(xy 369.686371 -265.342416) (xy 369.656995 -265.382849) (xy 369.621655 -265.418189) (xy 369.581222 -265.447565)
			(xy 369.53669 -265.470255) (xy 369.489158 -265.485699) (xy 369.439795 -265.493518) (xy 369.389817 -265.493518)
			(xy 369.340454 -265.485699) (xy 369.292922 -265.470255) (xy 369.24839 -265.447565) (xy 369.207957 -265.418189)
			(xy 369.172617 -265.382849) (xy 369.143241 -265.342416) (xy 369.120551 -265.297884) (xy 369.105107 -265.250352)
			(xy 369.097288 -265.200989) (xy 359.712779 -265.200989) (xy 359.711305 -265.204547) (xy 359.697124 -265.21872)
			(xy 359.678597 -265.226385) (xy 359.668572 -265.2268) (xy 359.464356 -265.2268) (xy 359.4443 -265.226342)
			(xy 359.404893 -265.218859) (xy 359.367577 -265.204147) (xy 359.333666 -265.182723) (xy 359.304354 -265.155341)
			(xy 359.292144 -265.139424) (xy 359.284524 -265.131042) (xy 359.263979 -265.11246) (xy 359.22831 -265.070079)
			(xy 359.199634 -265.022687) (xy 359.178642 -264.971426) (xy 359.16584 -264.917532) (xy 359.161537 -264.862307)
			(xy 349.730175 -264.862307) (xy 349.75539 -264.866301) (xy 349.802922 -264.881745) (xy 349.847454 -264.904435)
			(xy 349.887887 -264.933811) (xy 349.923227 -264.969151) (xy 349.952603 -265.009584) (xy 349.975293 -265.054116)
			(xy 349.990737 -265.101648) (xy 349.998556 -265.151011) (xy 349.999046 -265.176) (xy 349.998556 -265.200989)
			(xy 349.990737 -265.250352) (xy 349.975293 -265.297884) (xy 349.952603 -265.342416) (xy 349.923227 -265.382849)
			(xy 349.887887 -265.418189) (xy 349.847454 -265.447565) (xy 349.802922 -265.470255) (xy 349.75539 -265.485699)
			(xy 349.706027 -265.493518) (xy 349.656049 -265.493518) (xy 349.606686 -265.485699) (xy 349.559154 -265.470255)
			(xy 349.514622 -265.447565) (xy 349.474189 -265.418189) (xy 349.438849 -265.382849) (xy 349.409473 -265.342416)
			(xy 349.386783 -265.297884) (xy 349.371339 -265.250352) (xy 349.36352 -265.200989) (xy 349.060262 -265.200989)
			(xy 349.060262 -265.397234) (xy 349.059734 -265.407076) (xy 349.052163 -265.425252) (xy 349.04553 -265.43254)
			(xy 348.960186 -265.517884) (xy 348.953469 -265.525121) (xy 348.945865 -265.543326) (xy 348.945454 -265.55319)
			(xy 348.945454 -265.986006) (xy 349.833184 -265.986006) (xy 349.833682 -265.96016) (xy 349.842071 -265.909153)
			(xy 349.858595 -265.860173) (xy 349.882821 -265.814509) (xy 349.91411 -265.773362) (xy 349.951641 -265.737815)
			(xy 349.994424 -265.708803) (xy 350.041335 -265.68709) (xy 350.066102 -265.679682) (xy 350.069651 -265.6786)
			(xy 350.076408 -265.675536) (xy 350.079564 -265.673586) (xy 350.096733 -265.663287) (xy 350.133997 -265.648656)
			(xy 350.173339 -265.641244) (xy 350.193356 -265.64082) (xy 350.448372 -265.64082) (xy 350.448372 -265.649964)
			(xy 350.448848 -265.65998) (xy 350.456501 -265.67849) (xy 350.470656 -265.692663) (xy 350.489157 -265.700339)
			(xy 350.499172 -265.700764) (xy 350.66224 -265.700764) (xy 350.67224 -265.70127) (xy 350.690709 -265.70895)
			(xy 350.704852 -265.723095) (xy 350.712531 -265.741564) (xy 350.71304 -265.751564) (xy 350.71304 -265.986006)
			(xy 351.713038 -265.986006) (xy 351.71366 -265.957836) (xy 351.723632 -265.902384) (xy 351.743212 -265.849555)
			(xy 351.75698 -265.82497) (xy 351.758965 -265.821382) (xy 351.761901 -265.813726) (xy 351.762822 -265.80973)
			(xy 351.76754 -265.789512) (xy 351.783842 -265.751333) (xy 351.807221 -265.717028) (xy 351.836794 -265.687894)
			(xy 351.871445 -265.66503) (xy 351.909863 -265.649301) (xy 351.950599 -265.6413) (xy 351.971356 -265.64082)
			(xy 352.226372 -265.64082) (xy 352.226372 -265.649964) (xy 352.226848 -265.65998) (xy 352.234501 -265.67849)
			(xy 352.248656 -265.692663) (xy 352.267157 -265.700339) (xy 352.277172 -265.700764) (xy 352.44024 -265.700764)
			(xy 352.45024 -265.70127) (xy 352.468709 -265.70895) (xy 352.482852 -265.723095) (xy 352.490531 -265.741564)
			(xy 352.49104 -265.751564) (xy 352.49104 -265.986006) (xy 353.593146 -265.986006) (xy 353.593603 -265.962259)
			(xy 353.600659 -265.915294) (xy 353.614629 -265.869902) (xy 353.635202 -265.827096) (xy 353.661919 -265.787831)
			(xy 353.677728 -265.770106) (xy 353.680126 -265.767458) (xy 353.684203 -265.76159) (xy 353.685856 -265.758422)
			(xy 353.695118 -265.741085) (xy 353.718897 -265.709796) (xy 353.747995 -265.683382) (xy 353.781433 -265.662733)
			(xy 353.818082 -265.648546) (xy 353.856707 -265.641298) (xy 353.876356 -265.64082) (xy 354.131372 -265.64082)
			(xy 354.131372 -265.649964) (xy 354.131848 -265.65998) (xy 354.139501 -265.67849) (xy 354.153656 -265.692663)
			(xy 354.172157 -265.700339) (xy 354.182172 -265.700764) (xy 354.34524 -265.700764) (xy 354.35524 -265.70127)
			(xy 354.373709 -265.70895) (xy 354.387852 -265.723095) (xy 354.395531 -265.741564) (xy 354.39604 -265.751564)
			(xy 354.39604 -265.986006) (xy 355.473 -265.986006) (xy 355.473523 -265.960564) (xy 355.481644 -265.910332)
			(xy 355.497663 -265.862034) (xy 355.521171 -265.816906) (xy 355.551569 -265.776098) (xy 355.588078 -265.740654)
			(xy 355.608636 -265.725656) (xy 355.618288 -265.716766) (xy 355.633717 -265.699382) (xy 355.670629 -265.671147)
			(xy 355.712756 -265.651528) (xy 355.758121 -265.641443) (xy 355.781356 -265.64082) (xy 356.036372 -265.64082)
			(xy 356.036372 -265.649964) (xy 356.036848 -265.65998) (xy 356.044501 -265.67849) (xy 356.058656 -265.692663)
			(xy 356.077157 -265.700339) (xy 356.087172 -265.700764) (xy 356.25024 -265.700764) (xy 356.26024 -265.70127)
			(xy 356.278709 -265.70895) (xy 356.292852 -265.723095) (xy 356.300531 -265.741564) (xy 356.30104 -265.751564)
			(xy 356.30104 -266.15517) (xy 357.345996 -266.15517) (xy 357.345996 -265.85545) (xy 357.346388 -265.834403)
			(xy 357.354386 -265.793082) (xy 357.37032 -265.754127) (xy 357.393571 -265.719045) (xy 357.423242 -265.689194)
			(xy 357.458182 -265.66573) (xy 357.49704 -265.649561) (xy 357.538312 -265.641312) (xy 357.559356 -265.64082)
			(xy 357.814372 -265.64082) (xy 357.814372 -265.649964) (xy 357.814848 -265.65998) (xy 357.822501 -265.67849)
			(xy 357.836656 -265.692663) (xy 357.855157 -265.700339) (xy 357.865172 -265.700764) (xy 358.02824 -265.700764)
			(xy 358.03824 -265.70127) (xy 358.056709 -265.70895) (xy 358.070852 -265.723095) (xy 358.078531 -265.741564)
			(xy 358.07904 -265.751564) (xy 358.07904 -265.986006) (xy 361.10672 -265.986006) (xy 361.10713 -265.963431)
			(xy 361.113567 -265.91874) (xy 361.126254 -265.875407) (xy 361.144938 -265.834302) (xy 361.156758 -265.815064)
			(xy 361.158772 -265.811603) (xy 361.161836 -265.804205) (xy 361.162854 -265.800332) (xy 361.16837 -265.781031)
			(xy 361.185591 -265.744777) (xy 361.209279 -265.712376) (xy 361.238601 -265.684969) (xy 361.272526 -265.663521)
			(xy 361.309859 -265.648786) (xy 361.349288 -265.641282) (xy 361.369356 -265.64082) (xy 361.624372 -265.64082)
			(xy 361.624372 -265.649964) (xy 361.624848 -265.65998) (xy 361.632501 -265.67849) (xy 361.646656 -265.692663)
			(xy 361.665157 -265.700339) (xy 361.675172 -265.700764) (xy 361.83824 -265.700764) (xy 361.84824 -265.70127)
			(xy 361.866709 -265.70895) (xy 361.880852 -265.723095) (xy 361.888531 -265.741564) (xy 361.88904 -265.751564)
			(xy 361.88904 -265.986006) (xy 362.986828 -265.986006) (xy 362.987321 -265.961069) (xy 362.995099 -265.911805)
			(xy 363.010467 -265.864358) (xy 363.033048 -265.819888) (xy 363.062289 -265.779486) (xy 363.079538 -265.76147)
			(xy 363.082046 -265.758964) (xy 363.086375 -265.753349) (xy 363.088174 -265.750294) (xy 363.099749 -265.730796)
			(xy 363.129677 -265.696748) (xy 363.166101 -265.66976) (xy 363.207389 -265.651041) (xy 363.251691 -265.64143)
			(xy 363.274356 -265.64082) (xy 363.529372 -265.64082) (xy 363.529372 -265.649964) (xy 363.529848 -265.65998)
			(xy 363.537501 -265.67849) (xy 363.551656 -265.692663) (xy 363.570157 -265.700339) (xy 363.580172 -265.700764)
			(xy 363.74324 -265.700764) (xy 363.75324 -265.70127) (xy 363.771709 -265.70895) (xy 363.785852 -265.723095)
			(xy 363.793531 -265.741564) (xy 363.79404 -265.751564) (xy 363.79404 -265.986006) (xy 364.866682 -265.986006)
			(xy 364.867166 -265.959655) (xy 364.875847 -265.907673) (xy 364.892988 -265.857837) (xy 364.91812 -265.811513)
			(xy 364.950552 -265.769972) (xy 364.989396 -265.734354) (xy 365.011208 -265.71956) (xy 365.021368 -265.710924)
			(xy 365.036718 -265.694779) (xy 365.072795 -265.668659) (xy 365.113509 -265.650598) (xy 365.157086 -265.641383)
			(xy 365.179356 -265.64082) (xy 365.434372 -265.64082) (xy 365.434372 -265.649964) (xy 365.434848 -265.65998)
			(xy 365.442501 -265.67849) (xy 365.456656 -265.692663) (xy 365.475157 -265.700339) (xy 365.485172 -265.700764)
			(xy 365.64824 -265.700764) (xy 365.65824 -265.70127) (xy 365.676709 -265.70895) (xy 365.690852 -265.723095)
			(xy 365.698531 -265.741564) (xy 365.69904 -265.751564) (xy 365.69904 -265.986006) (xy 366.74679 -265.986006)
			(xy 366.74732 -265.959359) (xy 366.756188 -265.90681) (xy 366.773695 -265.856475) (xy 366.79935 -265.809763)
			(xy 366.832435 -265.767984) (xy 366.872023 -265.732306) (xy 366.917005 -265.703728) (xy 366.941354 -265.69289)
			(xy 366.952784 -265.686032) (xy 366.971811 -265.671979) (xy 367.014562 -265.651761) (xy 367.06071 -265.641427)
			(xy 367.084356 -265.64082) (xy 367.339372 -265.64082) (xy 367.339372 -265.649964) (xy 367.339848 -265.65998)
			(xy 367.347501 -265.67849) (xy 367.361656 -265.692663) (xy 367.380157 -265.700339) (xy 367.390172 -265.700764)
			(xy 367.55324 -265.700764) (xy 367.56324 -265.70127) (xy 367.581709 -265.70895) (xy 367.595852 -265.723095)
			(xy 367.603531 -265.741564) (xy 367.60404 -265.751564) (xy 367.60404 -265.986006) (xy 368.626898 -265.986006)
			(xy 368.627446 -265.959928) (xy 368.635969 -265.908473) (xy 368.652774 -265.859098) (xy 368.677408 -265.813126)
			(xy 368.709211 -265.771788) (xy 368.747333 -265.736193) (xy 368.790751 -265.707294) (xy 368.838302 -265.685865)
			(xy 368.863372 -265.678666) (xy 368.866977 -265.677658) (xy 368.873864 -265.674726) (xy 368.877088 -265.672824)
			(xy 368.894065 -265.662767) (xy 368.930845 -265.648487) (xy 368.969628 -265.641238) (xy 368.989356 -265.64082)
			(xy 369.244372 -265.64082) (xy 369.244372 -265.649964) (xy 369.244848 -265.65998) (xy 369.252501 -265.67849)
			(xy 369.266656 -265.692663) (xy 369.285157 -265.700339) (xy 369.295172 -265.700764) (xy 369.45824 -265.700764)
			(xy 369.46824 -265.70127) (xy 369.486709 -265.70895) (xy 369.500852 -265.723095) (xy 369.508531 -265.741564)
			(xy 369.50904 -265.751564) (xy 369.50904 -265.986006) (xy 370.506752 -265.986006) (xy 370.507405 -265.956804)
			(xy 370.518064 -265.89938) (xy 370.539025 -265.844867) (xy 370.553742 -265.819636) (xy 370.555793 -265.816126)
			(xy 370.558849 -265.808593) (xy 370.559838 -265.80465) (xy 370.565005 -265.784923) (xy 370.581817 -265.747775)
			(xy 370.605377 -265.714495) (xy 370.634826 -265.686293) (xy 370.669093 -265.664194) (xy 370.706933 -265.649004)
			(xy 370.746968 -265.641273) (xy 370.767356 -265.64082) (xy 371.022372 -265.64082) (xy 371.022372 -265.649964)
			(xy 371.022848 -265.65998) (xy 371.030501 -265.67849) (xy 371.044656 -265.692663) (xy 371.063157 -265.700339)
			(xy 371.073172 -265.700764) (xy 371.23624 -265.700764) (xy 371.24624 -265.70127) (xy 371.264709 -265.70895)
			(xy 371.278852 -265.723095) (xy 371.286531 -265.741564) (xy 371.28704 -265.751564) (xy 371.28704 -265.986006)
			(xy 372.38686 -265.986006) (xy 372.387315 -265.961628) (xy 372.39475 -265.913442) (xy 372.409461 -265.866958)
			(xy 372.431103 -265.823268) (xy 372.459167 -265.783399) (xy 372.47576 -265.765534) (xy 372.483888 -265.754104)
			(xy 372.493298 -265.737288) (xy 372.51719 -265.707061) (xy 372.546117 -265.68161) (xy 372.57914 -265.66176)
			(xy 372.615188 -265.648154) (xy 372.653091 -265.641236) (xy 372.672356 -265.64082) (xy 372.927372 -265.64082)
			(xy 372.927372 -265.649964) (xy 372.927848 -265.65998) (xy 372.935501 -265.67849) (xy 372.949656 -265.692663)
			(xy 372.968157 -265.700339) (xy 372.978172 -265.700764) (xy 373.14124 -265.700764) (xy 373.15124 -265.70127)
			(xy 373.169709 -265.70895) (xy 373.183852 -265.723095) (xy 373.191531 -265.741564) (xy 373.19204 -265.751564)
			(xy 373.19204 -266.010995) (xy 374.267204 -266.010995) (xy 374.267204 -265.961017) (xy 374.275023 -265.911654)
			(xy 374.290467 -265.864122) (xy 374.313157 -265.81959) (xy 374.342533 -265.779157) (xy 374.377873 -265.743817)
			(xy 374.418306 -265.714441) (xy 374.462838 -265.691751) (xy 374.51037 -265.676307) (xy 374.559733 -265.668488)
			(xy 374.609711 -265.668488) (xy 374.659074 -265.676307) (xy 374.706606 -265.691751) (xy 374.751138 -265.714441)
			(xy 374.791571 -265.743817) (xy 374.826911 -265.779157) (xy 374.856287 -265.81959) (xy 374.878977 -265.864122)
			(xy 374.894421 -265.911654) (xy 374.90224 -265.961017) (xy 374.90273 -265.986006) (xy 376.148595 -265.986006)
			(xy 376.15269 -265.935278) (xy 376.164869 -265.885864) (xy 376.184817 -265.839044) (xy 376.212018 -265.79603)
			(xy 376.245766 -265.757936) (xy 376.285188 -265.725749) (xy 376.329262 -265.700303) (xy 376.376848 -265.682256)
			(xy 376.426712 -265.672076) (xy 376.477564 -265.670027) (xy 376.528085 -265.676161) (xy 376.576969 -265.690321)
			(xy 376.622948 -265.712138) (xy 376.664832 -265.741048) (xy 376.701536 -265.776303) (xy 376.732109 -265.816989)
			(xy 376.75576 -265.862052) (xy 376.771876 -265.910326) (xy 376.78004 -265.96056) (xy 376.780552 -265.986006)
			(xy 376.780049 -266.010995) (xy 377.087366 -266.010995) (xy 377.087366 -265.961017) (xy 377.095185 -265.911654)
			(xy 377.110629 -265.864122) (xy 377.133319 -265.81959) (xy 377.162695 -265.779157) (xy 377.198035 -265.743817)
			(xy 377.238468 -265.714441) (xy 377.283 -265.691751) (xy 377.330532 -265.676307) (xy 377.379895 -265.668488)
			(xy 377.429873 -265.668488) (xy 377.479236 -265.676307) (xy 377.526768 -265.691751) (xy 377.5713 -265.714441)
			(xy 377.611733 -265.743817) (xy 377.647073 -265.779157) (xy 377.676449 -265.81959) (xy 377.699139 -265.864122)
			(xy 377.714583 -265.911654) (xy 377.722402 -265.961017) (xy 377.722892 -265.986006) (xy 378.968503 -265.986006)
			(xy 378.972598 -265.935278) (xy 378.984777 -265.885864) (xy 379.004725 -265.839044) (xy 379.031926 -265.79603)
			(xy 379.065674 -265.757936) (xy 379.105096 -265.725749) (xy 379.14917 -265.700303) (xy 379.196756 -265.682256)
			(xy 379.24662 -265.672076) (xy 379.297472 -265.670027) (xy 379.347993 -265.676161) (xy 379.396877 -265.690321)
			(xy 379.442856 -265.712138) (xy 379.48474 -265.741048) (xy 379.521444 -265.776303) (xy 379.552017 -265.816989)
			(xy 379.575668 -265.862052) (xy 379.591784 -265.910326) (xy 379.599948 -265.96056) (xy 379.60046 -265.986006)
			(xy 379.599957 -266.010995) (xy 379.907274 -266.010995) (xy 379.907274 -265.961017) (xy 379.915093 -265.911654)
			(xy 379.930537 -265.864122) (xy 379.953227 -265.81959) (xy 379.982603 -265.779157) (xy 380.017943 -265.743817)
			(xy 380.058376 -265.714441) (xy 380.102908 -265.691751) (xy 380.15044 -265.676307) (xy 380.199803 -265.668488)
			(xy 380.249781 -265.668488) (xy 380.299144 -265.676307) (xy 380.346676 -265.691751) (xy 380.391208 -265.714441)
			(xy 380.431641 -265.743817) (xy 380.466981 -265.779157) (xy 380.496357 -265.81959) (xy 380.519047 -265.864122)
			(xy 380.534491 -265.911654) (xy 380.54231 -265.961017) (xy 380.5428 -265.986006) (xy 380.54231 -266.010995)
			(xy 380.534491 -266.060358) (xy 380.519047 -266.10789) (xy 380.496357 -266.152422) (xy 380.466981 -266.192855)
			(xy 380.431641 -266.228195) (xy 380.391208 -266.257571) (xy 380.346676 -266.280261) (xy 380.299144 -266.295705)
			(xy 380.249781 -266.303524) (xy 380.199803 -266.303524) (xy 380.15044 -266.295705) (xy 380.102908 -266.280261)
			(xy 380.058376 -266.257571) (xy 380.017943 -266.228195) (xy 379.982603 -266.192855) (xy 379.953227 -266.152422)
			(xy 379.930537 -266.10789) (xy 379.915093 -266.060358) (xy 379.907274 -266.010995) (xy 379.599957 -266.010995)
			(xy 379.599948 -266.011452) (xy 379.591784 -266.061686) (xy 379.575668 -266.10996) (xy 379.552017 -266.155023)
			(xy 379.521444 -266.195709) (xy 379.48474 -266.230964) (xy 379.442856 -266.259874) (xy 379.396877 -266.281691)
			(xy 379.347993 -266.295851) (xy 379.297472 -266.301985) (xy 379.24662 -266.299936) (xy 379.196756 -266.289756)
			(xy 379.14917 -266.271709) (xy 379.105096 -266.246263) (xy 379.065674 -266.214076) (xy 379.031926 -266.175982)
			(xy 379.004725 -266.132968) (xy 378.984777 -266.086148) (xy 378.972598 -266.036734) (xy 378.968503 -265.986006)
			(xy 377.722892 -265.986006) (xy 377.722402 -266.010995) (xy 377.714583 -266.060358) (xy 377.699139 -266.10789)
			(xy 377.676449 -266.152422) (xy 377.647073 -266.192855) (xy 377.611733 -266.228195) (xy 377.5713 -266.257571)
			(xy 377.526768 -266.280261) (xy 377.479236 -266.295705) (xy 377.429873 -266.303524) (xy 377.379895 -266.303524)
			(xy 377.330532 -266.295705) (xy 377.283 -266.280261) (xy 377.238468 -266.257571) (xy 377.198035 -266.228195)
			(xy 377.162695 -266.192855) (xy 377.133319 -266.152422) (xy 377.110629 -266.10789) (xy 377.095185 -266.060358)
			(xy 377.087366 -266.010995) (xy 376.780049 -266.010995) (xy 376.78004 -266.011452) (xy 376.771876 -266.061686)
			(xy 376.75576 -266.10996) (xy 376.732109 -266.155023) (xy 376.701536 -266.195709) (xy 376.664832 -266.230964)
			(xy 376.622948 -266.259874) (xy 376.576969 -266.281691) (xy 376.528085 -266.295851) (xy 376.477564 -266.301985)
			(xy 376.426712 -266.299936) (xy 376.376848 -266.289756) (xy 376.329262 -266.271709) (xy 376.285188 -266.246263)
			(xy 376.245766 -266.214076) (xy 376.212018 -266.175982) (xy 376.184817 -266.132968) (xy 376.164869 -266.086148)
			(xy 376.15269 -266.036734) (xy 376.148595 -265.986006) (xy 374.90273 -265.986006) (xy 374.90224 -266.010995)
			(xy 374.894421 -266.060358) (xy 374.878977 -266.10789) (xy 374.856287 -266.152422) (xy 374.826911 -266.192855)
			(xy 374.791571 -266.228195) (xy 374.751138 -266.257571) (xy 374.706606 -266.280261) (xy 374.659074 -266.295705)
			(xy 374.609711 -266.303524) (xy 374.559733 -266.303524) (xy 374.51037 -266.295705) (xy 374.462838 -266.280261)
			(xy 374.418306 -266.257571) (xy 374.377873 -266.228195) (xy 374.342533 -266.192855) (xy 374.313157 -266.152422)
			(xy 374.290467 -266.10789) (xy 374.275023 -266.060358) (xy 374.267204 -266.010995) (xy 373.19204 -266.010995)
			(xy 373.19204 -266.259056) (xy 373.191674 -266.269094) (xy 373.184037 -266.287655) (xy 373.169842 -266.301846)
			(xy 373.151278 -266.309477) (xy 373.14124 -266.309856) (xy 372.927372 -266.309856) (xy 372.927372 -266.319)
			(xy 372.92698 -266.329025) (xy 372.919305 -266.347547) (xy 372.905124 -266.36172) (xy 372.886597 -266.369385)
			(xy 372.876572 -266.3698) (xy 372.672356 -266.3698) (xy 372.651713 -266.369347) (xy 372.611201 -266.36139)
			(xy 372.572972 -266.345801) (xy 372.538448 -266.323159) (xy 372.508916 -266.294309) (xy 372.485474 -266.260323)
			(xy 372.468997 -266.222468) (xy 372.464076 -266.202414) (xy 372.462713 -266.196898) (xy 372.457835 -266.186639)
			(xy 372.454424 -266.182094) (xy 372.438546 -266.160966) (xy 372.41332 -266.114524) (xy 372.396108 -266.064556)
			(xy 372.387381 -266.012431) (xy 372.38686 -265.986006) (xy 371.28704 -265.986006) (xy 371.28704 -266.259056)
			(xy 371.286674 -266.269094) (xy 371.279037 -266.287655) (xy 371.264842 -266.301846) (xy 371.246278 -266.309477)
			(xy 371.23624 -266.309856) (xy 371.022372 -266.309856) (xy 371.022372 -266.319) (xy 371.02198 -266.329025)
			(xy 371.014305 -266.347547) (xy 371.000124 -266.36172) (xy 370.981597 -266.369385) (xy 370.971572 -266.3698)
			(xy 370.767356 -266.3698) (xy 370.746298 -266.369225) (xy 370.704997 -266.360983) (xy 370.666112 -266.344806)
			(xy 370.631151 -266.321322) (xy 370.60147 -266.291442) (xy 370.578221 -266.256325) (xy 370.562305 -266.217332)
			(xy 370.554339 -266.175977) (xy 370.553996 -266.154916) (xy 370.553996 -266.152884) (xy 370.539199 -266.127589)
			(xy 370.518133 -266.072911) (xy 370.507418 -266.015304) (xy 370.506752 -265.986006) (xy 369.50904 -265.986006)
			(xy 369.50904 -266.259056) (xy 369.508674 -266.269094) (xy 369.501037 -266.287655) (xy 369.486842 -266.301846)
			(xy 369.468278 -266.309477) (xy 369.45824 -266.309856) (xy 369.244372 -266.309856) (xy 369.244372 -266.319)
			(xy 369.24398 -266.329025) (xy 369.236305 -266.347547) (xy 369.222124 -266.36172) (xy 369.203597 -266.369385)
			(xy 369.193572 -266.3698) (xy 368.989356 -266.3698) (xy 368.969554 -266.369382) (xy 368.930631 -266.362073)
			(xy 368.893722 -266.347714) (xy 368.860093 -266.326796) (xy 368.830896 -266.300037) (xy 368.818668 -266.284456)
			(xy 368.815069 -266.279931) (xy 368.806218 -266.272494) (xy 368.801142 -266.269724) (xy 368.778999 -266.258016)
			(xy 368.738433 -266.228633) (xy 368.702971 -266.193258) (xy 368.67349 -266.152764) (xy 368.650717 -266.108151)
			(xy 368.635215 -266.060521) (xy 368.627366 -266.011051) (xy 368.626898 -265.986006) (xy 367.60404 -265.986006)
			(xy 367.60404 -266.259056) (xy 367.603674 -266.269094) (xy 367.596037 -266.287655) (xy 367.581842 -266.301846)
			(xy 367.563278 -266.309477) (xy 367.55324 -266.309856) (xy 367.339372 -266.309856) (xy 367.339372 -266.319)
			(xy 367.33898 -266.329025) (xy 367.331305 -266.347547) (xy 367.317124 -266.36172) (xy 367.298597 -266.369385)
			(xy 367.288572 -266.3698) (xy 367.084356 -266.3698) (xy 367.06221 -266.369225) (xy 367.018873 -266.360065)
			(xy 366.978348 -266.342188) (xy 366.942365 -266.316357) (xy 366.912465 -266.283678) (xy 366.900714 -266.264898)
			(xy 366.897731 -266.260129) (xy 366.890041 -266.251926) (xy 366.885474 -266.248642) (xy 366.864483 -266.23369)
			(xy 366.827166 -266.198149) (xy 366.796067 -266.157056) (xy 366.772002 -266.111486) (xy 366.7556 -266.062632)
			(xy 366.747289 -266.011773) (xy 366.74679 -265.986006) (xy 365.69904 -265.986006) (xy 365.69904 -266.259056)
			(xy 365.698674 -266.269094) (xy 365.691037 -266.287655) (xy 365.676842 -266.301846) (xy 365.658278 -266.309477)
			(xy 365.64824 -266.309856) (xy 365.434372 -266.309856) (xy 365.434372 -266.319) (xy 365.43398 -266.329025)
			(xy 365.426305 -266.347547) (xy 365.412124 -266.36172) (xy 365.393597 -266.369385) (xy 365.383572 -266.3698)
			(xy 365.179356 -266.3698) (xy 365.158441 -266.369248) (xy 365.117418 -266.361067) (xy 365.078769 -266.345066)
			(xy 365.043969 -266.321854) (xy 365.014346 -266.292319) (xy 364.991032 -266.257587) (xy 364.982506 -266.238482)
			(xy 364.980243 -266.233396) (xy 364.973825 -266.224301) (xy 364.969806 -266.220448) (xy 364.950704 -266.20225)
			(xy 364.918237 -266.160669) (xy 364.893074 -266.114301) (xy 364.875905 -266.064417) (xy 364.867201 -266.012384)
			(xy 364.866682 -265.986006) (xy 363.79404 -265.986006) (xy 363.79404 -266.259056) (xy 363.793674 -266.269094)
			(xy 363.786037 -266.287655) (xy 363.771842 -266.301846) (xy 363.753278 -266.309477) (xy 363.74324 -266.309856)
			(xy 363.529372 -266.309856) (xy 363.529372 -266.319) (xy 363.52898 -266.329025) (xy 363.521305 -266.347547)
			(xy 363.507124 -266.36172) (xy 363.488597 -266.369385) (xy 363.478572 -266.3698) (xy 363.274356 -266.3698)
			(xy 363.253945 -266.369317) (xy 363.213872 -266.361519) (xy 363.176009 -266.346254) (xy 363.141734 -266.324078)
			(xy 363.112293 -266.295796) (xy 363.088758 -266.262439) (xy 363.071985 -266.22522) (xy 363.066838 -266.205462)
			(xy 363.065363 -266.199951) (xy 363.060369 -266.189696) (xy 363.056932 -266.185142) (xy 363.040528 -266.163794)
			(xy 363.014347 -266.116758) (xy 362.996465 -266.065984) (xy 362.987394 -266.012922) (xy 362.986828 -265.986006)
			(xy 361.88904 -265.986006) (xy 361.88904 -266.259056) (xy 361.888674 -266.269094) (xy 361.881037 -266.287655)
			(xy 361.866842 -266.301846) (xy 361.848278 -266.309477) (xy 361.83824 -266.309856) (xy 361.624372 -266.309856)
			(xy 361.624372 -266.319) (xy 361.62398 -266.329025) (xy 361.616305 -266.347547) (xy 361.602124 -266.36172)
			(xy 361.583597 -266.369385) (xy 361.573572 -266.3698) (xy 361.369356 -266.3698) (xy 361.348425 -266.36929)
			(xy 361.307366 -266.361129) (xy 361.268683 -266.345128) (xy 361.233856 -266.3219) (xy 361.204221 -266.292334)
			(xy 361.18091 -266.257563) (xy 361.164818 -266.218917) (xy 361.15656 -266.177878) (xy 361.155996 -266.156948)
			(xy 361.155996 -266.156186) (xy 361.14429 -266.13702) (xy 361.125846 -266.096071) (xy 361.11336 -266.052931)
			(xy 361.107082 -266.008462) (xy 361.10672 -265.986006) (xy 358.07904 -265.986006) (xy 358.07904 -266.259056)
			(xy 358.078674 -266.269094) (xy 358.071037 -266.287655) (xy 358.056842 -266.301846) (xy 358.038278 -266.309477)
			(xy 358.02824 -266.309856) (xy 357.814372 -266.309856) (xy 357.814372 -266.319) (xy 357.81398 -266.329025)
			(xy 357.806305 -266.347547) (xy 357.792124 -266.36172) (xy 357.773597 -266.369385) (xy 357.763572 -266.3698)
			(xy 357.559356 -266.3698) (xy 357.538311 -266.369316) (xy 357.497036 -266.361067) (xy 357.458174 -266.344898)
			(xy 357.423231 -266.321433) (xy 357.393557 -266.291582) (xy 357.370301 -266.256498) (xy 357.354364 -266.217541)
			(xy 357.346362 -266.176218) (xy 357.345996 -266.15517) (xy 356.30104 -266.15517) (xy 356.30104 -266.259056)
			(xy 356.300674 -266.269094) (xy 356.293037 -266.287655) (xy 356.278842 -266.301846) (xy 356.260278 -266.309477)
			(xy 356.25024 -266.309856) (xy 356.036372 -266.309856) (xy 356.036372 -266.319) (xy 356.03598 -266.329025)
			(xy 356.028305 -266.347547) (xy 356.014124 -266.36172) (xy 355.995597 -266.369385) (xy 355.985572 -266.3698)
			(xy 355.781356 -266.3698) (xy 355.759965 -266.369238) (xy 355.718044 -266.360692) (xy 355.678664 -266.343972)
			(xy 355.6434 -266.319747) (xy 355.613665 -266.288987) (xy 355.59065 -266.252922) (xy 355.582474 -266.233148)
			(xy 355.580304 -266.228047) (xy 355.574159 -266.218823) (xy 355.570282 -266.21486) (xy 355.552219 -266.196763)
			(xy 355.521563 -266.155845) (xy 355.497852 -266.110547) (xy 355.481695 -266.062039) (xy 355.473511 -266.01157)
			(xy 355.473 -265.986006) (xy 354.39604 -265.986006) (xy 354.39604 -266.259056) (xy 354.395674 -266.269094)
			(xy 354.388037 -266.287655) (xy 354.373842 -266.301846) (xy 354.355278 -266.309477) (xy 354.34524 -266.309856)
			(xy 354.131372 -266.309856) (xy 354.131372 -266.319) (xy 354.13098 -266.329025) (xy 354.123305 -266.347547)
			(xy 354.109124 -266.36172) (xy 354.090597 -266.369385) (xy 354.080572 -266.3698) (xy 353.876356 -266.3698)
			(xy 353.85547 -266.369294) (xy 353.814495 -266.361168) (xy 353.775881 -266.345233) (xy 353.7411 -266.322098)
			(xy 353.711478 -266.292645) (xy 353.688145 -266.257997) (xy 353.67199 -266.219475) (xy 353.667314 -266.199112)
			(xy 353.666077 -266.193562) (xy 353.661464 -266.183172) (xy 353.65817 -266.178538) (xy 353.642894 -266.157654)
			(xy 353.618638 -266.111951) (xy 353.602086 -266.062929) (xy 353.593675 -266.011876) (xy 353.593146 -265.986006)
			(xy 352.49104 -265.986006) (xy 352.49104 -266.259056) (xy 352.490674 -266.269094) (xy 352.483037 -266.287655)
			(xy 352.468842 -266.301846) (xy 352.450278 -266.309477) (xy 352.44024 -266.309856) (xy 352.226372 -266.309856)
			(xy 352.226372 -266.319) (xy 352.22598 -266.329025) (xy 352.218305 -266.347547) (xy 352.204124 -266.36172)
			(xy 352.185597 -266.369385) (xy 352.175572 -266.3698) (xy 351.971356 -266.3698) (xy 351.950298 -266.369225)
			(xy 351.908997 -266.360983) (xy 351.870112 -266.344806) (xy 351.835151 -266.321322) (xy 351.80547 -266.291442)
			(xy 351.782221 -266.256325) (xy 351.766305 -266.217332) (xy 351.758339 -266.175977) (xy 351.757996 -266.154916)
			(xy 351.757996 -266.149328) (xy 351.743868 -266.124455) (xy 351.723802 -266.070891) (xy 351.713623 -266.014606)
			(xy 351.713038 -265.986006) (xy 350.71304 -265.986006) (xy 350.71304 -266.259056) (xy 350.712674 -266.269094)
			(xy 350.705037 -266.287655) (xy 350.690842 -266.301846) (xy 350.672278 -266.309477) (xy 350.66224 -266.309856)
			(xy 350.448372 -266.309856) (xy 350.448372 -266.319) (xy 350.44798 -266.329025) (xy 350.440305 -266.347547)
			(xy 350.426124 -266.36172) (xy 350.407597 -266.369385) (xy 350.397572 -266.3698) (xy 350.193356 -266.3698)
			(xy 350.173381 -266.369294) (xy 350.134135 -266.361829) (xy 350.096957 -266.347204) (xy 350.063143 -266.325928)
			(xy 350.03387 -266.298741) (xy 350.021652 -266.282932) (xy 350.01808 -266.278329) (xy 350.009228 -266.27076)
			(xy 350.004126 -266.267946) (xy 349.982397 -266.256042) (xy 349.94255 -266.226604) (xy 349.907752 -266.191341)
			(xy 349.878845 -266.151107) (xy 349.856529 -266.106876) (xy 349.841344 -266.059719) (xy 349.833658 -266.010777)
			(xy 349.833184 -265.986006) (xy 348.945454 -265.986006) (xy 348.945454 -266.238228) (xy 348.945915 -266.248105)
			(xy 348.953355 -266.266405) (xy 348.959932 -266.273788) (xy 348.960186 -266.274042) (xy 349.20809 -266.521946)
			(xy 349.208598 -266.522454) (xy 349.215982 -266.529029) (xy 349.234281 -266.536463) (xy 349.244158 -266.536932)
			(xy 349.47352 -266.536932) (xy 349.47719 -266.536888) (xy 349.484458 -266.53587) (xy 349.487998 -266.5349)
			(xy 349.508572 -266.52855) (xy 349.514414 -266.525248) (xy 349.539668 -266.510461) (xy 349.594257 -266.489392)
			(xy 349.651781 -266.47868) (xy 349.681038 -266.478004) (xy 349.70758 -266.478531) (xy 349.759929 -266.487333)
			(xy 349.785178 -266.49553) (xy 349.785432 -266.49553) (xy 349.801865 -266.501413) (xy 349.833434 -266.516306)
			(xy 349.848424 -266.525248) (xy 349.854012 -266.528804) (xy 349.874332 -266.5349) (xy 349.877811 -266.535852)
			(xy 349.88495 -266.536877) (xy 349.888556 -266.536932) (xy 350.390714 -266.536932) (xy 350.394658 -266.536845)
			(xy 350.402443 -266.535572) (xy 350.406208 -266.534392) (xy 350.427798 -266.527534) (xy 350.433894 -266.523216)
			(xy 350.45467 -266.509518) (xy 350.499467 -266.487847) (xy 350.547004 -266.473132) (xy 350.59621 -266.465705)
			(xy 350.621092 -266.465304) (xy 350.645974 -266.46573) (xy 350.695182 -266.473141) (xy 350.742725 -266.48784)
			(xy 350.787528 -266.509498) (xy 350.80829 -266.523216) (xy 350.814386 -266.527534) (xy 350.835976 -266.534392)
			(xy 350.839748 -266.535539) (xy 350.847529 -266.536815) (xy 350.85147 -266.536932) (xy 351.353628 -266.536932)
			(xy 351.357298 -266.536887) (xy 351.364566 -266.535868) (xy 351.368106 -266.5349) (xy 351.38868 -266.52855)
			(xy 351.394522 -266.525248) (xy 351.419776 -266.510462) (xy 351.474365 -266.489394) (xy 351.531889 -266.478684)
			(xy 351.561146 -266.478004) (xy 351.587688 -266.478532) (xy 351.640036 -266.487335) (xy 351.665286 -266.49553)
			(xy 351.66554 -266.49553) (xy 351.681973 -266.501414) (xy 351.713541 -266.516307) (xy 351.728532 -266.525248)
			(xy 351.73412 -266.528804) (xy 351.75444 -266.5349) (xy 351.757919 -266.535851) (xy 351.765058 -266.536875)
			(xy 351.768664 -266.536932) (xy 352.293682 -266.536932) (xy 352.297351 -266.536883) (xy 352.304617 -266.535857)
			(xy 352.30816 -266.5349) (xy 352.328734 -266.52855) (xy 352.334576 -266.525248) (xy 352.359829 -266.510458)
			(xy 352.414417 -266.489383) (xy 352.471942 -266.478664) (xy 352.5012 -266.478004) (xy 352.527741 -266.478536)
			(xy 352.580086 -266.487347) (xy 352.60534 -266.49553) (xy 352.605594 -266.49553) (xy 352.622028 -266.501411)
			(xy 352.653599 -266.516301) (xy 352.668586 -266.525248) (xy 352.674174 -266.528804) (xy 352.694494 -266.5349)
			(xy 352.697973 -266.535847) (xy 352.705112 -266.536864) (xy 352.708718 -266.536932) (xy 353.233482 -266.536932)
			(xy 353.237151 -266.536883) (xy 353.244417 -266.535857) (xy 353.24796 -266.5349) (xy 353.268534 -266.52855)
			(xy 353.274376 -266.525248) (xy 353.299629 -266.510458) (xy 353.354217 -266.489383) (xy 353.411742 -266.478664)
			(xy 353.441 -266.478004) (xy 353.467541 -266.478536) (xy 353.519886 -266.487347) (xy 353.54514 -266.49553)
			(xy 353.545394 -266.49553) (xy 353.561828 -266.501411) (xy 353.593399 -266.516301) (xy 353.608386 -266.525248)
			(xy 353.613974 -266.528804) (xy 353.634294 -266.5349) (xy 353.637773 -266.535847) (xy 353.644912 -266.536864)
			(xy 353.648518 -266.536932) (xy 354.150676 -266.536932) (xy 354.154619 -266.53684) (xy 354.162401 -266.535558)
			(xy 354.16617 -266.534392) (xy 354.18776 -266.527534) (xy 354.193856 -266.523216) (xy 354.214633 -266.509522)
			(xy 354.259431 -266.487859) (xy 354.306969 -266.473153) (xy 354.356173 -266.465735) (xy 354.381054 -266.465304)
			(xy 354.405934 -266.465735) (xy 354.455139 -266.473154) (xy 354.502676 -266.487861) (xy 354.547473 -266.509524)
			(xy 354.568252 -266.523216) (xy 354.574348 -266.527534) (xy 354.595938 -266.534392) (xy 354.59971 -266.535541)
			(xy 354.60749 -266.536823) (xy 354.611432 -266.536932) (xy 355.11359 -266.536932) (xy 355.117259 -266.536883)
			(xy 355.124525 -266.535855) (xy 355.128068 -266.5349) (xy 355.148642 -266.52855) (xy 355.154484 -266.525248)
			(xy 355.179737 -266.510459) (xy 355.234325 -266.489385) (xy 355.291851 -266.478667) (xy 355.321108 -266.478004)
			(xy 355.347649 -266.478537) (xy 355.399994 -266.487349) (xy 355.425248 -266.49553) (xy 355.425502 -266.49553)
			(xy 355.441936 -266.501412) (xy 355.473506 -266.516302) (xy 355.488494 -266.525248) (xy 355.494082 -266.528804)
			(xy 355.514402 -266.5349) (xy 355.517881 -266.535847) (xy 355.525021 -266.536862) (xy 355.528626 -266.536932)
			(xy 356.053644 -266.536932) (xy 356.057314 -266.536886) (xy 356.064581 -266.535865) (xy 356.068122 -266.5349)
			(xy 356.088696 -266.52855) (xy 356.094538 -266.525248) (xy 356.119792 -266.510463) (xy 356.174381 -266.489398)
			(xy 356.231906 -266.478691) (xy 356.261162 -266.478004) (xy 356.287703 -266.478533) (xy 356.340051 -266.487338)
			(xy 356.365302 -266.49553) (xy 356.365556 -266.49553) (xy 356.381988 -266.501414) (xy 356.413556 -266.51631)
			(xy 356.428548 -266.525248) (xy 356.434136 -266.528804) (xy 356.454456 -266.5349) (xy 356.457935 -266.53585)
			(xy 356.465074 -266.536872) (xy 356.46868 -266.536932) (xy 356.993698 -266.536932) (xy 356.997368 -266.536889)
			(xy 357.004638 -266.535875) (xy 357.008176 -266.5349) (xy 357.02875 -266.52855) (xy 357.034592 -266.525248)
			(xy 357.059845 -266.510459) (xy 357.114434 -266.489387) (xy 357.171959 -266.478671) (xy 357.201216 -266.478004)
			(xy 357.227757 -266.478537) (xy 357.280101 -266.487351) (xy 357.305356 -266.49553) (xy 357.30561 -266.49553)
			(xy 357.322043 -266.501412) (xy 357.353614 -266.516303) (xy 357.368602 -266.525248) (xy 357.37419 -266.528804)
			(xy 357.39451 -266.5349) (xy 357.39799 -266.535846) (xy 357.405129 -266.536861) (xy 357.408734 -266.536932)
			(xy 357.910638 -266.536932) (xy 357.914582 -266.536843) (xy 357.922366 -266.535566) (xy 357.926132 -266.534392)
			(xy 357.947722 -266.527534) (xy 357.953818 -266.523216) (xy 357.974595 -266.509519) (xy 358.019392 -266.487852)
			(xy 358.066929 -266.47314) (xy 358.116135 -266.465717) (xy 358.141016 -266.465304) (xy 358.165897 -266.465732)
			(xy 358.215104 -266.473146) (xy 358.262644 -266.487848) (xy 358.307445 -266.509508) (xy 358.328214 -266.523216)
			(xy 358.33431 -266.527534) (xy 358.3559 -266.534392) (xy 358.359673 -266.535537) (xy 358.367453 -266.53681)
			(xy 358.371394 -266.536932) (xy 361.687364 -266.536932) (xy 361.691033 -266.536884) (xy 361.6983 -266.535861)
			(xy 361.701842 -266.5349) (xy 361.722416 -266.52855) (xy 361.728258 -266.525248) (xy 361.753511 -266.510456)
			(xy 361.808099 -266.489378) (xy 361.865624 -266.478656) (xy 361.894882 -266.478004) (xy 361.921423 -266.478535)
			(xy 361.97377 -266.487343) (xy 361.999022 -266.49553) (xy 361.999276 -266.49553) (xy 362.015708 -266.501415)
			(xy 362.047275 -266.516312) (xy 362.062268 -266.525248) (xy 362.067856 -266.528804) (xy 362.088176 -266.5349)
			(xy 362.091655 -266.535849) (xy 362.098794 -266.536868) (xy 362.1024 -266.536932) (xy 362.627164 -266.536932)
			(xy 362.630833 -266.536884) (xy 362.6381 -266.535861) (xy 362.641642 -266.5349) (xy 362.662216 -266.52855)
			(xy 362.668058 -266.525248) (xy 362.693311 -266.510456) (xy 362.747899 -266.489378) (xy 362.805424 -266.478656)
			(xy 362.834682 -266.478004) (xy 362.861223 -266.478535) (xy 362.91357 -266.487343) (xy 362.938822 -266.49553)
			(xy 362.939076 -266.49553) (xy 362.955508 -266.501415) (xy 362.987075 -266.516312) (xy 363.002068 -266.525248)
			(xy 363.007656 -266.528804) (xy 363.027976 -266.5349) (xy 363.031455 -266.535849) (xy 363.038594 -266.536868)
			(xy 363.0422 -266.536932) (xy 363.567218 -266.536932) (xy 363.570888 -266.536888) (xy 363.578156 -266.535871)
			(xy 363.581696 -266.5349) (xy 363.60227 -266.52855) (xy 363.608112 -266.525248) (xy 363.633366 -266.510461)
			(xy 363.687954 -266.489392) (xy 363.745479 -266.478679) (xy 363.774736 -266.478004) (xy 363.801278 -266.478531)
			(xy 363.853627 -266.487332) (xy 363.878876 -266.49553) (xy 363.87913 -266.49553) (xy 363.895563 -266.501413)
			(xy 363.927132 -266.516306) (xy 363.942122 -266.525248) (xy 363.94771 -266.528804) (xy 363.96803 -266.5349)
			(xy 363.971509 -266.535852) (xy 363.978648 -266.536877) (xy 363.982254 -266.536932) (xy 364.484412 -266.536932)
			(xy 364.488356 -266.536845) (xy 364.496142 -266.535572) (xy 364.499906 -266.534392) (xy 364.521496 -266.527534)
			(xy 364.527592 -266.523216) (xy 364.54837 -266.509524) (xy 364.593168 -266.487866) (xy 364.640706 -266.473165)
			(xy 364.68991 -266.465753) (xy 364.71479 -266.465304) (xy 364.739672 -266.46573) (xy 364.78888 -266.47314)
			(xy 364.836423 -266.48784) (xy 364.881226 -266.509497) (xy 364.901988 -266.523216) (xy 364.908084 -266.527534)
			(xy 364.929674 -266.534392) (xy 364.933446 -266.535539) (xy 364.941227 -266.536815) (xy 364.945168 -266.536932)
			(xy 365.447326 -266.536932) (xy 365.450996 -266.536887) (xy 365.458264 -266.535869) (xy 365.461804 -266.5349)
			(xy 365.482378 -266.52855) (xy 365.48822 -266.525248) (xy 365.513474 -266.510461) (xy 365.568063 -266.489394)
			(xy 365.625587 -266.478683) (xy 365.654844 -266.478004) (xy 365.681386 -266.478532) (xy 365.733734 -266.487334)
			(xy 365.758984 -266.49553) (xy 365.759238 -266.49553) (xy 365.775671 -266.501414) (xy 365.807239 -266.516307)
			(xy 365.82223 -266.525248) (xy 365.827818 -266.528804) (xy 365.848138 -266.5349) (xy 365.851617 -266.535851)
			(xy 365.858756 -266.536876) (xy 365.862362 -266.536932) (xy 366.38738 -266.536932) (xy 366.391049 -266.536883)
			(xy 366.398315 -266.535858) (xy 366.401858 -266.5349) (xy 366.422432 -266.52855) (xy 366.428274 -266.525248)
			(xy 366.453527 -266.510458) (xy 366.508115 -266.489382) (xy 366.56564 -266.478663) (xy 366.594898 -266.478004)
			(xy 366.621439 -266.478536) (xy 366.673784 -266.487347) (xy 366.699038 -266.49553) (xy 366.699292 -266.49553)
			(xy 366.715726 -266.501411) (xy 366.747297 -266.516301) (xy 366.762284 -266.525248) (xy 366.767872 -266.528804)
			(xy 366.788192 -266.5349) (xy 366.791671 -266.535848) (xy 366.79881 -266.536864) (xy 366.802416 -266.536932)
			(xy 367.32718 -266.536932) (xy 367.330849 -266.536883) (xy 367.338115 -266.535858) (xy 367.341658 -266.5349)
			(xy 367.362232 -266.52855) (xy 367.368074 -266.525248) (xy 367.393327 -266.510458) (xy 367.447915 -266.489382)
			(xy 367.50544 -266.478663) (xy 367.534698 -266.478004) (xy 367.561239 -266.478536) (xy 367.613584 -266.487347)
			(xy 367.638838 -266.49553) (xy 367.639092 -266.49553) (xy 367.655526 -266.501411) (xy 367.687097 -266.516301)
			(xy 367.702084 -266.525248) (xy 367.707672 -266.528804) (xy 367.727992 -266.5349) (xy 367.731471 -266.535848)
			(xy 367.73861 -266.536864) (xy 367.742216 -266.536932) (xy 368.244374 -266.536932) (xy 368.248317 -266.53684)
			(xy 368.2561 -266.535558) (xy 368.259868 -266.534392) (xy 368.281458 -266.527534) (xy 368.287554 -266.523216)
			(xy 368.308331 -266.509522) (xy 368.353129 -266.487859) (xy 368.400667 -266.473152) (xy 368.449871 -266.465734)
			(xy 368.474752 -266.465304) (xy 368.499633 -266.465735) (xy 368.548837 -266.473153) (xy 368.596374 -266.48786)
			(xy 368.641172 -266.509523) (xy 368.66195 -266.523216) (xy 368.668046 -266.527534) (xy 368.689636 -266.534392)
			(xy 368.693408 -266.535541) (xy 368.701188 -266.536824) (xy 368.70513 -266.536932) (xy 369.207288 -266.536932)
			(xy 369.210957 -266.536883) (xy 369.218223 -266.535856) (xy 369.221766 -266.5349) (xy 369.24234 -266.52855)
			(xy 369.248182 -266.525248) (xy 369.273435 -266.510458) (xy 369.328023 -266.489384) (xy 369.385548 -266.478666)
			(xy 369.414806 -266.478004) (xy 369.441347 -266.478537) (xy 369.493692 -266.487349) (xy 369.518946 -266.49553)
			(xy 369.5192 -266.49553) (xy 369.535634 -266.501412) (xy 369.567204 -266.516302) (xy 369.582192 -266.525248)
			(xy 369.58778 -266.528804) (xy 369.6081 -266.5349) (xy 369.611579 -266.535847) (xy 369.618718 -266.536863)
			(xy 369.622324 -266.536932) (xy 370.147342 -266.536932) (xy 370.151012 -266.536886) (xy 370.158279 -266.535865)
			(xy 370.16182 -266.5349) (xy 370.182394 -266.52855) (xy 370.188236 -266.525248) (xy 370.21349 -266.510463)
			(xy 370.268079 -266.489398) (xy 370.325604 -266.47869) (xy 370.35486 -266.478004) (xy 370.381402 -266.478533)
			(xy 370.433749 -266.487338) (xy 370.459 -266.49553) (xy 370.459254 -266.49553) (xy 370.475686 -266.501414)
			(xy 370.507254 -266.516309) (xy 370.522246 -266.525248) (xy 370.527834 -266.528804) (xy 370.548154 -266.5349)
			(xy 370.551633 -266.53585) (xy 370.558772 -266.536872) (xy 370.562378 -266.536932) (xy 371.087396 -266.536932)
			(xy 371.091066 -266.536889) (xy 371.098336 -266.535875) (xy 371.101874 -266.5349) (xy 371.122448 -266.52855)
			(xy 371.12829 -266.525248) (xy 371.153543 -266.510459) (xy 371.208132 -266.489386) (xy 371.265657 -266.47867)
			(xy 371.294914 -266.478004) (xy 371.321455 -266.478537) (xy 371.373799 -266.487351) (xy 371.399054 -266.49553)
			(xy 371.399308 -266.49553) (xy 371.415742 -266.501412) (xy 371.447312 -266.516303) (xy 371.4623 -266.525248)
			(xy 371.467888 -266.528804) (xy 371.488208 -266.5349) (xy 371.491688 -266.535846) (xy 371.498827 -266.536861)
			(xy 371.502432 -266.536932) (xy 372.004336 -266.536932) (xy 372.00828 -266.536843) (xy 372.016064 -266.535567)
			(xy 372.01983 -266.534392) (xy 372.04142 -266.527534) (xy 372.047516 -266.523216) (xy 372.068293 -266.509519)
			(xy 372.11309 -266.487851) (xy 372.160627 -266.473139) (xy 372.209833 -266.465716) (xy 372.234714 -266.465304)
			(xy 372.259595 -266.465732) (xy 372.308802 -266.473145) (xy 372.356343 -266.487848) (xy 372.401144 -266.509507)
			(xy 372.421912 -266.523216) (xy 372.428008 -266.527534) (xy 372.449598 -266.534392) (xy 372.453371 -266.535537)
			(xy 372.461151 -266.53681) (xy 372.465092 -266.536932) (xy 372.96725 -266.536932) (xy 372.970855 -266.536866)
			(xy 372.977992 -266.53584) (xy 372.981474 -266.5349) (xy 373.001794 -266.528804) (xy 373.007382 -266.525248)
			(xy 373.032641 -266.510471) (xy 373.08723 -266.489409) (xy 373.14475 -266.478679) (xy 373.174006 -266.478004)
			(xy 373.178578 -266.478004) (xy 373.181372 -266.478004) (xy 373.205792 -266.478956) (xy 373.253922 -266.48743)
			(xy 373.300188 -266.503169) (xy 373.343502 -266.525801) (xy 373.382842 -266.554794) (xy 373.417283 -266.589465)
			(xy 373.446014 -266.628997) (xy 373.468358 -266.67246) (xy 373.483789 -266.71883) (xy 373.491943 -266.767014)
			(xy 373.492776 -266.79144) (xy 373.492776 -266.795504) (xy 373.492292 -266.821001) (xy 373.797304 -266.821001)
			(xy 373.797304 -266.771023) (xy 373.805123 -266.72166) (xy 373.820567 -266.674128) (xy 373.843257 -266.629596)
			(xy 373.872633 -266.589163) (xy 373.907973 -266.553823) (xy 373.948406 -266.524447) (xy 373.992938 -266.501757)
			(xy 374.04047 -266.486313) (xy 374.089833 -266.478494) (xy 374.139811 -266.478494) (xy 374.189174 -266.486313)
			(xy 374.236706 -266.501757) (xy 374.281238 -266.524447) (xy 374.321671 -266.553823) (xy 374.357011 -266.589163)
			(xy 374.386387 -266.629596) (xy 374.409077 -266.674128) (xy 374.424521 -266.72166) (xy 374.43234 -266.771023)
			(xy 374.43283 -266.796012) (xy 374.43234 -266.821001) (xy 374.737358 -266.821001) (xy 374.737358 -266.771023)
			(xy 374.745177 -266.72166) (xy 374.760621 -266.674128) (xy 374.783311 -266.629596) (xy 374.812687 -266.589163)
			(xy 374.848027 -266.553823) (xy 374.88846 -266.524447) (xy 374.932992 -266.501757) (xy 374.980524 -266.486313)
			(xy 375.029887 -266.478494) (xy 375.079865 -266.478494) (xy 375.129228 -266.486313) (xy 375.17676 -266.501757)
			(xy 375.221292 -266.524447) (xy 375.261725 -266.553823) (xy 375.297065 -266.589163) (xy 375.326441 -266.629596)
			(xy 375.349131 -266.674128) (xy 375.364575 -266.72166) (xy 375.372394 -266.771023) (xy 375.372884 -266.796012)
			(xy 375.678695 -266.796012) (xy 375.68279 -266.745284) (xy 375.694969 -266.69587) (xy 375.714917 -266.64905)
			(xy 375.742118 -266.606036) (xy 375.775866 -266.567942) (xy 375.815288 -266.535755) (xy 375.859362 -266.510309)
			(xy 375.906948 -266.492262) (xy 375.956812 -266.482082) (xy 376.007664 -266.480033) (xy 376.058185 -266.486167)
			(xy 376.107069 -266.500327) (xy 376.153048 -266.522144) (xy 376.194932 -266.551054) (xy 376.231636 -266.586309)
			(xy 376.262209 -266.626995) (xy 376.28586 -266.672058) (xy 376.301976 -266.720332) (xy 376.31014 -266.770566)
			(xy 376.310652 -266.796012) (xy 376.310149 -266.821001) (xy 376.617212 -266.821001) (xy 376.617212 -266.771023)
			(xy 376.625031 -266.72166) (xy 376.640475 -266.674128) (xy 376.663165 -266.629596) (xy 376.692541 -266.589163)
			(xy 376.727881 -266.553823) (xy 376.768314 -266.524447) (xy 376.812846 -266.501757) (xy 376.860378 -266.486313)
			(xy 376.909741 -266.478494) (xy 376.959719 -266.478494) (xy 377.009082 -266.486313) (xy 377.056614 -266.501757)
			(xy 377.101146 -266.524447) (xy 377.141579 -266.553823) (xy 377.176919 -266.589163) (xy 377.206295 -266.629596)
			(xy 377.228985 -266.674128) (xy 377.244429 -266.72166) (xy 377.252248 -266.771023) (xy 377.252738 -266.796012)
			(xy 377.558549 -266.796012) (xy 377.562644 -266.745284) (xy 377.574823 -266.69587) (xy 377.594771 -266.64905)
			(xy 377.621972 -266.606036) (xy 377.65572 -266.567942) (xy 377.695142 -266.535755) (xy 377.739216 -266.510309)
			(xy 377.786802 -266.492262) (xy 377.836666 -266.482082) (xy 377.887518 -266.480033) (xy 377.938039 -266.486167)
			(xy 377.986923 -266.500327) (xy 378.032902 -266.522144) (xy 378.074786 -266.551054) (xy 378.11149 -266.586309)
			(xy 378.142063 -266.626995) (xy 378.165714 -266.672058) (xy 378.18183 -266.720332) (xy 378.189994 -266.770566)
			(xy 378.190506 -266.796012) (xy 378.190003 -266.821001) (xy 378.49732 -266.821001) (xy 378.49732 -266.771023)
			(xy 378.505139 -266.72166) (xy 378.520583 -266.674128) (xy 378.543273 -266.629596) (xy 378.572649 -266.589163)
			(xy 378.607989 -266.553823) (xy 378.648422 -266.524447) (xy 378.692954 -266.501757) (xy 378.740486 -266.486313)
			(xy 378.789849 -266.478494) (xy 378.839827 -266.478494) (xy 378.88919 -266.486313) (xy 378.936722 -266.501757)
			(xy 378.981254 -266.524447) (xy 379.021687 -266.553823) (xy 379.057027 -266.589163) (xy 379.086403 -266.629596)
			(xy 379.109093 -266.674128) (xy 379.124537 -266.72166) (xy 379.132356 -266.771023) (xy 379.132846 -266.796012)
			(xy 379.438657 -266.796012) (xy 379.442752 -266.745284) (xy 379.454931 -266.69587) (xy 379.474879 -266.64905)
			(xy 379.50208 -266.606036) (xy 379.535828 -266.567942) (xy 379.57525 -266.535755) (xy 379.619324 -266.510309)
			(xy 379.66691 -266.492262) (xy 379.716774 -266.482082) (xy 379.767626 -266.480033) (xy 379.818147 -266.486167)
			(xy 379.867031 -266.500327) (xy 379.91301 -266.522144) (xy 379.954894 -266.551054) (xy 379.991598 -266.586309)
			(xy 380.022171 -266.626995) (xy 380.045822 -266.672058) (xy 380.061938 -266.720332) (xy 380.070102 -266.770566)
			(xy 380.070614 -266.796012) (xy 380.378711 -266.796012) (xy 380.382806 -266.745284) (xy 380.394985 -266.69587)
			(xy 380.414933 -266.64905) (xy 380.442134 -266.606036) (xy 380.475882 -266.567942) (xy 380.515304 -266.535755)
			(xy 380.559378 -266.510309) (xy 380.606964 -266.492262) (xy 380.656828 -266.482082) (xy 380.70768 -266.480033)
			(xy 380.758201 -266.486167) (xy 380.807085 -266.500327) (xy 380.853064 -266.522144) (xy 380.894948 -266.551054)
			(xy 380.931652 -266.586309) (xy 380.962225 -266.626995) (xy 380.985876 -266.672058) (xy 381.001992 -266.720332)
			(xy 381.010156 -266.770566) (xy 381.010668 -266.796012) (xy 381.010156 -266.821458) (xy 381.001992 -266.871692)
			(xy 380.985876 -266.919966) (xy 380.962225 -266.965029) (xy 380.931652 -267.005715) (xy 380.894948 -267.04097)
			(xy 380.853064 -267.06988) (xy 380.807085 -267.091697) (xy 380.758201 -267.105857) (xy 380.70768 -267.111991)
			(xy 380.656828 -267.109942) (xy 380.606964 -267.099762) (xy 380.559378 -267.081715) (xy 380.515304 -267.056269)
			(xy 380.475882 -267.024082) (xy 380.442134 -266.985988) (xy 380.414933 -266.942974) (xy 380.394985 -266.896154)
			(xy 380.382806 -266.84674) (xy 380.378711 -266.796012) (xy 380.070614 -266.796012) (xy 380.070102 -266.821458)
			(xy 380.061938 -266.871692) (xy 380.045822 -266.919966) (xy 380.022171 -266.965029) (xy 379.991598 -267.005715)
			(xy 379.954894 -267.04097) (xy 379.91301 -267.06988) (xy 379.867031 -267.091697) (xy 379.818147 -267.105857)
			(xy 379.767626 -267.111991) (xy 379.716774 -267.109942) (xy 379.66691 -267.099762) (xy 379.619324 -267.081715)
			(xy 379.57525 -267.056269) (xy 379.535828 -267.024082) (xy 379.50208 -266.985988) (xy 379.474879 -266.942974)
			(xy 379.454931 -266.896154) (xy 379.442752 -266.84674) (xy 379.438657 -266.796012) (xy 379.132846 -266.796012)
			(xy 379.132356 -266.821001) (xy 379.124537 -266.870364) (xy 379.109093 -266.917896) (xy 379.086403 -266.962428)
			(xy 379.057027 -267.002861) (xy 379.021687 -267.038201) (xy 378.981254 -267.067577) (xy 378.936722 -267.090267)
			(xy 378.88919 -267.105711) (xy 378.839827 -267.11353) (xy 378.789849 -267.11353) (xy 378.740486 -267.105711)
			(xy 378.692954 -267.090267) (xy 378.648422 -267.067577) (xy 378.607989 -267.038201) (xy 378.572649 -267.002861)
			(xy 378.543273 -266.962428) (xy 378.520583 -266.917896) (xy 378.505139 -266.870364) (xy 378.49732 -266.821001)
			(xy 378.190003 -266.821001) (xy 378.189994 -266.821458) (xy 378.18183 -266.871692) (xy 378.165714 -266.919966)
			(xy 378.142063 -266.965029) (xy 378.11149 -267.005715) (xy 378.074786 -267.04097) (xy 378.032902 -267.06988)
			(xy 377.986923 -267.091697) (xy 377.938039 -267.105857) (xy 377.887518 -267.111991) (xy 377.836666 -267.109942)
			(xy 377.786802 -267.099762) (xy 377.739216 -267.081715) (xy 377.695142 -267.056269) (xy 377.65572 -267.024082)
			(xy 377.621972 -266.985988) (xy 377.594771 -266.942974) (xy 377.574823 -266.896154) (xy 377.562644 -266.84674)
			(xy 377.558549 -266.796012) (xy 377.252738 -266.796012) (xy 377.252248 -266.821001) (xy 377.244429 -266.870364)
			(xy 377.228985 -266.917896) (xy 377.206295 -266.962428) (xy 377.176919 -267.002861) (xy 377.141579 -267.038201)
			(xy 377.101146 -267.067577) (xy 377.056614 -267.090267) (xy 377.009082 -267.105711) (xy 376.959719 -267.11353)
			(xy 376.909741 -267.11353) (xy 376.860378 -267.105711) (xy 376.812846 -267.090267) (xy 376.768314 -267.067577)
			(xy 376.727881 -267.038201) (xy 376.692541 -267.002861) (xy 376.663165 -266.962428) (xy 376.640475 -266.917896)
			(xy 376.625031 -266.870364) (xy 376.617212 -266.821001) (xy 376.310149 -266.821001) (xy 376.31014 -266.821458)
			(xy 376.301976 -266.871692) (xy 376.28586 -266.919966) (xy 376.262209 -266.965029) (xy 376.231636 -267.005715)
			(xy 376.194932 -267.04097) (xy 376.153048 -267.06988) (xy 376.107069 -267.091697) (xy 376.058185 -267.105857)
			(xy 376.007664 -267.111991) (xy 375.956812 -267.109942) (xy 375.906948 -267.099762) (xy 375.859362 -267.081715)
			(xy 375.815288 -267.056269) (xy 375.775866 -267.024082) (xy 375.742118 -266.985988) (xy 375.714917 -266.942974)
			(xy 375.694969 -266.896154) (xy 375.68279 -266.84674) (xy 375.678695 -266.796012) (xy 375.372884 -266.796012)
			(xy 375.372394 -266.821001) (xy 375.364575 -266.870364) (xy 375.349131 -266.917896) (xy 375.326441 -266.962428)
			(xy 375.297065 -267.002861) (xy 375.261725 -267.038201) (xy 375.221292 -267.067577) (xy 375.17676 -267.090267)
			(xy 375.129228 -267.105711) (xy 375.079865 -267.11353) (xy 375.029887 -267.11353) (xy 374.980524 -267.105711)
			(xy 374.932992 -267.090267) (xy 374.88846 -267.067577) (xy 374.848027 -267.038201) (xy 374.812687 -267.002861)
			(xy 374.783311 -266.962428) (xy 374.760621 -266.917896) (xy 374.745177 -266.870364) (xy 374.737358 -266.821001)
			(xy 374.43234 -266.821001) (xy 374.424521 -266.870364) (xy 374.409077 -266.917896) (xy 374.386387 -266.962428)
			(xy 374.357011 -267.002861) (xy 374.321671 -267.038201) (xy 374.281238 -267.067577) (xy 374.236706 -267.090267)
			(xy 374.189174 -267.105711) (xy 374.139811 -267.11353) (xy 374.089833 -267.11353) (xy 374.04047 -267.105711)
			(xy 373.992938 -267.090267) (xy 373.948406 -267.067577) (xy 373.907973 -267.038201) (xy 373.872633 -267.002861)
			(xy 373.843257 -266.962428) (xy 373.820567 -266.917896) (xy 373.805123 -266.870364) (xy 373.797304 -266.821001)
			(xy 373.492292 -266.821001) (xy 373.492248 -266.823322) (xy 373.482672 -266.878125) (xy 373.473726 -266.90447)
			(xy 373.470853 -266.913574) (xy 373.471347 -266.932645) (xy 373.478748 -266.950228) (xy 373.485156 -266.957302)
			(xy 373.50827 -266.980924) (xy 373.508524 -266.981178) (xy 373.646192 -267.118846) (xy 373.6467 -267.119354)
			(xy 373.654084 -267.125929) (xy 373.672383 -267.133362) (xy 373.68226 -267.133832) (xy 373.732552 -267.133832)
			(xy 373.753909 -267.134336) (xy 373.795777 -267.142793) (xy 373.83513 -267.159399) (xy 373.870399 -267.183493)
			(xy 373.900178 -267.214114) (xy 373.92328 -267.25004) (xy 373.938784 -267.28984) (xy 373.946072 -267.331927)
			(xy 373.945912 -267.353288) (xy 373.945912 -267.397484) (xy 373.946351 -267.407547) (xy 373.954088 -267.426128)
			(xy 373.960898 -267.433552) (xy 374.106948 -267.579602) (xy 374.113602 -267.585687) (xy 374.129988 -267.593186)
			(xy 374.147952 -267.594611) (xy 374.156732 -267.592556) (xy 374.253252 -267.565124) (xy 374.272048 -267.545566)
			(xy 374.27535 -267.53185) (xy 374.282087 -267.506151) (xy 374.302924 -267.457285) (xy 374.331583 -267.412554)
			(xy 374.367268 -267.3732) (xy 374.40899 -267.340315) (xy 374.455591 -267.31481) (xy 374.505778 -267.297393)
			(xy 374.55816 -267.288547) (xy 374.584722 -267.28801) (xy 374.60971 -267.288502) (xy 374.659069 -267.296323)
			(xy 374.706597 -267.31177) (xy 374.751124 -267.334461) (xy 374.791553 -267.363838) (xy 374.826888 -267.399178)
			(xy 374.85626 -267.43961) (xy 374.878946 -267.48414) (xy 374.894386 -267.53167) (xy 374.902201 -267.58103)
			(xy 374.90273 -267.606018) (xy 374.902234 -267.631007) (xy 376.147312 -267.631007) (xy 376.147312 -267.581029)
			(xy 376.155131 -267.531666) (xy 376.170575 -267.484134) (xy 376.193265 -267.439602) (xy 376.222641 -267.399169)
			(xy 376.257981 -267.363829) (xy 376.298414 -267.334453) (xy 376.342946 -267.311763) (xy 376.390478 -267.296319)
			(xy 376.439841 -267.2885) (xy 376.489819 -267.2885) (xy 376.539182 -267.296319) (xy 376.586714 -267.311763)
			(xy 376.631246 -267.334453) (xy 376.671679 -267.363829) (xy 376.707019 -267.399169) (xy 376.736395 -267.439602)
			(xy 376.759085 -267.484134) (xy 376.774529 -267.531666) (xy 376.782348 -267.581029) (xy 376.782838 -267.606018)
			(xy 377.088649 -267.606018) (xy 377.092744 -267.55529) (xy 377.104923 -267.505876) (xy 377.124871 -267.459056)
			(xy 377.152072 -267.416042) (xy 377.18582 -267.377948) (xy 377.225242 -267.345761) (xy 377.269316 -267.320315)
			(xy 377.316902 -267.302268) (xy 377.366766 -267.292088) (xy 377.417618 -267.290039) (xy 377.468139 -267.296173)
			(xy 377.517023 -267.310333) (xy 377.563002 -267.33215) (xy 377.604886 -267.36106) (xy 377.64159 -267.396315)
			(xy 377.672163 -267.437001) (xy 377.695814 -267.482064) (xy 377.71193 -267.530338) (xy 377.720094 -267.580572)
			(xy 377.720606 -267.606018) (xy 377.720103 -267.631007) (xy 378.02742 -267.631007) (xy 378.02742 -267.581029)
			(xy 378.035239 -267.531666) (xy 378.050683 -267.484134) (xy 378.073373 -267.439602) (xy 378.102749 -267.399169)
			(xy 378.138089 -267.363829) (xy 378.178522 -267.334453) (xy 378.223054 -267.311763) (xy 378.270586 -267.296319)
			(xy 378.319949 -267.2885) (xy 378.369927 -267.2885) (xy 378.41929 -267.296319) (xy 378.466822 -267.311763)
			(xy 378.511354 -267.334453) (xy 378.551787 -267.363829) (xy 378.587127 -267.399169) (xy 378.616503 -267.439602)
			(xy 378.639193 -267.484134) (xy 378.654637 -267.531666) (xy 378.662456 -267.581029) (xy 378.662946 -267.606018)
			(xy 378.662456 -267.631007) (xy 378.96722 -267.631007) (xy 378.96722 -267.581029) (xy 378.975039 -267.531666)
			(xy 378.990483 -267.484134) (xy 379.013173 -267.439602) (xy 379.042549 -267.399169) (xy 379.077889 -267.363829)
			(xy 379.118322 -267.334453) (xy 379.162854 -267.311763) (xy 379.210386 -267.296319) (xy 379.259749 -267.2885)
			(xy 379.309727 -267.2885) (xy 379.35909 -267.296319) (xy 379.406622 -267.311763) (xy 379.451154 -267.334453)
			(xy 379.491587 -267.363829) (xy 379.526927 -267.399169) (xy 379.556303 -267.439602) (xy 379.578993 -267.484134)
			(xy 379.594437 -267.531666) (xy 379.602256 -267.581029) (xy 379.602746 -267.606018) (xy 379.602256 -267.631007)
			(xy 379.907274 -267.631007) (xy 379.907274 -267.581029) (xy 379.915093 -267.531666) (xy 379.930537 -267.484134)
			(xy 379.953227 -267.439602) (xy 379.982603 -267.399169) (xy 380.017943 -267.363829) (xy 380.058376 -267.334453)
			(xy 380.102908 -267.311763) (xy 380.15044 -267.296319) (xy 380.199803 -267.2885) (xy 380.249781 -267.2885)
			(xy 380.299144 -267.296319) (xy 380.346676 -267.311763) (xy 380.391208 -267.334453) (xy 380.431641 -267.363829)
			(xy 380.466981 -267.399169) (xy 380.496357 -267.439602) (xy 380.519047 -267.484134) (xy 380.534491 -267.531666)
			(xy 380.54231 -267.581029) (xy 380.5428 -267.606018) (xy 380.54231 -267.631007) (xy 380.534491 -267.68037)
			(xy 380.519047 -267.727902) (xy 380.496357 -267.772434) (xy 380.466981 -267.812867) (xy 380.431641 -267.848207)
			(xy 380.391208 -267.877583) (xy 380.346676 -267.900273) (xy 380.299144 -267.915717) (xy 380.249781 -267.923536)
			(xy 380.199803 -267.923536) (xy 380.15044 -267.915717) (xy 380.102908 -267.900273) (xy 380.058376 -267.877583)
			(xy 380.017943 -267.848207) (xy 379.982603 -267.812867) (xy 379.953227 -267.772434) (xy 379.930537 -267.727902)
			(xy 379.915093 -267.68037) (xy 379.907274 -267.631007) (xy 379.602256 -267.631007) (xy 379.594437 -267.68037)
			(xy 379.578993 -267.727902) (xy 379.556303 -267.772434) (xy 379.526927 -267.812867) (xy 379.491587 -267.848207)
			(xy 379.451154 -267.877583) (xy 379.406622 -267.900273) (xy 379.35909 -267.915717) (xy 379.309727 -267.923536)
			(xy 379.259749 -267.923536) (xy 379.210386 -267.915717) (xy 379.162854 -267.900273) (xy 379.118322 -267.877583)
			(xy 379.077889 -267.848207) (xy 379.042549 -267.812867) (xy 379.013173 -267.772434) (xy 378.990483 -267.727902)
			(xy 378.975039 -267.68037) (xy 378.96722 -267.631007) (xy 378.662456 -267.631007) (xy 378.654637 -267.68037)
			(xy 378.639193 -267.727902) (xy 378.616503 -267.772434) (xy 378.587127 -267.812867) (xy 378.551787 -267.848207)
			(xy 378.511354 -267.877583) (xy 378.466822 -267.900273) (xy 378.41929 -267.915717) (xy 378.369927 -267.923536)
			(xy 378.319949 -267.923536) (xy 378.270586 -267.915717) (xy 378.223054 -267.900273) (xy 378.178522 -267.877583)
			(xy 378.138089 -267.848207) (xy 378.102749 -267.812867) (xy 378.073373 -267.772434) (xy 378.050683 -267.727902)
			(xy 378.035239 -267.68037) (xy 378.02742 -267.631007) (xy 377.720103 -267.631007) (xy 377.720094 -267.631464)
			(xy 377.71193 -267.681698) (xy 377.695814 -267.729972) (xy 377.672163 -267.775035) (xy 377.64159 -267.815721)
			(xy 377.604886 -267.850976) (xy 377.563002 -267.879886) (xy 377.517023 -267.901703) (xy 377.468139 -267.915863)
			(xy 377.417618 -267.921997) (xy 377.366766 -267.919948) (xy 377.316902 -267.909768) (xy 377.269316 -267.891721)
			(xy 377.225242 -267.866275) (xy 377.18582 -267.834088) (xy 377.152072 -267.795994) (xy 377.124871 -267.75298)
			(xy 377.104923 -267.70616) (xy 377.092744 -267.656746) (xy 377.088649 -267.606018) (xy 376.782838 -267.606018)
			(xy 376.782348 -267.631007) (xy 376.774529 -267.68037) (xy 376.759085 -267.727902) (xy 376.736395 -267.772434)
			(xy 376.707019 -267.812867) (xy 376.671679 -267.848207) (xy 376.631246 -267.877583) (xy 376.586714 -267.900273)
			(xy 376.539182 -267.915717) (xy 376.489819 -267.923536) (xy 376.439841 -267.923536) (xy 376.390478 -267.915717)
			(xy 376.342946 -267.900273) (xy 376.298414 -267.877583) (xy 376.257981 -267.848207) (xy 376.222641 -267.812867)
			(xy 376.193265 -267.772434) (xy 376.170575 -267.727902) (xy 376.155131 -267.68037) (xy 376.147312 -267.631007)
			(xy 374.902234 -267.631007) (xy 374.902203 -267.632586) (xy 374.893388 -267.684985) (xy 374.875991 -267.735191)
			(xy 374.850493 -267.781809) (xy 374.817606 -267.823543) (xy 374.778241 -267.859233) (xy 374.733494 -267.887886)
			(xy 374.684608 -267.908707) (xy 374.65889 -267.91539) (xy 374.645174 -267.918692) (xy 374.625616 -267.937488)
			(xy 374.598184 -268.034008) (xy 374.596037 -268.042786) (xy 374.597402 -268.060794) (xy 374.604966 -268.077193)
			(xy 374.611138 -268.083792) (xy 374.703594 -268.176248) (xy 374.709763 -268.18192) (xy 374.724799 -268.189295)
			(xy 374.733058 -268.190726) (xy 374.735852 -268.191234) (xy 374.81637 -268.193266) (xy 374.834404 -268.186662)
			(xy 374.84177 -268.180058) (xy 374.859383 -268.164694) (xy 374.898271 -268.138769) (xy 374.940538 -268.118822)
			(xy 374.985272 -268.105284) (xy 375.031507 -268.098447) (xy 375.054876 -268.098016) (xy 375.079868 -268.098479)
			(xy 375.129236 -268.106295) (xy 375.176774 -268.121739) (xy 375.22131 -268.144429) (xy 375.261748 -268.173808)
			(xy 375.297092 -268.209152) (xy 375.326471 -268.24959) (xy 375.349161 -268.294126) (xy 375.364605 -268.341664)
			(xy 375.372421 -268.391032) (xy 375.372884 -268.416024) (xy 375.372383 -268.441013) (xy 375.677412 -268.441013)
			(xy 375.677412 -268.391035) (xy 375.685231 -268.341672) (xy 375.700675 -268.29414) (xy 375.723365 -268.249608)
			(xy 375.752741 -268.209175) (xy 375.788081 -268.173835) (xy 375.828514 -268.144459) (xy 375.873046 -268.121769)
			(xy 375.920578 -268.106325) (xy 375.969941 -268.098506) (xy 376.019919 -268.098506) (xy 376.069282 -268.106325)
			(xy 376.116814 -268.121769) (xy 376.161346 -268.144459) (xy 376.201779 -268.173835) (xy 376.237119 -268.209175)
			(xy 376.266495 -268.249608) (xy 376.289185 -268.29414) (xy 376.304629 -268.341672) (xy 376.312448 -268.391035)
			(xy 376.312938 -268.416024) (xy 376.312448 -268.441013) (xy 376.617212 -268.441013) (xy 376.617212 -268.391035)
			(xy 376.625031 -268.341672) (xy 376.640475 -268.29414) (xy 376.663165 -268.249608) (xy 376.692541 -268.209175)
			(xy 376.727881 -268.173835) (xy 376.768314 -268.144459) (xy 376.812846 -268.121769) (xy 376.860378 -268.106325)
			(xy 376.909741 -268.098506) (xy 376.959719 -268.098506) (xy 377.009082 -268.106325) (xy 377.056614 -268.121769)
			(xy 377.101146 -268.144459) (xy 377.141579 -268.173835) (xy 377.176919 -268.209175) (xy 377.206295 -268.249608)
			(xy 377.228985 -268.29414) (xy 377.244429 -268.341672) (xy 377.252248 -268.391035) (xy 377.252738 -268.416024)
			(xy 377.252248 -268.441013) (xy 377.557266 -268.441013) (xy 377.557266 -268.391035) (xy 377.565085 -268.341672)
			(xy 377.580529 -268.29414) (xy 377.603219 -268.249608) (xy 377.632595 -268.209175) (xy 377.667935 -268.173835)
			(xy 377.708368 -268.144459) (xy 377.7529 -268.121769) (xy 377.800432 -268.106325) (xy 377.849795 -268.098506)
			(xy 377.899773 -268.098506) (xy 377.949136 -268.106325) (xy 377.996668 -268.121769) (xy 378.0412 -268.144459)
			(xy 378.081633 -268.173835) (xy 378.116973 -268.209175) (xy 378.146349 -268.249608) (xy 378.169039 -268.29414)
			(xy 378.184483 -268.341672) (xy 378.192302 -268.391035) (xy 378.192792 -268.416024) (xy 378.192302 -268.441013)
			(xy 379.437374 -268.441013) (xy 379.437374 -268.391035) (xy 379.445193 -268.341672) (xy 379.460637 -268.29414)
			(xy 379.483327 -268.249608) (xy 379.512703 -268.209175) (xy 379.548043 -268.173835) (xy 379.588476 -268.144459)
			(xy 379.633008 -268.121769) (xy 379.68054 -268.106325) (xy 379.729903 -268.098506) (xy 379.779881 -268.098506)
			(xy 379.829244 -268.106325) (xy 379.876776 -268.121769) (xy 379.921308 -268.144459) (xy 379.961741 -268.173835)
			(xy 379.997081 -268.209175) (xy 380.026457 -268.249608) (xy 380.049147 -268.29414) (xy 380.064591 -268.341672)
			(xy 380.07241 -268.391035) (xy 380.0729 -268.416024) (xy 380.07241 -268.441013) (xy 380.377174 -268.441013)
			(xy 380.377174 -268.391035) (xy 380.384993 -268.341672) (xy 380.400437 -268.29414) (xy 380.423127 -268.249608)
			(xy 380.452503 -268.209175) (xy 380.487843 -268.173835) (xy 380.528276 -268.144459) (xy 380.572808 -268.121769)
			(xy 380.62034 -268.106325) (xy 380.669703 -268.098506) (xy 380.719681 -268.098506) (xy 380.769044 -268.106325)
			(xy 380.816576 -268.121769) (xy 380.861108 -268.144459) (xy 380.901541 -268.173835) (xy 380.936881 -268.209175)
			(xy 380.966257 -268.249608) (xy 380.988947 -268.29414) (xy 381.004391 -268.341672) (xy 381.01221 -268.391035)
			(xy 381.0127 -268.416024) (xy 381.01221 -268.441013) (xy 381.004391 -268.490376) (xy 380.988947 -268.537908)
			(xy 380.966257 -268.58244) (xy 380.936881 -268.622873) (xy 380.901541 -268.658213) (xy 380.861108 -268.687589)
			(xy 380.816576 -268.710279) (xy 380.769044 -268.725723) (xy 380.719681 -268.733542) (xy 380.669703 -268.733542)
			(xy 380.62034 -268.725723) (xy 380.572808 -268.710279) (xy 380.528276 -268.687589) (xy 380.487843 -268.658213)
			(xy 380.452503 -268.622873) (xy 380.423127 -268.58244) (xy 380.400437 -268.537908) (xy 380.384993 -268.490376)
			(xy 380.377174 -268.441013) (xy 380.07241 -268.441013) (xy 380.064591 -268.490376) (xy 380.049147 -268.537908)
			(xy 380.026457 -268.58244) (xy 379.997081 -268.622873) (xy 379.961741 -268.658213) (xy 379.921308 -268.687589)
			(xy 379.876776 -268.710279) (xy 379.829244 -268.725723) (xy 379.779881 -268.733542) (xy 379.729903 -268.733542)
			(xy 379.68054 -268.725723) (xy 379.633008 -268.710279) (xy 379.588476 -268.687589) (xy 379.548043 -268.658213)
			(xy 379.512703 -268.622873) (xy 379.483327 -268.58244) (xy 379.460637 -268.537908) (xy 379.445193 -268.490376)
			(xy 379.437374 -268.441013) (xy 378.192302 -268.441013) (xy 378.184483 -268.490376) (xy 378.169039 -268.537908)
			(xy 378.146349 -268.58244) (xy 378.116973 -268.622873) (xy 378.081633 -268.658213) (xy 378.0412 -268.687589)
			(xy 377.996668 -268.710279) (xy 377.949136 -268.725723) (xy 377.899773 -268.733542) (xy 377.849795 -268.733542)
			(xy 377.800432 -268.725723) (xy 377.7529 -268.710279) (xy 377.708368 -268.687589) (xy 377.667935 -268.658213)
			(xy 377.632595 -268.622873) (xy 377.603219 -268.58244) (xy 377.580529 -268.537908) (xy 377.565085 -268.490376)
			(xy 377.557266 -268.441013) (xy 377.252248 -268.441013) (xy 377.244429 -268.490376) (xy 377.228985 -268.537908)
			(xy 377.206295 -268.58244) (xy 377.176919 -268.622873) (xy 377.141579 -268.658213) (xy 377.101146 -268.687589)
			(xy 377.056614 -268.710279) (xy 377.009082 -268.725723) (xy 376.959719 -268.733542) (xy 376.909741 -268.733542)
			(xy 376.860378 -268.725723) (xy 376.812846 -268.710279) (xy 376.768314 -268.687589) (xy 376.727881 -268.658213)
			(xy 376.692541 -268.622873) (xy 376.663165 -268.58244) (xy 376.640475 -268.537908) (xy 376.625031 -268.490376)
			(xy 376.617212 -268.441013) (xy 376.312448 -268.441013) (xy 376.304629 -268.490376) (xy 376.289185 -268.537908)
			(xy 376.266495 -268.58244) (xy 376.237119 -268.622873) (xy 376.201779 -268.658213) (xy 376.161346 -268.687589)
			(xy 376.116814 -268.710279) (xy 376.069282 -268.725723) (xy 376.019919 -268.733542) (xy 375.969941 -268.733542)
			(xy 375.920578 -268.725723) (xy 375.873046 -268.710279) (xy 375.828514 -268.687589) (xy 375.788081 -268.658213)
			(xy 375.752741 -268.622873) (xy 375.723365 -268.58244) (xy 375.700675 -268.537908) (xy 375.685231 -268.490376)
			(xy 375.677412 -268.441013) (xy 375.372383 -268.441013) (xy 375.372371 -268.441614) (xy 375.364174 -268.492133)
			(xy 375.347997 -268.540689) (xy 375.324256 -268.58603) (xy 375.293564 -268.626985) (xy 375.256711 -268.6625)
			(xy 375.214649 -268.691657) (xy 375.168462 -268.713706) (xy 375.14403 -268.721332) (xy 375.143776 -268.721332)
			(xy 375.133446 -268.724927) (xy 375.116964 -268.73927) (xy 375.107947 -268.759173) (xy 375.107454 -268.7701)
			(xy 375.107454 -268.953488) (xy 375.107708 -268.957298) (xy 375.108713 -268.966019) (xy 375.115831 -268.982052)
			(xy 375.127951 -268.994734) (xy 375.135648 -268.998954) (xy 375.140728 -269.000986) (xy 375.242582 -269.038832)
			(xy 375.273062 -269.030958) (xy 375.28373 -269.018766) (xy 375.302008 -268.998371) (xy 375.344285 -268.963565)
			(xy 375.3919 -268.936516) (xy 375.443445 -268.918025) (xy 375.497395 -268.908639) (xy 375.524776 -268.908022)
			(xy 375.549766 -268.908485) (xy 375.599131 -268.9163) (xy 375.646666 -268.931742) (xy 375.6912 -268.95443)
			(xy 375.731636 -268.983806) (xy 375.766978 -269.019146) (xy 375.796357 -269.05958) (xy 375.819049 -269.104112)
			(xy 375.834494 -269.151645) (xy 375.842313 -269.20101) (xy 375.842313 -269.25099) (xy 375.842308 -269.251019)
			(xy 376.147312 -269.251019) (xy 376.147312 -269.201041) (xy 376.155131 -269.151678) (xy 376.170575 -269.104146)
			(xy 376.193265 -269.059614) (xy 376.222641 -269.019181) (xy 376.257981 -268.983841) (xy 376.298414 -268.954465)
			(xy 376.342946 -268.931775) (xy 376.390478 -268.916331) (xy 376.439841 -268.908512) (xy 376.489819 -268.908512)
			(xy 376.539182 -268.916331) (xy 376.586714 -268.931775) (xy 376.631246 -268.954465) (xy 376.671679 -268.983841)
			(xy 376.707019 -269.019181) (xy 376.736395 -269.059614) (xy 376.759085 -269.104146) (xy 376.774529 -269.151678)
			(xy 376.782348 -269.201041) (xy 376.782838 -269.22603) (xy 377.088649 -269.22603) (xy 377.092744 -269.175302)
			(xy 377.104923 -269.125888) (xy 377.124871 -269.079068) (xy 377.152072 -269.036054) (xy 377.18582 -268.99796)
			(xy 377.225242 -268.965773) (xy 377.269316 -268.940327) (xy 377.316902 -268.92228) (xy 377.366766 -268.9121)
			(xy 377.417618 -268.910051) (xy 377.468139 -268.916185) (xy 377.517023 -268.930345) (xy 377.563002 -268.952162)
			(xy 377.604886 -268.981072) (xy 377.64159 -269.016327) (xy 377.672163 -269.057013) (xy 377.695814 -269.102076)
			(xy 377.71193 -269.15035) (xy 377.720094 -269.200584) (xy 377.720606 -269.22603) (xy 377.720103 -269.251019)
			(xy 378.02742 -269.251019) (xy 378.02742 -269.201041) (xy 378.035239 -269.151678) (xy 378.050683 -269.104146)
			(xy 378.073373 -269.059614) (xy 378.102749 -269.019181) (xy 378.138089 -268.983841) (xy 378.178522 -268.954465)
			(xy 378.223054 -268.931775) (xy 378.270586 -268.916331) (xy 378.319949 -268.908512) (xy 378.369927 -268.908512)
			(xy 378.41929 -268.916331) (xy 378.466822 -268.931775) (xy 378.511354 -268.954465) (xy 378.551787 -268.983841)
			(xy 378.587127 -269.019181) (xy 378.616503 -269.059614) (xy 378.639193 -269.104146) (xy 378.654637 -269.151678)
			(xy 378.662456 -269.201041) (xy 378.662946 -269.22603) (xy 378.662456 -269.251019) (xy 378.96722 -269.251019)
			(xy 378.96722 -269.201041) (xy 378.975039 -269.151678) (xy 378.990483 -269.104146) (xy 379.013173 -269.059614)
			(xy 379.042549 -269.019181) (xy 379.077889 -268.983841) (xy 379.118322 -268.954465) (xy 379.162854 -268.931775)
			(xy 379.210386 -268.916331) (xy 379.259749 -268.908512) (xy 379.309727 -268.908512) (xy 379.35909 -268.916331)
			(xy 379.406622 -268.931775) (xy 379.451154 -268.954465) (xy 379.491587 -268.983841) (xy 379.526927 -269.019181)
			(xy 379.556303 -269.059614) (xy 379.578993 -269.104146) (xy 379.594437 -269.151678) (xy 379.602256 -269.201041)
			(xy 379.602746 -269.22603) (xy 379.602256 -269.251019) (xy 379.907274 -269.251019) (xy 379.907274 -269.201041)
			(xy 379.915093 -269.151678) (xy 379.930537 -269.104146) (xy 379.953227 -269.059614) (xy 379.982603 -269.019181)
			(xy 380.017943 -268.983841) (xy 380.058376 -268.954465) (xy 380.102908 -268.931775) (xy 380.15044 -268.916331)
			(xy 380.199803 -268.908512) (xy 380.249781 -268.908512) (xy 380.299144 -268.916331) (xy 380.346676 -268.931775)
			(xy 380.391208 -268.954465) (xy 380.431641 -268.983841) (xy 380.466981 -269.019181) (xy 380.496357 -269.059614)
			(xy 380.519047 -269.104146) (xy 380.534491 -269.151678) (xy 380.54231 -269.201041) (xy 380.5428 -269.22603)
			(xy 380.54231 -269.251019) (xy 380.534491 -269.300382) (xy 380.519047 -269.347914) (xy 380.496357 -269.392446)
			(xy 380.466981 -269.432879) (xy 380.431641 -269.468219) (xy 380.391208 -269.497595) (xy 380.346676 -269.520285)
			(xy 380.299144 -269.535729) (xy 380.249781 -269.543548) (xy 380.199803 -269.543548) (xy 380.15044 -269.535729)
			(xy 380.102908 -269.520285) (xy 380.058376 -269.497595) (xy 380.017943 -269.468219) (xy 379.982603 -269.432879)
			(xy 379.953227 -269.392446) (xy 379.930537 -269.347914) (xy 379.915093 -269.300382) (xy 379.907274 -269.251019)
			(xy 379.602256 -269.251019) (xy 379.594437 -269.300382) (xy 379.578993 -269.347914) (xy 379.556303 -269.392446)
			(xy 379.526927 -269.432879) (xy 379.491587 -269.468219) (xy 379.451154 -269.497595) (xy 379.406622 -269.520285)
			(xy 379.35909 -269.535729) (xy 379.309727 -269.543548) (xy 379.259749 -269.543548) (xy 379.210386 -269.535729)
			(xy 379.162854 -269.520285) (xy 379.118322 -269.497595) (xy 379.077889 -269.468219) (xy 379.042549 -269.432879)
			(xy 379.013173 -269.392446) (xy 378.990483 -269.347914) (xy 378.975039 -269.300382) (xy 378.96722 -269.251019)
			(xy 378.662456 -269.251019) (xy 378.654637 -269.300382) (xy 378.639193 -269.347914) (xy 378.616503 -269.392446)
			(xy 378.587127 -269.432879) (xy 378.551787 -269.468219) (xy 378.511354 -269.497595) (xy 378.466822 -269.520285)
			(xy 378.41929 -269.535729) (xy 378.369927 -269.543548) (xy 378.319949 -269.543548) (xy 378.270586 -269.535729)
			(xy 378.223054 -269.520285) (xy 378.178522 -269.497595) (xy 378.138089 -269.468219) (xy 378.102749 -269.432879)
			(xy 378.073373 -269.392446) (xy 378.050683 -269.347914) (xy 378.035239 -269.300382) (xy 378.02742 -269.251019)
			(xy 377.720103 -269.251019) (xy 377.720094 -269.251476) (xy 377.71193 -269.30171) (xy 377.695814 -269.349984)
			(xy 377.672163 -269.395047) (xy 377.64159 -269.435733) (xy 377.604886 -269.470988) (xy 377.563002 -269.499898)
			(xy 377.517023 -269.521715) (xy 377.468139 -269.535875) (xy 377.417618 -269.542009) (xy 377.366766 -269.53996)
			(xy 377.316902 -269.52978) (xy 377.269316 -269.511733) (xy 377.225242 -269.486287) (xy 377.18582 -269.4541)
			(xy 377.152072 -269.416006) (xy 377.124871 -269.372992) (xy 377.104923 -269.326172) (xy 377.092744 -269.276758)
			(xy 377.088649 -269.22603) (xy 376.782838 -269.22603) (xy 376.782348 -269.251019) (xy 376.774529 -269.300382)
			(xy 376.759085 -269.347914) (xy 376.736395 -269.392446) (xy 376.707019 -269.432879) (xy 376.671679 -269.468219)
			(xy 376.631246 -269.497595) (xy 376.586714 -269.520285) (xy 376.539182 -269.535729) (xy 376.489819 -269.543548)
			(xy 376.439841 -269.543548) (xy 376.390478 -269.535729) (xy 376.342946 -269.520285) (xy 376.298414 -269.497595)
			(xy 376.257981 -269.468219) (xy 376.222641 -269.432879) (xy 376.193265 -269.392446) (xy 376.170575 -269.347914)
			(xy 376.155131 -269.300382) (xy 376.147312 -269.251019) (xy 375.842308 -269.251019) (xy 375.834494 -269.300355)
			(xy 375.819049 -269.347888) (xy 375.796357 -269.39242) (xy 375.766978 -269.432854) (xy 375.731636 -269.468194)
			(xy 375.6912 -269.49757) (xy 375.646666 -269.520258) (xy 375.599131 -269.5357) (xy 375.549766 -269.543515)
			(xy 375.524776 -269.544038) (xy 375.497394 -269.543462) (xy 375.443442 -269.534069) (xy 375.391899 -269.515566)
			(xy 375.344292 -269.4885) (xy 375.302029 -269.453672) (xy 375.28373 -269.433294) (xy 375.273062 -269.421102)
			(xy 375.242582 -269.413228) (xy 375.140728 -269.451074) (xy 375.135648 -269.453106) (xy 375.127993 -269.457375)
			(xy 375.115916 -269.470061) (xy 375.108791 -269.486062) (xy 375.107708 -269.494762) (xy 375.107454 -269.498572)
			(xy 375.107454 -269.68196) (xy 375.107979 -269.692873) (xy 375.117026 -269.712736) (xy 375.133476 -269.727082)
			(xy 375.143776 -269.730728) (xy 375.14403 -269.730728) (xy 375.168454 -269.738388) (xy 375.214658 -269.76041)
			(xy 375.256736 -269.789551) (xy 375.293601 -269.825057) (xy 375.324301 -269.866012) (xy 375.348043 -269.911356)
			(xy 375.364212 -269.959918) (xy 375.372391 -270.010444) (xy 375.372884 -270.036036) (xy 375.678695 -270.036036)
			(xy 375.68279 -269.985308) (xy 375.694969 -269.935894) (xy 375.714917 -269.889074) (xy 375.742118 -269.84606)
			(xy 375.775866 -269.807966) (xy 375.815288 -269.775779) (xy 375.859362 -269.750333) (xy 375.906948 -269.732286)
			(xy 375.956812 -269.722106) (xy 376.007664 -269.720057) (xy 376.058185 -269.726191) (xy 376.107069 -269.740351)
			(xy 376.153048 -269.762168) (xy 376.194932 -269.791078) (xy 376.231636 -269.826333) (xy 376.262209 -269.867019)
			(xy 376.28586 -269.912082) (xy 376.301976 -269.960356) (xy 376.31014 -270.01059) (xy 376.310652 -270.036036)
			(xy 376.310149 -270.061025) (xy 376.617212 -270.061025) (xy 376.617212 -270.011047) (xy 376.625031 -269.961684)
			(xy 376.640475 -269.914152) (xy 376.663165 -269.86962) (xy 376.692541 -269.829187) (xy 376.727881 -269.793847)
			(xy 376.768314 -269.764471) (xy 376.812846 -269.741781) (xy 376.860378 -269.726337) (xy 376.909741 -269.718518)
			(xy 376.959719 -269.718518) (xy 377.009082 -269.726337) (xy 377.056614 -269.741781) (xy 377.101146 -269.764471)
			(xy 377.141579 -269.793847) (xy 377.176919 -269.829187) (xy 377.206295 -269.86962) (xy 377.228985 -269.914152)
			(xy 377.244429 -269.961684) (xy 377.252248 -270.011047) (xy 377.252738 -270.036036) (xy 377.558549 -270.036036)
			(xy 377.562644 -269.985308) (xy 377.574823 -269.935894) (xy 377.594771 -269.889074) (xy 377.621972 -269.84606)
			(xy 377.65572 -269.807966) (xy 377.695142 -269.775779) (xy 377.739216 -269.750333) (xy 377.786802 -269.732286)
			(xy 377.836666 -269.722106) (xy 377.887518 -269.720057) (xy 377.938039 -269.726191) (xy 377.986923 -269.740351)
			(xy 378.032902 -269.762168) (xy 378.074786 -269.791078) (xy 378.11149 -269.826333) (xy 378.142063 -269.867019)
			(xy 378.165714 -269.912082) (xy 378.18183 -269.960356) (xy 378.189994 -270.01059) (xy 378.190506 -270.036036)
			(xy 378.190003 -270.061025) (xy 378.49732 -270.061025) (xy 378.49732 -270.011047) (xy 378.505139 -269.961684)
			(xy 378.520583 -269.914152) (xy 378.543273 -269.86962) (xy 378.572649 -269.829187) (xy 378.607989 -269.793847)
			(xy 378.648422 -269.764471) (xy 378.692954 -269.741781) (xy 378.740486 -269.726337) (xy 378.789849 -269.718518)
			(xy 378.839827 -269.718518) (xy 378.88919 -269.726337) (xy 378.936722 -269.741781) (xy 378.981254 -269.764471)
			(xy 379.021687 -269.793847) (xy 379.057027 -269.829187) (xy 379.086403 -269.86962) (xy 379.109093 -269.914152)
			(xy 379.124537 -269.961684) (xy 379.132356 -270.011047) (xy 379.132846 -270.036036) (xy 379.438657 -270.036036)
			(xy 379.442752 -269.985308) (xy 379.454931 -269.935894) (xy 379.474879 -269.889074) (xy 379.50208 -269.84606)
			(xy 379.535828 -269.807966) (xy 379.57525 -269.775779) (xy 379.619324 -269.750333) (xy 379.66691 -269.732286)
			(xy 379.716774 -269.722106) (xy 379.767626 -269.720057) (xy 379.818147 -269.726191) (xy 379.867031 -269.740351)
			(xy 379.91301 -269.762168) (xy 379.954894 -269.791078) (xy 379.991598 -269.826333) (xy 380.022171 -269.867019)
			(xy 380.045822 -269.912082) (xy 380.061938 -269.960356) (xy 380.070102 -270.01059) (xy 380.070614 -270.036036)
			(xy 380.378711 -270.036036) (xy 380.382806 -269.985308) (xy 380.394985 -269.935894) (xy 380.414933 -269.889074)
			(xy 380.442134 -269.84606) (xy 380.475882 -269.807966) (xy 380.515304 -269.775779) (xy 380.559378 -269.750333)
			(xy 380.606964 -269.732286) (xy 380.656828 -269.722106) (xy 380.70768 -269.720057) (xy 380.758201 -269.726191)
			(xy 380.807085 -269.740351) (xy 380.853064 -269.762168) (xy 380.894948 -269.791078) (xy 380.931652 -269.826333)
			(xy 380.962225 -269.867019) (xy 380.985876 -269.912082) (xy 381.001992 -269.960356) (xy 381.010156 -270.01059)
			(xy 381.010668 -270.036036) (xy 381.010156 -270.061482) (xy 381.001992 -270.111716) (xy 380.985876 -270.15999)
			(xy 380.962225 -270.205053) (xy 380.931652 -270.245739) (xy 380.894948 -270.280994) (xy 380.853064 -270.309904)
			(xy 380.807085 -270.331721) (xy 380.758201 -270.345881) (xy 380.70768 -270.352015) (xy 380.656828 -270.349966)
			(xy 380.606964 -270.339786) (xy 380.559378 -270.321739) (xy 380.515304 -270.296293) (xy 380.475882 -270.264106)
			(xy 380.442134 -270.226012) (xy 380.414933 -270.182998) (xy 380.394985 -270.136178) (xy 380.382806 -270.086764)
			(xy 380.378711 -270.036036) (xy 380.070614 -270.036036) (xy 380.070102 -270.061482) (xy 380.061938 -270.111716)
			(xy 380.045822 -270.15999) (xy 380.022171 -270.205053) (xy 379.991598 -270.245739) (xy 379.954894 -270.280994)
			(xy 379.91301 -270.309904) (xy 379.867031 -270.331721) (xy 379.818147 -270.345881) (xy 379.767626 -270.352015)
			(xy 379.716774 -270.349966) (xy 379.66691 -270.339786) (xy 379.619324 -270.321739) (xy 379.57525 -270.296293)
			(xy 379.535828 -270.264106) (xy 379.50208 -270.226012) (xy 379.474879 -270.182998) (xy 379.454931 -270.136178)
			(xy 379.442752 -270.086764) (xy 379.438657 -270.036036) (xy 379.132846 -270.036036) (xy 379.132356 -270.061025)
			(xy 379.124537 -270.110388) (xy 379.109093 -270.15792) (xy 379.086403 -270.202452) (xy 379.057027 -270.242885)
			(xy 379.021687 -270.278225) (xy 378.981254 -270.307601) (xy 378.936722 -270.330291) (xy 378.88919 -270.345735)
			(xy 378.839827 -270.353554) (xy 378.789849 -270.353554) (xy 378.740486 -270.345735) (xy 378.692954 -270.330291)
			(xy 378.648422 -270.307601) (xy 378.607989 -270.278225) (xy 378.572649 -270.242885) (xy 378.543273 -270.202452)
			(xy 378.520583 -270.15792) (xy 378.505139 -270.110388) (xy 378.49732 -270.061025) (xy 378.190003 -270.061025)
			(xy 378.189994 -270.061482) (xy 378.18183 -270.111716) (xy 378.165714 -270.15999) (xy 378.142063 -270.205053)
			(xy 378.11149 -270.245739) (xy 378.074786 -270.280994) (xy 378.032902 -270.309904) (xy 377.986923 -270.331721)
			(xy 377.938039 -270.345881) (xy 377.887518 -270.352015) (xy 377.836666 -270.349966) (xy 377.786802 -270.339786)
			(xy 377.739216 -270.321739) (xy 377.695142 -270.296293) (xy 377.65572 -270.264106) (xy 377.621972 -270.226012)
			(xy 377.594771 -270.182998) (xy 377.574823 -270.136178) (xy 377.562644 -270.086764) (xy 377.558549 -270.036036)
			(xy 377.252738 -270.036036) (xy 377.252248 -270.061025) (xy 377.244429 -270.110388) (xy 377.228985 -270.15792)
			(xy 377.206295 -270.202452) (xy 377.176919 -270.242885) (xy 377.141579 -270.278225) (xy 377.101146 -270.307601)
			(xy 377.056614 -270.330291) (xy 377.009082 -270.345735) (xy 376.959719 -270.353554) (xy 376.909741 -270.353554)
			(xy 376.860378 -270.345735) (xy 376.812846 -270.330291) (xy 376.768314 -270.307601) (xy 376.727881 -270.278225)
			(xy 376.692541 -270.242885) (xy 376.663165 -270.202452) (xy 376.640475 -270.15792) (xy 376.625031 -270.110388)
			(xy 376.617212 -270.061025) (xy 376.310149 -270.061025) (xy 376.31014 -270.061482) (xy 376.301976 -270.111716)
			(xy 376.28586 -270.15999) (xy 376.262209 -270.205053) (xy 376.231636 -270.245739) (xy 376.194932 -270.280994)
			(xy 376.153048 -270.309904) (xy 376.107069 -270.331721) (xy 376.058185 -270.345881) (xy 376.007664 -270.352015)
			(xy 375.956812 -270.349966) (xy 375.906948 -270.339786) (xy 375.859362 -270.321739) (xy 375.815288 -270.296293)
			(xy 375.775866 -270.264106) (xy 375.742118 -270.226012) (xy 375.714917 -270.182998) (xy 375.694969 -270.136178)
			(xy 375.68279 -270.086764) (xy 375.678695 -270.036036) (xy 375.372884 -270.036036) (xy 375.372378 -270.061613)
			(xy 375.364202 -270.112109) (xy 375.34805 -270.160645) (xy 375.324338 -270.205971) (xy 375.293678 -270.246917)
			(xy 375.256861 -270.28243) (xy 375.214834 -270.311592) (xy 375.168682 -270.333653) (xy 375.144284 -270.341344)
			(xy 375.143776 -270.341344) (xy 375.133437 -270.344935) (xy 375.116929 -270.359274) (xy 375.10788 -270.379178)
			(xy 375.107454 -270.390112) (xy 375.107454 -270.846042) (xy 376.148595 -270.846042) (xy 376.15269 -270.795314)
			(xy 376.164869 -270.7459) (xy 376.184817 -270.69908) (xy 376.212018 -270.656066) (xy 376.245766 -270.617972)
			(xy 376.285188 -270.585785) (xy 376.329262 -270.560339) (xy 376.376848 -270.542292) (xy 376.426712 -270.532112)
			(xy 376.477564 -270.530063) (xy 376.528085 -270.536197) (xy 376.576969 -270.550357) (xy 376.622948 -270.572174)
			(xy 376.664832 -270.601084) (xy 376.701536 -270.636339) (xy 376.732109 -270.677025) (xy 376.75576 -270.722088)
			(xy 376.771876 -270.770362) (xy 376.78004 -270.820596) (xy 376.780552 -270.846042) (xy 377.088649 -270.846042)
			(xy 377.092744 -270.795314) (xy 377.104923 -270.7459) (xy 377.124871 -270.69908) (xy 377.152072 -270.656066)
			(xy 377.18582 -270.617972) (xy 377.225242 -270.585785) (xy 377.269316 -270.560339) (xy 377.316902 -270.542292)
			(xy 377.366766 -270.532112) (xy 377.417618 -270.530063) (xy 377.468139 -270.536197) (xy 377.517023 -270.550357)
			(xy 377.563002 -270.572174) (xy 377.604886 -270.601084) (xy 377.64159 -270.636339) (xy 377.672163 -270.677025)
			(xy 377.695814 -270.722088) (xy 377.71193 -270.770362) (xy 377.720094 -270.820596) (xy 377.720606 -270.846042)
			(xy 378.968503 -270.846042) (xy 378.972598 -270.795314) (xy 378.984777 -270.7459) (xy 379.004725 -270.69908)
			(xy 379.031926 -270.656066) (xy 379.065674 -270.617972) (xy 379.105096 -270.585785) (xy 379.14917 -270.560339)
			(xy 379.196756 -270.542292) (xy 379.24662 -270.532112) (xy 379.297472 -270.530063) (xy 379.347993 -270.536197)
			(xy 379.396877 -270.550357) (xy 379.442856 -270.572174) (xy 379.48474 -270.601084) (xy 379.521444 -270.636339)
			(xy 379.552017 -270.677025) (xy 379.575668 -270.722088) (xy 379.591784 -270.770362) (xy 379.599948 -270.820596)
			(xy 379.60046 -270.846042) (xy 379.599957 -270.871031) (xy 379.907274 -270.871031) (xy 379.907274 -270.821053)
			(xy 379.915093 -270.77169) (xy 379.930537 -270.724158) (xy 379.953227 -270.679626) (xy 379.982603 -270.639193)
			(xy 380.017943 -270.603853) (xy 380.058376 -270.574477) (xy 380.102908 -270.551787) (xy 380.15044 -270.536343)
			(xy 380.199803 -270.528524) (xy 380.249781 -270.528524) (xy 380.299144 -270.536343) (xy 380.346676 -270.551787)
			(xy 380.391208 -270.574477) (xy 380.431641 -270.603853) (xy 380.466981 -270.639193) (xy 380.496357 -270.679626)
			(xy 380.519047 -270.724158) (xy 380.534491 -270.77169) (xy 380.54231 -270.821053) (xy 380.5428 -270.846042)
			(xy 380.54231 -270.871031) (xy 380.534491 -270.920394) (xy 380.519047 -270.967926) (xy 380.496357 -271.012458)
			(xy 380.466981 -271.052891) (xy 380.431641 -271.088231) (xy 380.391208 -271.117607) (xy 380.346676 -271.140297)
			(xy 380.299144 -271.155741) (xy 380.249781 -271.16356) (xy 380.199803 -271.16356) (xy 380.15044 -271.155741)
			(xy 380.102908 -271.140297) (xy 380.058376 -271.117607) (xy 380.017943 -271.088231) (xy 379.982603 -271.052891)
			(xy 379.953227 -271.012458) (xy 379.930537 -270.967926) (xy 379.915093 -270.920394) (xy 379.907274 -270.871031)
			(xy 379.599957 -270.871031) (xy 379.599948 -270.871488) (xy 379.591784 -270.921722) (xy 379.575668 -270.969996)
			(xy 379.552017 -271.015059) (xy 379.521444 -271.055745) (xy 379.48474 -271.091) (xy 379.442856 -271.11991)
			(xy 379.396877 -271.141727) (xy 379.347993 -271.155887) (xy 379.297472 -271.162021) (xy 379.24662 -271.159972)
			(xy 379.196756 -271.149792) (xy 379.14917 -271.131745) (xy 379.105096 -271.106299) (xy 379.065674 -271.074112)
			(xy 379.031926 -271.036018) (xy 379.004725 -270.993004) (xy 378.984777 -270.946184) (xy 378.972598 -270.89677)
			(xy 378.968503 -270.846042) (xy 377.720606 -270.846042) (xy 377.720094 -270.871488) (xy 377.71193 -270.921722)
			(xy 377.695814 -270.969996) (xy 377.672163 -271.015059) (xy 377.64159 -271.055745) (xy 377.604886 -271.091)
			(xy 377.563002 -271.11991) (xy 377.517023 -271.141727) (xy 377.468139 -271.155887) (xy 377.417618 -271.162021)
			(xy 377.366766 -271.159972) (xy 377.316902 -271.149792) (xy 377.269316 -271.131745) (xy 377.225242 -271.106299)
			(xy 377.18582 -271.074112) (xy 377.152072 -271.036018) (xy 377.124871 -270.993004) (xy 377.104923 -270.946184)
			(xy 377.092744 -270.89677) (xy 377.088649 -270.846042) (xy 376.780552 -270.846042) (xy 376.78004 -270.871488)
			(xy 376.771876 -270.921722) (xy 376.75576 -270.969996) (xy 376.732109 -271.015059) (xy 376.701536 -271.055745)
			(xy 376.664832 -271.091) (xy 376.622948 -271.11991) (xy 376.576969 -271.141727) (xy 376.528085 -271.155887)
			(xy 376.477564 -271.162021) (xy 376.426712 -271.159972) (xy 376.376848 -271.149792) (xy 376.329262 -271.131745)
			(xy 376.285188 -271.106299) (xy 376.245766 -271.074112) (xy 376.212018 -271.036018) (xy 376.184817 -270.993004)
			(xy 376.164869 -270.946184) (xy 376.15269 -270.89677) (xy 376.148595 -270.846042) (xy 375.107454 -270.846042)
			(xy 375.107454 -271.301972) (xy 375.107981 -271.312883) (xy 375.117031 -271.332742) (xy 375.13348 -271.347085)
			(xy 375.143776 -271.35074) (xy 375.14403 -271.35074) (xy 375.168453 -271.3584) (xy 375.214656 -271.380423)
			(xy 375.256733 -271.409564) (xy 375.293597 -271.44507) (xy 375.324296 -271.486025) (xy 375.348036 -271.531369)
			(xy 375.364203 -271.579931) (xy 375.372381 -271.630456) (xy 375.372884 -271.656048) (xy 375.678695 -271.656048)
			(xy 375.68279 -271.60532) (xy 375.694969 -271.555906) (xy 375.714917 -271.509086) (xy 375.742118 -271.466072)
			(xy 375.775866 -271.427978) (xy 375.815288 -271.395791) (xy 375.859362 -271.370345) (xy 375.906948 -271.352298)
			(xy 375.956812 -271.342118) (xy 376.007664 -271.340069) (xy 376.058185 -271.346203) (xy 376.107069 -271.360363)
			(xy 376.153048 -271.38218) (xy 376.194932 -271.41109) (xy 376.231636 -271.446345) (xy 376.262209 -271.487031)
			(xy 376.28586 -271.532094) (xy 376.301976 -271.580368) (xy 376.31014 -271.630602) (xy 376.310652 -271.656048)
			(xy 376.310149 -271.681037) (xy 376.617212 -271.681037) (xy 376.617212 -271.631059) (xy 376.625031 -271.581696)
			(xy 376.640475 -271.534164) (xy 376.663165 -271.489632) (xy 376.692541 -271.449199) (xy 376.727881 -271.413859)
			(xy 376.768314 -271.384483) (xy 376.812846 -271.361793) (xy 376.860378 -271.346349) (xy 376.909741 -271.33853)
			(xy 376.959719 -271.33853) (xy 377.009082 -271.346349) (xy 377.056614 -271.361793) (xy 377.101146 -271.384483)
			(xy 377.141579 -271.413859) (xy 377.176919 -271.449199) (xy 377.206295 -271.489632) (xy 377.228985 -271.534164)
			(xy 377.244429 -271.581696) (xy 377.252248 -271.631059) (xy 377.252738 -271.656048) (xy 377.558549 -271.656048)
			(xy 377.562644 -271.60532) (xy 377.574823 -271.555906) (xy 377.594771 -271.509086) (xy 377.621972 -271.466072)
			(xy 377.65572 -271.427978) (xy 377.695142 -271.395791) (xy 377.739216 -271.370345) (xy 377.786802 -271.352298)
			(xy 377.836666 -271.342118) (xy 377.887518 -271.340069) (xy 377.938039 -271.346203) (xy 377.986923 -271.360363)
			(xy 378.032902 -271.38218) (xy 378.074786 -271.41109) (xy 378.11149 -271.446345) (xy 378.142063 -271.487031)
			(xy 378.165714 -271.532094) (xy 378.18183 -271.580368) (xy 378.189994 -271.630602) (xy 378.190506 -271.656048)
			(xy 378.190003 -271.681037) (xy 378.49732 -271.681037) (xy 378.49732 -271.631059) (xy 378.505139 -271.581696)
			(xy 378.520583 -271.534164) (xy 378.543273 -271.489632) (xy 378.572649 -271.449199) (xy 378.607989 -271.413859)
			(xy 378.648422 -271.384483) (xy 378.692954 -271.361793) (xy 378.740486 -271.346349) (xy 378.789849 -271.33853)
			(xy 378.839827 -271.33853) (xy 378.88919 -271.346349) (xy 378.936722 -271.361793) (xy 378.981254 -271.384483)
			(xy 379.021687 -271.413859) (xy 379.057027 -271.449199) (xy 379.086403 -271.489632) (xy 379.109093 -271.534164)
			(xy 379.124537 -271.581696) (xy 379.132356 -271.631059) (xy 379.132846 -271.656048) (xy 379.438657 -271.656048)
			(xy 379.442752 -271.60532) (xy 379.454931 -271.555906) (xy 379.474879 -271.509086) (xy 379.50208 -271.466072)
			(xy 379.535828 -271.427978) (xy 379.57525 -271.395791) (xy 379.619324 -271.370345) (xy 379.66691 -271.352298)
			(xy 379.716774 -271.342118) (xy 379.767626 -271.340069) (xy 379.818147 -271.346203) (xy 379.867031 -271.360363)
			(xy 379.91301 -271.38218) (xy 379.954894 -271.41109) (xy 379.991598 -271.446345) (xy 380.022171 -271.487031)
			(xy 380.045822 -271.532094) (xy 380.061938 -271.580368) (xy 380.070102 -271.630602) (xy 380.070614 -271.656048)
			(xy 380.378711 -271.656048) (xy 380.382806 -271.60532) (xy 380.394985 -271.555906) (xy 380.414933 -271.509086)
			(xy 380.442134 -271.466072) (xy 380.475882 -271.427978) (xy 380.515304 -271.395791) (xy 380.559378 -271.370345)
			(xy 380.606964 -271.352298) (xy 380.656828 -271.342118) (xy 380.70768 -271.340069) (xy 380.758201 -271.346203)
			(xy 380.807085 -271.360363) (xy 380.853064 -271.38218) (xy 380.894948 -271.41109) (xy 380.931652 -271.446345)
			(xy 380.962225 -271.487031) (xy 380.985876 -271.532094) (xy 381.001992 -271.580368) (xy 381.010156 -271.630602)
			(xy 381.010668 -271.656048) (xy 381.010156 -271.681494) (xy 381.001992 -271.731728) (xy 380.985876 -271.780002)
			(xy 380.962225 -271.825065) (xy 380.931652 -271.865751) (xy 380.894948 -271.901006) (xy 380.853064 -271.929916)
			(xy 380.807085 -271.951733) (xy 380.758201 -271.965893) (xy 380.70768 -271.972027) (xy 380.656828 -271.969978)
			(xy 380.606964 -271.959798) (xy 380.559378 -271.941751) (xy 380.515304 -271.916305) (xy 380.475882 -271.884118)
			(xy 380.442134 -271.846024) (xy 380.414933 -271.80301) (xy 380.394985 -271.75619) (xy 380.382806 -271.706776)
			(xy 380.378711 -271.656048) (xy 380.070614 -271.656048) (xy 380.070102 -271.681494) (xy 380.061938 -271.731728)
			(xy 380.045822 -271.780002) (xy 380.022171 -271.825065) (xy 379.991598 -271.865751) (xy 379.954894 -271.901006)
			(xy 379.91301 -271.929916) (xy 379.867031 -271.951733) (xy 379.818147 -271.965893) (xy 379.767626 -271.972027)
			(xy 379.716774 -271.969978) (xy 379.66691 -271.959798) (xy 379.619324 -271.941751) (xy 379.57525 -271.916305)
			(xy 379.535828 -271.884118) (xy 379.50208 -271.846024) (xy 379.474879 -271.80301) (xy 379.454931 -271.75619)
			(xy 379.442752 -271.706776) (xy 379.438657 -271.656048) (xy 379.132846 -271.656048) (xy 379.132356 -271.681037)
			(xy 379.124537 -271.7304) (xy 379.109093 -271.777932) (xy 379.086403 -271.822464) (xy 379.057027 -271.862897)
			(xy 379.021687 -271.898237) (xy 378.981254 -271.927613) (xy 378.936722 -271.950303) (xy 378.88919 -271.965747)
			(xy 378.839827 -271.973566) (xy 378.789849 -271.973566) (xy 378.740486 -271.965747) (xy 378.692954 -271.950303)
			(xy 378.648422 -271.927613) (xy 378.607989 -271.898237) (xy 378.572649 -271.862897) (xy 378.543273 -271.822464)
			(xy 378.520583 -271.777932) (xy 378.505139 -271.7304) (xy 378.49732 -271.681037) (xy 378.190003 -271.681037)
			(xy 378.189994 -271.681494) (xy 378.18183 -271.731728) (xy 378.165714 -271.780002) (xy 378.142063 -271.825065)
			(xy 378.11149 -271.865751) (xy 378.074786 -271.901006) (xy 378.032902 -271.929916) (xy 377.986923 -271.951733)
			(xy 377.938039 -271.965893) (xy 377.887518 -271.972027) (xy 377.836666 -271.969978) (xy 377.786802 -271.959798)
			(xy 377.739216 -271.941751) (xy 377.695142 -271.916305) (xy 377.65572 -271.884118) (xy 377.621972 -271.846024)
			(xy 377.594771 -271.80301) (xy 377.574823 -271.75619) (xy 377.562644 -271.706776) (xy 377.558549 -271.656048)
			(xy 377.252738 -271.656048) (xy 377.252248 -271.681037) (xy 377.244429 -271.7304) (xy 377.228985 -271.777932)
			(xy 377.206295 -271.822464) (xy 377.176919 -271.862897) (xy 377.141579 -271.898237) (xy 377.101146 -271.927613)
			(xy 377.056614 -271.950303) (xy 377.009082 -271.965747) (xy 376.959719 -271.973566) (xy 376.909741 -271.973566)
			(xy 376.860378 -271.965747) (xy 376.812846 -271.950303) (xy 376.768314 -271.927613) (xy 376.727881 -271.898237)
			(xy 376.692541 -271.862897) (xy 376.663165 -271.822464) (xy 376.640475 -271.777932) (xy 376.625031 -271.7304)
			(xy 376.617212 -271.681037) (xy 376.310149 -271.681037) (xy 376.31014 -271.681494) (xy 376.301976 -271.731728)
			(xy 376.28586 -271.780002) (xy 376.262209 -271.825065) (xy 376.231636 -271.865751) (xy 376.194932 -271.901006)
			(xy 376.153048 -271.929916) (xy 376.107069 -271.951733) (xy 376.058185 -271.965893) (xy 376.007664 -271.972027)
			(xy 375.956812 -271.969978) (xy 375.906948 -271.959798) (xy 375.859362 -271.941751) (xy 375.815288 -271.916305)
			(xy 375.775866 -271.884118) (xy 375.742118 -271.846024) (xy 375.714917 -271.80301) (xy 375.694969 -271.75619)
			(xy 375.68279 -271.706776) (xy 375.678695 -271.656048) (xy 375.372884 -271.656048) (xy 375.372377 -271.681624)
			(xy 375.3642 -271.732119) (xy 375.348046 -271.780653) (xy 375.324334 -271.825978) (xy 375.293674 -271.866923)
			(xy 375.256856 -271.902434) (xy 375.21483 -271.931595) (xy 375.168679 -271.953654) (xy 375.144284 -271.961356)
			(xy 375.143776 -271.961356) (xy 375.133438 -271.964947) (xy 375.116934 -271.979287) (xy 375.107889 -271.999191)
			(xy 375.107454 -272.010124) (xy 375.107454 -272.193512) (xy 375.107708 -272.197322) (xy 375.108717 -272.206041)
			(xy 375.11584 -272.222068) (xy 375.127961 -272.234744) (xy 375.135648 -272.238978) (xy 375.140728 -272.24101)
			(xy 375.242582 -272.278856) (xy 375.273062 -272.270982) (xy 375.28373 -272.25879) (xy 375.302007 -272.238394)
			(xy 375.344283 -272.203585) (xy 375.391898 -272.176534) (xy 375.443443 -272.158042) (xy 375.497395 -272.148655)
			(xy 375.524776 -272.148046) (xy 375.549772 -272.148509) (xy 375.599149 -272.156326) (xy 375.646695 -272.171771)
			(xy 375.69124 -272.194465) (xy 375.731686 -272.223848) (xy 375.767037 -272.259196) (xy 375.796422 -272.29964)
			(xy 375.819119 -272.344182) (xy 375.834569 -272.391727) (xy 375.842389 -272.441104) (xy 375.842389 -272.466054)
			(xy 376.148595 -272.466054) (xy 376.15269 -272.415326) (xy 376.164869 -272.365912) (xy 376.184817 -272.319092)
			(xy 376.212018 -272.276078) (xy 376.245766 -272.237984) (xy 376.285188 -272.205797) (xy 376.329262 -272.180351)
			(xy 376.376848 -272.162304) (xy 376.426712 -272.152124) (xy 376.477564 -272.150075) (xy 376.528085 -272.156209)
			(xy 376.576969 -272.170369) (xy 376.622948 -272.192186) (xy 376.664832 -272.221096) (xy 376.701536 -272.256351)
			(xy 376.732109 -272.297037) (xy 376.75576 -272.3421) (xy 376.771876 -272.390374) (xy 376.78004 -272.440608)
			(xy 376.780552 -272.466054) (xy 377.088649 -272.466054) (xy 377.092744 -272.415326) (xy 377.104923 -272.365912)
			(xy 377.124871 -272.319092) (xy 377.152072 -272.276078) (xy 377.18582 -272.237984) (xy 377.225242 -272.205797)
			(xy 377.269316 -272.180351) (xy 377.316902 -272.162304) (xy 377.366766 -272.152124) (xy 377.417618 -272.150075)
			(xy 377.468139 -272.156209) (xy 377.517023 -272.170369) (xy 377.563002 -272.192186) (xy 377.604886 -272.221096)
			(xy 377.64159 -272.256351) (xy 377.672163 -272.297037) (xy 377.695814 -272.3421) (xy 377.71193 -272.390374)
			(xy 377.720094 -272.440608) (xy 377.720606 -272.466054) (xy 377.720103 -272.491043) (xy 378.02742 -272.491043)
			(xy 378.02742 -272.441065) (xy 378.035239 -272.391702) (xy 378.050683 -272.34417) (xy 378.073373 -272.299638)
			(xy 378.102749 -272.259205) (xy 378.138089 -272.223865) (xy 378.178522 -272.194489) (xy 378.223054 -272.171799)
			(xy 378.270586 -272.156355) (xy 378.319949 -272.148536) (xy 378.369927 -272.148536) (xy 378.41929 -272.156355)
			(xy 378.466822 -272.171799) (xy 378.511354 -272.194489) (xy 378.551787 -272.223865) (xy 378.587127 -272.259205)
			(xy 378.616503 -272.299638) (xy 378.639193 -272.34417) (xy 378.654637 -272.391702) (xy 378.662456 -272.441065)
			(xy 378.662946 -272.466054) (xy 378.968503 -272.466054) (xy 378.972598 -272.415326) (xy 378.984777 -272.365912)
			(xy 379.004725 -272.319092) (xy 379.031926 -272.276078) (xy 379.065674 -272.237984) (xy 379.105096 -272.205797)
			(xy 379.14917 -272.180351) (xy 379.196756 -272.162304) (xy 379.24662 -272.152124) (xy 379.297472 -272.150075)
			(xy 379.347993 -272.156209) (xy 379.396877 -272.170369) (xy 379.442856 -272.192186) (xy 379.48474 -272.221096)
			(xy 379.521444 -272.256351) (xy 379.552017 -272.297037) (xy 379.575668 -272.3421) (xy 379.591784 -272.390374)
			(xy 379.599948 -272.440608) (xy 379.60046 -272.466054) (xy 379.599957 -272.491043) (xy 379.907274 -272.491043)
			(xy 379.907274 -272.441065) (xy 379.915093 -272.391702) (xy 379.930537 -272.34417) (xy 379.953227 -272.299638)
			(xy 379.982603 -272.259205) (xy 380.017943 -272.223865) (xy 380.058376 -272.194489) (xy 380.102908 -272.171799)
			(xy 380.15044 -272.156355) (xy 380.199803 -272.148536) (xy 380.249781 -272.148536) (xy 380.299144 -272.156355)
			(xy 380.346676 -272.171799) (xy 380.391208 -272.194489) (xy 380.431641 -272.223865) (xy 380.466981 -272.259205)
			(xy 380.496357 -272.299638) (xy 380.519047 -272.34417) (xy 380.534491 -272.391702) (xy 380.54231 -272.441065)
			(xy 380.5428 -272.466054) (xy 380.54231 -272.491043) (xy 380.534491 -272.540406) (xy 380.519047 -272.587938)
			(xy 380.496357 -272.63247) (xy 380.466981 -272.672903) (xy 380.431641 -272.708243) (xy 380.391208 -272.737619)
			(xy 380.346676 -272.760309) (xy 380.299144 -272.775753) (xy 380.249781 -272.783572) (xy 380.199803 -272.783572)
			(xy 380.15044 -272.775753) (xy 380.102908 -272.760309) (xy 380.058376 -272.737619) (xy 380.017943 -272.708243)
			(xy 379.982603 -272.672903) (xy 379.953227 -272.63247) (xy 379.930537 -272.587938) (xy 379.915093 -272.540406)
			(xy 379.907274 -272.491043) (xy 379.599957 -272.491043) (xy 379.599948 -272.4915) (xy 379.591784 -272.541734)
			(xy 379.575668 -272.590008) (xy 379.552017 -272.635071) (xy 379.521444 -272.675757) (xy 379.48474 -272.711012)
			(xy 379.442856 -272.739922) (xy 379.396877 -272.761739) (xy 379.347993 -272.775899) (xy 379.297472 -272.782033)
			(xy 379.24662 -272.779984) (xy 379.196756 -272.769804) (xy 379.14917 -272.751757) (xy 379.105096 -272.726311)
			(xy 379.065674 -272.694124) (xy 379.031926 -272.65603) (xy 379.004725 -272.613016) (xy 378.984777 -272.566196)
			(xy 378.972598 -272.516782) (xy 378.968503 -272.466054) (xy 378.662946 -272.466054) (xy 378.662456 -272.491043)
			(xy 378.654637 -272.540406) (xy 378.639193 -272.587938) (xy 378.616503 -272.63247) (xy 378.587127 -272.672903)
			(xy 378.551787 -272.708243) (xy 378.511354 -272.737619) (xy 378.466822 -272.760309) (xy 378.41929 -272.775753)
			(xy 378.369927 -272.783572) (xy 378.319949 -272.783572) (xy 378.270586 -272.775753) (xy 378.223054 -272.760309)
			(xy 378.178522 -272.737619) (xy 378.138089 -272.708243) (xy 378.102749 -272.672903) (xy 378.073373 -272.63247)
			(xy 378.050683 -272.587938) (xy 378.035239 -272.540406) (xy 378.02742 -272.491043) (xy 377.720103 -272.491043)
			(xy 377.720094 -272.4915) (xy 377.71193 -272.541734) (xy 377.695814 -272.590008) (xy 377.672163 -272.635071)
			(xy 377.64159 -272.675757) (xy 377.604886 -272.711012) (xy 377.563002 -272.739922) (xy 377.517023 -272.761739)
			(xy 377.468139 -272.775899) (xy 377.417618 -272.782033) (xy 377.366766 -272.779984) (xy 377.316902 -272.769804)
			(xy 377.269316 -272.751757) (xy 377.225242 -272.726311) (xy 377.18582 -272.694124) (xy 377.152072 -272.65603)
			(xy 377.124871 -272.613016) (xy 377.104923 -272.566196) (xy 377.092744 -272.516782) (xy 377.088649 -272.466054)
			(xy 376.780552 -272.466054) (xy 376.78004 -272.4915) (xy 376.771876 -272.541734) (xy 376.75576 -272.590008)
			(xy 376.732109 -272.635071) (xy 376.701536 -272.675757) (xy 376.664832 -272.711012) (xy 376.622948 -272.739922)
			(xy 376.576969 -272.761739) (xy 376.528085 -272.775899) (xy 376.477564 -272.782033) (xy 376.426712 -272.779984)
			(xy 376.376848 -272.769804) (xy 376.329262 -272.751757) (xy 376.285188 -272.726311) (xy 376.245766 -272.694124)
			(xy 376.212018 -272.65603) (xy 376.184817 -272.613016) (xy 376.164869 -272.566196) (xy 376.15269 -272.516782)
			(xy 376.148595 -272.466054) (xy 375.842389 -272.466054) (xy 375.842389 -272.491096) (xy 375.834569 -272.540473)
			(xy 375.819119 -272.588018) (xy 375.796422 -272.63256) (xy 375.767037 -272.673004) (xy 375.731686 -272.708352)
			(xy 375.69124 -272.737735) (xy 375.646695 -272.760429) (xy 375.599149 -272.775874) (xy 375.549772 -272.783691)
			(xy 375.524776 -272.784062) (xy 375.497394 -272.783486) (xy 375.443441 -272.774094) (xy 375.391897 -272.755592)
			(xy 375.344289 -272.728527) (xy 375.302024 -272.693701) (xy 375.28373 -272.673318) (xy 375.273062 -272.661126)
			(xy 375.242582 -272.653252) (xy 375.140728 -272.691098) (xy 375.135648 -272.69313) (xy 375.127986 -272.697396)
			(xy 375.11589 -272.710077) (xy 375.108742 -272.726078) (xy 375.107708 -272.734786) (xy 375.107454 -272.738596)
			(xy 375.107454 -272.921984) (xy 375.107984 -272.932894) (xy 375.117035 -272.952749) (xy 375.133484 -272.967087)
			(xy 375.143776 -272.970752) (xy 375.14403 -272.970752) (xy 375.168453 -272.978412) (xy 375.214655 -273.000435)
			(xy 375.256731 -273.029576) (xy 375.293593 -273.065083) (xy 375.324291 -273.106038) (xy 375.348029 -273.151382)
			(xy 375.364195 -273.199944) (xy 375.37237 -273.250469) (xy 375.372884 -273.27606) (xy 375.678695 -273.27606)
			(xy 375.68279 -273.225332) (xy 375.694969 -273.175918) (xy 375.714917 -273.129098) (xy 375.742118 -273.086084)
			(xy 375.775866 -273.04799) (xy 375.815288 -273.015803) (xy 375.859362 -272.990357) (xy 375.906948 -272.97231)
			(xy 375.956812 -272.96213) (xy 376.007664 -272.960081) (xy 376.058185 -272.966215) (xy 376.107069 -272.980375)
			(xy 376.153048 -273.002192) (xy 376.194932 -273.031102) (xy 376.231636 -273.066357) (xy 376.262209 -273.107043)
			(xy 376.28586 -273.152106) (xy 376.301976 -273.20038) (xy 376.31014 -273.250614) (xy 376.310652 -273.27606)
			(xy 376.310149 -273.301049) (xy 376.617212 -273.301049) (xy 376.617212 -273.251071) (xy 376.625031 -273.201708)
			(xy 376.640475 -273.154176) (xy 376.663165 -273.109644) (xy 376.692541 -273.069211) (xy 376.727881 -273.033871)
			(xy 376.768314 -273.004495) (xy 376.812846 -272.981805) (xy 376.860378 -272.966361) (xy 376.909741 -272.958542)
			(xy 376.959719 -272.958542) (xy 377.009082 -272.966361) (xy 377.056614 -272.981805) (xy 377.101146 -273.004495)
			(xy 377.141579 -273.033871) (xy 377.176919 -273.069211) (xy 377.206295 -273.109644) (xy 377.228985 -273.154176)
			(xy 377.244429 -273.201708) (xy 377.252248 -273.251071) (xy 377.252738 -273.27606) (xy 377.558549 -273.27606)
			(xy 377.562644 -273.225332) (xy 377.574823 -273.175918) (xy 377.594771 -273.129098) (xy 377.621972 -273.086084)
			(xy 377.65572 -273.04799) (xy 377.695142 -273.015803) (xy 377.739216 -272.990357) (xy 377.786802 -272.97231)
			(xy 377.836666 -272.96213) (xy 377.887518 -272.960081) (xy 377.938039 -272.966215) (xy 377.986923 -272.980375)
			(xy 378.032902 -273.002192) (xy 378.074786 -273.031102) (xy 378.11149 -273.066357) (xy 378.142063 -273.107043)
			(xy 378.165714 -273.152106) (xy 378.18183 -273.20038) (xy 378.189994 -273.250614) (xy 378.190506 -273.27606)
			(xy 379.438657 -273.27606) (xy 379.442752 -273.225332) (xy 379.454931 -273.175918) (xy 379.474879 -273.129098)
			(xy 379.50208 -273.086084) (xy 379.535828 -273.04799) (xy 379.57525 -273.015803) (xy 379.619324 -272.990357)
			(xy 379.66691 -272.97231) (xy 379.716774 -272.96213) (xy 379.767626 -272.960081) (xy 379.818147 -272.966215)
			(xy 379.867031 -272.980375) (xy 379.91301 -273.002192) (xy 379.954894 -273.031102) (xy 379.991598 -273.066357)
			(xy 380.022171 -273.107043) (xy 380.045822 -273.152106) (xy 380.061938 -273.20038) (xy 380.070102 -273.250614)
			(xy 380.070614 -273.27606) (xy 380.378711 -273.27606) (xy 380.382806 -273.225332) (xy 380.394985 -273.175918)
			(xy 380.414933 -273.129098) (xy 380.442134 -273.086084) (xy 380.475882 -273.04799) (xy 380.515304 -273.015803)
			(xy 380.559378 -272.990357) (xy 380.606964 -272.97231) (xy 380.656828 -272.96213) (xy 380.70768 -272.960081)
			(xy 380.758201 -272.966215) (xy 380.807085 -272.980375) (xy 380.853064 -273.002192) (xy 380.894948 -273.031102)
			(xy 380.931652 -273.066357) (xy 380.962225 -273.107043) (xy 380.985876 -273.152106) (xy 381.001992 -273.20038)
			(xy 381.010156 -273.250614) (xy 381.010668 -273.27606) (xy 381.010156 -273.301506) (xy 381.001992 -273.35174)
			(xy 380.985876 -273.400014) (xy 380.962225 -273.445077) (xy 380.931652 -273.485763) (xy 380.894948 -273.521018)
			(xy 380.853064 -273.549928) (xy 380.807085 -273.571745) (xy 380.758201 -273.585905) (xy 380.70768 -273.592039)
			(xy 380.656828 -273.58999) (xy 380.606964 -273.57981) (xy 380.559378 -273.561763) (xy 380.515304 -273.536317)
			(xy 380.475882 -273.50413) (xy 380.442134 -273.466036) (xy 380.414933 -273.423022) (xy 380.394985 -273.376202)
			(xy 380.382806 -273.326788) (xy 380.378711 -273.27606) (xy 380.070614 -273.27606) (xy 380.070102 -273.301506)
			(xy 380.061938 -273.35174) (xy 380.045822 -273.400014) (xy 380.022171 -273.445077) (xy 379.991598 -273.485763)
			(xy 379.954894 -273.521018) (xy 379.91301 -273.549928) (xy 379.867031 -273.571745) (xy 379.818147 -273.585905)
			(xy 379.767626 -273.592039) (xy 379.716774 -273.58999) (xy 379.66691 -273.57981) (xy 379.619324 -273.561763)
			(xy 379.57525 -273.536317) (xy 379.535828 -273.50413) (xy 379.50208 -273.466036) (xy 379.474879 -273.423022)
			(xy 379.454931 -273.376202) (xy 379.442752 -273.326788) (xy 379.438657 -273.27606) (xy 378.190506 -273.27606)
			(xy 378.189994 -273.301506) (xy 378.18183 -273.35174) (xy 378.165714 -273.400014) (xy 378.142063 -273.445077)
			(xy 378.11149 -273.485763) (xy 378.074786 -273.521018) (xy 378.032902 -273.549928) (xy 377.986923 -273.571745)
			(xy 377.938039 -273.585905) (xy 377.887518 -273.592039) (xy 377.836666 -273.58999) (xy 377.786802 -273.57981)
			(xy 377.739216 -273.561763) (xy 377.695142 -273.536317) (xy 377.65572 -273.50413) (xy 377.621972 -273.466036)
			(xy 377.594771 -273.423022) (xy 377.574823 -273.376202) (xy 377.562644 -273.326788) (xy 377.558549 -273.27606)
			(xy 377.252738 -273.27606) (xy 377.252248 -273.301049) (xy 377.244429 -273.350412) (xy 377.228985 -273.397944)
			(xy 377.206295 -273.442476) (xy 377.176919 -273.482909) (xy 377.141579 -273.518249) (xy 377.101146 -273.547625)
			(xy 377.056614 -273.570315) (xy 377.009082 -273.585759) (xy 376.959719 -273.593578) (xy 376.909741 -273.593578)
			(xy 376.860378 -273.585759) (xy 376.812846 -273.570315) (xy 376.768314 -273.547625) (xy 376.727881 -273.518249)
			(xy 376.692541 -273.482909) (xy 376.663165 -273.442476) (xy 376.640475 -273.397944) (xy 376.625031 -273.350412)
			(xy 376.617212 -273.301049) (xy 376.310149 -273.301049) (xy 376.31014 -273.301506) (xy 376.301976 -273.35174)
			(xy 376.28586 -273.400014) (xy 376.262209 -273.445077) (xy 376.231636 -273.485763) (xy 376.194932 -273.521018)
			(xy 376.153048 -273.549928) (xy 376.107069 -273.571745) (xy 376.058185 -273.585905) (xy 376.007664 -273.592039)
			(xy 375.956812 -273.58999) (xy 375.906948 -273.57981) (xy 375.859362 -273.561763) (xy 375.815288 -273.536317)
			(xy 375.775866 -273.50413) (xy 375.742118 -273.466036) (xy 375.714917 -273.423022) (xy 375.694969 -273.376202)
			(xy 375.68279 -273.326788) (xy 375.678695 -273.27606) (xy 375.372884 -273.27606) (xy 375.372377 -273.301636)
			(xy 375.364197 -273.352129) (xy 375.348043 -273.400662) (xy 375.324329 -273.445985) (xy 375.293669 -273.486928)
			(xy 375.256851 -273.522438) (xy 375.214826 -273.551597) (xy 375.168675 -273.573656) (xy 375.144284 -273.581368)
			(xy 375.143776 -273.581368) (xy 375.133439 -273.58496) (xy 375.116938 -273.5993) (xy 375.107898 -273.619204)
			(xy 375.107454 -273.630136) (xy 375.107454 -274.086066) (xy 376.148595 -274.086066) (xy 376.15269 -274.035338)
			(xy 376.164869 -273.985924) (xy 376.184817 -273.939104) (xy 376.212018 -273.89609) (xy 376.245766 -273.857996)
			(xy 376.285188 -273.825809) (xy 376.329262 -273.800363) (xy 376.376848 -273.782316) (xy 376.426712 -273.772136)
			(xy 376.477564 -273.770087) (xy 376.528085 -273.776221) (xy 376.576969 -273.790381) (xy 376.622948 -273.812198)
			(xy 376.664832 -273.841108) (xy 376.701536 -273.876363) (xy 376.732109 -273.917049) (xy 376.75576 -273.962112)
			(xy 376.771876 -274.010386) (xy 376.78004 -274.06062) (xy 376.780552 -274.086066) (xy 377.088649 -274.086066)
			(xy 377.092744 -274.035338) (xy 377.104923 -273.985924) (xy 377.124871 -273.939104) (xy 377.152072 -273.89609)
			(xy 377.18582 -273.857996) (xy 377.225242 -273.825809) (xy 377.269316 -273.800363) (xy 377.316902 -273.782316)
			(xy 377.366766 -273.772136) (xy 377.417618 -273.770087) (xy 377.468139 -273.776221) (xy 377.517023 -273.790381)
			(xy 377.563002 -273.812198) (xy 377.604886 -273.841108) (xy 377.64159 -273.876363) (xy 377.672163 -273.917049)
			(xy 377.695814 -273.962112) (xy 377.71193 -274.010386) (xy 377.720094 -274.06062) (xy 377.720606 -274.086066)
			(xy 377.720103 -274.111055) (xy 378.02742 -274.111055) (xy 378.02742 -274.061077) (xy 378.035239 -274.011714)
			(xy 378.050683 -273.964182) (xy 378.073373 -273.91965) (xy 378.102749 -273.879217) (xy 378.138089 -273.843877)
			(xy 378.178522 -273.814501) (xy 378.223054 -273.791811) (xy 378.270586 -273.776367) (xy 378.319949 -273.768548)
			(xy 378.369927 -273.768548) (xy 378.41929 -273.776367) (xy 378.466822 -273.791811) (xy 378.511354 -273.814501)
			(xy 378.551787 -273.843877) (xy 378.587127 -273.879217) (xy 378.616503 -273.91965) (xy 378.639193 -273.964182)
			(xy 378.654637 -274.011714) (xy 378.662456 -274.061077) (xy 378.662946 -274.086066) (xy 378.968503 -274.086066)
			(xy 378.972598 -274.035338) (xy 378.984777 -273.985924) (xy 379.004725 -273.939104) (xy 379.031926 -273.89609)
			(xy 379.065674 -273.857996) (xy 379.105096 -273.825809) (xy 379.14917 -273.800363) (xy 379.196756 -273.782316)
			(xy 379.24662 -273.772136) (xy 379.297472 -273.770087) (xy 379.347993 -273.776221) (xy 379.396877 -273.790381)
			(xy 379.442856 -273.812198) (xy 379.48474 -273.841108) (xy 379.521444 -273.876363) (xy 379.552017 -273.917049)
			(xy 379.575668 -273.962112) (xy 379.591784 -274.010386) (xy 379.599948 -274.06062) (xy 379.60046 -274.086066)
			(xy 379.599957 -274.111055) (xy 379.907274 -274.111055) (xy 379.907274 -274.061077) (xy 379.915093 -274.011714)
			(xy 379.930537 -273.964182) (xy 379.953227 -273.91965) (xy 379.982603 -273.879217) (xy 380.017943 -273.843877)
			(xy 380.058376 -273.814501) (xy 380.102908 -273.791811) (xy 380.15044 -273.776367) (xy 380.199803 -273.768548)
			(xy 380.249781 -273.768548) (xy 380.299144 -273.776367) (xy 380.346676 -273.791811) (xy 380.391208 -273.814501)
			(xy 380.431641 -273.843877) (xy 380.466981 -273.879217) (xy 380.496357 -273.91965) (xy 380.519047 -273.964182)
			(xy 380.534491 -274.011714) (xy 380.54231 -274.061077) (xy 380.5428 -274.086066) (xy 380.54231 -274.111055)
			(xy 380.534491 -274.160418) (xy 380.519047 -274.20795) (xy 380.496357 -274.252482) (xy 380.466981 -274.292915)
			(xy 380.431641 -274.328255) (xy 380.391208 -274.357631) (xy 380.346676 -274.380321) (xy 380.299144 -274.395765)
			(xy 380.249781 -274.403584) (xy 380.199803 -274.403584) (xy 380.15044 -274.395765) (xy 380.102908 -274.380321)
			(xy 380.058376 -274.357631) (xy 380.017943 -274.328255) (xy 379.982603 -274.292915) (xy 379.953227 -274.252482)
			(xy 379.930537 -274.20795) (xy 379.915093 -274.160418) (xy 379.907274 -274.111055) (xy 379.599957 -274.111055)
			(xy 379.599948 -274.111512) (xy 379.591784 -274.161746) (xy 379.575668 -274.21002) (xy 379.552017 -274.255083)
			(xy 379.521444 -274.295769) (xy 379.48474 -274.331024) (xy 379.442856 -274.359934) (xy 379.396877 -274.381751)
			(xy 379.347993 -274.395911) (xy 379.297472 -274.402045) (xy 379.24662 -274.399996) (xy 379.196756 -274.389816)
			(xy 379.14917 -274.371769) (xy 379.105096 -274.346323) (xy 379.065674 -274.314136) (xy 379.031926 -274.276042)
			(xy 379.004725 -274.233028) (xy 378.984777 -274.186208) (xy 378.972598 -274.136794) (xy 378.968503 -274.086066)
			(xy 378.662946 -274.086066) (xy 378.662456 -274.111055) (xy 378.654637 -274.160418) (xy 378.639193 -274.20795)
			(xy 378.616503 -274.252482) (xy 378.587127 -274.292915) (xy 378.551787 -274.328255) (xy 378.511354 -274.357631)
			(xy 378.466822 -274.380321) (xy 378.41929 -274.395765) (xy 378.369927 -274.403584) (xy 378.319949 -274.403584)
			(xy 378.270586 -274.395765) (xy 378.223054 -274.380321) (xy 378.178522 -274.357631) (xy 378.138089 -274.328255)
			(xy 378.102749 -274.292915) (xy 378.073373 -274.252482) (xy 378.050683 -274.20795) (xy 378.035239 -274.160418)
			(xy 378.02742 -274.111055) (xy 377.720103 -274.111055) (xy 377.720094 -274.111512) (xy 377.71193 -274.161746)
			(xy 377.695814 -274.21002) (xy 377.672163 -274.255083) (xy 377.64159 -274.295769) (xy 377.604886 -274.331024)
			(xy 377.563002 -274.359934) (xy 377.517023 -274.381751) (xy 377.468139 -274.395911) (xy 377.417618 -274.402045)
			(xy 377.366766 -274.399996) (xy 377.316902 -274.389816) (xy 377.269316 -274.371769) (xy 377.225242 -274.346323)
			(xy 377.18582 -274.314136) (xy 377.152072 -274.276042) (xy 377.124871 -274.233028) (xy 377.104923 -274.186208)
			(xy 377.092744 -274.136794) (xy 377.088649 -274.086066) (xy 376.780552 -274.086066) (xy 376.78004 -274.111512)
			(xy 376.771876 -274.161746) (xy 376.75576 -274.21002) (xy 376.732109 -274.255083) (xy 376.701536 -274.295769)
			(xy 376.664832 -274.331024) (xy 376.622948 -274.359934) (xy 376.576969 -274.381751) (xy 376.528085 -274.395911)
			(xy 376.477564 -274.402045) (xy 376.426712 -274.399996) (xy 376.376848 -274.389816) (xy 376.329262 -274.371769)
			(xy 376.285188 -274.346323) (xy 376.245766 -274.314136) (xy 376.212018 -274.276042) (xy 376.184817 -274.233028)
			(xy 376.164869 -274.186208) (xy 376.15269 -274.136794) (xy 376.148595 -274.086066) (xy 375.107454 -274.086066)
			(xy 375.107454 -274.541996) (xy 375.107986 -274.552904) (xy 375.11704 -274.572755) (xy 375.133489 -274.58709)
			(xy 375.143776 -274.590764) (xy 375.14403 -274.590764) (xy 375.168456 -274.598423) (xy 375.214665 -274.620444)
			(xy 375.25675 -274.649583) (xy 375.293622 -274.685088) (xy 375.32433 -274.726042) (xy 375.34808 -274.771386)
			(xy 375.364258 -274.81995) (xy 375.372448 -274.870478) (xy 375.372884 -274.896072) (xy 375.678695 -274.896072)
			(xy 375.68279 -274.845344) (xy 375.694969 -274.79593) (xy 375.714917 -274.74911) (xy 375.742118 -274.706096)
			(xy 375.775866 -274.668002) (xy 375.815288 -274.635815) (xy 375.859362 -274.610369) (xy 375.906948 -274.592322)
			(xy 375.956812 -274.582142) (xy 376.007664 -274.580093) (xy 376.058185 -274.586227) (xy 376.107069 -274.600387)
			(xy 376.153048 -274.622204) (xy 376.194932 -274.651114) (xy 376.231636 -274.686369) (xy 376.262209 -274.727055)
			(xy 376.28586 -274.772118) (xy 376.301976 -274.820392) (xy 376.31014 -274.870626) (xy 376.310652 -274.896072)
			(xy 376.310149 -274.921061) (xy 376.617212 -274.921061) (xy 376.617212 -274.871083) (xy 376.625031 -274.82172)
			(xy 376.640475 -274.774188) (xy 376.663165 -274.729656) (xy 376.692541 -274.689223) (xy 376.727881 -274.653883)
			(xy 376.768314 -274.624507) (xy 376.812846 -274.601817) (xy 376.860378 -274.586373) (xy 376.909741 -274.578554)
			(xy 376.959719 -274.578554) (xy 377.009082 -274.586373) (xy 377.056614 -274.601817) (xy 377.101146 -274.624507)
			(xy 377.141579 -274.653883) (xy 377.176919 -274.689223) (xy 377.206295 -274.729656) (xy 377.228985 -274.774188)
			(xy 377.244429 -274.82172) (xy 377.252248 -274.871083) (xy 377.252738 -274.896072) (xy 377.558549 -274.896072)
			(xy 377.562644 -274.845344) (xy 377.574823 -274.79593) (xy 377.594771 -274.74911) (xy 377.621972 -274.706096)
			(xy 377.65572 -274.668002) (xy 377.695142 -274.635815) (xy 377.739216 -274.610369) (xy 377.786802 -274.592322)
			(xy 377.836666 -274.582142) (xy 377.887518 -274.580093) (xy 377.938039 -274.586227) (xy 377.986923 -274.600387)
			(xy 378.032902 -274.622204) (xy 378.074786 -274.651114) (xy 378.11149 -274.686369) (xy 378.142063 -274.727055)
			(xy 378.165714 -274.772118) (xy 378.18183 -274.820392) (xy 378.189994 -274.870626) (xy 378.190506 -274.896072)
			(xy 378.190003 -274.921061) (xy 378.49732 -274.921061) (xy 378.49732 -274.871083) (xy 378.505139 -274.82172)
			(xy 378.520583 -274.774188) (xy 378.543273 -274.729656) (xy 378.572649 -274.689223) (xy 378.607989 -274.653883)
			(xy 378.648422 -274.624507) (xy 378.692954 -274.601817) (xy 378.740486 -274.586373) (xy 378.789849 -274.578554)
			(xy 378.839827 -274.578554) (xy 378.88919 -274.586373) (xy 378.936722 -274.601817) (xy 378.981254 -274.624507)
			(xy 379.021687 -274.653883) (xy 379.057027 -274.689223) (xy 379.086403 -274.729656) (xy 379.109093 -274.774188)
			(xy 379.124537 -274.82172) (xy 379.132356 -274.871083) (xy 379.132846 -274.896072) (xy 379.438657 -274.896072)
			(xy 379.442752 -274.845344) (xy 379.454931 -274.79593) (xy 379.474879 -274.74911) (xy 379.50208 -274.706096)
			(xy 379.535828 -274.668002) (xy 379.57525 -274.635815) (xy 379.619324 -274.610369) (xy 379.66691 -274.592322)
			(xy 379.716774 -274.582142) (xy 379.767626 -274.580093) (xy 379.818147 -274.586227) (xy 379.867031 -274.600387)
			(xy 379.91301 -274.622204) (xy 379.954894 -274.651114) (xy 379.991598 -274.686369) (xy 380.022171 -274.727055)
			(xy 380.045822 -274.772118) (xy 380.061938 -274.820392) (xy 380.070102 -274.870626) (xy 380.070614 -274.896072)
			(xy 380.378711 -274.896072) (xy 380.382806 -274.845344) (xy 380.394985 -274.79593) (xy 380.414933 -274.74911)
			(xy 380.442134 -274.706096) (xy 380.475882 -274.668002) (xy 380.515304 -274.635815) (xy 380.559378 -274.610369)
			(xy 380.606964 -274.592322) (xy 380.656828 -274.582142) (xy 380.70768 -274.580093) (xy 380.758201 -274.586227)
			(xy 380.807085 -274.600387) (xy 380.853064 -274.622204) (xy 380.894948 -274.651114) (xy 380.931652 -274.686369)
			(xy 380.962225 -274.727055) (xy 380.985876 -274.772118) (xy 381.001992 -274.820392) (xy 381.010156 -274.870626)
			(xy 381.010668 -274.896072) (xy 381.010156 -274.921518) (xy 381.001992 -274.971752) (xy 380.985876 -275.020026)
			(xy 380.962225 -275.065089) (xy 380.931652 -275.105775) (xy 380.894948 -275.14103) (xy 380.853064 -275.16994)
			(xy 380.807085 -275.191757) (xy 380.758201 -275.205917) (xy 380.70768 -275.212051) (xy 380.656828 -275.210002)
			(xy 380.606964 -275.199822) (xy 380.559378 -275.181775) (xy 380.515304 -275.156329) (xy 380.475882 -275.124142)
			(xy 380.442134 -275.086048) (xy 380.414933 -275.043034) (xy 380.394985 -274.996214) (xy 380.382806 -274.9468)
			(xy 380.378711 -274.896072) (xy 380.070614 -274.896072) (xy 380.070102 -274.921518) (xy 380.061938 -274.971752)
			(xy 380.045822 -275.020026) (xy 380.022171 -275.065089) (xy 379.991598 -275.105775) (xy 379.954894 -275.14103)
			(xy 379.91301 -275.16994) (xy 379.867031 -275.191757) (xy 379.818147 -275.205917) (xy 379.767626 -275.212051)
			(xy 379.716774 -275.210002) (xy 379.66691 -275.199822) (xy 379.619324 -275.181775) (xy 379.57525 -275.156329)
			(xy 379.535828 -275.124142) (xy 379.50208 -275.086048) (xy 379.474879 -275.043034) (xy 379.454931 -274.996214)
			(xy 379.442752 -274.9468) (xy 379.438657 -274.896072) (xy 379.132846 -274.896072) (xy 379.132356 -274.921061)
			(xy 379.124537 -274.970424) (xy 379.109093 -275.017956) (xy 379.086403 -275.062488) (xy 379.057027 -275.102921)
			(xy 379.021687 -275.138261) (xy 378.981254 -275.167637) (xy 378.936722 -275.190327) (xy 378.88919 -275.205771)
			(xy 378.839827 -275.21359) (xy 378.789849 -275.21359) (xy 378.740486 -275.205771) (xy 378.692954 -275.190327)
			(xy 378.648422 -275.167637) (xy 378.607989 -275.138261) (xy 378.572649 -275.102921) (xy 378.543273 -275.062488)
			(xy 378.520583 -275.017956) (xy 378.505139 -274.970424) (xy 378.49732 -274.921061) (xy 378.190003 -274.921061)
			(xy 378.189994 -274.921518) (xy 378.18183 -274.971752) (xy 378.165714 -275.020026) (xy 378.142063 -275.065089)
			(xy 378.11149 -275.105775) (xy 378.074786 -275.14103) (xy 378.032902 -275.16994) (xy 377.986923 -275.191757)
			(xy 377.938039 -275.205917) (xy 377.887518 -275.212051) (xy 377.836666 -275.210002) (xy 377.786802 -275.199822)
			(xy 377.739216 -275.181775) (xy 377.695142 -275.156329) (xy 377.65572 -275.124142) (xy 377.621972 -275.086048)
			(xy 377.594771 -275.043034) (xy 377.574823 -274.996214) (xy 377.562644 -274.9468) (xy 377.558549 -274.896072)
			(xy 377.252738 -274.896072) (xy 377.252248 -274.921061) (xy 377.244429 -274.970424) (xy 377.228985 -275.017956)
			(xy 377.206295 -275.062488) (xy 377.176919 -275.102921) (xy 377.141579 -275.138261) (xy 377.101146 -275.167637)
			(xy 377.056614 -275.190327) (xy 377.009082 -275.205771) (xy 376.959719 -275.21359) (xy 376.909741 -275.21359)
			(xy 376.860378 -275.205771) (xy 376.812846 -275.190327) (xy 376.768314 -275.167637) (xy 376.727881 -275.138261)
			(xy 376.692541 -275.102921) (xy 376.663165 -275.062488) (xy 376.640475 -275.017956) (xy 376.625031 -274.970424)
			(xy 376.617212 -274.921061) (xy 376.310149 -274.921061) (xy 376.31014 -274.921518) (xy 376.301976 -274.971752)
			(xy 376.28586 -275.020026) (xy 376.262209 -275.065089) (xy 376.231636 -275.105775) (xy 376.194932 -275.14103)
			(xy 376.153048 -275.16994) (xy 376.107069 -275.191757) (xy 376.058185 -275.205917) (xy 376.007664 -275.212051)
			(xy 375.956812 -275.210002) (xy 375.906948 -275.199822) (xy 375.859362 -275.181775) (xy 375.815288 -275.156329)
			(xy 375.775866 -275.124142) (xy 375.742118 -275.086048) (xy 375.714917 -275.043034) (xy 375.694969 -274.996214)
			(xy 375.68279 -274.9468) (xy 375.678695 -274.896072) (xy 375.372884 -274.896072) (xy 375.372376 -274.921647)
			(xy 375.364195 -274.972139) (xy 375.348039 -275.020671) (xy 375.324325 -275.065992) (xy 375.293664 -275.106934)
			(xy 375.256847 -275.142441) (xy 375.214821 -275.1716) (xy 375.168671 -275.193657) (xy 375.144284 -275.20138)
			(xy 375.143776 -275.20138) (xy 375.133441 -275.204973) (xy 375.116943 -275.219313) (xy 375.107908 -275.239217)
			(xy 375.107454 -275.250148) (xy 375.107454 -275.433536) (xy 375.107708 -275.437346) (xy 375.10872 -275.446062)
			(xy 375.115848 -275.462083) (xy 375.12797 -275.474753) (xy 375.135648 -275.479002) (xy 375.140728 -275.481034)
			(xy 375.242582 -275.51888) (xy 375.273062 -275.511006) (xy 375.28373 -275.498814) (xy 375.302007 -275.478417)
			(xy 375.344281 -275.443605) (xy 375.391896 -275.416552) (xy 375.443442 -275.398058) (xy 375.497394 -275.388671)
			(xy 375.524776 -275.38807) (xy 375.54977 -275.388533) (xy 375.599144 -275.396349) (xy 375.646686 -275.411794)
			(xy 375.691227 -275.434485) (xy 375.73167 -275.463866) (xy 375.767018 -275.499212) (xy 375.796402 -275.539652)
			(xy 375.819097 -275.584192) (xy 375.834545 -275.631733) (xy 375.842365 -275.681106) (xy 375.842365 -275.706078)
			(xy 376.148595 -275.706078) (xy 376.15269 -275.65535) (xy 376.164869 -275.605936) (xy 376.184817 -275.559116)
			(xy 376.212018 -275.516102) (xy 376.245766 -275.478008) (xy 376.285188 -275.445821) (xy 376.329262 -275.420375)
			(xy 376.376848 -275.402328) (xy 376.426712 -275.392148) (xy 376.477564 -275.390099) (xy 376.528085 -275.396233)
			(xy 376.576969 -275.410393) (xy 376.622948 -275.43221) (xy 376.664832 -275.46112) (xy 376.701536 -275.496375)
			(xy 376.732109 -275.537061) (xy 376.75576 -275.582124) (xy 376.771876 -275.630398) (xy 376.78004 -275.680632)
			(xy 376.780552 -275.706078) (xy 377.088649 -275.706078) (xy 377.092744 -275.65535) (xy 377.104923 -275.605936)
			(xy 377.124871 -275.559116) (xy 377.152072 -275.516102) (xy 377.18582 -275.478008) (xy 377.225242 -275.445821)
			(xy 377.269316 -275.420375) (xy 377.316902 -275.402328) (xy 377.366766 -275.392148) (xy 377.417618 -275.390099)
			(xy 377.468139 -275.396233) (xy 377.517023 -275.410393) (xy 377.563002 -275.43221) (xy 377.604886 -275.46112)
			(xy 377.64159 -275.496375) (xy 377.672163 -275.537061) (xy 377.695814 -275.582124) (xy 377.71193 -275.630398)
			(xy 377.720094 -275.680632) (xy 377.720606 -275.706078) (xy 378.968503 -275.706078) (xy 378.972598 -275.65535)
			(xy 378.984777 -275.605936) (xy 379.004725 -275.559116) (xy 379.031926 -275.516102) (xy 379.065674 -275.478008)
			(xy 379.105096 -275.445821) (xy 379.14917 -275.420375) (xy 379.196756 -275.402328) (xy 379.24662 -275.392148)
			(xy 379.297472 -275.390099) (xy 379.347993 -275.396233) (xy 379.396877 -275.410393) (xy 379.442856 -275.43221)
			(xy 379.48474 -275.46112) (xy 379.521444 -275.496375) (xy 379.552017 -275.537061) (xy 379.575668 -275.582124)
			(xy 379.591784 -275.630398) (xy 379.599948 -275.680632) (xy 379.60046 -275.706078) (xy 379.599957 -275.731067)
			(xy 379.907274 -275.731067) (xy 379.907274 -275.681089) (xy 379.915093 -275.631726) (xy 379.930537 -275.584194)
			(xy 379.953227 -275.539662) (xy 379.982603 -275.499229) (xy 380.017943 -275.463889) (xy 380.058376 -275.434513)
			(xy 380.102908 -275.411823) (xy 380.15044 -275.396379) (xy 380.199803 -275.38856) (xy 380.249781 -275.38856)
			(xy 380.299144 -275.396379) (xy 380.346676 -275.411823) (xy 380.391208 -275.434513) (xy 380.431641 -275.463889)
			(xy 380.466981 -275.499229) (xy 380.496357 -275.539662) (xy 380.519047 -275.584194) (xy 380.534491 -275.631726)
			(xy 380.54231 -275.681089) (xy 380.5428 -275.706078) (xy 380.54231 -275.731067) (xy 380.534491 -275.78043)
			(xy 380.519047 -275.827962) (xy 380.496357 -275.872494) (xy 380.466981 -275.912927) (xy 380.431641 -275.948267)
			(xy 380.391208 -275.977643) (xy 380.346676 -276.000333) (xy 380.299144 -276.015777) (xy 380.249781 -276.023596)
			(xy 380.199803 -276.023596) (xy 380.15044 -276.015777) (xy 380.102908 -276.000333) (xy 380.058376 -275.977643)
			(xy 380.017943 -275.948267) (xy 379.982603 -275.912927) (xy 379.953227 -275.872494) (xy 379.930537 -275.827962)
			(xy 379.915093 -275.78043) (xy 379.907274 -275.731067) (xy 379.599957 -275.731067) (xy 379.599948 -275.731524)
			(xy 379.591784 -275.781758) (xy 379.575668 -275.830032) (xy 379.552017 -275.875095) (xy 379.521444 -275.915781)
			(xy 379.48474 -275.951036) (xy 379.442856 -275.979946) (xy 379.396877 -276.001763) (xy 379.347993 -276.015923)
			(xy 379.297472 -276.022057) (xy 379.24662 -276.020008) (xy 379.196756 -276.009828) (xy 379.14917 -275.991781)
			(xy 379.105096 -275.966335) (xy 379.065674 -275.934148) (xy 379.031926 -275.896054) (xy 379.004725 -275.85304)
			(xy 378.984777 -275.80622) (xy 378.972598 -275.756806) (xy 378.968503 -275.706078) (xy 377.720606 -275.706078)
			(xy 377.720094 -275.731524) (xy 377.71193 -275.781758) (xy 377.695814 -275.830032) (xy 377.672163 -275.875095)
			(xy 377.64159 -275.915781) (xy 377.604886 -275.951036) (xy 377.563002 -275.979946) (xy 377.517023 -276.001763)
			(xy 377.468139 -276.015923) (xy 377.417618 -276.022057) (xy 377.366766 -276.020008) (xy 377.316902 -276.009828)
			(xy 377.269316 -275.991781) (xy 377.225242 -275.966335) (xy 377.18582 -275.934148) (xy 377.152072 -275.896054)
			(xy 377.124871 -275.85304) (xy 377.104923 -275.80622) (xy 377.092744 -275.756806) (xy 377.088649 -275.706078)
			(xy 376.780552 -275.706078) (xy 376.78004 -275.731524) (xy 376.771876 -275.781758) (xy 376.75576 -275.830032)
			(xy 376.732109 -275.875095) (xy 376.701536 -275.915781) (xy 376.664832 -275.951036) (xy 376.622948 -275.979946)
			(xy 376.576969 -276.001763) (xy 376.528085 -276.015923) (xy 376.477564 -276.022057) (xy 376.426712 -276.020008)
			(xy 376.376848 -276.009828) (xy 376.329262 -275.991781) (xy 376.285188 -275.966335) (xy 376.245766 -275.934148)
			(xy 376.212018 -275.896054) (xy 376.184817 -275.85304) (xy 376.164869 -275.80622) (xy 376.15269 -275.756806)
			(xy 376.148595 -275.706078) (xy 375.842365 -275.706078) (xy 375.842365 -275.731094) (xy 375.834545 -275.780467)
			(xy 375.819097 -275.828008) (xy 375.796402 -275.872548) (xy 375.767018 -275.912988) (xy 375.73167 -275.948334)
			(xy 375.691227 -275.977715) (xy 375.646686 -276.000406) (xy 375.599144 -276.015851) (xy 375.54977 -276.023667)
			(xy 375.524776 -276.024086) (xy 375.497394 -276.023511) (xy 375.44344 -276.014119) (xy 375.391895 -275.995618)
			(xy 375.344285 -275.968554) (xy 375.302019 -275.93373) (xy 375.28373 -275.913342) (xy 375.273062 -275.90115)
			(xy 375.242582 -275.893276) (xy 375.140728 -275.931122) (xy 375.135648 -275.933154) (xy 375.127988 -275.937421)
			(xy 375.115898 -275.950104) (xy 375.108757 -275.966104) (xy 375.107708 -275.97481) (xy 375.107454 -275.97862)
			(xy 375.107454 -276.162008) (xy 375.107988 -276.172915) (xy 375.117045 -276.192761) (xy 375.133493 -276.207092)
			(xy 375.143776 -276.210776) (xy 375.14403 -276.210776) (xy 375.168456 -276.218435) (xy 375.214664 -276.240456)
			(xy 375.256747 -276.269596) (xy 375.293618 -276.305101) (xy 375.324324 -276.346055) (xy 375.348073 -276.391399)
			(xy 375.36425 -276.439963) (xy 375.372437 -276.49049) (xy 375.372884 -276.516084) (xy 375.678695 -276.516084)
			(xy 375.68279 -276.465356) (xy 375.694969 -276.415942) (xy 375.714917 -276.369122) (xy 375.742118 -276.326108)
			(xy 375.775866 -276.288014) (xy 375.815288 -276.255827) (xy 375.859362 -276.230381) (xy 375.906948 -276.212334)
			(xy 375.956812 -276.202154) (xy 376.007664 -276.200105) (xy 376.058185 -276.206239) (xy 376.107069 -276.220399)
			(xy 376.153048 -276.242216) (xy 376.194932 -276.271126) (xy 376.231636 -276.306381) (xy 376.262209 -276.347067)
			(xy 376.28586 -276.39213) (xy 376.301976 -276.440404) (xy 376.31014 -276.490638) (xy 376.310652 -276.516084)
			(xy 376.310149 -276.541073) (xy 376.617212 -276.541073) (xy 376.617212 -276.491095) (xy 376.625031 -276.441732)
			(xy 376.640475 -276.3942) (xy 376.663165 -276.349668) (xy 376.692541 -276.309235) (xy 376.727881 -276.273895)
			(xy 376.768314 -276.244519) (xy 376.812846 -276.221829) (xy 376.860378 -276.206385) (xy 376.909741 -276.198566)
			(xy 376.959719 -276.198566) (xy 377.009082 -276.206385) (xy 377.056614 -276.221829) (xy 377.101146 -276.244519)
			(xy 377.141579 -276.273895) (xy 377.176919 -276.309235) (xy 377.206295 -276.349668) (xy 377.228985 -276.3942)
			(xy 377.244429 -276.441732) (xy 377.252248 -276.491095) (xy 377.252738 -276.516084) (xy 377.558549 -276.516084)
			(xy 377.562644 -276.465356) (xy 377.574823 -276.415942) (xy 377.594771 -276.369122) (xy 377.621972 -276.326108)
			(xy 377.65572 -276.288014) (xy 377.695142 -276.255827) (xy 377.739216 -276.230381) (xy 377.786802 -276.212334)
			(xy 377.836666 -276.202154) (xy 377.887518 -276.200105) (xy 377.938039 -276.206239) (xy 377.986923 -276.220399)
			(xy 378.032902 -276.242216) (xy 378.074786 -276.271126) (xy 378.11149 -276.306381) (xy 378.142063 -276.347067)
			(xy 378.165714 -276.39213) (xy 378.18183 -276.440404) (xy 378.189994 -276.490638) (xy 378.190506 -276.516084)
			(xy 378.190003 -276.541073) (xy 378.49732 -276.541073) (xy 378.49732 -276.491095) (xy 378.505139 -276.441732)
			(xy 378.520583 -276.3942) (xy 378.543273 -276.349668) (xy 378.572649 -276.309235) (xy 378.607989 -276.273895)
			(xy 378.648422 -276.244519) (xy 378.692954 -276.221829) (xy 378.740486 -276.206385) (xy 378.789849 -276.198566)
			(xy 378.839827 -276.198566) (xy 378.88919 -276.206385) (xy 378.936722 -276.221829) (xy 378.981254 -276.244519)
			(xy 379.021687 -276.273895) (xy 379.057027 -276.309235) (xy 379.086403 -276.349668) (xy 379.109093 -276.3942)
			(xy 379.124537 -276.441732) (xy 379.132356 -276.491095) (xy 379.132846 -276.516084) (xy 379.438657 -276.516084)
			(xy 379.442752 -276.465356) (xy 379.454931 -276.415942) (xy 379.474879 -276.369122) (xy 379.50208 -276.326108)
			(xy 379.535828 -276.288014) (xy 379.57525 -276.255827) (xy 379.619324 -276.230381) (xy 379.66691 -276.212334)
			(xy 379.716774 -276.202154) (xy 379.767626 -276.200105) (xy 379.818147 -276.206239) (xy 379.867031 -276.220399)
			(xy 379.91301 -276.242216) (xy 379.954894 -276.271126) (xy 379.991598 -276.306381) (xy 380.022171 -276.347067)
			(xy 380.045822 -276.39213) (xy 380.061938 -276.440404) (xy 380.070102 -276.490638) (xy 380.070614 -276.516084)
			(xy 380.378711 -276.516084) (xy 380.382806 -276.465356) (xy 380.394985 -276.415942) (xy 380.414933 -276.369122)
			(xy 380.442134 -276.326108) (xy 380.475882 -276.288014) (xy 380.515304 -276.255827) (xy 380.559378 -276.230381)
			(xy 380.606964 -276.212334) (xy 380.656828 -276.202154) (xy 380.70768 -276.200105) (xy 380.758201 -276.206239)
			(xy 380.807085 -276.220399) (xy 380.853064 -276.242216) (xy 380.894948 -276.271126) (xy 380.931652 -276.306381)
			(xy 380.962225 -276.347067) (xy 380.985876 -276.39213) (xy 381.001992 -276.440404) (xy 381.010156 -276.490638)
			(xy 381.010668 -276.516084) (xy 381.010156 -276.54153) (xy 381.001992 -276.591764) (xy 380.985876 -276.640038)
			(xy 380.962225 -276.685101) (xy 380.931652 -276.725787) (xy 380.894948 -276.761042) (xy 380.853064 -276.789952)
			(xy 380.807085 -276.811769) (xy 380.758201 -276.825929) (xy 380.70768 -276.832063) (xy 380.656828 -276.830014)
			(xy 380.606964 -276.819834) (xy 380.559378 -276.801787) (xy 380.515304 -276.776341) (xy 380.475882 -276.744154)
			(xy 380.442134 -276.70606) (xy 380.414933 -276.663046) (xy 380.394985 -276.616226) (xy 380.382806 -276.566812)
			(xy 380.378711 -276.516084) (xy 380.070614 -276.516084) (xy 380.070102 -276.54153) (xy 380.061938 -276.591764)
			(xy 380.045822 -276.640038) (xy 380.022171 -276.685101) (xy 379.991598 -276.725787) (xy 379.954894 -276.761042)
			(xy 379.91301 -276.789952) (xy 379.867031 -276.811769) (xy 379.818147 -276.825929) (xy 379.767626 -276.832063)
			(xy 379.716774 -276.830014) (xy 379.66691 -276.819834) (xy 379.619324 -276.801787) (xy 379.57525 -276.776341)
			(xy 379.535828 -276.744154) (xy 379.50208 -276.70606) (xy 379.474879 -276.663046) (xy 379.454931 -276.616226)
			(xy 379.442752 -276.566812) (xy 379.438657 -276.516084) (xy 379.132846 -276.516084) (xy 379.132356 -276.541073)
			(xy 379.124537 -276.590436) (xy 379.109093 -276.637968) (xy 379.086403 -276.6825) (xy 379.057027 -276.722933)
			(xy 379.021687 -276.758273) (xy 378.981254 -276.787649) (xy 378.936722 -276.810339) (xy 378.88919 -276.825783)
			(xy 378.839827 -276.833602) (xy 378.789849 -276.833602) (xy 378.740486 -276.825783) (xy 378.692954 -276.810339)
			(xy 378.648422 -276.787649) (xy 378.607989 -276.758273) (xy 378.572649 -276.722933) (xy 378.543273 -276.6825)
			(xy 378.520583 -276.637968) (xy 378.505139 -276.590436) (xy 378.49732 -276.541073) (xy 378.190003 -276.541073)
			(xy 378.189994 -276.54153) (xy 378.18183 -276.591764) (xy 378.165714 -276.640038) (xy 378.142063 -276.685101)
			(xy 378.11149 -276.725787) (xy 378.074786 -276.761042) (xy 378.032902 -276.789952) (xy 377.986923 -276.811769)
			(xy 377.938039 -276.825929) (xy 377.887518 -276.832063) (xy 377.836666 -276.830014) (xy 377.786802 -276.819834)
			(xy 377.739216 -276.801787) (xy 377.695142 -276.776341) (xy 377.65572 -276.744154) (xy 377.621972 -276.70606)
			(xy 377.594771 -276.663046) (xy 377.574823 -276.616226) (xy 377.562644 -276.566812) (xy 377.558549 -276.516084)
			(xy 377.252738 -276.516084) (xy 377.252248 -276.541073) (xy 377.244429 -276.590436) (xy 377.228985 -276.637968)
			(xy 377.206295 -276.6825) (xy 377.176919 -276.722933) (xy 377.141579 -276.758273) (xy 377.101146 -276.787649)
			(xy 377.056614 -276.810339) (xy 377.009082 -276.825783) (xy 376.959719 -276.833602) (xy 376.909741 -276.833602)
			(xy 376.860378 -276.825783) (xy 376.812846 -276.810339) (xy 376.768314 -276.787649) (xy 376.727881 -276.758273)
			(xy 376.692541 -276.722933) (xy 376.663165 -276.6825) (xy 376.640475 -276.637968) (xy 376.625031 -276.590436)
			(xy 376.617212 -276.541073) (xy 376.310149 -276.541073) (xy 376.31014 -276.54153) (xy 376.301976 -276.591764)
			(xy 376.28586 -276.640038) (xy 376.262209 -276.685101) (xy 376.231636 -276.725787) (xy 376.194932 -276.761042)
			(xy 376.153048 -276.789952) (xy 376.107069 -276.811769) (xy 376.058185 -276.825929) (xy 376.007664 -276.832063)
			(xy 375.956812 -276.830014) (xy 375.906948 -276.819834) (xy 375.859362 -276.801787) (xy 375.815288 -276.776341)
			(xy 375.775866 -276.744154) (xy 375.742118 -276.70606) (xy 375.714917 -276.663046) (xy 375.694969 -276.616226)
			(xy 375.68279 -276.566812) (xy 375.678695 -276.516084) (xy 375.372884 -276.516084) (xy 375.372375 -276.541659)
			(xy 375.364192 -276.592149) (xy 375.348035 -276.640679) (xy 375.324321 -276.685999) (xy 375.293659 -276.726939)
			(xy 375.256842 -276.762445) (xy 375.214817 -276.791602) (xy 375.168668 -276.813658) (xy 375.144284 -276.821392)
			(xy 375.143776 -276.821392) (xy 375.133442 -276.824985) (xy 375.116948 -276.839326) (xy 375.107917 -276.85923)
			(xy 375.107454 -276.87016) (xy 375.107454 -277.32609) (xy 376.148595 -277.32609) (xy 376.15269 -277.275362)
			(xy 376.164869 -277.225948) (xy 376.184817 -277.179128) (xy 376.212018 -277.136114) (xy 376.245766 -277.09802)
			(xy 376.285188 -277.065833) (xy 376.329262 -277.040387) (xy 376.376848 -277.02234) (xy 376.426712 -277.01216)
			(xy 376.477564 -277.010111) (xy 376.528085 -277.016245) (xy 376.576969 -277.030405) (xy 376.622948 -277.052222)
			(xy 376.664832 -277.081132) (xy 376.701536 -277.116387) (xy 376.732109 -277.157073) (xy 376.75576 -277.202136)
			(xy 376.771876 -277.25041) (xy 376.78004 -277.300644) (xy 376.780552 -277.32609) (xy 377.088649 -277.32609)
			(xy 377.092744 -277.275362) (xy 377.104923 -277.225948) (xy 377.124871 -277.179128) (xy 377.152072 -277.136114)
			(xy 377.18582 -277.09802) (xy 377.225242 -277.065833) (xy 377.269316 -277.040387) (xy 377.316902 -277.02234)
			(xy 377.366766 -277.01216) (xy 377.417618 -277.010111) (xy 377.468139 -277.016245) (xy 377.517023 -277.030405)
			(xy 377.563002 -277.052222) (xy 377.604886 -277.081132) (xy 377.64159 -277.116387) (xy 377.672163 -277.157073)
			(xy 377.695814 -277.202136) (xy 377.71193 -277.25041) (xy 377.720094 -277.300644) (xy 377.720606 -277.32609)
			(xy 377.720103 -277.351079) (xy 378.02742 -277.351079) (xy 378.02742 -277.301101) (xy 378.035239 -277.251738)
			(xy 378.050683 -277.204206) (xy 378.073373 -277.159674) (xy 378.102749 -277.119241) (xy 378.138089 -277.083901)
			(xy 378.178522 -277.054525) (xy 378.223054 -277.031835) (xy 378.270586 -277.016391) (xy 378.319949 -277.008572)
			(xy 378.369927 -277.008572) (xy 378.41929 -277.016391) (xy 378.466822 -277.031835) (xy 378.511354 -277.054525)
			(xy 378.551787 -277.083901) (xy 378.587127 -277.119241) (xy 378.616503 -277.159674) (xy 378.639193 -277.204206)
			(xy 378.654637 -277.251738) (xy 378.662456 -277.301101) (xy 378.662946 -277.32609) (xy 378.968503 -277.32609)
			(xy 378.972598 -277.275362) (xy 378.984777 -277.225948) (xy 379.004725 -277.179128) (xy 379.031926 -277.136114)
			(xy 379.065674 -277.09802) (xy 379.105096 -277.065833) (xy 379.14917 -277.040387) (xy 379.196756 -277.02234)
			(xy 379.24662 -277.01216) (xy 379.297472 -277.010111) (xy 379.347993 -277.016245) (xy 379.396877 -277.030405)
			(xy 379.442856 -277.052222) (xy 379.48474 -277.081132) (xy 379.521444 -277.116387) (xy 379.552017 -277.157073)
			(xy 379.575668 -277.202136) (xy 379.591784 -277.25041) (xy 379.599948 -277.300644) (xy 379.60046 -277.32609)
			(xy 379.599957 -277.351079) (xy 379.907274 -277.351079) (xy 379.907274 -277.301101) (xy 379.915093 -277.251738)
			(xy 379.930537 -277.204206) (xy 379.953227 -277.159674) (xy 379.982603 -277.119241) (xy 380.017943 -277.083901)
			(xy 380.058376 -277.054525) (xy 380.102908 -277.031835) (xy 380.15044 -277.016391) (xy 380.199803 -277.008572)
			(xy 380.249781 -277.008572) (xy 380.299144 -277.016391) (xy 380.346676 -277.031835) (xy 380.391208 -277.054525)
			(xy 380.431641 -277.083901) (xy 380.466981 -277.119241) (xy 380.496357 -277.159674) (xy 380.519047 -277.204206)
			(xy 380.534491 -277.251738) (xy 380.54231 -277.301101) (xy 380.5428 -277.32609) (xy 380.54231 -277.351079)
			(xy 380.534491 -277.400442) (xy 380.519047 -277.447974) (xy 380.496357 -277.492506) (xy 380.466981 -277.532939)
			(xy 380.431641 -277.568279) (xy 380.391208 -277.597655) (xy 380.346676 -277.620345) (xy 380.299144 -277.635789)
			(xy 380.249781 -277.643608) (xy 380.199803 -277.643608) (xy 380.15044 -277.635789) (xy 380.102908 -277.620345)
			(xy 380.058376 -277.597655) (xy 380.017943 -277.568279) (xy 379.982603 -277.532939) (xy 379.953227 -277.492506)
			(xy 379.930537 -277.447974) (xy 379.915093 -277.400442) (xy 379.907274 -277.351079) (xy 379.599957 -277.351079)
			(xy 379.599948 -277.351536) (xy 379.591784 -277.40177) (xy 379.575668 -277.450044) (xy 379.552017 -277.495107)
			(xy 379.521444 -277.535793) (xy 379.48474 -277.571048) (xy 379.442856 -277.599958) (xy 379.396877 -277.621775)
			(xy 379.347993 -277.635935) (xy 379.297472 -277.642069) (xy 379.24662 -277.64002) (xy 379.196756 -277.62984)
			(xy 379.14917 -277.611793) (xy 379.105096 -277.586347) (xy 379.065674 -277.55416) (xy 379.031926 -277.516066)
			(xy 379.004725 -277.473052) (xy 378.984777 -277.426232) (xy 378.972598 -277.376818) (xy 378.968503 -277.32609)
			(xy 378.662946 -277.32609) (xy 378.662456 -277.351079) (xy 378.654637 -277.400442) (xy 378.639193 -277.447974)
			(xy 378.616503 -277.492506) (xy 378.587127 -277.532939) (xy 378.551787 -277.568279) (xy 378.511354 -277.597655)
			(xy 378.466822 -277.620345) (xy 378.41929 -277.635789) (xy 378.369927 -277.643608) (xy 378.319949 -277.643608)
			(xy 378.270586 -277.635789) (xy 378.223054 -277.620345) (xy 378.178522 -277.597655) (xy 378.138089 -277.568279)
			(xy 378.102749 -277.532939) (xy 378.073373 -277.492506) (xy 378.050683 -277.447974) (xy 378.035239 -277.400442)
			(xy 378.02742 -277.351079) (xy 377.720103 -277.351079) (xy 377.720094 -277.351536) (xy 377.71193 -277.40177)
			(xy 377.695814 -277.450044) (xy 377.672163 -277.495107) (xy 377.64159 -277.535793) (xy 377.604886 -277.571048)
			(xy 377.563002 -277.599958) (xy 377.517023 -277.621775) (xy 377.468139 -277.635935) (xy 377.417618 -277.642069)
			(xy 377.366766 -277.64002) (xy 377.316902 -277.62984) (xy 377.269316 -277.611793) (xy 377.225242 -277.586347)
			(xy 377.18582 -277.55416) (xy 377.152072 -277.516066) (xy 377.124871 -277.473052) (xy 377.104923 -277.426232)
			(xy 377.092744 -277.376818) (xy 377.088649 -277.32609) (xy 376.780552 -277.32609) (xy 376.78004 -277.351536)
			(xy 376.771876 -277.40177) (xy 376.75576 -277.450044) (xy 376.732109 -277.495107) (xy 376.701536 -277.535793)
			(xy 376.664832 -277.571048) (xy 376.622948 -277.599958) (xy 376.576969 -277.621775) (xy 376.528085 -277.635935)
			(xy 376.477564 -277.642069) (xy 376.426712 -277.64002) (xy 376.376848 -277.62984) (xy 376.329262 -277.611793)
			(xy 376.285188 -277.586347) (xy 376.245766 -277.55416) (xy 376.212018 -277.516066) (xy 376.184817 -277.473052)
			(xy 376.164869 -277.426232) (xy 376.15269 -277.376818) (xy 376.148595 -277.32609) (xy 375.107454 -277.32609)
			(xy 375.107454 -277.78202) (xy 375.107972 -277.792938) (xy 375.117011 -277.812815) (xy 375.133461 -277.827174)
			(xy 375.143776 -277.830788) (xy 375.14403 -277.830788) (xy 375.168455 -277.838447) (xy 375.214662 -277.860469)
			(xy 375.256744 -277.889608) (xy 375.293614 -277.925114) (xy 375.324319 -277.966068) (xy 375.348066 -278.011412)
			(xy 375.364241 -278.059975) (xy 375.372427 -278.110503) (xy 375.372884 -278.136096) (xy 375.678695 -278.136096)
			(xy 375.68279 -278.085368) (xy 375.694969 -278.035954) (xy 375.714917 -277.989134) (xy 375.742118 -277.94612)
			(xy 375.775866 -277.908026) (xy 375.815288 -277.875839) (xy 375.859362 -277.850393) (xy 375.906948 -277.832346)
			(xy 375.956812 -277.822166) (xy 376.007664 -277.820117) (xy 376.058185 -277.826251) (xy 376.107069 -277.840411)
			(xy 376.153048 -277.862228) (xy 376.194932 -277.891138) (xy 376.231636 -277.926393) (xy 376.262209 -277.967079)
			(xy 376.28586 -278.012142) (xy 376.301976 -278.060416) (xy 376.31014 -278.11065) (xy 376.310652 -278.136096)
			(xy 376.310149 -278.161085) (xy 376.617212 -278.161085) (xy 376.617212 -278.111107) (xy 376.625031 -278.061744)
			(xy 376.640475 -278.014212) (xy 376.663165 -277.96968) (xy 376.692541 -277.929247) (xy 376.727881 -277.893907)
			(xy 376.768314 -277.864531) (xy 376.812846 -277.841841) (xy 376.860378 -277.826397) (xy 376.909741 -277.818578)
			(xy 376.959719 -277.818578) (xy 377.009082 -277.826397) (xy 377.056614 -277.841841) (xy 377.101146 -277.864531)
			(xy 377.141579 -277.893907) (xy 377.176919 -277.929247) (xy 377.206295 -277.96968) (xy 377.228985 -278.014212)
			(xy 377.244429 -278.061744) (xy 377.252248 -278.111107) (xy 377.252738 -278.136096) (xy 377.558549 -278.136096)
			(xy 377.562644 -278.085368) (xy 377.574823 -278.035954) (xy 377.594771 -277.989134) (xy 377.621972 -277.94612)
			(xy 377.65572 -277.908026) (xy 377.695142 -277.875839) (xy 377.739216 -277.850393) (xy 377.786802 -277.832346)
			(xy 377.836666 -277.822166) (xy 377.887518 -277.820117) (xy 377.938039 -277.826251) (xy 377.986923 -277.840411)
			(xy 378.032902 -277.862228) (xy 378.074786 -277.891138) (xy 378.11149 -277.926393) (xy 378.142063 -277.967079)
			(xy 378.165714 -278.012142) (xy 378.18183 -278.060416) (xy 378.189994 -278.11065) (xy 378.190506 -278.136096)
			(xy 379.438657 -278.136096) (xy 379.442752 -278.085368) (xy 379.454931 -278.035954) (xy 379.474879 -277.989134)
			(xy 379.50208 -277.94612) (xy 379.535828 -277.908026) (xy 379.57525 -277.875839) (xy 379.619324 -277.850393)
			(xy 379.66691 -277.832346) (xy 379.716774 -277.822166) (xy 379.767626 -277.820117) (xy 379.818147 -277.826251)
			(xy 379.867031 -277.840411) (xy 379.91301 -277.862228) (xy 379.954894 -277.891138) (xy 379.991598 -277.926393)
			(xy 380.022171 -277.967079) (xy 380.045822 -278.012142) (xy 380.061938 -278.060416) (xy 380.070102 -278.11065)
			(xy 380.070614 -278.136096) (xy 380.378711 -278.136096) (xy 380.382806 -278.085368) (xy 380.394985 -278.035954)
			(xy 380.414933 -277.989134) (xy 380.442134 -277.94612) (xy 380.475882 -277.908026) (xy 380.515304 -277.875839)
			(xy 380.559378 -277.850393) (xy 380.606964 -277.832346) (xy 380.656828 -277.822166) (xy 380.70768 -277.820117)
			(xy 380.758201 -277.826251) (xy 380.807085 -277.840411) (xy 380.853064 -277.862228) (xy 380.894948 -277.891138)
			(xy 380.931652 -277.926393) (xy 380.962225 -277.967079) (xy 380.985876 -278.012142) (xy 381.001992 -278.060416)
			(xy 381.010156 -278.11065) (xy 381.010668 -278.136096) (xy 381.010156 -278.161542) (xy 381.001992 -278.211776)
			(xy 380.985876 -278.26005) (xy 380.962225 -278.305113) (xy 380.931652 -278.345799) (xy 380.894948 -278.381054)
			(xy 380.853064 -278.409964) (xy 380.807085 -278.431781) (xy 380.758201 -278.445941) (xy 380.70768 -278.452075)
			(xy 380.656828 -278.450026) (xy 380.606964 -278.439846) (xy 380.559378 -278.421799) (xy 380.515304 -278.396353)
			(xy 380.475882 -278.364166) (xy 380.442134 -278.326072) (xy 380.414933 -278.283058) (xy 380.394985 -278.236238)
			(xy 380.382806 -278.186824) (xy 380.378711 -278.136096) (xy 380.070614 -278.136096) (xy 380.070102 -278.161542)
			(xy 380.061938 -278.211776) (xy 380.045822 -278.26005) (xy 380.022171 -278.305113) (xy 379.991598 -278.345799)
			(xy 379.954894 -278.381054) (xy 379.91301 -278.409964) (xy 379.867031 -278.431781) (xy 379.818147 -278.445941)
			(xy 379.767626 -278.452075) (xy 379.716774 -278.450026) (xy 379.66691 -278.439846) (xy 379.619324 -278.421799)
			(xy 379.57525 -278.396353) (xy 379.535828 -278.364166) (xy 379.50208 -278.326072) (xy 379.474879 -278.283058)
			(xy 379.454931 -278.236238) (xy 379.442752 -278.186824) (xy 379.438657 -278.136096) (xy 378.190506 -278.136096)
			(xy 378.189994 -278.161542) (xy 378.18183 -278.211776) (xy 378.165714 -278.26005) (xy 378.142063 -278.305113)
			(xy 378.11149 -278.345799) (xy 378.074786 -278.381054) (xy 378.032902 -278.409964) (xy 377.986923 -278.431781)
			(xy 377.938039 -278.445941) (xy 377.887518 -278.452075) (xy 377.836666 -278.450026) (xy 377.786802 -278.439846)
			(xy 377.739216 -278.421799) (xy 377.695142 -278.396353) (xy 377.65572 -278.364166) (xy 377.621972 -278.326072)
			(xy 377.594771 -278.283058) (xy 377.574823 -278.236238) (xy 377.562644 -278.186824) (xy 377.558549 -278.136096)
			(xy 377.252738 -278.136096) (xy 377.252248 -278.161085) (xy 377.244429 -278.210448) (xy 377.228985 -278.25798)
			(xy 377.206295 -278.302512) (xy 377.176919 -278.342945) (xy 377.141579 -278.378285) (xy 377.101146 -278.407661)
			(xy 377.056614 -278.430351) (xy 377.009082 -278.445795) (xy 376.959719 -278.453614) (xy 376.909741 -278.453614)
			(xy 376.860378 -278.445795) (xy 376.812846 -278.430351) (xy 376.768314 -278.407661) (xy 376.727881 -278.378285)
			(xy 376.692541 -278.342945) (xy 376.663165 -278.302512) (xy 376.640475 -278.25798) (xy 376.625031 -278.210448)
			(xy 376.617212 -278.161085) (xy 376.310149 -278.161085) (xy 376.31014 -278.161542) (xy 376.301976 -278.211776)
			(xy 376.28586 -278.26005) (xy 376.262209 -278.305113) (xy 376.231636 -278.345799) (xy 376.194932 -278.381054)
			(xy 376.153048 -278.409964) (xy 376.107069 -278.431781) (xy 376.058185 -278.445941) (xy 376.007664 -278.452075)
			(xy 375.956812 -278.450026) (xy 375.906948 -278.439846) (xy 375.859362 -278.421799) (xy 375.815288 -278.396353)
			(xy 375.775866 -278.364166) (xy 375.742118 -278.326072) (xy 375.714917 -278.283058) (xy 375.694969 -278.236238)
			(xy 375.68279 -278.186824) (xy 375.678695 -278.136096) (xy 375.372884 -278.136096) (xy 375.372374 -278.16167)
			(xy 375.36419 -278.212159) (xy 375.348032 -278.260688) (xy 375.324316 -278.306006) (xy 375.293655 -278.346944)
			(xy 375.256837 -278.382449) (xy 375.214813 -278.411605) (xy 375.168664 -278.43366) (xy 375.144284 -278.441404)
			(xy 375.143776 -278.441404) (xy 375.133443 -278.444998) (xy 375.116952 -278.45934) (xy 375.107926 -278.479243)
			(xy 375.107454 -278.490172) (xy 375.107454 -278.67356) (xy 375.107708 -278.67737) (xy 375.108724 -278.686084)
			(xy 375.115856 -278.702099) (xy 375.127979 -278.714762) (xy 375.135648 -278.719026) (xy 375.140728 -278.721058)
			(xy 375.242582 -278.758904) (xy 375.273062 -278.75103) (xy 375.28373 -278.738838) (xy 375.302006 -278.718439)
			(xy 375.34428 -278.683625) (xy 375.391894 -278.65657) (xy 375.443441 -278.638075) (xy 375.497394 -278.628686)
			(xy 375.524776 -278.628094) (xy 375.549768 -278.628557) (xy 375.599138 -278.636373) (xy 375.646677 -278.651816)
			(xy 375.691215 -278.674506) (xy 375.731654 -278.703884) (xy 375.767 -278.739227) (xy 375.796382 -278.779665)
			(xy 375.819075 -278.824201) (xy 375.834522 -278.871739) (xy 375.842342 -278.921108) (xy 375.842342 -278.946102)
			(xy 376.148595 -278.946102) (xy 376.15269 -278.895374) (xy 376.164869 -278.84596) (xy 376.184817 -278.79914)
			(xy 376.212018 -278.756126) (xy 376.245766 -278.718032) (xy 376.285188 -278.685845) (xy 376.329262 -278.660399)
			(xy 376.376848 -278.642352) (xy 376.426712 -278.632172) (xy 376.477564 -278.630123) (xy 376.528085 -278.636257)
			(xy 376.576969 -278.650417) (xy 376.622948 -278.672234) (xy 376.664832 -278.701144) (xy 376.701536 -278.736399)
			(xy 376.732109 -278.777085) (xy 376.75576 -278.822148) (xy 376.771876 -278.870422) (xy 376.78004 -278.920656)
			(xy 376.780552 -278.946102) (xy 377.088649 -278.946102) (xy 377.092744 -278.895374) (xy 377.104923 -278.84596)
			(xy 377.124871 -278.79914) (xy 377.152072 -278.756126) (xy 377.18582 -278.718032) (xy 377.225242 -278.685845)
			(xy 377.269316 -278.660399) (xy 377.316902 -278.642352) (xy 377.366766 -278.632172) (xy 377.417618 -278.630123)
			(xy 377.468139 -278.636257) (xy 377.517023 -278.650417) (xy 377.563002 -278.672234) (xy 377.604886 -278.701144)
			(xy 377.64159 -278.736399) (xy 377.672163 -278.777085) (xy 377.695814 -278.822148) (xy 377.71193 -278.870422)
			(xy 377.720094 -278.920656) (xy 377.720606 -278.946102) (xy 377.720103 -278.971091) (xy 378.02742 -278.971091)
			(xy 378.02742 -278.921113) (xy 378.035239 -278.87175) (xy 378.050683 -278.824218) (xy 378.073373 -278.779686)
			(xy 378.102749 -278.739253) (xy 378.138089 -278.703913) (xy 378.178522 -278.674537) (xy 378.223054 -278.651847)
			(xy 378.270586 -278.636403) (xy 378.319949 -278.628584) (xy 378.369927 -278.628584) (xy 378.41929 -278.636403)
			(xy 378.466822 -278.651847) (xy 378.511354 -278.674537) (xy 378.551787 -278.703913) (xy 378.587127 -278.739253)
			(xy 378.616503 -278.779686) (xy 378.639193 -278.824218) (xy 378.654637 -278.87175) (xy 378.662456 -278.921113)
			(xy 378.662946 -278.946102) (xy 378.968503 -278.946102) (xy 378.972598 -278.895374) (xy 378.984777 -278.84596)
			(xy 379.004725 -278.79914) (xy 379.031926 -278.756126) (xy 379.065674 -278.718032) (xy 379.105096 -278.685845)
			(xy 379.14917 -278.660399) (xy 379.196756 -278.642352) (xy 379.24662 -278.632172) (xy 379.297472 -278.630123)
			(xy 379.347993 -278.636257) (xy 379.396877 -278.650417) (xy 379.442856 -278.672234) (xy 379.48474 -278.701144)
			(xy 379.521444 -278.736399) (xy 379.552017 -278.777085) (xy 379.575668 -278.822148) (xy 379.591784 -278.870422)
			(xy 379.599948 -278.920656) (xy 379.60046 -278.946102) (xy 379.599957 -278.971091) (xy 379.907274 -278.971091)
			(xy 379.907274 -278.921113) (xy 379.915093 -278.87175) (xy 379.930537 -278.824218) (xy 379.953227 -278.779686)
			(xy 379.982603 -278.739253) (xy 380.017943 -278.703913) (xy 380.058376 -278.674537) (xy 380.102908 -278.651847)
			(xy 380.15044 -278.636403) (xy 380.199803 -278.628584) (xy 380.249781 -278.628584) (xy 380.299144 -278.636403)
			(xy 380.346676 -278.651847) (xy 380.391208 -278.674537) (xy 380.431641 -278.703913) (xy 380.466981 -278.739253)
			(xy 380.496357 -278.779686) (xy 380.519047 -278.824218) (xy 380.534491 -278.87175) (xy 380.54231 -278.921113)
			(xy 380.5428 -278.946102) (xy 380.54231 -278.971091) (xy 380.534491 -279.020454) (xy 380.519047 -279.067986)
			(xy 380.496357 -279.112518) (xy 380.466981 -279.152951) (xy 380.431641 -279.188291) (xy 380.391208 -279.217667)
			(xy 380.346676 -279.240357) (xy 380.299144 -279.255801) (xy 380.249781 -279.26362) (xy 380.199803 -279.26362)
			(xy 380.15044 -279.255801) (xy 380.102908 -279.240357) (xy 380.058376 -279.217667) (xy 380.017943 -279.188291)
			(xy 379.982603 -279.152951) (xy 379.953227 -279.112518) (xy 379.930537 -279.067986) (xy 379.915093 -279.020454)
			(xy 379.907274 -278.971091) (xy 379.599957 -278.971091) (xy 379.599948 -278.971548) (xy 379.591784 -279.021782)
			(xy 379.575668 -279.070056) (xy 379.552017 -279.115119) (xy 379.521444 -279.155805) (xy 379.48474 -279.19106)
			(xy 379.442856 -279.21997) (xy 379.396877 -279.241787) (xy 379.347993 -279.255947) (xy 379.297472 -279.262081)
			(xy 379.24662 -279.260032) (xy 379.196756 -279.249852) (xy 379.14917 -279.231805) (xy 379.105096 -279.206359)
			(xy 379.065674 -279.174172) (xy 379.031926 -279.136078) (xy 379.004725 -279.093064) (xy 378.984777 -279.046244)
			(xy 378.972598 -278.99683) (xy 378.968503 -278.946102) (xy 378.662946 -278.946102) (xy 378.662456 -278.971091)
			(xy 378.654637 -279.020454) (xy 378.639193 -279.067986) (xy 378.616503 -279.112518) (xy 378.587127 -279.152951)
			(xy 378.551787 -279.188291) (xy 378.511354 -279.217667) (xy 378.466822 -279.240357) (xy 378.41929 -279.255801)
			(xy 378.369927 -279.26362) (xy 378.319949 -279.26362) (xy 378.270586 -279.255801) (xy 378.223054 -279.240357)
			(xy 378.178522 -279.217667) (xy 378.138089 -279.188291) (xy 378.102749 -279.152951) (xy 378.073373 -279.112518)
			(xy 378.050683 -279.067986) (xy 378.035239 -279.020454) (xy 378.02742 -278.971091) (xy 377.720103 -278.971091)
			(xy 377.720094 -278.971548) (xy 377.71193 -279.021782) (xy 377.695814 -279.070056) (xy 377.672163 -279.115119)
			(xy 377.64159 -279.155805) (xy 377.604886 -279.19106) (xy 377.563002 -279.21997) (xy 377.517023 -279.241787)
			(xy 377.468139 -279.255947) (xy 377.417618 -279.262081) (xy 377.366766 -279.260032) (xy 377.316902 -279.249852)
			(xy 377.269316 -279.231805) (xy 377.225242 -279.206359) (xy 377.18582 -279.174172) (xy 377.152072 -279.136078)
			(xy 377.124871 -279.093064) (xy 377.104923 -279.046244) (xy 377.092744 -278.99683) (xy 377.088649 -278.946102)
			(xy 376.780552 -278.946102) (xy 376.78004 -278.971548) (xy 376.771876 -279.021782) (xy 376.75576 -279.070056)
			(xy 376.732109 -279.115119) (xy 376.701536 -279.155805) (xy 376.664832 -279.19106) (xy 376.622948 -279.21997)
			(xy 376.576969 -279.241787) (xy 376.528085 -279.255947) (xy 376.477564 -279.262081) (xy 376.426712 -279.260032)
			(xy 376.376848 -279.249852) (xy 376.329262 -279.231805) (xy 376.285188 -279.206359) (xy 376.245766 -279.174172)
			(xy 376.212018 -279.136078) (xy 376.184817 -279.093064) (xy 376.164869 -279.046244) (xy 376.15269 -278.99683)
			(xy 376.148595 -278.946102) (xy 375.842342 -278.946102) (xy 375.842342 -278.971092) (xy 375.834522 -279.020461)
			(xy 375.819075 -279.067999) (xy 375.796382 -279.112535) (xy 375.767 -279.152973) (xy 375.731654 -279.188316)
			(xy 375.691215 -279.217694) (xy 375.646677 -279.240384) (xy 375.599138 -279.255827) (xy 375.549768 -279.263643)
			(xy 375.524776 -279.26411) (xy 375.498973 -279.263614) (xy 375.448044 -279.255291) (xy 375.399127 -279.238852)
			(xy 375.353508 -279.214727) (xy 375.312384 -279.183551) (xy 375.276836 -279.146142) (xy 375.247796 -279.103483)
			(xy 375.226028 -279.056693) (xy 375.212103 -279.007002) (xy 375.2088 -278.981408) (xy 375.206514 -278.962104)
			(xy 375.177812 -278.936196) (xy 375.158254 -278.936196) (xy 375.148252 -278.936692) (xy 375.129776 -278.94436)
			(xy 375.115636 -278.958511) (xy 375.107984 -278.976994) (xy 375.107454 -278.986996) (xy 375.107454 -279.065736)
			(xy 375.106925 -279.075577) (xy 375.099353 -279.093752) (xy 375.092722 -279.101042) (xy 374.741186 -279.452578)
			(xy 374.734468 -279.459814) (xy 374.726861 -279.478019) (xy 374.726454 -279.487884) (xy 374.726454 -279.756108)
			(xy 375.678695 -279.756108) (xy 375.68279 -279.70538) (xy 375.694969 -279.655966) (xy 375.714917 -279.609146)
			(xy 375.742118 -279.566132) (xy 375.775866 -279.528038) (xy 375.815288 -279.495851) (xy 375.859362 -279.470405)
			(xy 375.906948 -279.452358) (xy 375.956812 -279.442178) (xy 376.007664 -279.440129) (xy 376.058185 -279.446263)
			(xy 376.107069 -279.460423) (xy 376.153048 -279.48224) (xy 376.194932 -279.51115) (xy 376.231636 -279.546405)
			(xy 376.262209 -279.587091) (xy 376.28586 -279.632154) (xy 376.301976 -279.680428) (xy 376.31014 -279.730662)
			(xy 376.310652 -279.756108) (xy 376.310149 -279.781097) (xy 376.617212 -279.781097) (xy 376.617212 -279.731119)
			(xy 376.625031 -279.681756) (xy 376.640475 -279.634224) (xy 376.663165 -279.589692) (xy 376.692541 -279.549259)
			(xy 376.727881 -279.513919) (xy 376.768314 -279.484543) (xy 376.812846 -279.461853) (xy 376.860378 -279.446409)
			(xy 376.909741 -279.43859) (xy 376.959719 -279.43859) (xy 377.009082 -279.446409) (xy 377.056614 -279.461853)
			(xy 377.101146 -279.484543) (xy 377.141579 -279.513919) (xy 377.176919 -279.549259) (xy 377.206295 -279.589692)
			(xy 377.228985 -279.634224) (xy 377.244429 -279.681756) (xy 377.252248 -279.731119) (xy 377.252738 -279.756108)
			(xy 377.558549 -279.756108) (xy 377.562644 -279.70538) (xy 377.574823 -279.655966) (xy 377.594771 -279.609146)
			(xy 377.621972 -279.566132) (xy 377.65572 -279.528038) (xy 377.695142 -279.495851) (xy 377.739216 -279.470405)
			(xy 377.786802 -279.452358) (xy 377.836666 -279.442178) (xy 377.887518 -279.440129) (xy 377.938039 -279.446263)
			(xy 377.986923 -279.460423) (xy 378.032902 -279.48224) (xy 378.074786 -279.51115) (xy 378.11149 -279.546405)
			(xy 378.142063 -279.587091) (xy 378.165714 -279.632154) (xy 378.18183 -279.680428) (xy 378.189994 -279.730662)
			(xy 378.190506 -279.756108) (xy 378.190003 -279.781097) (xy 378.49732 -279.781097) (xy 378.49732 -279.731119)
			(xy 378.505139 -279.681756) (xy 378.520583 -279.634224) (xy 378.543273 -279.589692) (xy 378.572649 -279.549259)
			(xy 378.607989 -279.513919) (xy 378.648422 -279.484543) (xy 378.692954 -279.461853) (xy 378.740486 -279.446409)
			(xy 378.789849 -279.43859) (xy 378.839827 -279.43859) (xy 378.88919 -279.446409) (xy 378.936722 -279.461853)
			(xy 378.981254 -279.484543) (xy 379.021687 -279.513919) (xy 379.057027 -279.549259) (xy 379.086403 -279.589692)
			(xy 379.109093 -279.634224) (xy 379.124537 -279.681756) (xy 379.132356 -279.731119) (xy 379.132846 -279.756108)
			(xy 379.438657 -279.756108) (xy 379.442752 -279.70538) (xy 379.454931 -279.655966) (xy 379.474879 -279.609146)
			(xy 379.50208 -279.566132) (xy 379.535828 -279.528038) (xy 379.57525 -279.495851) (xy 379.619324 -279.470405)
			(xy 379.66691 -279.452358) (xy 379.716774 -279.442178) (xy 379.767626 -279.440129) (xy 379.818147 -279.446263)
			(xy 379.867031 -279.460423) (xy 379.91301 -279.48224) (xy 379.954894 -279.51115) (xy 379.991598 -279.546405)
			(xy 380.022171 -279.587091) (xy 380.045822 -279.632154) (xy 380.061938 -279.680428) (xy 380.070102 -279.730662)
			(xy 380.070614 -279.756108) (xy 380.378711 -279.756108) (xy 380.382806 -279.70538) (xy 380.394985 -279.655966)
			(xy 380.414933 -279.609146) (xy 380.442134 -279.566132) (xy 380.475882 -279.528038) (xy 380.515304 -279.495851)
			(xy 380.559378 -279.470405) (xy 380.606964 -279.452358) (xy 380.656828 -279.442178) (xy 380.70768 -279.440129)
			(xy 380.758201 -279.446263) (xy 380.807085 -279.460423) (xy 380.853064 -279.48224) (xy 380.894948 -279.51115)
			(xy 380.931652 -279.546405) (xy 380.962225 -279.587091) (xy 380.985876 -279.632154) (xy 381.001992 -279.680428)
			(xy 381.010156 -279.730662) (xy 381.010668 -279.756108) (xy 381.010156 -279.781554) (xy 381.001992 -279.831788)
			(xy 380.985876 -279.880062) (xy 380.962225 -279.925125) (xy 380.931652 -279.965811) (xy 380.894948 -280.001066)
			(xy 380.853064 -280.029976) (xy 380.807085 -280.051793) (xy 380.758201 -280.065953) (xy 380.70768 -280.072087)
			(xy 380.656828 -280.070038) (xy 380.606964 -280.059858) (xy 380.559378 -280.041811) (xy 380.515304 -280.016365)
			(xy 380.475882 -279.984178) (xy 380.442134 -279.946084) (xy 380.414933 -279.90307) (xy 380.394985 -279.85625)
			(xy 380.382806 -279.806836) (xy 380.378711 -279.756108) (xy 380.070614 -279.756108) (xy 380.070102 -279.781554)
			(xy 380.061938 -279.831788) (xy 380.045822 -279.880062) (xy 380.022171 -279.925125) (xy 379.991598 -279.965811)
			(xy 379.954894 -280.001066) (xy 379.91301 -280.029976) (xy 379.867031 -280.051793) (xy 379.818147 -280.065953)
			(xy 379.767626 -280.072087) (xy 379.716774 -280.070038) (xy 379.66691 -280.059858) (xy 379.619324 -280.041811)
			(xy 379.57525 -280.016365) (xy 379.535828 -279.984178) (xy 379.50208 -279.946084) (xy 379.474879 -279.90307)
			(xy 379.454931 -279.85625) (xy 379.442752 -279.806836) (xy 379.438657 -279.756108) (xy 379.132846 -279.756108)
			(xy 379.132356 -279.781097) (xy 379.124537 -279.83046) (xy 379.109093 -279.877992) (xy 379.086403 -279.922524)
			(xy 379.057027 -279.962957) (xy 379.021687 -279.998297) (xy 378.981254 -280.027673) (xy 378.936722 -280.050363)
			(xy 378.88919 -280.065807) (xy 378.839827 -280.073626) (xy 378.789849 -280.073626) (xy 378.740486 -280.065807)
			(xy 378.692954 -280.050363) (xy 378.648422 -280.027673) (xy 378.607989 -279.998297) (xy 378.572649 -279.962957)
			(xy 378.543273 -279.922524) (xy 378.520583 -279.877992) (xy 378.505139 -279.83046) (xy 378.49732 -279.781097)
			(xy 378.190003 -279.781097) (xy 378.189994 -279.781554) (xy 378.18183 -279.831788) (xy 378.165714 -279.880062)
			(xy 378.142063 -279.925125) (xy 378.11149 -279.965811) (xy 378.074786 -280.001066) (xy 378.032902 -280.029976)
			(xy 377.986923 -280.051793) (xy 377.938039 -280.065953) (xy 377.887518 -280.072087) (xy 377.836666 -280.070038)
			(xy 377.786802 -280.059858) (xy 377.739216 -280.041811) (xy 377.695142 -280.016365) (xy 377.65572 -279.984178)
			(xy 377.621972 -279.946084) (xy 377.594771 -279.90307) (xy 377.574823 -279.85625) (xy 377.562644 -279.806836)
			(xy 377.558549 -279.756108) (xy 377.252738 -279.756108) (xy 377.252248 -279.781097) (xy 377.244429 -279.83046)
			(xy 377.228985 -279.877992) (xy 377.206295 -279.922524) (xy 377.176919 -279.962957) (xy 377.141579 -279.998297)
			(xy 377.101146 -280.027673) (xy 377.056614 -280.050363) (xy 377.009082 -280.065807) (xy 376.959719 -280.073626)
			(xy 376.909741 -280.073626) (xy 376.860378 -280.065807) (xy 376.812846 -280.050363) (xy 376.768314 -280.027673)
			(xy 376.727881 -279.998297) (xy 376.692541 -279.962957) (xy 376.663165 -279.922524) (xy 376.640475 -279.877992)
			(xy 376.625031 -279.83046) (xy 376.617212 -279.781097) (xy 376.310149 -279.781097) (xy 376.31014 -279.781554)
			(xy 376.301976 -279.831788) (xy 376.28586 -279.880062) (xy 376.262209 -279.925125) (xy 376.231636 -279.965811)
			(xy 376.194932 -280.001066) (xy 376.153048 -280.029976) (xy 376.107069 -280.051793) (xy 376.058185 -280.065953)
			(xy 376.007664 -280.072087) (xy 375.956812 -280.070038) (xy 375.906948 -280.059858) (xy 375.859362 -280.041811)
			(xy 375.815288 -280.016365) (xy 375.775866 -279.984178) (xy 375.742118 -279.946084) (xy 375.714917 -279.90307)
			(xy 375.694969 -279.85625) (xy 375.68279 -279.806836) (xy 375.678695 -279.756108) (xy 374.726454 -279.756108)
			(xy 374.726454 -280.238454) (xy 374.726616 -280.244958) (xy 374.729822 -280.257564) (xy 374.732804 -280.263346)
			(xy 374.747028 -280.288746) (xy 374.755156 -280.297382) (xy 374.760236 -280.300938) (xy 374.781745 -280.315812)
			(xy 374.820038 -280.351422) (xy 374.85199 -280.392817) (xy 374.876738 -280.438882) (xy 374.893617 -280.488374)
			(xy 374.90217 -280.539962) (xy 374.902169 -280.591103) (xy 375.207258 -280.591103) (xy 375.207258 -280.541125)
			(xy 375.215077 -280.491762) (xy 375.230521 -280.44423) (xy 375.253211 -280.399698) (xy 375.282587 -280.359265)
			(xy 375.317927 -280.323925) (xy 375.35836 -280.294549) (xy 375.402892 -280.271859) (xy 375.450424 -280.256415)
			(xy 375.499787 -280.248596) (xy 375.549765 -280.248596) (xy 375.599128 -280.256415) (xy 375.64666 -280.271859)
			(xy 375.691192 -280.294549) (xy 375.731625 -280.323925) (xy 375.766965 -280.359265) (xy 375.796341 -280.399698)
			(xy 375.819031 -280.44423) (xy 375.834475 -280.491762) (xy 375.842294 -280.541125) (xy 375.842784 -280.566114)
			(xy 376.148595 -280.566114) (xy 376.15269 -280.515386) (xy 376.164869 -280.465972) (xy 376.184817 -280.419152)
			(xy 376.212018 -280.376138) (xy 376.245766 -280.338044) (xy 376.285188 -280.305857) (xy 376.329262 -280.280411)
			(xy 376.376848 -280.262364) (xy 376.426712 -280.252184) (xy 376.477564 -280.250135) (xy 376.528085 -280.256269)
			(xy 376.576969 -280.270429) (xy 376.622948 -280.292246) (xy 376.664832 -280.321156) (xy 376.701536 -280.356411)
			(xy 376.732109 -280.397097) (xy 376.75576 -280.44216) (xy 376.771876 -280.490434) (xy 376.78004 -280.540668)
			(xy 376.780552 -280.566114) (xy 377.088649 -280.566114) (xy 377.092744 -280.515386) (xy 377.104923 -280.465972)
			(xy 377.124871 -280.419152) (xy 377.152072 -280.376138) (xy 377.18582 -280.338044) (xy 377.225242 -280.305857)
			(xy 377.269316 -280.280411) (xy 377.316902 -280.262364) (xy 377.366766 -280.252184) (xy 377.417618 -280.250135)
			(xy 377.468139 -280.256269) (xy 377.517023 -280.270429) (xy 377.563002 -280.292246) (xy 377.604886 -280.321156)
			(xy 377.64159 -280.356411) (xy 377.672163 -280.397097) (xy 377.695814 -280.44216) (xy 377.71193 -280.490434)
			(xy 377.720094 -280.540668) (xy 377.720606 -280.566114) (xy 378.968503 -280.566114) (xy 378.972598 -280.515386)
			(xy 378.984777 -280.465972) (xy 379.004725 -280.419152) (xy 379.031926 -280.376138) (xy 379.065674 -280.338044)
			(xy 379.105096 -280.305857) (xy 379.14917 -280.280411) (xy 379.196756 -280.262364) (xy 379.24662 -280.252184)
			(xy 379.297472 -280.250135) (xy 379.347993 -280.256269) (xy 379.396877 -280.270429) (xy 379.442856 -280.292246)
			(xy 379.48474 -280.321156) (xy 379.521444 -280.356411) (xy 379.552017 -280.397097) (xy 379.575668 -280.44216)
			(xy 379.591784 -280.490434) (xy 379.599948 -280.540668) (xy 379.60046 -280.566114) (xy 379.599957 -280.591103)
			(xy 379.907274 -280.591103) (xy 379.907274 -280.541125) (xy 379.915093 -280.491762) (xy 379.930537 -280.44423)
			(xy 379.953227 -280.399698) (xy 379.982603 -280.359265) (xy 380.017943 -280.323925) (xy 380.058376 -280.294549)
			(xy 380.102908 -280.271859) (xy 380.15044 -280.256415) (xy 380.199803 -280.248596) (xy 380.249781 -280.248596)
			(xy 380.299144 -280.256415) (xy 380.346676 -280.271859) (xy 380.391208 -280.294549) (xy 380.431641 -280.323925)
			(xy 380.466981 -280.359265) (xy 380.496357 -280.399698) (xy 380.519047 -280.44423) (xy 380.534491 -280.491762)
			(xy 380.54231 -280.541125) (xy 380.5428 -280.566114) (xy 380.54231 -280.591103) (xy 380.534491 -280.640466)
			(xy 380.519047 -280.687998) (xy 380.496357 -280.73253) (xy 380.466981 -280.772963) (xy 380.431641 -280.808303)
			(xy 380.391208 -280.837679) (xy 380.346676 -280.860369) (xy 380.299144 -280.875813) (xy 380.249781 -280.883632)
			(xy 380.199803 -280.883632) (xy 380.15044 -280.875813) (xy 380.102908 -280.860369) (xy 380.058376 -280.837679)
			(xy 380.017943 -280.808303) (xy 379.982603 -280.772963) (xy 379.953227 -280.73253) (xy 379.930537 -280.687998)
			(xy 379.915093 -280.640466) (xy 379.907274 -280.591103) (xy 379.599957 -280.591103) (xy 379.599948 -280.59156)
			(xy 379.591784 -280.641794) (xy 379.575668 -280.690068) (xy 379.552017 -280.735131) (xy 379.521444 -280.775817)
			(xy 379.48474 -280.811072) (xy 379.442856 -280.839982) (xy 379.396877 -280.861799) (xy 379.347993 -280.875959)
			(xy 379.297472 -280.882093) (xy 379.24662 -280.880044) (xy 379.196756 -280.869864) (xy 379.14917 -280.851817)
			(xy 379.105096 -280.826371) (xy 379.065674 -280.794184) (xy 379.031926 -280.75609) (xy 379.004725 -280.713076)
			(xy 378.984777 -280.666256) (xy 378.972598 -280.616842) (xy 378.968503 -280.566114) (xy 377.720606 -280.566114)
			(xy 377.720094 -280.59156) (xy 377.71193 -280.641794) (xy 377.695814 -280.690068) (xy 377.672163 -280.735131)
			(xy 377.64159 -280.775817) (xy 377.604886 -280.811072) (xy 377.563002 -280.839982) (xy 377.517023 -280.861799)
			(xy 377.468139 -280.875959) (xy 377.417618 -280.882093) (xy 377.366766 -280.880044) (xy 377.316902 -280.869864)
			(xy 377.269316 -280.851817) (xy 377.225242 -280.826371) (xy 377.18582 -280.794184) (xy 377.152072 -280.75609)
			(xy 377.124871 -280.713076) (xy 377.104923 -280.666256) (xy 377.092744 -280.616842) (xy 377.088649 -280.566114)
			(xy 376.780552 -280.566114) (xy 376.78004 -280.59156) (xy 376.771876 -280.641794) (xy 376.75576 -280.690068)
			(xy 376.732109 -280.735131) (xy 376.701536 -280.775817) (xy 376.664832 -280.811072) (xy 376.622948 -280.839982)
			(xy 376.576969 -280.861799) (xy 376.528085 -280.875959) (xy 376.477564 -280.882093) (xy 376.426712 -280.880044)
			(xy 376.376848 -280.869864) (xy 376.329262 -280.851817) (xy 376.285188 -280.826371) (xy 376.245766 -280.794184)
			(xy 376.212018 -280.75609) (xy 376.184817 -280.713076) (xy 376.164869 -280.666256) (xy 376.15269 -280.616842)
			(xy 376.148595 -280.566114) (xy 375.842784 -280.566114) (xy 375.842294 -280.591103) (xy 375.834475 -280.640466)
			(xy 375.819031 -280.687998) (xy 375.796341 -280.73253) (xy 375.766965 -280.772963) (xy 375.731625 -280.808303)
			(xy 375.691192 -280.837679) (xy 375.64666 -280.860369) (xy 375.599128 -280.875813) (xy 375.549765 -280.883632)
			(xy 375.499787 -280.883632) (xy 375.450424 -280.875813) (xy 375.402892 -280.860369) (xy 375.35836 -280.837679)
			(xy 375.317927 -280.808303) (xy 375.282587 -280.772963) (xy 375.253211 -280.73253) (xy 375.230521 -280.687998)
			(xy 375.215077 -280.640466) (xy 375.207258 -280.591103) (xy 374.902169 -280.591103) (xy 374.902169 -280.592254)
			(xy 374.893613 -280.643841) (xy 374.876732 -280.693333) (xy 374.851981 -280.739396) (xy 374.820028 -280.780789)
			(xy 374.781733 -280.816397) (xy 374.760236 -280.83129) (xy 374.755156 -280.834846) (xy 374.747028 -280.843482)
			(xy 374.732804 -280.868882) (xy 374.72982 -280.874665) (xy 374.726601 -280.887269) (xy 374.726454 -280.893774)
			(xy 374.726454 -281.025346) (xy 374.726844 -281.034449) (xy 374.733207 -281.05151) (xy 374.74509 -281.065306)
			(xy 374.75287 -281.07005) (xy 374.829324 -281.111452) (xy 374.835538 -281.114539) (xy 374.849057 -281.117637)
			(xy 374.855994 -281.117548) (xy 374.86971 -281.11704) (xy 374.881648 -281.10942) (xy 374.901078 -281.097277)
			(xy 374.942688 -281.078094) (xy 374.986621 -281.065084) (xy 375.031967 -281.058517) (xy 375.054876 -281.058112)
			(xy 375.06148 -281.058112) (xy 375.086128 -281.059087) (xy 375.134693 -281.067711) (xy 375.181344 -281.083732)
			(xy 375.224961 -281.106764) (xy 375.264499 -281.136256) (xy 375.299007 -281.1715) (xy 375.32766 -281.21165)
			(xy 375.349768 -281.255743) (xy 375.364802 -281.302721) (xy 375.3724 -281.351457) (xy 375.372884 -281.37612)
			(xy 375.678695 -281.37612) (xy 375.68279 -281.325392) (xy 375.694969 -281.275978) (xy 375.714917 -281.229158)
			(xy 375.742118 -281.186144) (xy 375.775866 -281.14805) (xy 375.815288 -281.115863) (xy 375.859362 -281.090417)
			(xy 375.906948 -281.07237) (xy 375.956812 -281.06219) (xy 376.007664 -281.060141) (xy 376.058185 -281.066275)
			(xy 376.107069 -281.080435) (xy 376.153048 -281.102252) (xy 376.194932 -281.131162) (xy 376.231636 -281.166417)
			(xy 376.262209 -281.207103) (xy 376.28586 -281.252166) (xy 376.301976 -281.30044) (xy 376.31014 -281.350674)
			(xy 376.310652 -281.37612) (xy 376.310149 -281.401109) (xy 376.617212 -281.401109) (xy 376.617212 -281.351131)
			(xy 376.625031 -281.301768) (xy 376.640475 -281.254236) (xy 376.663165 -281.209704) (xy 376.692541 -281.169271)
			(xy 376.727881 -281.133931) (xy 376.768314 -281.104555) (xy 376.812846 -281.081865) (xy 376.860378 -281.066421)
			(xy 376.909741 -281.058602) (xy 376.959719 -281.058602) (xy 377.009082 -281.066421) (xy 377.056614 -281.081865)
			(xy 377.101146 -281.104555) (xy 377.141579 -281.133931) (xy 377.176919 -281.169271) (xy 377.206295 -281.209704)
			(xy 377.228985 -281.254236) (xy 377.244429 -281.301768) (xy 377.252248 -281.351131) (xy 377.252738 -281.37612)
			(xy 377.558549 -281.37612) (xy 377.562644 -281.325392) (xy 377.574823 -281.275978) (xy 377.594771 -281.229158)
			(xy 377.621972 -281.186144) (xy 377.65572 -281.14805) (xy 377.695142 -281.115863) (xy 377.739216 -281.090417)
			(xy 377.786802 -281.07237) (xy 377.836666 -281.06219) (xy 377.887518 -281.060141) (xy 377.938039 -281.066275)
			(xy 377.986923 -281.080435) (xy 378.032902 -281.102252) (xy 378.074786 -281.131162) (xy 378.11149 -281.166417)
			(xy 378.142063 -281.207103) (xy 378.165714 -281.252166) (xy 378.18183 -281.30044) (xy 378.189994 -281.350674)
			(xy 378.190506 -281.37612) (xy 378.190003 -281.401109) (xy 378.49732 -281.401109) (xy 378.49732 -281.351131)
			(xy 378.505139 -281.301768) (xy 378.520583 -281.254236) (xy 378.543273 -281.209704) (xy 378.572649 -281.169271)
			(xy 378.607989 -281.133931) (xy 378.648422 -281.104555) (xy 378.692954 -281.081865) (xy 378.740486 -281.066421)
			(xy 378.789849 -281.058602) (xy 378.839827 -281.058602) (xy 378.88919 -281.066421) (xy 378.936722 -281.081865)
			(xy 378.981254 -281.104555) (xy 379.021687 -281.133931) (xy 379.057027 -281.169271) (xy 379.086403 -281.209704)
			(xy 379.109093 -281.254236) (xy 379.124537 -281.301768) (xy 379.132356 -281.351131) (xy 379.132846 -281.37612)
			(xy 379.438657 -281.37612) (xy 379.442752 -281.325392) (xy 379.454931 -281.275978) (xy 379.474879 -281.229158)
			(xy 379.50208 -281.186144) (xy 379.535828 -281.14805) (xy 379.57525 -281.115863) (xy 379.619324 -281.090417)
			(xy 379.66691 -281.07237) (xy 379.716774 -281.06219) (xy 379.767626 -281.060141) (xy 379.818147 -281.066275)
			(xy 379.867031 -281.080435) (xy 379.91301 -281.102252) (xy 379.954894 -281.131162) (xy 379.991598 -281.166417)
			(xy 380.022171 -281.207103) (xy 380.045822 -281.252166) (xy 380.061938 -281.30044) (xy 380.070102 -281.350674)
			(xy 380.070614 -281.37612) (xy 380.378711 -281.37612) (xy 380.382806 -281.325392) (xy 380.394985 -281.275978)
			(xy 380.414933 -281.229158) (xy 380.442134 -281.186144) (xy 380.475882 -281.14805) (xy 380.515304 -281.115863)
			(xy 380.559378 -281.090417) (xy 380.606964 -281.07237) (xy 380.656828 -281.06219) (xy 380.70768 -281.060141)
			(xy 380.758201 -281.066275) (xy 380.807085 -281.080435) (xy 380.853064 -281.102252) (xy 380.894948 -281.131162)
			(xy 380.931652 -281.166417) (xy 380.962225 -281.207103) (xy 380.985876 -281.252166) (xy 381.001992 -281.30044)
			(xy 381.010156 -281.350674) (xy 381.010668 -281.37612) (xy 381.010156 -281.401566) (xy 381.001992 -281.4518)
			(xy 380.985876 -281.500074) (xy 380.962225 -281.545137) (xy 380.931652 -281.585823) (xy 380.894948 -281.621078)
			(xy 380.853064 -281.649988) (xy 380.807085 -281.671805) (xy 380.758201 -281.685965) (xy 380.70768 -281.692099)
			(xy 380.656828 -281.69005) (xy 380.606964 -281.67987) (xy 380.559378 -281.661823) (xy 380.515304 -281.636377)
			(xy 380.475882 -281.60419) (xy 380.442134 -281.566096) (xy 380.414933 -281.523082) (xy 380.394985 -281.476262)
			(xy 380.382806 -281.426848) (xy 380.378711 -281.37612) (xy 380.070614 -281.37612) (xy 380.070102 -281.401566)
			(xy 380.061938 -281.4518) (xy 380.045822 -281.500074) (xy 380.022171 -281.545137) (xy 379.991598 -281.585823)
			(xy 379.954894 -281.621078) (xy 379.91301 -281.649988) (xy 379.867031 -281.671805) (xy 379.818147 -281.685965)
			(xy 379.767626 -281.692099) (xy 379.716774 -281.69005) (xy 379.66691 -281.67987) (xy 379.619324 -281.661823)
			(xy 379.57525 -281.636377) (xy 379.535828 -281.60419) (xy 379.50208 -281.566096) (xy 379.474879 -281.523082)
			(xy 379.454931 -281.476262) (xy 379.442752 -281.426848) (xy 379.438657 -281.37612) (xy 379.132846 -281.37612)
			(xy 379.132356 -281.401109) (xy 379.124537 -281.450472) (xy 379.109093 -281.498004) (xy 379.086403 -281.542536)
			(xy 379.057027 -281.582969) (xy 379.021687 -281.618309) (xy 378.981254 -281.647685) (xy 378.936722 -281.670375)
			(xy 378.88919 -281.685819) (xy 378.839827 -281.693638) (xy 378.789849 -281.693638) (xy 378.740486 -281.685819)
			(xy 378.692954 -281.670375) (xy 378.648422 -281.647685) (xy 378.607989 -281.618309) (xy 378.572649 -281.582969)
			(xy 378.543273 -281.542536) (xy 378.520583 -281.498004) (xy 378.505139 -281.450472) (xy 378.49732 -281.401109)
			(xy 378.190003 -281.401109) (xy 378.189994 -281.401566) (xy 378.18183 -281.4518) (xy 378.165714 -281.500074)
			(xy 378.142063 -281.545137) (xy 378.11149 -281.585823) (xy 378.074786 -281.621078) (xy 378.032902 -281.649988)
			(xy 377.986923 -281.671805) (xy 377.938039 -281.685965) (xy 377.887518 -281.692099) (xy 377.836666 -281.69005)
			(xy 377.786802 -281.67987) (xy 377.739216 -281.661823) (xy 377.695142 -281.636377) (xy 377.65572 -281.60419)
			(xy 377.621972 -281.566096) (xy 377.594771 -281.523082) (xy 377.574823 -281.476262) (xy 377.562644 -281.426848)
			(xy 377.558549 -281.37612) (xy 377.252738 -281.37612) (xy 377.252248 -281.401109) (xy 377.244429 -281.450472)
			(xy 377.228985 -281.498004) (xy 377.206295 -281.542536) (xy 377.176919 -281.582969) (xy 377.141579 -281.618309)
			(xy 377.101146 -281.647685) (xy 377.056614 -281.670375) (xy 377.009082 -281.685819) (xy 376.959719 -281.693638)
			(xy 376.909741 -281.693638) (xy 376.860378 -281.685819) (xy 376.812846 -281.670375) (xy 376.768314 -281.647685)
			(xy 376.727881 -281.618309) (xy 376.692541 -281.582969) (xy 376.663165 -281.542536) (xy 376.640475 -281.498004)
			(xy 376.625031 -281.450472) (xy 376.617212 -281.401109) (xy 376.310149 -281.401109) (xy 376.31014 -281.401566)
			(xy 376.301976 -281.4518) (xy 376.28586 -281.500074) (xy 376.262209 -281.545137) (xy 376.231636 -281.585823)
			(xy 376.194932 -281.621078) (xy 376.153048 -281.649988) (xy 376.107069 -281.671805) (xy 376.058185 -281.685965)
			(xy 376.007664 -281.692099) (xy 375.956812 -281.69005) (xy 375.906948 -281.67987) (xy 375.859362 -281.661823)
			(xy 375.815288 -281.636377) (xy 375.775866 -281.60419) (xy 375.742118 -281.566096) (xy 375.714917 -281.523082)
			(xy 375.694969 -281.476262) (xy 375.68279 -281.426848) (xy 375.678695 -281.37612) (xy 375.372884 -281.37612)
			(xy 375.372317 -281.40305) (xy 375.363243 -281.456141) (xy 375.345356 -281.506945) (xy 375.319169 -281.554011)
			(xy 375.285429 -281.595995) (xy 375.245101 -281.631696) (xy 375.222516 -281.646376) (xy 375.22277 -281.646376)
			(xy 375.203779 -281.65771) (xy 375.16333 -281.675591) (xy 375.120793 -281.687692) (xy 375.076989 -281.693779)
			(xy 375.054876 -281.694128) (xy 375.031967 -281.693727) (xy 374.986623 -281.687151) (xy 374.942692 -281.674137)
			(xy 374.901083 -281.654956) (xy 374.881648 -281.64282) (xy 374.88114 -281.642566) (xy 374.875385 -281.639181)
			(xy 374.862652 -281.635185) (xy 374.855994 -281.634692) (xy 374.84177 -281.63393) (xy 374.75287 -281.68219)
			(xy 374.74503 -281.686872) (xy 374.733072 -281.700655) (xy 374.72674 -281.717768) (xy 374.726454 -281.726894)
			(xy 374.726454 -281.858466) (xy 374.726617 -281.86497) (xy 374.729826 -281.877574) (xy 374.732804 -281.883358)
			(xy 374.747028 -281.908758) (xy 374.754902 -281.917394) (xy 374.760236 -281.92095) (xy 374.781193 -281.935435)
			(xy 374.81864 -281.96997) (xy 374.850114 -282.010024) (xy 374.874811 -282.054577) (xy 374.892104 -282.102493)
			(xy 374.901551 -282.15255) (xy 374.90273 -282.177998) (xy 374.90273 -282.186126) (xy 376.148595 -282.186126)
			(xy 376.15269 -282.135398) (xy 376.164869 -282.085984) (xy 376.184817 -282.039164) (xy 376.212018 -281.99615)
			(xy 376.245766 -281.958056) (xy 376.285188 -281.925869) (xy 376.329262 -281.900423) (xy 376.376848 -281.882376)
			(xy 376.426712 -281.872196) (xy 376.477564 -281.870147) (xy 376.528085 -281.876281) (xy 376.576969 -281.890441)
			(xy 376.622948 -281.912258) (xy 376.664832 -281.941168) (xy 376.701536 -281.976423) (xy 376.732109 -282.017109)
			(xy 376.75576 -282.062172) (xy 376.771876 -282.110446) (xy 376.78004 -282.16068) (xy 376.780552 -282.186126)
			(xy 377.088649 -282.186126) (xy 377.092744 -282.135398) (xy 377.104923 -282.085984) (xy 377.124871 -282.039164)
			(xy 377.152072 -281.99615) (xy 377.18582 -281.958056) (xy 377.225242 -281.925869) (xy 377.269316 -281.900423)
			(xy 377.316902 -281.882376) (xy 377.366766 -281.872196) (xy 377.417618 -281.870147) (xy 377.468139 -281.876281)
			(xy 377.517023 -281.890441) (xy 377.563002 -281.912258) (xy 377.604886 -281.941168) (xy 377.64159 -281.976423)
			(xy 377.672163 -282.017109) (xy 377.695814 -282.062172) (xy 377.71193 -282.110446) (xy 377.720094 -282.16068)
			(xy 377.720606 -282.186126) (xy 377.720103 -282.211115) (xy 378.02742 -282.211115) (xy 378.02742 -282.161137)
			(xy 378.035239 -282.111774) (xy 378.050683 -282.064242) (xy 378.073373 -282.01971) (xy 378.102749 -281.979277)
			(xy 378.138089 -281.943937) (xy 378.178522 -281.914561) (xy 378.223054 -281.891871) (xy 378.270586 -281.876427)
			(xy 378.319949 -281.868608) (xy 378.369927 -281.868608) (xy 378.41929 -281.876427) (xy 378.466822 -281.891871)
			(xy 378.511354 -281.914561) (xy 378.551787 -281.943937) (xy 378.587127 -281.979277) (xy 378.616503 -282.01971)
			(xy 378.639193 -282.064242) (xy 378.654637 -282.111774) (xy 378.662456 -282.161137) (xy 378.662946 -282.186126)
			(xy 378.968503 -282.186126) (xy 378.972598 -282.135398) (xy 378.984777 -282.085984) (xy 379.004725 -282.039164)
			(xy 379.031926 -281.99615) (xy 379.065674 -281.958056) (xy 379.105096 -281.925869) (xy 379.14917 -281.900423)
			(xy 379.196756 -281.882376) (xy 379.24662 -281.872196) (xy 379.297472 -281.870147) (xy 379.347993 -281.876281)
			(xy 379.396877 -281.890441) (xy 379.442856 -281.912258) (xy 379.48474 -281.941168) (xy 379.521444 -281.976423)
			(xy 379.552017 -282.017109) (xy 379.575668 -282.062172) (xy 379.591784 -282.110446) (xy 379.599948 -282.16068)
			(xy 379.60046 -282.186126) (xy 379.599957 -282.211115) (xy 379.907274 -282.211115) (xy 379.907274 -282.161137)
			(xy 379.915093 -282.111774) (xy 379.930537 -282.064242) (xy 379.953227 -282.01971) (xy 379.982603 -281.979277)
			(xy 380.017943 -281.943937) (xy 380.058376 -281.914561) (xy 380.102908 -281.891871) (xy 380.15044 -281.876427)
			(xy 380.199803 -281.868608) (xy 380.249781 -281.868608) (xy 380.299144 -281.876427) (xy 380.346676 -281.891871)
			(xy 380.391208 -281.914561) (xy 380.431641 -281.943937) (xy 380.466981 -281.979277) (xy 380.496357 -282.01971)
			(xy 380.519047 -282.064242) (xy 380.534491 -282.111774) (xy 380.54231 -282.161137) (xy 380.5428 -282.186126)
			(xy 380.54231 -282.211115) (xy 380.534491 -282.260478) (xy 380.519047 -282.30801) (xy 380.496357 -282.352542)
			(xy 380.466981 -282.392975) (xy 380.431641 -282.428315) (xy 380.391208 -282.457691) (xy 380.346676 -282.480381)
			(xy 380.299144 -282.495825) (xy 380.249781 -282.503644) (xy 380.199803 -282.503644) (xy 380.15044 -282.495825)
			(xy 380.102908 -282.480381) (xy 380.058376 -282.457691) (xy 380.017943 -282.428315) (xy 379.982603 -282.392975)
			(xy 379.953227 -282.352542) (xy 379.930537 -282.30801) (xy 379.915093 -282.260478) (xy 379.907274 -282.211115)
			(xy 379.599957 -282.211115) (xy 379.599948 -282.211572) (xy 379.591784 -282.261806) (xy 379.575668 -282.31008)
			(xy 379.552017 -282.355143) (xy 379.521444 -282.395829) (xy 379.48474 -282.431084) (xy 379.442856 -282.459994)
			(xy 379.396877 -282.481811) (xy 379.347993 -282.495971) (xy 379.297472 -282.502105) (xy 379.24662 -282.500056)
			(xy 379.196756 -282.489876) (xy 379.14917 -282.471829) (xy 379.105096 -282.446383) (xy 379.065674 -282.414196)
			(xy 379.031926 -282.376102) (xy 379.004725 -282.333088) (xy 378.984777 -282.286268) (xy 378.972598 -282.236854)
			(xy 378.968503 -282.186126) (xy 378.662946 -282.186126) (xy 378.662456 -282.211115) (xy 378.654637 -282.260478)
			(xy 378.639193 -282.30801) (xy 378.616503 -282.352542) (xy 378.587127 -282.392975) (xy 378.551787 -282.428315)
			(xy 378.511354 -282.457691) (xy 378.466822 -282.480381) (xy 378.41929 -282.495825) (xy 378.369927 -282.503644)
			(xy 378.319949 -282.503644) (xy 378.270586 -282.495825) (xy 378.223054 -282.480381) (xy 378.178522 -282.457691)
			(xy 378.138089 -282.428315) (xy 378.102749 -282.392975) (xy 378.073373 -282.352542) (xy 378.050683 -282.30801)
			(xy 378.035239 -282.260478) (xy 378.02742 -282.211115) (xy 377.720103 -282.211115) (xy 377.720094 -282.211572)
			(xy 377.71193 -282.261806) (xy 377.695814 -282.31008) (xy 377.672163 -282.355143) (xy 377.64159 -282.395829)
			(xy 377.604886 -282.431084) (xy 377.563002 -282.459994) (xy 377.517023 -282.481811) (xy 377.468139 -282.495971)
			(xy 377.417618 -282.502105) (xy 377.366766 -282.500056) (xy 377.316902 -282.489876) (xy 377.269316 -282.471829)
			(xy 377.225242 -282.446383) (xy 377.18582 -282.414196) (xy 377.152072 -282.376102) (xy 377.124871 -282.333088)
			(xy 377.104923 -282.286268) (xy 377.092744 -282.236854) (xy 377.088649 -282.186126) (xy 376.780552 -282.186126)
			(xy 376.78004 -282.211572) (xy 376.771876 -282.261806) (xy 376.75576 -282.31008) (xy 376.732109 -282.355143)
			(xy 376.701536 -282.395829) (xy 376.664832 -282.431084) (xy 376.622948 -282.459994) (xy 376.576969 -282.481811)
			(xy 376.528085 -282.495971) (xy 376.477564 -282.502105) (xy 376.426712 -282.500056) (xy 376.376848 -282.489876)
			(xy 376.329262 -282.471829) (xy 376.285188 -282.446383) (xy 376.245766 -282.414196) (xy 376.212018 -282.376102)
			(xy 376.184817 -282.333088) (xy 376.164869 -282.286268) (xy 376.15269 -282.236854) (xy 376.148595 -282.186126)
			(xy 374.90273 -282.186126) (xy 374.902276 -282.210397) (xy 374.894907 -282.258375) (xy 374.880327 -282.304675)
			(xy 374.858876 -282.34822) (xy 374.831054 -282.387996) (xy 374.814592 -282.405836) (xy 374.814592 -282.40609)
			(xy 374.808103 -282.413554) (xy 374.80085 -282.431933) (xy 374.80105 -282.451691) (xy 374.808674 -282.46992)
			(xy 374.815354 -282.47721) (xy 375.00179 -282.663646) (xy 375.009596 -282.670661) (xy 375.02914 -282.678249)
			(xy 375.039636 -282.678378) (xy 375.054876 -282.678124) (xy 375.079868 -282.678587) (xy 375.129236 -282.686403)
			(xy 375.176773 -282.701847) (xy 375.221308 -282.724538) (xy 375.261746 -282.753917) (xy 375.297088 -282.789261)
			(xy 375.326466 -282.829698) (xy 375.349156 -282.874235) (xy 375.364599 -282.921772) (xy 375.372413 -282.97114)
			(xy 375.372884 -282.996132) (xy 375.678695 -282.996132) (xy 375.68279 -282.945404) (xy 375.694969 -282.89599)
			(xy 375.714917 -282.84917) (xy 375.742118 -282.806156) (xy 375.775866 -282.768062) (xy 375.815288 -282.735875)
			(xy 375.859362 -282.710429) (xy 375.906948 -282.692382) (xy 375.956812 -282.682202) (xy 376.007664 -282.680153)
			(xy 376.058185 -282.686287) (xy 376.107069 -282.700447) (xy 376.153048 -282.722264) (xy 376.194932 -282.751174)
			(xy 376.231636 -282.786429) (xy 376.262209 -282.827115) (xy 376.28586 -282.872178) (xy 376.301976 -282.920452)
			(xy 376.31014 -282.970686) (xy 376.310652 -282.996132) (xy 376.310149 -283.021121) (xy 376.617212 -283.021121)
			(xy 376.617212 -282.971143) (xy 376.625031 -282.92178) (xy 376.640475 -282.874248) (xy 376.663165 -282.829716)
			(xy 376.692541 -282.789283) (xy 376.727881 -282.753943) (xy 376.768314 -282.724567) (xy 376.812846 -282.701877)
			(xy 376.860378 -282.686433) (xy 376.909741 -282.678614) (xy 376.959719 -282.678614) (xy 377.009082 -282.686433)
			(xy 377.056614 -282.701877) (xy 377.101146 -282.724567) (xy 377.141579 -282.753943) (xy 377.176919 -282.789283)
			(xy 377.206295 -282.829716) (xy 377.228985 -282.874248) (xy 377.244429 -282.92178) (xy 377.252248 -282.971143)
			(xy 377.252738 -282.996132) (xy 377.558549 -282.996132) (xy 377.562644 -282.945404) (xy 377.574823 -282.89599)
			(xy 377.594771 -282.84917) (xy 377.621972 -282.806156) (xy 377.65572 -282.768062) (xy 377.695142 -282.735875)
			(xy 377.739216 -282.710429) (xy 377.786802 -282.692382) (xy 377.836666 -282.682202) (xy 377.887518 -282.680153)
			(xy 377.938039 -282.686287) (xy 377.986923 -282.700447) (xy 378.032902 -282.722264) (xy 378.074786 -282.751174)
			(xy 378.11149 -282.786429) (xy 378.142063 -282.827115) (xy 378.165714 -282.872178) (xy 378.18183 -282.920452)
			(xy 378.189994 -282.970686) (xy 378.190506 -282.996132) (xy 379.438657 -282.996132) (xy 379.442752 -282.945404)
			(xy 379.454931 -282.89599) (xy 379.474879 -282.84917) (xy 379.50208 -282.806156) (xy 379.535828 -282.768062)
			(xy 379.57525 -282.735875) (xy 379.619324 -282.710429) (xy 379.66691 -282.692382) (xy 379.716774 -282.682202)
			(xy 379.767626 -282.680153) (xy 379.818147 -282.686287) (xy 379.867031 -282.700447) (xy 379.91301 -282.722264)
			(xy 379.954894 -282.751174) (xy 379.991598 -282.786429) (xy 380.022171 -282.827115) (xy 380.045822 -282.872178)
			(xy 380.061938 -282.920452) (xy 380.070102 -282.970686) (xy 380.070614 -282.996132) (xy 380.378711 -282.996132)
			(xy 380.382806 -282.945404) (xy 380.394985 -282.89599) (xy 380.414933 -282.84917) (xy 380.442134 -282.806156)
			(xy 380.475882 -282.768062) (xy 380.515304 -282.735875) (xy 380.559378 -282.710429) (xy 380.606964 -282.692382)
			(xy 380.656828 -282.682202) (xy 380.70768 -282.680153) (xy 380.758201 -282.686287) (xy 380.807085 -282.700447)
			(xy 380.853064 -282.722264) (xy 380.894948 -282.751174) (xy 380.931652 -282.786429) (xy 380.962225 -282.827115)
			(xy 380.985876 -282.872178) (xy 381.001992 -282.920452) (xy 381.010156 -282.970686) (xy 381.010668 -282.996132)
			(xy 381.010156 -283.021578) (xy 381.001992 -283.071812) (xy 380.985876 -283.120086) (xy 380.962225 -283.165149)
			(xy 380.931652 -283.205835) (xy 380.894948 -283.24109) (xy 380.853064 -283.27) (xy 380.807085 -283.291817)
			(xy 380.758201 -283.305977) (xy 380.70768 -283.312111) (xy 380.656828 -283.310062) (xy 380.606964 -283.299882)
			(xy 380.559378 -283.281835) (xy 380.515304 -283.256389) (xy 380.475882 -283.224202) (xy 380.442134 -283.186108)
			(xy 380.414933 -283.143094) (xy 380.394985 -283.096274) (xy 380.382806 -283.04686) (xy 380.378711 -282.996132)
			(xy 380.070614 -282.996132) (xy 380.070102 -283.021578) (xy 380.061938 -283.071812) (xy 380.045822 -283.120086)
			(xy 380.022171 -283.165149) (xy 379.991598 -283.205835) (xy 379.954894 -283.24109) (xy 379.91301 -283.27)
			(xy 379.867031 -283.291817) (xy 379.818147 -283.305977) (xy 379.767626 -283.312111) (xy 379.716774 -283.310062)
			(xy 379.66691 -283.299882) (xy 379.619324 -283.281835) (xy 379.57525 -283.256389) (xy 379.535828 -283.224202)
			(xy 379.50208 -283.186108) (xy 379.474879 -283.143094) (xy 379.454931 -283.096274) (xy 379.442752 -283.04686)
			(xy 379.438657 -282.996132) (xy 378.190506 -282.996132) (xy 378.189994 -283.021578) (xy 378.18183 -283.071812)
			(xy 378.165714 -283.120086) (xy 378.142063 -283.165149) (xy 378.11149 -283.205835) (xy 378.074786 -283.24109)
			(xy 378.032902 -283.27) (xy 377.986923 -283.291817) (xy 377.938039 -283.305977) (xy 377.887518 -283.312111)
			(xy 377.836666 -283.310062) (xy 377.786802 -283.299882) (xy 377.739216 -283.281835) (xy 377.695142 -283.256389)
			(xy 377.65572 -283.224202) (xy 377.621972 -283.186108) (xy 377.594771 -283.143094) (xy 377.574823 -283.096274)
			(xy 377.562644 -283.04686) (xy 377.558549 -282.996132) (xy 377.252738 -282.996132) (xy 377.252248 -283.021121)
			(xy 377.244429 -283.070484) (xy 377.228985 -283.118016) (xy 377.206295 -283.162548) (xy 377.176919 -283.202981)
			(xy 377.141579 -283.238321) (xy 377.101146 -283.267697) (xy 377.056614 -283.290387) (xy 377.009082 -283.305831)
			(xy 376.959719 -283.31365) (xy 376.909741 -283.31365) (xy 376.860378 -283.305831) (xy 376.812846 -283.290387)
			(xy 376.768314 -283.267697) (xy 376.727881 -283.238321) (xy 376.692541 -283.202981) (xy 376.663165 -283.162548)
			(xy 376.640475 -283.118016) (xy 376.625031 -283.070484) (xy 376.617212 -283.021121) (xy 376.310149 -283.021121)
			(xy 376.31014 -283.021578) (xy 376.301976 -283.071812) (xy 376.28586 -283.120086) (xy 376.262209 -283.165149)
			(xy 376.231636 -283.205835) (xy 376.194932 -283.24109) (xy 376.153048 -283.27) (xy 376.107069 -283.291817)
			(xy 376.058185 -283.305977) (xy 376.007664 -283.312111) (xy 375.956812 -283.310062) (xy 375.906948 -283.299882)
			(xy 375.859362 -283.281835) (xy 375.815288 -283.256389) (xy 375.775866 -283.224202) (xy 375.742118 -283.186108)
			(xy 375.714917 -283.143094) (xy 375.694969 -283.096274) (xy 375.68279 -283.04686) (xy 375.678695 -282.996132)
			(xy 375.372884 -282.996132) (xy 375.372297 -283.023661) (xy 375.362815 -283.077897) (xy 375.34414 -283.129691)
			(xy 375.316828 -283.177498) (xy 375.281696 -283.219891) (xy 375.261124 -283.238194) (xy 375.25706 -283.24175)
			(xy 375.25071 -283.249878) (xy 375.239534 -283.2735) (xy 375.237214 -283.278663) (xy 375.234655 -283.289687)
			(xy 375.234454 -283.295344) (xy 375.234454 -283.43352) (xy 375.234787 -283.442162) (xy 375.240529 -283.458463)
			(xy 375.251383 -283.471913) (xy 375.258584 -283.4767) (xy 375.341896 -283.527754) (xy 375.368058 -283.529024)
			(xy 375.379996 -283.522674) (xy 375.402419 -283.51177) (xy 375.449839 -283.496369) (xy 375.499085 -283.488581)
			(xy 375.524014 -283.48813) (xy 375.53011 -283.48813) (xy 375.554825 -283.489013) (xy 375.603547 -283.497482)
			(xy 375.650371 -283.513392) (xy 375.694168 -283.536358) (xy 375.733881 -283.565827) (xy 375.768555 -283.601089)
			(xy 375.797352 -283.641292) (xy 375.819578 -283.685469) (xy 375.834698 -283.732554) (xy 375.842348 -283.781411)
			(xy 375.842784 -283.806138) (xy 376.148595 -283.806138) (xy 376.15269 -283.75541) (xy 376.164869 -283.705996)
			(xy 376.184817 -283.659176) (xy 376.212018 -283.616162) (xy 376.245766 -283.578068) (xy 376.285188 -283.545881)
			(xy 376.329262 -283.520435) (xy 376.376848 -283.502388) (xy 376.426712 -283.492208) (xy 376.477564 -283.490159)
			(xy 376.528085 -283.496293) (xy 376.576969 -283.510453) (xy 376.622948 -283.53227) (xy 376.664832 -283.56118)
			(xy 376.701536 -283.596435) (xy 376.732109 -283.637121) (xy 376.75576 -283.682184) (xy 376.771876 -283.730458)
			(xy 376.78004 -283.780692) (xy 376.780552 -283.806138) (xy 377.088649 -283.806138) (xy 377.092744 -283.75541)
			(xy 377.104923 -283.705996) (xy 377.124871 -283.659176) (xy 377.152072 -283.616162) (xy 377.18582 -283.578068)
			(xy 377.225242 -283.545881) (xy 377.269316 -283.520435) (xy 377.316902 -283.502388) (xy 377.366766 -283.492208)
			(xy 377.417618 -283.490159) (xy 377.468139 -283.496293) (xy 377.517023 -283.510453) (xy 377.563002 -283.53227)
			(xy 377.604886 -283.56118) (xy 377.64159 -283.596435) (xy 377.672163 -283.637121) (xy 377.695814 -283.682184)
			(xy 377.71193 -283.730458) (xy 377.720094 -283.780692) (xy 377.720606 -283.806138) (xy 377.720103 -283.831127)
			(xy 378.02742 -283.831127) (xy 378.02742 -283.781149) (xy 378.035239 -283.731786) (xy 378.050683 -283.684254)
			(xy 378.073373 -283.639722) (xy 378.102749 -283.599289) (xy 378.138089 -283.563949) (xy 378.178522 -283.534573)
			(xy 378.223054 -283.511883) (xy 378.270586 -283.496439) (xy 378.319949 -283.48862) (xy 378.369927 -283.48862)
			(xy 378.41929 -283.496439) (xy 378.466822 -283.511883) (xy 378.511354 -283.534573) (xy 378.551787 -283.563949)
			(xy 378.587127 -283.599289) (xy 378.616503 -283.639722) (xy 378.639193 -283.684254) (xy 378.654637 -283.731786)
			(xy 378.662456 -283.781149) (xy 378.662946 -283.806138) (xy 378.968503 -283.806138) (xy 378.972598 -283.75541)
			(xy 378.984777 -283.705996) (xy 379.004725 -283.659176) (xy 379.031926 -283.616162) (xy 379.065674 -283.578068)
			(xy 379.105096 -283.545881) (xy 379.14917 -283.520435) (xy 379.196756 -283.502388) (xy 379.24662 -283.492208)
			(xy 379.297472 -283.490159) (xy 379.347993 -283.496293) (xy 379.396877 -283.510453) (xy 379.442856 -283.53227)
			(xy 379.48474 -283.56118) (xy 379.521444 -283.596435) (xy 379.552017 -283.637121) (xy 379.575668 -283.682184)
			(xy 379.591784 -283.730458) (xy 379.599948 -283.780692) (xy 379.60046 -283.806138) (xy 379.599957 -283.831127)
			(xy 379.907274 -283.831127) (xy 379.907274 -283.781149) (xy 379.915093 -283.731786) (xy 379.930537 -283.684254)
			(xy 379.953227 -283.639722) (xy 379.982603 -283.599289) (xy 380.017943 -283.563949) (xy 380.058376 -283.534573)
			(xy 380.102908 -283.511883) (xy 380.15044 -283.496439) (xy 380.199803 -283.48862) (xy 380.249781 -283.48862)
			(xy 380.299144 -283.496439) (xy 380.346676 -283.511883) (xy 380.391208 -283.534573) (xy 380.431641 -283.563949)
			(xy 380.466981 -283.599289) (xy 380.496357 -283.639722) (xy 380.519047 -283.684254) (xy 380.534491 -283.731786)
			(xy 380.54231 -283.781149) (xy 380.5428 -283.806138) (xy 380.54231 -283.831127) (xy 380.534491 -283.88049)
			(xy 380.519047 -283.928022) (xy 380.496357 -283.972554) (xy 380.466981 -284.012987) (xy 380.431641 -284.048327)
			(xy 380.391208 -284.077703) (xy 380.346676 -284.100393) (xy 380.299144 -284.115837) (xy 380.249781 -284.123656)
			(xy 380.199803 -284.123656) (xy 380.15044 -284.115837) (xy 380.102908 -284.100393) (xy 380.058376 -284.077703)
			(xy 380.017943 -284.048327) (xy 379.982603 -284.012987) (xy 379.953227 -283.972554) (xy 379.930537 -283.928022)
			(xy 379.915093 -283.88049) (xy 379.907274 -283.831127) (xy 379.599957 -283.831127) (xy 379.599948 -283.831584)
			(xy 379.591784 -283.881818) (xy 379.575668 -283.930092) (xy 379.552017 -283.975155) (xy 379.521444 -284.015841)
			(xy 379.48474 -284.051096) (xy 379.442856 -284.080006) (xy 379.396877 -284.101823) (xy 379.347993 -284.115983)
			(xy 379.297472 -284.122117) (xy 379.24662 -284.120068) (xy 379.196756 -284.109888) (xy 379.14917 -284.091841)
			(xy 379.105096 -284.066395) (xy 379.065674 -284.034208) (xy 379.031926 -283.996114) (xy 379.004725 -283.9531)
			(xy 378.984777 -283.90628) (xy 378.972598 -283.856866) (xy 378.968503 -283.806138) (xy 378.662946 -283.806138)
			(xy 378.662456 -283.831127) (xy 378.654637 -283.88049) (xy 378.639193 -283.928022) (xy 378.616503 -283.972554)
			(xy 378.587127 -284.012987) (xy 378.551787 -284.048327) (xy 378.511354 -284.077703) (xy 378.466822 -284.100393)
			(xy 378.41929 -284.115837) (xy 378.369927 -284.123656) (xy 378.319949 -284.123656) (xy 378.270586 -284.115837)
			(xy 378.223054 -284.100393) (xy 378.178522 -284.077703) (xy 378.138089 -284.048327) (xy 378.102749 -284.012987)
			(xy 378.073373 -283.972554) (xy 378.050683 -283.928022) (xy 378.035239 -283.88049) (xy 378.02742 -283.831127)
			(xy 377.720103 -283.831127) (xy 377.720094 -283.831584) (xy 377.71193 -283.881818) (xy 377.695814 -283.930092)
			(xy 377.672163 -283.975155) (xy 377.64159 -284.015841) (xy 377.604886 -284.051096) (xy 377.563002 -284.080006)
			(xy 377.517023 -284.101823) (xy 377.468139 -284.115983) (xy 377.417618 -284.122117) (xy 377.366766 -284.120068)
			(xy 377.316902 -284.109888) (xy 377.269316 -284.091841) (xy 377.225242 -284.066395) (xy 377.18582 -284.034208)
			(xy 377.152072 -283.996114) (xy 377.124871 -283.9531) (xy 377.104923 -283.90628) (xy 377.092744 -283.856866)
			(xy 377.088649 -283.806138) (xy 376.780552 -283.806138) (xy 376.78004 -283.831584) (xy 376.771876 -283.881818)
			(xy 376.75576 -283.930092) (xy 376.732109 -283.975155) (xy 376.701536 -284.015841) (xy 376.664832 -284.051096)
			(xy 376.622948 -284.080006) (xy 376.576969 -284.101823) (xy 376.528085 -284.115983) (xy 376.477564 -284.122117)
			(xy 376.426712 -284.120068) (xy 376.376848 -284.109888) (xy 376.329262 -284.091841) (xy 376.285188 -284.066395)
			(xy 376.245766 -284.034208) (xy 376.212018 -283.996114) (xy 376.184817 -283.9531) (xy 376.164869 -283.90628)
			(xy 376.15269 -283.856866) (xy 376.148595 -283.806138) (xy 375.842784 -283.806138) (xy 375.842291 -283.831125)
			(xy 375.834468 -283.880482) (xy 375.81902 -283.928007) (xy 375.796328 -283.972531) (xy 375.76695 -284.012957)
			(xy 375.73161 -284.04829) (xy 375.691178 -284.07766) (xy 375.64665 -284.100344) (xy 375.599121 -284.115782)
			(xy 375.549763 -284.123596) (xy 375.524776 -284.124146) (xy 375.524522 -284.124146) (xy 375.499513 -284.123669)
			(xy 375.450106 -284.115883) (xy 375.402519 -284.100482) (xy 375.379996 -284.089602) (xy 375.368058 -284.083252)
			(xy 375.341896 -284.084522) (xy 375.258584 -284.135576) (xy 375.251389 -284.140436) (xy 375.240519 -284.153961)
			(xy 375.234775 -284.170334) (xy 375.234454 -284.17901) (xy 375.234454 -284.316932) (xy 375.234638 -284.322591)
			(xy 375.237205 -284.333615) (xy 375.239534 -284.338776) (xy 375.25071 -284.362398) (xy 375.25706 -284.370526)
			(xy 375.261124 -284.374082) (xy 375.279867 -284.390667) (xy 375.312405 -284.428693) (xy 375.338584 -284.471347)
			(xy 375.357758 -284.517575) (xy 375.369453 -284.566236) (xy 375.373381 -284.616129) (xy 375.37338 -284.616144)
			(xy 375.678695 -284.616144) (xy 375.68279 -284.565416) (xy 375.694969 -284.516002) (xy 375.714917 -284.469182)
			(xy 375.742118 -284.426168) (xy 375.775866 -284.388074) (xy 375.815288 -284.355887) (xy 375.859362 -284.330441)
			(xy 375.906948 -284.312394) (xy 375.956812 -284.302214) (xy 376.007664 -284.300165) (xy 376.058185 -284.306299)
			(xy 376.107069 -284.320459) (xy 376.153048 -284.342276) (xy 376.194932 -284.371186) (xy 376.231636 -284.406441)
			(xy 376.262209 -284.447127) (xy 376.28586 -284.49219) (xy 376.301976 -284.540464) (xy 376.31014 -284.590698)
			(xy 376.310652 -284.616144) (xy 376.310149 -284.641133) (xy 376.617212 -284.641133) (xy 376.617212 -284.591155)
			(xy 376.625031 -284.541792) (xy 376.640475 -284.49426) (xy 376.663165 -284.449728) (xy 376.692541 -284.409295)
			(xy 376.727881 -284.373955) (xy 376.768314 -284.344579) (xy 376.812846 -284.321889) (xy 376.860378 -284.306445)
			(xy 376.909741 -284.298626) (xy 376.959719 -284.298626) (xy 377.009082 -284.306445) (xy 377.056614 -284.321889)
			(xy 377.101146 -284.344579) (xy 377.141579 -284.373955) (xy 377.176919 -284.409295) (xy 377.206295 -284.449728)
			(xy 377.228985 -284.49426) (xy 377.244429 -284.541792) (xy 377.252248 -284.591155) (xy 377.252738 -284.616144)
			(xy 377.558549 -284.616144) (xy 377.562644 -284.565416) (xy 377.574823 -284.516002) (xy 377.594771 -284.469182)
			(xy 377.621972 -284.426168) (xy 377.65572 -284.388074) (xy 377.695142 -284.355887) (xy 377.739216 -284.330441)
			(xy 377.786802 -284.312394) (xy 377.836666 -284.302214) (xy 377.887518 -284.300165) (xy 377.938039 -284.306299)
			(xy 377.986923 -284.320459) (xy 378.032902 -284.342276) (xy 378.074786 -284.371186) (xy 378.11149 -284.406441)
			(xy 378.142063 -284.447127) (xy 378.165714 -284.49219) (xy 378.18183 -284.540464) (xy 378.189994 -284.590698)
			(xy 378.190506 -284.616144) (xy 378.190003 -284.641133) (xy 378.49732 -284.641133) (xy 378.49732 -284.591155)
			(xy 378.505139 -284.541792) (xy 378.520583 -284.49426) (xy 378.543273 -284.449728) (xy 378.572649 -284.409295)
			(xy 378.607989 -284.373955) (xy 378.648422 -284.344579) (xy 378.692954 -284.321889) (xy 378.740486 -284.306445)
			(xy 378.789849 -284.298626) (xy 378.839827 -284.298626) (xy 378.88919 -284.306445) (xy 378.936722 -284.321889)
			(xy 378.981254 -284.344579) (xy 379.021687 -284.373955) (xy 379.057027 -284.409295) (xy 379.086403 -284.449728)
			(xy 379.109093 -284.49426) (xy 379.124537 -284.541792) (xy 379.132356 -284.591155) (xy 379.132846 -284.616144)
			(xy 379.438657 -284.616144) (xy 379.442752 -284.565416) (xy 379.454931 -284.516002) (xy 379.474879 -284.469182)
			(xy 379.50208 -284.426168) (xy 379.535828 -284.388074) (xy 379.57525 -284.355887) (xy 379.619324 -284.330441)
			(xy 379.66691 -284.312394) (xy 379.716774 -284.302214) (xy 379.767626 -284.300165) (xy 379.818147 -284.306299)
			(xy 379.867031 -284.320459) (xy 379.91301 -284.342276) (xy 379.954894 -284.371186) (xy 379.991598 -284.406441)
			(xy 380.022171 -284.447127) (xy 380.045822 -284.49219) (xy 380.061938 -284.540464) (xy 380.070102 -284.590698)
			(xy 380.070614 -284.616144) (xy 380.378711 -284.616144) (xy 380.382806 -284.565416) (xy 380.394985 -284.516002)
			(xy 380.414933 -284.469182) (xy 380.442134 -284.426168) (xy 380.475882 -284.388074) (xy 380.515304 -284.355887)
			(xy 380.559378 -284.330441) (xy 380.606964 -284.312394) (xy 380.656828 -284.302214) (xy 380.70768 -284.300165)
			(xy 380.758201 -284.306299) (xy 380.807085 -284.320459) (xy 380.853064 -284.342276) (xy 380.894948 -284.371186)
			(xy 380.931652 -284.406441) (xy 380.962225 -284.447127) (xy 380.985876 -284.49219) (xy 381.001992 -284.540464)
			(xy 381.010156 -284.590698) (xy 381.010668 -284.616144) (xy 381.010156 -284.64159) (xy 381.001992 -284.691824)
			(xy 380.985876 -284.740098) (xy 380.962225 -284.785161) (xy 380.931652 -284.825847) (xy 380.894948 -284.861102)
			(xy 380.853064 -284.890012) (xy 380.807085 -284.911829) (xy 380.758201 -284.925989) (xy 380.70768 -284.932123)
			(xy 380.656828 -284.930074) (xy 380.606964 -284.919894) (xy 380.559378 -284.901847) (xy 380.515304 -284.876401)
			(xy 380.475882 -284.844214) (xy 380.442134 -284.80612) (xy 380.414933 -284.763106) (xy 380.394985 -284.716286)
			(xy 380.382806 -284.666872) (xy 380.378711 -284.616144) (xy 380.070614 -284.616144) (xy 380.070102 -284.64159)
			(xy 380.061938 -284.691824) (xy 380.045822 -284.740098) (xy 380.022171 -284.785161) (xy 379.991598 -284.825847)
			(xy 379.954894 -284.861102) (xy 379.91301 -284.890012) (xy 379.867031 -284.911829) (xy 379.818147 -284.925989)
			(xy 379.767626 -284.932123) (xy 379.716774 -284.930074) (xy 379.66691 -284.919894) (xy 379.619324 -284.901847)
			(xy 379.57525 -284.876401) (xy 379.535828 -284.844214) (xy 379.50208 -284.80612) (xy 379.474879 -284.763106)
			(xy 379.454931 -284.716286) (xy 379.442752 -284.666872) (xy 379.438657 -284.616144) (xy 379.132846 -284.616144)
			(xy 379.132356 -284.641133) (xy 379.124537 -284.690496) (xy 379.109093 -284.738028) (xy 379.086403 -284.78256)
			(xy 379.057027 -284.822993) (xy 379.021687 -284.858333) (xy 378.981254 -284.887709) (xy 378.936722 -284.910399)
			(xy 378.88919 -284.925843) (xy 378.839827 -284.933662) (xy 378.789849 -284.933662) (xy 378.740486 -284.925843)
			(xy 378.692954 -284.910399) (xy 378.648422 -284.887709) (xy 378.607989 -284.858333) (xy 378.572649 -284.822993)
			(xy 378.543273 -284.78256) (xy 378.520583 -284.738028) (xy 378.505139 -284.690496) (xy 378.49732 -284.641133)
			(xy 378.190003 -284.641133) (xy 378.189994 -284.64159) (xy 378.18183 -284.691824) (xy 378.165714 -284.740098)
			(xy 378.142063 -284.785161) (xy 378.11149 -284.825847) (xy 378.074786 -284.861102) (xy 378.032902 -284.890012)
			(xy 377.986923 -284.911829) (xy 377.938039 -284.925989) (xy 377.887518 -284.932123) (xy 377.836666 -284.930074)
			(xy 377.786802 -284.919894) (xy 377.739216 -284.901847) (xy 377.695142 -284.876401) (xy 377.65572 -284.844214)
			(xy 377.621972 -284.80612) (xy 377.594771 -284.763106) (xy 377.574823 -284.716286) (xy 377.562644 -284.666872)
			(xy 377.558549 -284.616144) (xy 377.252738 -284.616144) (xy 377.252248 -284.641133) (xy 377.244429 -284.690496)
			(xy 377.228985 -284.738028) (xy 377.206295 -284.78256) (xy 377.176919 -284.822993) (xy 377.141579 -284.858333)
			(xy 377.101146 -284.887709) (xy 377.056614 -284.910399) (xy 377.009082 -284.925843) (xy 376.959719 -284.933662)
			(xy 376.909741 -284.933662) (xy 376.860378 -284.925843) (xy 376.812846 -284.910399) (xy 376.768314 -284.887709)
			(xy 376.727881 -284.858333) (xy 376.692541 -284.822993) (xy 376.663165 -284.78256) (xy 376.640475 -284.738028)
			(xy 376.625031 -284.690496) (xy 376.617212 -284.641133) (xy 376.310149 -284.641133) (xy 376.31014 -284.64159)
			(xy 376.301976 -284.691824) (xy 376.28586 -284.740098) (xy 376.262209 -284.785161) (xy 376.231636 -284.825847)
			(xy 376.194932 -284.861102) (xy 376.153048 -284.890012) (xy 376.107069 -284.911829) (xy 376.058185 -284.925989)
			(xy 376.007664 -284.932123) (xy 375.956812 -284.930074) (xy 375.906948 -284.919894) (xy 375.859362 -284.901847)
			(xy 375.815288 -284.876401) (xy 375.775866 -284.844214) (xy 375.742118 -284.80612) (xy 375.714917 -284.763106)
			(xy 375.694969 -284.716286) (xy 375.68279 -284.666872) (xy 375.678695 -284.616144) (xy 375.37338 -284.616144)
			(xy 375.369444 -284.66602) (xy 375.35774 -284.714679) (xy 375.338558 -284.760904) (xy 375.312371 -284.803553)
			(xy 375.279827 -284.841573) (xy 375.261124 -284.858206) (xy 375.25706 -284.861762) (xy 375.25071 -284.86989)
			(xy 375.239534 -284.893512) (xy 375.237215 -284.898675) (xy 375.234659 -284.909699) (xy 375.234454 -284.915356)
			(xy 375.234454 -285.42615) (xy 376.148595 -285.42615) (xy 376.15269 -285.375422) (xy 376.164869 -285.326008)
			(xy 376.184817 -285.279188) (xy 376.212018 -285.236174) (xy 376.245766 -285.19808) (xy 376.285188 -285.165893)
			(xy 376.329262 -285.140447) (xy 376.376848 -285.1224) (xy 376.426712 -285.11222) (xy 376.477564 -285.110171)
			(xy 376.528085 -285.116305) (xy 376.576969 -285.130465) (xy 376.622948 -285.152282) (xy 376.664832 -285.181192)
			(xy 376.701536 -285.216447) (xy 376.732109 -285.257133) (xy 376.75576 -285.302196) (xy 376.771876 -285.35047)
			(xy 376.78004 -285.400704) (xy 376.780552 -285.42615) (xy 377.088649 -285.42615) (xy 377.092744 -285.375422)
			(xy 377.104923 -285.326008) (xy 377.124871 -285.279188) (xy 377.152072 -285.236174) (xy 377.18582 -285.19808)
			(xy 377.225242 -285.165893) (xy 377.269316 -285.140447) (xy 377.316902 -285.1224) (xy 377.366766 -285.11222)
			(xy 377.417618 -285.110171) (xy 377.468139 -285.116305) (xy 377.517023 -285.130465) (xy 377.563002 -285.152282)
			(xy 377.604886 -285.181192) (xy 377.64159 -285.216447) (xy 377.672163 -285.257133) (xy 377.695814 -285.302196)
			(xy 377.71193 -285.35047) (xy 377.720094 -285.400704) (xy 377.720606 -285.42615) (xy 378.968503 -285.42615)
			(xy 378.972598 -285.375422) (xy 378.984777 -285.326008) (xy 379.004725 -285.279188) (xy 379.031926 -285.236174)
			(xy 379.065674 -285.19808) (xy 379.105096 -285.165893) (xy 379.14917 -285.140447) (xy 379.196756 -285.1224)
			(xy 379.24662 -285.11222) (xy 379.297472 -285.110171) (xy 379.347993 -285.116305) (xy 379.396877 -285.130465)
			(xy 379.442856 -285.152282) (xy 379.48474 -285.181192) (xy 379.521444 -285.216447) (xy 379.552017 -285.257133)
			(xy 379.575668 -285.302196) (xy 379.591784 -285.35047) (xy 379.599948 -285.400704) (xy 379.60046 -285.42615)
			(xy 379.599957 -285.451139) (xy 379.907274 -285.451139) (xy 379.907274 -285.401161) (xy 379.915093 -285.351798)
			(xy 379.930537 -285.304266) (xy 379.953227 -285.259734) (xy 379.982603 -285.219301) (xy 380.017943 -285.183961)
			(xy 380.058376 -285.154585) (xy 380.102908 -285.131895) (xy 380.15044 -285.116451) (xy 380.199803 -285.108632)
			(xy 380.249781 -285.108632) (xy 380.299144 -285.116451) (xy 380.346676 -285.131895) (xy 380.391208 -285.154585)
			(xy 380.431641 -285.183961) (xy 380.466981 -285.219301) (xy 380.496357 -285.259734) (xy 380.519047 -285.304266)
			(xy 380.534491 -285.351798) (xy 380.54231 -285.401161) (xy 380.5428 -285.42615) (xy 380.54231 -285.451139)
			(xy 380.534491 -285.500502) (xy 380.519047 -285.548034) (xy 380.496357 -285.592566) (xy 380.466981 -285.632999)
			(xy 380.431641 -285.668339) (xy 380.391208 -285.697715) (xy 380.346676 -285.720405) (xy 380.299144 -285.735849)
			(xy 380.249781 -285.743668) (xy 380.199803 -285.743668) (xy 380.15044 -285.735849) (xy 380.102908 -285.720405)
			(xy 380.058376 -285.697715) (xy 380.017943 -285.668339) (xy 379.982603 -285.632999) (xy 379.953227 -285.592566)
			(xy 379.930537 -285.548034) (xy 379.915093 -285.500502) (xy 379.907274 -285.451139) (xy 379.599957 -285.451139)
			(xy 379.599948 -285.451596) (xy 379.591784 -285.50183) (xy 379.575668 -285.550104) (xy 379.552017 -285.595167)
			(xy 379.521444 -285.635853) (xy 379.48474 -285.671108) (xy 379.442856 -285.700018) (xy 379.396877 -285.721835)
			(xy 379.347993 -285.735995) (xy 379.297472 -285.742129) (xy 379.24662 -285.74008) (xy 379.196756 -285.7299)
			(xy 379.14917 -285.711853) (xy 379.105096 -285.686407) (xy 379.065674 -285.65422) (xy 379.031926 -285.616126)
			(xy 379.004725 -285.573112) (xy 378.984777 -285.526292) (xy 378.972598 -285.476878) (xy 378.968503 -285.42615)
			(xy 377.720606 -285.42615) (xy 377.720094 -285.451596) (xy 377.71193 -285.50183) (xy 377.695814 -285.550104)
			(xy 377.672163 -285.595167) (xy 377.64159 -285.635853) (xy 377.604886 -285.671108) (xy 377.563002 -285.700018)
			(xy 377.517023 -285.721835) (xy 377.468139 -285.735995) (xy 377.417618 -285.742129) (xy 377.366766 -285.74008)
			(xy 377.316902 -285.7299) (xy 377.269316 -285.711853) (xy 377.225242 -285.686407) (xy 377.18582 -285.65422)
			(xy 377.152072 -285.616126) (xy 377.124871 -285.573112) (xy 377.104923 -285.526292) (xy 377.092744 -285.476878)
			(xy 377.088649 -285.42615) (xy 376.780552 -285.42615) (xy 376.78004 -285.451596) (xy 376.771876 -285.50183)
			(xy 376.75576 -285.550104) (xy 376.732109 -285.595167) (xy 376.701536 -285.635853) (xy 376.664832 -285.671108)
			(xy 376.622948 -285.700018) (xy 376.576969 -285.721835) (xy 376.528085 -285.735995) (xy 376.477564 -285.742129)
			(xy 376.426712 -285.74008) (xy 376.376848 -285.7299) (xy 376.329262 -285.711853) (xy 376.285188 -285.686407)
			(xy 376.245766 -285.65422) (xy 376.212018 -285.616126) (xy 376.184817 -285.573112) (xy 376.164869 -285.526292)
			(xy 376.15269 -285.476878) (xy 376.148595 -285.42615) (xy 375.234454 -285.42615) (xy 375.234454 -285.936944)
			(xy 375.234639 -285.942603) (xy 375.237208 -285.953626) (xy 375.239534 -285.958788) (xy 375.25071 -285.98241)
			(xy 375.25706 -285.990538) (xy 375.261124 -285.994094) (xy 375.279874 -286.010679) (xy 375.312426 -286.048707)
			(xy 375.338618 -286.091365) (xy 375.357804 -286.1376) (xy 375.369511 -286.186269) (xy 375.373447 -286.236156)
			(xy 375.678695 -286.236156) (xy 375.68279 -286.185428) (xy 375.694969 -286.136014) (xy 375.714917 -286.089194)
			(xy 375.742118 -286.04618) (xy 375.775866 -286.008086) (xy 375.815288 -285.975899) (xy 375.859362 -285.950453)
			(xy 375.906948 -285.932406) (xy 375.956812 -285.922226) (xy 376.007664 -285.920177) (xy 376.058185 -285.926311)
			(xy 376.107069 -285.940471) (xy 376.153048 -285.962288) (xy 376.194932 -285.991198) (xy 376.231636 -286.026453)
			(xy 376.262209 -286.067139) (xy 376.28586 -286.112202) (xy 376.301976 -286.160476) (xy 376.31014 -286.21071)
			(xy 376.310652 -286.236156) (xy 376.310149 -286.261145) (xy 376.617212 -286.261145) (xy 376.617212 -286.211167)
			(xy 376.625031 -286.161804) (xy 376.640475 -286.114272) (xy 376.663165 -286.06974) (xy 376.692541 -286.029307)
			(xy 376.727881 -285.993967) (xy 376.768314 -285.964591) (xy 376.812846 -285.941901) (xy 376.860378 -285.926457)
			(xy 376.909741 -285.918638) (xy 376.959719 -285.918638) (xy 377.009082 -285.926457) (xy 377.056614 -285.941901)
			(xy 377.101146 -285.964591) (xy 377.141579 -285.993967) (xy 377.176919 -286.029307) (xy 377.206295 -286.06974)
			(xy 377.228985 -286.114272) (xy 377.244429 -286.161804) (xy 377.252248 -286.211167) (xy 377.252738 -286.236156)
			(xy 377.558549 -286.236156) (xy 377.562644 -286.185428) (xy 377.574823 -286.136014) (xy 377.594771 -286.089194)
			(xy 377.621972 -286.04618) (xy 377.65572 -286.008086) (xy 377.695142 -285.975899) (xy 377.739216 -285.950453)
			(xy 377.786802 -285.932406) (xy 377.836666 -285.922226) (xy 377.887518 -285.920177) (xy 377.938039 -285.926311)
			(xy 377.986923 -285.940471) (xy 378.032902 -285.962288) (xy 378.074786 -285.991198) (xy 378.11149 -286.026453)
			(xy 378.142063 -286.067139) (xy 378.165714 -286.112202) (xy 378.18183 -286.160476) (xy 378.189994 -286.21071)
			(xy 378.190506 -286.236156) (xy 378.190003 -286.261145) (xy 378.49732 -286.261145) (xy 378.49732 -286.211167)
			(xy 378.505139 -286.161804) (xy 378.520583 -286.114272) (xy 378.543273 -286.06974) (xy 378.572649 -286.029307)
			(xy 378.607989 -285.993967) (xy 378.648422 -285.964591) (xy 378.692954 -285.941901) (xy 378.740486 -285.926457)
			(xy 378.789849 -285.918638) (xy 378.839827 -285.918638) (xy 378.88919 -285.926457) (xy 378.936722 -285.941901)
			(xy 378.981254 -285.964591) (xy 379.021687 -285.993967) (xy 379.057027 -286.029307) (xy 379.086403 -286.06974)
			(xy 379.109093 -286.114272) (xy 379.124537 -286.161804) (xy 379.132356 -286.211167) (xy 379.132846 -286.236156)
			(xy 379.438657 -286.236156) (xy 379.442752 -286.185428) (xy 379.454931 -286.136014) (xy 379.474879 -286.089194)
			(xy 379.50208 -286.04618) (xy 379.535828 -286.008086) (xy 379.57525 -285.975899) (xy 379.619324 -285.950453)
			(xy 379.66691 -285.932406) (xy 379.716774 -285.922226) (xy 379.767626 -285.920177) (xy 379.818147 -285.926311)
			(xy 379.867031 -285.940471) (xy 379.91301 -285.962288) (xy 379.954894 -285.991198) (xy 379.991598 -286.026453)
			(xy 380.022171 -286.067139) (xy 380.045822 -286.112202) (xy 380.061938 -286.160476) (xy 380.070102 -286.21071)
			(xy 380.070614 -286.236156) (xy 380.378711 -286.236156) (xy 380.382806 -286.185428) (xy 380.394985 -286.136014)
			(xy 380.414933 -286.089194) (xy 380.442134 -286.04618) (xy 380.475882 -286.008086) (xy 380.515304 -285.975899)
			(xy 380.559378 -285.950453) (xy 380.606964 -285.932406) (xy 380.656828 -285.922226) (xy 380.70768 -285.920177)
			(xy 380.758201 -285.926311) (xy 380.807085 -285.940471) (xy 380.853064 -285.962288) (xy 380.894948 -285.991198)
			(xy 380.931652 -286.026453) (xy 380.962225 -286.067139) (xy 380.985876 -286.112202) (xy 381.001992 -286.160476)
			(xy 381.010156 -286.21071) (xy 381.010668 -286.236156) (xy 381.010156 -286.261602) (xy 381.001992 -286.311836)
			(xy 380.985876 -286.36011) (xy 380.962225 -286.405173) (xy 380.931652 -286.445859) (xy 380.894948 -286.481114)
			(xy 380.853064 -286.510024) (xy 380.807085 -286.531841) (xy 380.758201 -286.546001) (xy 380.70768 -286.552135)
			(xy 380.656828 -286.550086) (xy 380.606964 -286.539906) (xy 380.559378 -286.521859) (xy 380.515304 -286.496413)
			(xy 380.475882 -286.464226) (xy 380.442134 -286.426132) (xy 380.414933 -286.383118) (xy 380.394985 -286.336298)
			(xy 380.382806 -286.286884) (xy 380.378711 -286.236156) (xy 380.070614 -286.236156) (xy 380.070102 -286.261602)
			(xy 380.061938 -286.311836) (xy 380.045822 -286.36011) (xy 380.022171 -286.405173) (xy 379.991598 -286.445859)
			(xy 379.954894 -286.481114) (xy 379.91301 -286.510024) (xy 379.867031 -286.531841) (xy 379.818147 -286.546001)
			(xy 379.767626 -286.552135) (xy 379.716774 -286.550086) (xy 379.66691 -286.539906) (xy 379.619324 -286.521859)
			(xy 379.57525 -286.496413) (xy 379.535828 -286.464226) (xy 379.50208 -286.426132) (xy 379.474879 -286.383118)
			(xy 379.454931 -286.336298) (xy 379.442752 -286.286884) (xy 379.438657 -286.236156) (xy 379.132846 -286.236156)
			(xy 379.132356 -286.261145) (xy 379.124537 -286.310508) (xy 379.109093 -286.35804) (xy 379.086403 -286.402572)
			(xy 379.057027 -286.443005) (xy 379.021687 -286.478345) (xy 378.981254 -286.507721) (xy 378.936722 -286.530411)
			(xy 378.88919 -286.545855) (xy 378.839827 -286.553674) (xy 378.789849 -286.553674) (xy 378.740486 -286.545855)
			(xy 378.692954 -286.530411) (xy 378.648422 -286.507721) (xy 378.607989 -286.478345) (xy 378.572649 -286.443005)
			(xy 378.543273 -286.402572) (xy 378.520583 -286.35804) (xy 378.505139 -286.310508) (xy 378.49732 -286.261145)
			(xy 378.190003 -286.261145) (xy 378.189994 -286.261602) (xy 378.18183 -286.311836) (xy 378.165714 -286.36011)
			(xy 378.142063 -286.405173) (xy 378.11149 -286.445859) (xy 378.074786 -286.481114) (xy 378.032902 -286.510024)
			(xy 377.986923 -286.531841) (xy 377.938039 -286.546001) (xy 377.887518 -286.552135) (xy 377.836666 -286.550086)
			(xy 377.786802 -286.539906) (xy 377.739216 -286.521859) (xy 377.695142 -286.496413) (xy 377.65572 -286.464226)
			(xy 377.621972 -286.426132) (xy 377.594771 -286.383118) (xy 377.574823 -286.336298) (xy 377.562644 -286.286884)
			(xy 377.558549 -286.236156) (xy 377.252738 -286.236156) (xy 377.252248 -286.261145) (xy 377.244429 -286.310508)
			(xy 377.228985 -286.35804) (xy 377.206295 -286.402572) (xy 377.176919 -286.443005) (xy 377.141579 -286.478345)
			(xy 377.101146 -286.507721) (xy 377.056614 -286.530411) (xy 377.009082 -286.545855) (xy 376.959719 -286.553674)
			(xy 376.909741 -286.553674) (xy 376.860378 -286.545855) (xy 376.812846 -286.530411) (xy 376.768314 -286.507721)
			(xy 376.727881 -286.478345) (xy 376.692541 -286.443005) (xy 376.663165 -286.402572) (xy 376.640475 -286.35804)
			(xy 376.625031 -286.310508) (xy 376.617212 -286.261145) (xy 376.310149 -286.261145) (xy 376.31014 -286.261602)
			(xy 376.301976 -286.311836) (xy 376.28586 -286.36011) (xy 376.262209 -286.405173) (xy 376.231636 -286.445859)
			(xy 376.194932 -286.481114) (xy 376.153048 -286.510024) (xy 376.107069 -286.531841) (xy 376.058185 -286.546001)
			(xy 376.007664 -286.552135) (xy 375.956812 -286.550086) (xy 375.906948 -286.539906) (xy 375.859362 -286.521859)
			(xy 375.815288 -286.496413) (xy 375.775866 -286.464226) (xy 375.742118 -286.426132) (xy 375.714917 -286.383118)
			(xy 375.694969 -286.336298) (xy 375.68279 -286.286884) (xy 375.678695 -286.236156) (xy 375.373447 -286.236156)
			(xy 375.373448 -286.236171) (xy 375.36952 -286.286074) (xy 375.357822 -286.334746) (xy 375.338644 -286.380984)
			(xy 375.31246 -286.423646) (xy 375.279915 -286.46168) (xy 375.261124 -286.478218) (xy 375.25706 -286.481774)
			(xy 375.25071 -286.489902) (xy 375.239534 -286.513524) (xy 375.237206 -286.518685) (xy 375.234631 -286.529709)
			(xy 375.234454 -286.535368) (xy 375.234454 -286.67329) (xy 375.234798 -286.681926) (xy 375.240556 -286.69821)
			(xy 375.251415 -286.711641) (xy 375.258584 -286.71647) (xy 375.341896 -286.767524) (xy 375.368058 -286.768794)
			(xy 375.379996 -286.762444) (xy 375.402419 -286.751541) (xy 375.449839 -286.736141) (xy 375.499085 -286.728354)
			(xy 375.524014 -286.7279) (xy 375.53011 -286.7279) (xy 375.554823 -286.728783) (xy 375.603541 -286.737253)
			(xy 375.650361 -286.753164) (xy 375.694152 -286.776131) (xy 375.73386 -286.805601) (xy 375.768526 -286.840864)
			(xy 375.797316 -286.881068) (xy 375.819533 -286.925244) (xy 375.834644 -286.972328) (xy 375.842283 -287.021183)
			(xy 375.842784 -287.045908) (xy 376.148595 -287.045908) (xy 376.15269 -286.99518) (xy 376.164869 -286.945766)
			(xy 376.184817 -286.898946) (xy 376.212018 -286.855932) (xy 376.245766 -286.817838) (xy 376.285188 -286.785651)
			(xy 376.329262 -286.760205) (xy 376.376848 -286.742158) (xy 376.426712 -286.731978) (xy 376.477564 -286.729929)
			(xy 376.528085 -286.736063) (xy 376.576969 -286.750223) (xy 376.622948 -286.77204) (xy 376.664832 -286.80095)
			(xy 376.701536 -286.836205) (xy 376.732109 -286.876891) (xy 376.75576 -286.921954) (xy 376.771876 -286.970228)
			(xy 376.78004 -287.020462) (xy 376.780552 -287.045908) (xy 377.088649 -287.045908) (xy 377.092744 -286.99518)
			(xy 377.104923 -286.945766) (xy 377.124871 -286.898946) (xy 377.152072 -286.855932) (xy 377.18582 -286.817838)
			(xy 377.225242 -286.785651) (xy 377.269316 -286.760205) (xy 377.316902 -286.742158) (xy 377.366766 -286.731978)
			(xy 377.417618 -286.729929) (xy 377.468139 -286.736063) (xy 377.517023 -286.750223) (xy 377.563002 -286.77204)
			(xy 377.604886 -286.80095) (xy 377.64159 -286.836205) (xy 377.672163 -286.876891) (xy 377.695814 -286.921954)
			(xy 377.71193 -286.970228) (xy 377.720094 -287.020462) (xy 377.720606 -287.045908) (xy 377.720098 -287.071151)
			(xy 378.02742 -287.071151) (xy 378.02742 -287.021173) (xy 378.035239 -286.97181) (xy 378.050683 -286.924278)
			(xy 378.073373 -286.879746) (xy 378.102749 -286.839313) (xy 378.138089 -286.803973) (xy 378.178522 -286.774597)
			(xy 378.223054 -286.751907) (xy 378.270586 -286.736463) (xy 378.319949 -286.728644) (xy 378.369927 -286.728644)
			(xy 378.41929 -286.736463) (xy 378.466822 -286.751907) (xy 378.511354 -286.774597) (xy 378.551787 -286.803973)
			(xy 378.587127 -286.839313) (xy 378.616503 -286.879746) (xy 378.639193 -286.924278) (xy 378.654637 -286.97181)
			(xy 378.662456 -287.021173) (xy 378.662941 -287.045908) (xy 378.968503 -287.045908) (xy 378.972598 -286.99518)
			(xy 378.984777 -286.945766) (xy 379.004725 -286.898946) (xy 379.031926 -286.855932) (xy 379.065674 -286.817838)
			(xy 379.105096 -286.785651) (xy 379.14917 -286.760205) (xy 379.196756 -286.742158) (xy 379.24662 -286.731978)
			(xy 379.297472 -286.729929) (xy 379.347993 -286.736063) (xy 379.396877 -286.750223) (xy 379.442856 -286.77204)
			(xy 379.48474 -286.80095) (xy 379.521444 -286.836205) (xy 379.552017 -286.876891) (xy 379.575668 -286.921954)
			(xy 379.591784 -286.970228) (xy 379.599948 -287.020462) (xy 379.60046 -287.045908) (xy 379.599957 -287.070897)
			(xy 379.907274 -287.070897) (xy 379.907274 -287.020919) (xy 379.915093 -286.971556) (xy 379.930537 -286.924024)
			(xy 379.953227 -286.879492) (xy 379.982603 -286.839059) (xy 380.017943 -286.803719) (xy 380.058376 -286.774343)
			(xy 380.102908 -286.751653) (xy 380.15044 -286.736209) (xy 380.199803 -286.72839) (xy 380.249781 -286.72839)
			(xy 380.299144 -286.736209) (xy 380.346676 -286.751653) (xy 380.391208 -286.774343) (xy 380.431641 -286.803719)
			(xy 380.466981 -286.839059) (xy 380.496357 -286.879492) (xy 380.519047 -286.924024) (xy 380.534491 -286.971556)
			(xy 380.54231 -287.020919) (xy 380.5428 -287.045908) (xy 380.54231 -287.070897) (xy 380.534491 -287.12026)
			(xy 380.519047 -287.167792) (xy 380.496357 -287.212324) (xy 380.466981 -287.252757) (xy 380.431641 -287.288097)
			(xy 380.391208 -287.317473) (xy 380.346676 -287.340163) (xy 380.299144 -287.355607) (xy 380.249781 -287.363426)
			(xy 380.199803 -287.363426) (xy 380.15044 -287.355607) (xy 380.102908 -287.340163) (xy 380.058376 -287.317473)
			(xy 380.017943 -287.288097) (xy 379.982603 -287.252757) (xy 379.953227 -287.212324) (xy 379.930537 -287.167792)
			(xy 379.915093 -287.12026) (xy 379.907274 -287.070897) (xy 379.599957 -287.070897) (xy 379.599948 -287.071354)
			(xy 379.591784 -287.121588) (xy 379.575668 -287.169862) (xy 379.552017 -287.214925) (xy 379.521444 -287.255611)
			(xy 379.48474 -287.290866) (xy 379.442856 -287.319776) (xy 379.396877 -287.341593) (xy 379.347993 -287.355753)
			(xy 379.297472 -287.361887) (xy 379.24662 -287.359838) (xy 379.196756 -287.349658) (xy 379.14917 -287.331611)
			(xy 379.105096 -287.306165) (xy 379.065674 -287.273978) (xy 379.031926 -287.235884) (xy 379.004725 -287.19287)
			(xy 378.984777 -287.14605) (xy 378.972598 -287.096636) (xy 378.968503 -287.045908) (xy 378.662941 -287.045908)
			(xy 378.662946 -287.046162) (xy 378.662456 -287.071151) (xy 378.654637 -287.120514) (xy 378.639193 -287.168046)
			(xy 378.616503 -287.212578) (xy 378.587127 -287.253011) (xy 378.551787 -287.288351) (xy 378.511354 -287.317727)
			(xy 378.466822 -287.340417) (xy 378.41929 -287.355861) (xy 378.369927 -287.36368) (xy 378.319949 -287.36368)
			(xy 378.270586 -287.355861) (xy 378.223054 -287.340417) (xy 378.178522 -287.317727) (xy 378.138089 -287.288351)
			(xy 378.102749 -287.253011) (xy 378.073373 -287.212578) (xy 378.050683 -287.168046) (xy 378.035239 -287.120514)
			(xy 378.02742 -287.071151) (xy 377.720098 -287.071151) (xy 377.720094 -287.071354) (xy 377.71193 -287.121588)
			(xy 377.695814 -287.169862) (xy 377.672163 -287.214925) (xy 377.64159 -287.255611) (xy 377.604886 -287.290866)
			(xy 377.563002 -287.319776) (xy 377.517023 -287.341593) (xy 377.468139 -287.355753) (xy 377.417618 -287.361887)
			(xy 377.366766 -287.359838) (xy 377.316902 -287.349658) (xy 377.269316 -287.331611) (xy 377.225242 -287.306165)
			(xy 377.18582 -287.273978) (xy 377.152072 -287.235884) (xy 377.124871 -287.19287) (xy 377.104923 -287.14605)
			(xy 377.092744 -287.096636) (xy 377.088649 -287.045908) (xy 376.780552 -287.045908) (xy 376.78004 -287.071354)
			(xy 376.771876 -287.121588) (xy 376.75576 -287.169862) (xy 376.732109 -287.214925) (xy 376.701536 -287.255611)
			(xy 376.664832 -287.290866) (xy 376.622948 -287.319776) (xy 376.576969 -287.341593) (xy 376.528085 -287.355753)
			(xy 376.477564 -287.361887) (xy 376.426712 -287.359838) (xy 376.376848 -287.349658) (xy 376.329262 -287.331611)
			(xy 376.285188 -287.306165) (xy 376.245766 -287.273978) (xy 376.212018 -287.235884) (xy 376.184817 -287.19287)
			(xy 376.164869 -287.14605) (xy 376.15269 -287.096636) (xy 376.148595 -287.045908) (xy 375.842784 -287.045908)
			(xy 375.842318 -287.070898) (xy 375.834498 -287.120263) (xy 375.819052 -287.167796) (xy 375.79636 -287.212328)
			(xy 375.76698 -287.252761) (xy 375.731637 -287.288101) (xy 375.691201 -287.317476) (xy 375.646667 -287.340164)
			(xy 375.599132 -287.355606) (xy 375.549766 -287.363421) (xy 375.524776 -287.363916) (xy 375.524522 -287.363916)
			(xy 375.499513 -287.363438) (xy 375.450107 -287.355652) (xy 375.40252 -287.34025) (xy 375.379996 -287.329372)
			(xy 375.368058 -287.323022) (xy 375.341896 -287.324292) (xy 375.258584 -287.375346) (xy 375.251386 -287.380204)
			(xy 375.240508 -287.393728) (xy 375.234755 -287.410102) (xy 375.234454 -287.41878) (xy 375.234454 -287.556956)
			(xy 375.234641 -287.562614) (xy 375.237212 -287.573636) (xy 375.239534 -287.5788) (xy 375.25071 -287.602422)
			(xy 375.25706 -287.61055) (xy 375.261124 -287.614106) (xy 375.279874 -287.630691) (xy 375.312423 -287.668719)
			(xy 375.338614 -287.711377) (xy 375.357798 -287.75761) (xy 375.369503 -287.806278) (xy 375.373438 -287.856168)
			(xy 375.678695 -287.856168) (xy 375.68279 -287.80544) (xy 375.694969 -287.756026) (xy 375.714917 -287.709206)
			(xy 375.742118 -287.666192) (xy 375.775866 -287.628098) (xy 375.815288 -287.595911) (xy 375.859362 -287.570465)
			(xy 375.906948 -287.552418) (xy 375.956812 -287.542238) (xy 376.007664 -287.540189) (xy 376.058185 -287.546323)
			(xy 376.107069 -287.560483) (xy 376.153048 -287.5823) (xy 376.194932 -287.61121) (xy 376.231636 -287.646465)
			(xy 376.262209 -287.687151) (xy 376.28586 -287.732214) (xy 376.301976 -287.780488) (xy 376.31014 -287.830722)
			(xy 376.310652 -287.856168) (xy 376.310149 -287.881157) (xy 376.617212 -287.881157) (xy 376.617212 -287.831179)
			(xy 376.625031 -287.781816) (xy 376.640475 -287.734284) (xy 376.663165 -287.689752) (xy 376.692541 -287.649319)
			(xy 376.727881 -287.613979) (xy 376.768314 -287.584603) (xy 376.812846 -287.561913) (xy 376.860378 -287.546469)
			(xy 376.909741 -287.53865) (xy 376.959719 -287.53865) (xy 377.009082 -287.546469) (xy 377.056614 -287.561913)
			(xy 377.101146 -287.584603) (xy 377.141579 -287.613979) (xy 377.176919 -287.649319) (xy 377.206295 -287.689752)
			(xy 377.228985 -287.734284) (xy 377.244429 -287.781816) (xy 377.252248 -287.831179) (xy 377.252738 -287.856168)
			(xy 377.558549 -287.856168) (xy 377.562644 -287.80544) (xy 377.574823 -287.756026) (xy 377.594771 -287.709206)
			(xy 377.621972 -287.666192) (xy 377.65572 -287.628098) (xy 377.695142 -287.595911) (xy 377.739216 -287.570465)
			(xy 377.786802 -287.552418) (xy 377.836666 -287.542238) (xy 377.887518 -287.540189) (xy 377.938039 -287.546323)
			(xy 377.986923 -287.560483) (xy 378.032902 -287.5823) (xy 378.074786 -287.61121) (xy 378.11149 -287.646465)
			(xy 378.142063 -287.687151) (xy 378.165714 -287.732214) (xy 378.18183 -287.780488) (xy 378.189994 -287.830722)
			(xy 378.190506 -287.856168) (xy 379.438657 -287.856168) (xy 379.442752 -287.80544) (xy 379.454931 -287.756026)
			(xy 379.474879 -287.709206) (xy 379.50208 -287.666192) (xy 379.535828 -287.628098) (xy 379.57525 -287.595911)
			(xy 379.619324 -287.570465) (xy 379.66691 -287.552418) (xy 379.716774 -287.542238) (xy 379.767626 -287.540189)
			(xy 379.818147 -287.546323) (xy 379.867031 -287.560483) (xy 379.91301 -287.5823) (xy 379.954894 -287.61121)
			(xy 379.991598 -287.646465) (xy 380.022171 -287.687151) (xy 380.045822 -287.732214) (xy 380.061938 -287.780488)
			(xy 380.070102 -287.830722) (xy 380.070614 -287.856168) (xy 380.378711 -287.856168) (xy 380.382806 -287.80544)
			(xy 380.394985 -287.756026) (xy 380.414933 -287.709206) (xy 380.442134 -287.666192) (xy 380.475882 -287.628098)
			(xy 380.515304 -287.595911) (xy 380.559378 -287.570465) (xy 380.606964 -287.552418) (xy 380.656828 -287.542238)
			(xy 380.70768 -287.540189) (xy 380.758201 -287.546323) (xy 380.807085 -287.560483) (xy 380.853064 -287.5823)
			(xy 380.894948 -287.61121) (xy 380.931652 -287.646465) (xy 380.962225 -287.687151) (xy 380.985876 -287.732214)
			(xy 381.001992 -287.780488) (xy 381.010156 -287.830722) (xy 381.010668 -287.856168) (xy 381.010156 -287.881614)
			(xy 381.001992 -287.931848) (xy 380.985876 -287.980122) (xy 380.962225 -288.025185) (xy 380.931652 -288.065871)
			(xy 380.894948 -288.101126) (xy 380.853064 -288.130036) (xy 380.807085 -288.151853) (xy 380.758201 -288.166013)
			(xy 380.70768 -288.172147) (xy 380.656828 -288.170098) (xy 380.606964 -288.159918) (xy 380.559378 -288.141871)
			(xy 380.515304 -288.116425) (xy 380.475882 -288.084238) (xy 380.442134 -288.046144) (xy 380.414933 -288.00313)
			(xy 380.394985 -287.95631) (xy 380.382806 -287.906896) (xy 380.378711 -287.856168) (xy 380.070614 -287.856168)
			(xy 380.070102 -287.881614) (xy 380.061938 -287.931848) (xy 380.045822 -287.980122) (xy 380.022171 -288.025185)
			(xy 379.991598 -288.065871) (xy 379.954894 -288.101126) (xy 379.91301 -288.130036) (xy 379.867031 -288.151853)
			(xy 379.818147 -288.166013) (xy 379.767626 -288.172147) (xy 379.716774 -288.170098) (xy 379.66691 -288.159918)
			(xy 379.619324 -288.141871) (xy 379.57525 -288.116425) (xy 379.535828 -288.084238) (xy 379.50208 -288.046144)
			(xy 379.474879 -288.00313) (xy 379.454931 -287.95631) (xy 379.442752 -287.906896) (xy 379.438657 -287.856168)
			(xy 378.190506 -287.856168) (xy 378.189994 -287.881614) (xy 378.18183 -287.931848) (xy 378.165714 -287.980122)
			(xy 378.142063 -288.025185) (xy 378.11149 -288.065871) (xy 378.074786 -288.101126) (xy 378.032902 -288.130036)
			(xy 377.986923 -288.151853) (xy 377.938039 -288.166013) (xy 377.887518 -288.172147) (xy 377.836666 -288.170098)
			(xy 377.786802 -288.159918) (xy 377.739216 -288.141871) (xy 377.695142 -288.116425) (xy 377.65572 -288.084238)
			(xy 377.621972 -288.046144) (xy 377.594771 -288.00313) (xy 377.574823 -287.95631) (xy 377.562644 -287.906896)
			(xy 377.558549 -287.856168) (xy 377.252738 -287.856168) (xy 377.252248 -287.881157) (xy 377.244429 -287.93052)
			(xy 377.228985 -287.978052) (xy 377.206295 -288.022584) (xy 377.176919 -288.063017) (xy 377.141579 -288.098357)
			(xy 377.101146 -288.127733) (xy 377.056614 -288.150423) (xy 377.009082 -288.165867) (xy 376.959719 -288.173686)
			(xy 376.909741 -288.173686) (xy 376.860378 -288.165867) (xy 376.812846 -288.150423) (xy 376.768314 -288.127733)
			(xy 376.727881 -288.098357) (xy 376.692541 -288.063017) (xy 376.663165 -288.022584) (xy 376.640475 -287.978052)
			(xy 376.625031 -287.93052) (xy 376.617212 -287.881157) (xy 376.310149 -287.881157) (xy 376.31014 -287.881614)
			(xy 376.301976 -287.931848) (xy 376.28586 -287.980122) (xy 376.262209 -288.025185) (xy 376.231636 -288.065871)
			(xy 376.194932 -288.101126) (xy 376.153048 -288.130036) (xy 376.107069 -288.151853) (xy 376.058185 -288.166013)
			(xy 376.007664 -288.172147) (xy 375.956812 -288.170098) (xy 375.906948 -288.159918) (xy 375.859362 -288.141871)
			(xy 375.815288 -288.116425) (xy 375.775866 -288.084238) (xy 375.742118 -288.046144) (xy 375.714917 -288.00313)
			(xy 375.694969 -287.95631) (xy 375.68279 -287.906896) (xy 375.678695 -287.856168) (xy 375.373438 -287.856168)
			(xy 375.373439 -287.856179) (xy 375.36951 -287.906081) (xy 375.357811 -287.95475) (xy 375.338633 -288.000986)
			(xy 375.312448 -288.043647) (xy 375.279903 -288.081679) (xy 375.261124 -288.09823) (xy 375.25706 -288.101786)
			(xy 375.25071 -288.109914) (xy 375.239534 -288.133536) (xy 375.237207 -288.138698) (xy 375.234635 -288.149721)
			(xy 375.234454 -288.15538) (xy 375.234454 -288.66592) (xy 376.148595 -288.66592) (xy 376.15269 -288.615192)
			(xy 376.164869 -288.565778) (xy 376.184817 -288.518958) (xy 376.212018 -288.475944) (xy 376.245766 -288.43785)
			(xy 376.285188 -288.405663) (xy 376.329262 -288.380217) (xy 376.376848 -288.36217) (xy 376.426712 -288.35199)
			(xy 376.477564 -288.349941) (xy 376.528085 -288.356075) (xy 376.576969 -288.370235) (xy 376.622948 -288.392052)
			(xy 376.664832 -288.420962) (xy 376.701536 -288.456217) (xy 376.732109 -288.496903) (xy 376.75576 -288.541966)
			(xy 376.771876 -288.59024) (xy 376.78004 -288.640474) (xy 376.780552 -288.66592) (xy 377.088649 -288.66592)
			(xy 377.092744 -288.615192) (xy 377.104923 -288.565778) (xy 377.124871 -288.518958) (xy 377.152072 -288.475944)
			(xy 377.18582 -288.43785) (xy 377.225242 -288.405663) (xy 377.269316 -288.380217) (xy 377.316902 -288.36217)
			(xy 377.366766 -288.35199) (xy 377.417618 -288.349941) (xy 377.468139 -288.356075) (xy 377.517023 -288.370235)
			(xy 377.563002 -288.392052) (xy 377.604886 -288.420962) (xy 377.64159 -288.456217) (xy 377.672163 -288.496903)
			(xy 377.695814 -288.541966) (xy 377.71193 -288.59024) (xy 377.720094 -288.640474) (xy 377.720606 -288.66592)
			(xy 377.720103 -288.690909) (xy 378.02742 -288.690909) (xy 378.02742 -288.640931) (xy 378.035239 -288.591568)
			(xy 378.050683 -288.544036) (xy 378.073373 -288.499504) (xy 378.102749 -288.459071) (xy 378.138089 -288.423731)
			(xy 378.178522 -288.394355) (xy 378.223054 -288.371665) (xy 378.270586 -288.356221) (xy 378.319949 -288.348402)
			(xy 378.369927 -288.348402) (xy 378.41929 -288.356221) (xy 378.466822 -288.371665) (xy 378.511354 -288.394355)
			(xy 378.551787 -288.423731) (xy 378.587127 -288.459071) (xy 378.616503 -288.499504) (xy 378.639193 -288.544036)
			(xy 378.654637 -288.591568) (xy 378.662456 -288.640931) (xy 378.662946 -288.66592) (xy 378.968503 -288.66592)
			(xy 378.972598 -288.615192) (xy 378.984777 -288.565778) (xy 379.004725 -288.518958) (xy 379.031926 -288.475944)
			(xy 379.065674 -288.43785) (xy 379.105096 -288.405663) (xy 379.14917 -288.380217) (xy 379.196756 -288.36217)
			(xy 379.24662 -288.35199) (xy 379.297472 -288.349941) (xy 379.347993 -288.356075) (xy 379.396877 -288.370235)
			(xy 379.442856 -288.392052) (xy 379.48474 -288.420962) (xy 379.521444 -288.456217) (xy 379.552017 -288.496903)
			(xy 379.575668 -288.541966) (xy 379.591784 -288.59024) (xy 379.599948 -288.640474) (xy 379.60046 -288.66592)
			(xy 379.599957 -288.690909) (xy 379.907274 -288.690909) (xy 379.907274 -288.640931) (xy 379.915093 -288.591568)
			(xy 379.930537 -288.544036) (xy 379.953227 -288.499504) (xy 379.982603 -288.459071) (xy 380.017943 -288.423731)
			(xy 380.058376 -288.394355) (xy 380.102908 -288.371665) (xy 380.15044 -288.356221) (xy 380.199803 -288.348402)
			(xy 380.249781 -288.348402) (xy 380.299144 -288.356221) (xy 380.346676 -288.371665) (xy 380.391208 -288.394355)
			(xy 380.431641 -288.423731) (xy 380.466981 -288.459071) (xy 380.496357 -288.499504) (xy 380.519047 -288.544036)
			(xy 380.534491 -288.591568) (xy 380.54231 -288.640931) (xy 380.5428 -288.66592) (xy 380.54231 -288.690909)
			(xy 380.534491 -288.740272) (xy 380.519047 -288.787804) (xy 380.496357 -288.832336) (xy 380.466981 -288.872769)
			(xy 380.431641 -288.908109) (xy 380.391208 -288.937485) (xy 380.346676 -288.960175) (xy 380.299144 -288.975619)
			(xy 380.249781 -288.983438) (xy 380.199803 -288.983438) (xy 380.15044 -288.975619) (xy 380.102908 -288.960175)
			(xy 380.058376 -288.937485) (xy 380.017943 -288.908109) (xy 379.982603 -288.872769) (xy 379.953227 -288.832336)
			(xy 379.930537 -288.787804) (xy 379.915093 -288.740272) (xy 379.907274 -288.690909) (xy 379.599957 -288.690909)
			(xy 379.599948 -288.691366) (xy 379.591784 -288.7416) (xy 379.575668 -288.789874) (xy 379.552017 -288.834937)
			(xy 379.521444 -288.875623) (xy 379.48474 -288.910878) (xy 379.442856 -288.939788) (xy 379.396877 -288.961605)
			(xy 379.347993 -288.975765) (xy 379.297472 -288.981899) (xy 379.24662 -288.97985) (xy 379.196756 -288.96967)
			(xy 379.14917 -288.951623) (xy 379.105096 -288.926177) (xy 379.065674 -288.89399) (xy 379.031926 -288.855896)
			(xy 379.004725 -288.812882) (xy 378.984777 -288.766062) (xy 378.972598 -288.716648) (xy 378.968503 -288.66592)
			(xy 378.662946 -288.66592) (xy 378.662456 -288.690909) (xy 378.654637 -288.740272) (xy 378.639193 -288.787804)
			(xy 378.616503 -288.832336) (xy 378.587127 -288.872769) (xy 378.551787 -288.908109) (xy 378.511354 -288.937485)
			(xy 378.466822 -288.960175) (xy 378.41929 -288.975619) (xy 378.369927 -288.983438) (xy 378.319949 -288.983438)
			(xy 378.270586 -288.975619) (xy 378.223054 -288.960175) (xy 378.178522 -288.937485) (xy 378.138089 -288.908109)
			(xy 378.102749 -288.872769) (xy 378.073373 -288.832336) (xy 378.050683 -288.787804) (xy 378.035239 -288.740272)
			(xy 378.02742 -288.690909) (xy 377.720103 -288.690909) (xy 377.720094 -288.691366) (xy 377.71193 -288.7416)
			(xy 377.695814 -288.789874) (xy 377.672163 -288.834937) (xy 377.64159 -288.875623) (xy 377.604886 -288.910878)
			(xy 377.563002 -288.939788) (xy 377.517023 -288.961605) (xy 377.468139 -288.975765) (xy 377.417618 -288.981899)
			(xy 377.366766 -288.97985) (xy 377.316902 -288.96967) (xy 377.269316 -288.951623) (xy 377.225242 -288.926177)
			(xy 377.18582 -288.89399) (xy 377.152072 -288.855896) (xy 377.124871 -288.812882) (xy 377.104923 -288.766062)
			(xy 377.092744 -288.716648) (xy 377.088649 -288.66592) (xy 376.780552 -288.66592) (xy 376.78004 -288.691366)
			(xy 376.771876 -288.7416) (xy 376.75576 -288.789874) (xy 376.732109 -288.834937) (xy 376.701536 -288.875623)
			(xy 376.664832 -288.910878) (xy 376.622948 -288.939788) (xy 376.576969 -288.961605) (xy 376.528085 -288.975765)
			(xy 376.477564 -288.981899) (xy 376.426712 -288.97985) (xy 376.376848 -288.96967) (xy 376.329262 -288.951623)
			(xy 376.285188 -288.926177) (xy 376.245766 -288.89399) (xy 376.212018 -288.855896) (xy 376.184817 -288.812882)
			(xy 376.164869 -288.766062) (xy 376.15269 -288.716648) (xy 376.148595 -288.66592) (xy 375.234454 -288.66592)
			(xy 375.234454 -289.176714) (xy 375.234636 -289.182373) (xy 375.237199 -289.1934) (xy 375.239534 -289.198558)
			(xy 375.25071 -289.22218) (xy 375.25706 -289.230308) (xy 375.261124 -289.233864) (xy 375.2817 -289.252163)
			(xy 375.316836 -289.294554) (xy 375.344147 -289.342362) (xy 375.36282 -289.394158) (xy 375.372296 -289.448396)
			(xy 375.372884 -289.475926) (xy 375.678695 -289.475926) (xy 375.68279 -289.425198) (xy 375.694969 -289.375784)
			(xy 375.714917 -289.328964) (xy 375.742118 -289.28595) (xy 375.775866 -289.247856) (xy 375.815288 -289.215669)
			(xy 375.859362 -289.190223) (xy 375.906948 -289.172176) (xy 375.956812 -289.161996) (xy 376.007664 -289.159947)
			(xy 376.058185 -289.166081) (xy 376.107069 -289.180241) (xy 376.153048 -289.202058) (xy 376.194932 -289.230968)
			(xy 376.231636 -289.266223) (xy 376.262209 -289.306909) (xy 376.28586 -289.351972) (xy 376.301976 -289.400246)
			(xy 376.31014 -289.45048) (xy 376.310652 -289.475926) (xy 376.310149 -289.500915) (xy 376.617212 -289.500915)
			(xy 376.617212 -289.450937) (xy 376.625031 -289.401574) (xy 376.640475 -289.354042) (xy 376.663165 -289.30951)
			(xy 376.692541 -289.269077) (xy 376.727881 -289.233737) (xy 376.768314 -289.204361) (xy 376.812846 -289.181671)
			(xy 376.860378 -289.166227) (xy 376.909741 -289.158408) (xy 376.959719 -289.158408) (xy 377.009082 -289.166227)
			(xy 377.056614 -289.181671) (xy 377.101146 -289.204361) (xy 377.141579 -289.233737) (xy 377.176919 -289.269077)
			(xy 377.206295 -289.30951) (xy 377.228985 -289.354042) (xy 377.244429 -289.401574) (xy 377.252248 -289.450937)
			(xy 377.252738 -289.475926) (xy 377.558549 -289.475926) (xy 377.562644 -289.425198) (xy 377.574823 -289.375784)
			(xy 377.594771 -289.328964) (xy 377.621972 -289.28595) (xy 377.65572 -289.247856) (xy 377.695142 -289.215669)
			(xy 377.739216 -289.190223) (xy 377.786802 -289.172176) (xy 377.836666 -289.161996) (xy 377.887518 -289.159947)
			(xy 377.938039 -289.166081) (xy 377.986923 -289.180241) (xy 378.032902 -289.202058) (xy 378.074786 -289.230968)
			(xy 378.11149 -289.266223) (xy 378.142063 -289.306909) (xy 378.165714 -289.351972) (xy 378.18183 -289.400246)
			(xy 378.189994 -289.45048) (xy 378.190506 -289.475926) (xy 378.190003 -289.500915) (xy 378.49732 -289.500915)
			(xy 378.49732 -289.450937) (xy 378.505139 -289.401574) (xy 378.520583 -289.354042) (xy 378.543273 -289.30951)
			(xy 378.572649 -289.269077) (xy 378.607989 -289.233737) (xy 378.648422 -289.204361) (xy 378.692954 -289.181671)
			(xy 378.740486 -289.166227) (xy 378.789849 -289.158408) (xy 378.839827 -289.158408) (xy 378.88919 -289.166227)
			(xy 378.936722 -289.181671) (xy 378.981254 -289.204361) (xy 379.021687 -289.233737) (xy 379.057027 -289.269077)
			(xy 379.086403 -289.30951) (xy 379.109093 -289.354042) (xy 379.124537 -289.401574) (xy 379.132356 -289.450937)
			(xy 379.132846 -289.475926) (xy 379.438657 -289.475926) (xy 379.442752 -289.425198) (xy 379.454931 -289.375784)
			(xy 379.474879 -289.328964) (xy 379.50208 -289.28595) (xy 379.535828 -289.247856) (xy 379.57525 -289.215669)
			(xy 379.619324 -289.190223) (xy 379.66691 -289.172176) (xy 379.716774 -289.161996) (xy 379.767626 -289.159947)
			(xy 379.818147 -289.166081) (xy 379.867031 -289.180241) (xy 379.91301 -289.202058) (xy 379.954894 -289.230968)
			(xy 379.991598 -289.266223) (xy 380.022171 -289.306909) (xy 380.045822 -289.351972) (xy 380.061938 -289.400246)
			(xy 380.070102 -289.45048) (xy 380.070614 -289.475926) (xy 380.378711 -289.475926) (xy 380.382806 -289.425198)
			(xy 380.394985 -289.375784) (xy 380.414933 -289.328964) (xy 380.442134 -289.28595) (xy 380.475882 -289.247856)
			(xy 380.515304 -289.215669) (xy 380.559378 -289.190223) (xy 380.606964 -289.172176) (xy 380.656828 -289.161996)
			(xy 380.70768 -289.159947) (xy 380.758201 -289.166081) (xy 380.807085 -289.180241) (xy 380.853064 -289.202058)
			(xy 380.894948 -289.230968) (xy 380.931652 -289.266223) (xy 380.962225 -289.306909) (xy 380.985876 -289.351972)
			(xy 381.001992 -289.400246) (xy 381.010156 -289.45048) (xy 381.010668 -289.475926) (xy 381.010156 -289.501372)
			(xy 381.001992 -289.551606) (xy 380.985876 -289.59988) (xy 380.962225 -289.644943) (xy 380.931652 -289.685629)
			(xy 380.894948 -289.720884) (xy 380.853064 -289.749794) (xy 380.807085 -289.771611) (xy 380.758201 -289.785771)
			(xy 380.70768 -289.791905) (xy 380.656828 -289.789856) (xy 380.606964 -289.779676) (xy 380.559378 -289.761629)
			(xy 380.515304 -289.736183) (xy 380.475882 -289.703996) (xy 380.442134 -289.665902) (xy 380.414933 -289.622888)
			(xy 380.394985 -289.576068) (xy 380.382806 -289.526654) (xy 380.378711 -289.475926) (xy 380.070614 -289.475926)
			(xy 380.070102 -289.501372) (xy 380.061938 -289.551606) (xy 380.045822 -289.59988) (xy 380.022171 -289.644943)
			(xy 379.991598 -289.685629) (xy 379.954894 -289.720884) (xy 379.91301 -289.749794) (xy 379.867031 -289.771611)
			(xy 379.818147 -289.785771) (xy 379.767626 -289.791905) (xy 379.716774 -289.789856) (xy 379.66691 -289.779676)
			(xy 379.619324 -289.761629) (xy 379.57525 -289.736183) (xy 379.535828 -289.703996) (xy 379.50208 -289.665902)
			(xy 379.474879 -289.622888) (xy 379.454931 -289.576068) (xy 379.442752 -289.526654) (xy 379.438657 -289.475926)
			(xy 379.132846 -289.475926) (xy 379.132356 -289.500915) (xy 379.124537 -289.550278) (xy 379.109093 -289.59781)
			(xy 379.086403 -289.642342) (xy 379.057027 -289.682775) (xy 379.021687 -289.718115) (xy 378.981254 -289.747491)
			(xy 378.936722 -289.770181) (xy 378.88919 -289.785625) (xy 378.839827 -289.793444) (xy 378.789849 -289.793444)
			(xy 378.740486 -289.785625) (xy 378.692954 -289.770181) (xy 378.648422 -289.747491) (xy 378.607989 -289.718115)
			(xy 378.572649 -289.682775) (xy 378.543273 -289.642342) (xy 378.520583 -289.59781) (xy 378.505139 -289.550278)
			(xy 378.49732 -289.500915) (xy 378.190003 -289.500915) (xy 378.189994 -289.501372) (xy 378.18183 -289.551606)
			(xy 378.165714 -289.59988) (xy 378.142063 -289.644943) (xy 378.11149 -289.685629) (xy 378.074786 -289.720884)
			(xy 378.032902 -289.749794) (xy 377.986923 -289.771611) (xy 377.938039 -289.785771) (xy 377.887518 -289.791905)
			(xy 377.836666 -289.789856) (xy 377.786802 -289.779676) (xy 377.739216 -289.761629) (xy 377.695142 -289.736183)
			(xy 377.65572 -289.703996) (xy 377.621972 -289.665902) (xy 377.594771 -289.622888) (xy 377.574823 -289.576068)
			(xy 377.562644 -289.526654) (xy 377.558549 -289.475926) (xy 377.252738 -289.475926) (xy 377.252248 -289.500915)
			(xy 377.244429 -289.550278) (xy 377.228985 -289.59781) (xy 377.206295 -289.642342) (xy 377.176919 -289.682775)
			(xy 377.141579 -289.718115) (xy 377.101146 -289.747491) (xy 377.056614 -289.770181) (xy 377.009082 -289.785625)
			(xy 376.959719 -289.793444) (xy 376.909741 -289.793444) (xy 376.860378 -289.785625) (xy 376.812846 -289.770181)
			(xy 376.768314 -289.747491) (xy 376.727881 -289.718115) (xy 376.692541 -289.682775) (xy 376.663165 -289.642342)
			(xy 376.640475 -289.59781) (xy 376.625031 -289.550278) (xy 376.617212 -289.500915) (xy 376.310149 -289.500915)
			(xy 376.31014 -289.501372) (xy 376.301976 -289.551606) (xy 376.28586 -289.59988) (xy 376.262209 -289.644943)
			(xy 376.231636 -289.685629) (xy 376.194932 -289.720884) (xy 376.153048 -289.749794) (xy 376.107069 -289.771611)
			(xy 376.058185 -289.785771) (xy 376.007664 -289.791905) (xy 375.956812 -289.789856) (xy 375.906948 -289.779676)
			(xy 375.859362 -289.761629) (xy 375.815288 -289.736183) (xy 375.775866 -289.703996) (xy 375.742118 -289.665902)
			(xy 375.714917 -289.622888) (xy 375.694969 -289.576068) (xy 375.68279 -289.526654) (xy 375.678695 -289.475926)
			(xy 375.372884 -289.475926) (xy 375.372884 -289.489642) (xy 375.371473 -289.512912) (xy 375.36267 -289.558691)
			(xy 375.355358 -289.580828) (xy 375.350532 -289.594798) (xy 375.356882 -289.622738) (xy 375.988326 -290.254182)
			(xy 375.994676 -290.259516) (xy 376.004279 -290.265685) (xy 376.0267 -290.269792) (xy 376.037856 -290.26739)
			(xy 376.134122 -290.24072) (xy 376.153172 -290.221162) (xy 376.156474 -290.207954) (xy 376.163425 -290.182567)
			(xy 376.184556 -290.134362) (xy 376.213337 -290.090296) (xy 376.248982 -290.051571) (xy 376.290518 -290.019244)
			(xy 376.336811 -289.9942) (xy 376.386596 -289.977121) (xy 376.438513 -289.968475) (xy 376.46483 -289.967924)
			(xy 376.489815 -289.968416) (xy 376.53917 -289.976238) (xy 376.586693 -289.991683) (xy 376.631215 -290.014372)
			(xy 376.671641 -290.043746) (xy 376.706973 -290.079082) (xy 376.736344 -290.11951) (xy 376.759028 -290.164035)
			(xy 376.774469 -290.21156) (xy 376.782286 -290.260915) (xy 376.782286 -290.285932) (xy 377.088649 -290.285932)
			(xy 377.092744 -290.235204) (xy 377.104923 -290.18579) (xy 377.124871 -290.13897) (xy 377.152072 -290.095956)
			(xy 377.18582 -290.057862) (xy 377.225242 -290.025675) (xy 377.269316 -290.000229) (xy 377.316902 -289.982182)
			(xy 377.366766 -289.972002) (xy 377.417618 -289.969953) (xy 377.468139 -289.976087) (xy 377.517023 -289.990247)
			(xy 377.563002 -290.012064) (xy 377.604886 -290.040974) (xy 377.64159 -290.076229) (xy 377.672163 -290.116915)
			(xy 377.695814 -290.161978) (xy 377.71193 -290.210252) (xy 377.720094 -290.260486) (xy 377.720606 -290.285932)
			(xy 378.968503 -290.285932) (xy 378.972598 -290.235204) (xy 378.984777 -290.18579) (xy 379.004725 -290.13897)
			(xy 379.031926 -290.095956) (xy 379.065674 -290.057862) (xy 379.105096 -290.025675) (xy 379.14917 -290.000229)
			(xy 379.196756 -289.982182) (xy 379.24662 -289.972002) (xy 379.297472 -289.969953) (xy 379.347993 -289.976087)
			(xy 379.396877 -289.990247) (xy 379.442856 -290.012064) (xy 379.48474 -290.040974) (xy 379.521444 -290.076229)
			(xy 379.552017 -290.116915) (xy 379.575668 -290.161978) (xy 379.591784 -290.210252) (xy 379.599948 -290.260486)
			(xy 379.60046 -290.285932) (xy 379.599957 -290.310921) (xy 379.907274 -290.310921) (xy 379.907274 -290.260943)
			(xy 379.915093 -290.21158) (xy 379.930537 -290.164048) (xy 379.953227 -290.119516) (xy 379.982603 -290.079083)
			(xy 380.017943 -290.043743) (xy 380.058376 -290.014367) (xy 380.102908 -289.991677) (xy 380.15044 -289.976233)
			(xy 380.199803 -289.968414) (xy 380.249781 -289.968414) (xy 380.299144 -289.976233) (xy 380.346676 -289.991677)
			(xy 380.391208 -290.014367) (xy 380.431641 -290.043743) (xy 380.466981 -290.079083) (xy 380.496357 -290.119516)
			(xy 380.519047 -290.164048) (xy 380.534491 -290.21158) (xy 380.54231 -290.260943) (xy 380.5428 -290.285932)
			(xy 380.54231 -290.310921) (xy 380.534491 -290.360284) (xy 380.519047 -290.407816) (xy 380.496357 -290.452348)
			(xy 380.466981 -290.492781) (xy 380.431641 -290.528121) (xy 380.391208 -290.557497) (xy 380.346676 -290.580187)
			(xy 380.299144 -290.595631) (xy 380.249781 -290.60345) (xy 380.199803 -290.60345) (xy 380.15044 -290.595631)
			(xy 380.102908 -290.580187) (xy 380.058376 -290.557497) (xy 380.017943 -290.528121) (xy 379.982603 -290.492781)
			(xy 379.953227 -290.452348) (xy 379.930537 -290.407816) (xy 379.915093 -290.360284) (xy 379.907274 -290.310921)
			(xy 379.599957 -290.310921) (xy 379.599948 -290.311378) (xy 379.591784 -290.361612) (xy 379.575668 -290.409886)
			(xy 379.552017 -290.454949) (xy 379.521444 -290.495635) (xy 379.48474 -290.53089) (xy 379.442856 -290.5598)
			(xy 379.396877 -290.581617) (xy 379.347993 -290.595777) (xy 379.297472 -290.601911) (xy 379.24662 -290.599862)
			(xy 379.196756 -290.589682) (xy 379.14917 -290.571635) (xy 379.105096 -290.546189) (xy 379.065674 -290.514002)
			(xy 379.031926 -290.475908) (xy 379.004725 -290.432894) (xy 378.984777 -290.386074) (xy 378.972598 -290.33666)
			(xy 378.968503 -290.285932) (xy 377.720606 -290.285932) (xy 377.720094 -290.311378) (xy 377.71193 -290.361612)
			(xy 377.695814 -290.409886) (xy 377.672163 -290.454949) (xy 377.64159 -290.495635) (xy 377.604886 -290.53089)
			(xy 377.563002 -290.5598) (xy 377.517023 -290.581617) (xy 377.468139 -290.595777) (xy 377.417618 -290.601911)
			(xy 377.366766 -290.599862) (xy 377.316902 -290.589682) (xy 377.269316 -290.571635) (xy 377.225242 -290.546189)
			(xy 377.18582 -290.514002) (xy 377.152072 -290.475908) (xy 377.124871 -290.432894) (xy 377.104923 -290.386074)
			(xy 377.092744 -290.33666) (xy 377.088649 -290.285932) (xy 376.782286 -290.285932) (xy 376.782286 -290.310885)
			(xy 376.774469 -290.36024) (xy 376.759028 -290.407765) (xy 376.736344 -290.45229) (xy 376.706973 -290.492718)
			(xy 376.671641 -290.528054) (xy 376.631215 -290.557428) (xy 376.586693 -290.580117) (xy 376.53917 -290.595562)
			(xy 376.489815 -290.603384) (xy 376.46483 -290.60394) (xy 376.440417 -290.603475) (xy 376.392168 -290.595979)
			(xy 376.34563 -290.581203) (xy 376.301894 -290.559494) (xy 376.281696 -290.545774) (xy 376.278394 -290.543742)
			(xy 376.270824 -290.539656) (xy 376.253967 -290.536275) (xy 376.236936 -290.538625) (xy 376.229118 -290.542218)
			(xy 376.150886 -290.582604) (xy 376.142799 -290.587228) (xy 376.130395 -290.601105) (xy 376.123793 -290.618508)
			(xy 376.123454 -290.627816) (xy 376.123454 -290.773612) (xy 376.123799 -290.782599) (xy 376.130006 -290.799466)
			(xy 376.141681 -290.813131) (xy 376.149362 -290.817808) (xy 376.149616 -290.818062) (xy 376.172091 -290.831171)
			(xy 376.212819 -290.863544) (xy 376.247734 -290.902114) (xy 376.275905 -290.945854) (xy 376.296581 -290.993595)
			(xy 376.309211 -291.044066) (xy 376.313456 -291.095919) (xy 376.311406 -291.120927) (xy 376.617212 -291.120927)
			(xy 376.617212 -291.070949) (xy 376.625031 -291.021586) (xy 376.640475 -290.974054) (xy 376.663165 -290.929522)
			(xy 376.692541 -290.889089) (xy 376.727881 -290.853749) (xy 376.768314 -290.824373) (xy 376.812846 -290.801683)
			(xy 376.860378 -290.786239) (xy 376.909741 -290.77842) (xy 376.959719 -290.77842) (xy 377.009082 -290.786239)
			(xy 377.056614 -290.801683) (xy 377.101146 -290.824373) (xy 377.141579 -290.853749) (xy 377.176919 -290.889089)
			(xy 377.206295 -290.929522) (xy 377.228985 -290.974054) (xy 377.244429 -291.021586) (xy 377.252248 -291.070949)
			(xy 377.252738 -291.095938) (xy 377.558549 -291.095938) (xy 377.562644 -291.04521) (xy 377.574823 -290.995796)
			(xy 377.594771 -290.948976) (xy 377.621972 -290.905962) (xy 377.65572 -290.867868) (xy 377.695142 -290.835681)
			(xy 377.739216 -290.810235) (xy 377.786802 -290.792188) (xy 377.836666 -290.782008) (xy 377.887518 -290.779959)
			(xy 377.938039 -290.786093) (xy 377.986923 -290.800253) (xy 378.032902 -290.82207) (xy 378.074786 -290.85098)
			(xy 378.11149 -290.886235) (xy 378.142063 -290.926921) (xy 378.165714 -290.971984) (xy 378.18183 -291.020258)
			(xy 378.189994 -291.070492) (xy 378.190506 -291.095938) (xy 378.190003 -291.120927) (xy 378.49732 -291.120927)
			(xy 378.49732 -291.070949) (xy 378.505139 -291.021586) (xy 378.520583 -290.974054) (xy 378.543273 -290.929522)
			(xy 378.572649 -290.889089) (xy 378.607989 -290.853749) (xy 378.648422 -290.824373) (xy 378.692954 -290.801683)
			(xy 378.740486 -290.786239) (xy 378.789849 -290.77842) (xy 378.839827 -290.77842) (xy 378.88919 -290.786239)
			(xy 378.936722 -290.801683) (xy 378.981254 -290.824373) (xy 379.021687 -290.853749) (xy 379.057027 -290.889089)
			(xy 379.086403 -290.929522) (xy 379.109093 -290.974054) (xy 379.124537 -291.021586) (xy 379.132356 -291.070949)
			(xy 379.132846 -291.095938) (xy 379.438657 -291.095938) (xy 379.442752 -291.04521) (xy 379.454931 -290.995796)
			(xy 379.474879 -290.948976) (xy 379.50208 -290.905962) (xy 379.535828 -290.867868) (xy 379.57525 -290.835681)
			(xy 379.619324 -290.810235) (xy 379.66691 -290.792188) (xy 379.716774 -290.782008) (xy 379.767626 -290.779959)
			(xy 379.818147 -290.786093) (xy 379.867031 -290.800253) (xy 379.91301 -290.82207) (xy 379.954894 -290.85098)
			(xy 379.991598 -290.886235) (xy 380.022171 -290.926921) (xy 380.045822 -290.971984) (xy 380.061938 -291.020258)
			(xy 380.070102 -291.070492) (xy 380.070614 -291.095938) (xy 380.378711 -291.095938) (xy 380.382806 -291.04521)
			(xy 380.394985 -290.995796) (xy 380.414933 -290.948976) (xy 380.442134 -290.905962) (xy 380.475882 -290.867868)
			(xy 380.515304 -290.835681) (xy 380.559378 -290.810235) (xy 380.606964 -290.792188) (xy 380.656828 -290.782008)
			(xy 380.70768 -290.779959) (xy 380.758201 -290.786093) (xy 380.807085 -290.800253) (xy 380.853064 -290.82207)
			(xy 380.894948 -290.85098) (xy 380.931652 -290.886235) (xy 380.962225 -290.926921) (xy 380.985876 -290.971984)
			(xy 381.001992 -291.020258) (xy 381.010156 -291.070492) (xy 381.010668 -291.095938) (xy 381.010156 -291.121384)
			(xy 381.001992 -291.171618) (xy 380.985876 -291.219892) (xy 380.962225 -291.264955) (xy 380.931652 -291.305641)
			(xy 380.894948 -291.340896) (xy 380.853064 -291.369806) (xy 380.807085 -291.391623) (xy 380.758201 -291.405783)
			(xy 380.70768 -291.411917) (xy 380.656828 -291.409868) (xy 380.606964 -291.399688) (xy 380.559378 -291.381641)
			(xy 380.515304 -291.356195) (xy 380.475882 -291.324008) (xy 380.442134 -291.285914) (xy 380.414933 -291.2429)
			(xy 380.394985 -291.19608) (xy 380.382806 -291.146666) (xy 380.378711 -291.095938) (xy 380.070614 -291.095938)
			(xy 380.070102 -291.121384) (xy 380.061938 -291.171618) (xy 380.045822 -291.219892) (xy 380.022171 -291.264955)
			(xy 379.991598 -291.305641) (xy 379.954894 -291.340896) (xy 379.91301 -291.369806) (xy 379.867031 -291.391623)
			(xy 379.818147 -291.405783) (xy 379.767626 -291.411917) (xy 379.716774 -291.409868) (xy 379.66691 -291.399688)
			(xy 379.619324 -291.381641) (xy 379.57525 -291.356195) (xy 379.535828 -291.324008) (xy 379.50208 -291.285914)
			(xy 379.474879 -291.2429) (xy 379.454931 -291.19608) (xy 379.442752 -291.146666) (xy 379.438657 -291.095938)
			(xy 379.132846 -291.095938) (xy 379.132356 -291.120927) (xy 379.124537 -291.17029) (xy 379.109093 -291.217822)
			(xy 379.086403 -291.262354) (xy 379.057027 -291.302787) (xy 379.021687 -291.338127) (xy 378.981254 -291.367503)
			(xy 378.936722 -291.390193) (xy 378.88919 -291.405637) (xy 378.839827 -291.413456) (xy 378.789849 -291.413456)
			(xy 378.740486 -291.405637) (xy 378.692954 -291.390193) (xy 378.648422 -291.367503) (xy 378.607989 -291.338127)
			(xy 378.572649 -291.302787) (xy 378.543273 -291.262354) (xy 378.520583 -291.217822) (xy 378.505139 -291.17029)
			(xy 378.49732 -291.120927) (xy 378.190003 -291.120927) (xy 378.189994 -291.121384) (xy 378.18183 -291.171618)
			(xy 378.165714 -291.219892) (xy 378.142063 -291.264955) (xy 378.11149 -291.305641) (xy 378.074786 -291.340896)
			(xy 378.032902 -291.369806) (xy 377.986923 -291.391623) (xy 377.938039 -291.405783) (xy 377.887518 -291.411917)
			(xy 377.836666 -291.409868) (xy 377.786802 -291.399688) (xy 377.739216 -291.381641) (xy 377.695142 -291.356195)
			(xy 377.65572 -291.324008) (xy 377.621972 -291.285914) (xy 377.594771 -291.2429) (xy 377.574823 -291.19608)
			(xy 377.562644 -291.146666) (xy 377.558549 -291.095938) (xy 377.252738 -291.095938) (xy 377.252248 -291.120927)
			(xy 377.244429 -291.17029) (xy 377.228985 -291.217822) (xy 377.206295 -291.262354) (xy 377.176919 -291.302787)
			(xy 377.141579 -291.338127) (xy 377.101146 -291.367503) (xy 377.056614 -291.390193) (xy 377.009082 -291.405637)
			(xy 376.959719 -291.413456) (xy 376.909741 -291.413456) (xy 376.860378 -291.405637) (xy 376.812846 -291.390193)
			(xy 376.768314 -291.367503) (xy 376.727881 -291.338127) (xy 376.692541 -291.302787) (xy 376.663165 -291.262354)
			(xy 376.640475 -291.217822) (xy 376.625031 -291.17029) (xy 376.617212 -291.120927) (xy 376.311406 -291.120927)
			(xy 376.309205 -291.147771) (xy 376.296569 -291.19824) (xy 376.275888 -291.245979) (xy 376.247711 -291.289715)
			(xy 376.212792 -291.328282) (xy 376.17206 -291.36065) (xy 376.149616 -291.373814) (xy 376.149362 -291.374068)
			(xy 376.14172 -291.37879) (xy 376.130079 -291.392457) (xy 376.123838 -291.409289) (xy 376.123454 -291.418264)
			(xy 376.123454 -291.56406) (xy 376.123866 -291.573356) (xy 376.130478 -291.590733) (xy 376.142819 -291.604638)
			(xy 376.150886 -291.609272) (xy 376.229118 -291.649658) (xy 376.236917 -291.653319) (xy 376.253968 -291.655706)
			(xy 376.270839 -291.652275) (xy 376.278394 -291.648134) (xy 376.280172 -291.647118) (xy 376.300505 -291.633187)
			(xy 376.344563 -291.611098) (xy 376.391497 -291.596058) (xy 376.440188 -291.588426) (xy 376.46483 -291.587936)
			(xy 376.489814 -291.588428) (xy 376.539167 -291.596249) (xy 376.586688 -291.611694) (xy 376.631209 -291.634382)
			(xy 376.671633 -291.663755) (xy 376.706964 -291.69909) (xy 376.736333 -291.739516) (xy 376.759017 -291.784039)
			(xy 376.774458 -291.831562) (xy 376.782274 -291.880916) (xy 376.782274 -291.905944) (xy 377.088649 -291.905944)
			(xy 377.092744 -291.855216) (xy 377.104923 -291.805802) (xy 377.124871 -291.758982) (xy 377.152072 -291.715968)
			(xy 377.18582 -291.677874) (xy 377.225242 -291.645687) (xy 377.269316 -291.620241) (xy 377.316902 -291.602194)
			(xy 377.366766 -291.592014) (xy 377.417618 -291.589965) (xy 377.468139 -291.596099) (xy 377.517023 -291.610259)
			(xy 377.563002 -291.632076) (xy 377.604886 -291.660986) (xy 377.64159 -291.696241) (xy 377.672163 -291.736927)
			(xy 377.695814 -291.78199) (xy 377.71193 -291.830264) (xy 377.720094 -291.880498) (xy 377.720606 -291.905944)
			(xy 377.720103 -291.930933) (xy 378.02742 -291.930933) (xy 378.02742 -291.880955) (xy 378.035239 -291.831592)
			(xy 378.050683 -291.78406) (xy 378.073373 -291.739528) (xy 378.102749 -291.699095) (xy 378.138089 -291.663755)
			(xy 378.178522 -291.634379) (xy 378.223054 -291.611689) (xy 378.270586 -291.596245) (xy 378.319949 -291.588426)
			(xy 378.369927 -291.588426) (xy 378.41929 -291.596245) (xy 378.466822 -291.611689) (xy 378.511354 -291.634379)
			(xy 378.551787 -291.663755) (xy 378.587127 -291.699095) (xy 378.616503 -291.739528) (xy 378.639193 -291.78406)
			(xy 378.654637 -291.831592) (xy 378.662456 -291.880955) (xy 378.662946 -291.905944) (xy 378.968503 -291.905944)
			(xy 378.972598 -291.855216) (xy 378.984777 -291.805802) (xy 379.004725 -291.758982) (xy 379.031926 -291.715968)
			(xy 379.065674 -291.677874) (xy 379.105096 -291.645687) (xy 379.14917 -291.620241) (xy 379.196756 -291.602194)
			(xy 379.24662 -291.592014) (xy 379.297472 -291.589965) (xy 379.347993 -291.596099) (xy 379.396877 -291.610259)
			(xy 379.442856 -291.632076) (xy 379.48474 -291.660986) (xy 379.521444 -291.696241) (xy 379.552017 -291.736927)
			(xy 379.575668 -291.78199) (xy 379.591784 -291.830264) (xy 379.599948 -291.880498) (xy 379.60046 -291.905944)
			(xy 379.599957 -291.930933) (xy 379.907274 -291.930933) (xy 379.907274 -291.880955) (xy 379.915093 -291.831592)
			(xy 379.930537 -291.78406) (xy 379.953227 -291.739528) (xy 379.982603 -291.699095) (xy 380.017943 -291.663755)
			(xy 380.058376 -291.634379) (xy 380.102908 -291.611689) (xy 380.15044 -291.596245) (xy 380.199803 -291.588426)
			(xy 380.249781 -291.588426) (xy 380.299144 -291.596245) (xy 380.346676 -291.611689) (xy 380.391208 -291.634379)
			(xy 380.431641 -291.663755) (xy 380.466981 -291.699095) (xy 380.496357 -291.739528) (xy 380.519047 -291.78406)
			(xy 380.534491 -291.831592) (xy 380.54231 -291.880955) (xy 380.5428 -291.905944) (xy 380.54231 -291.930933)
			(xy 380.534491 -291.980296) (xy 380.519047 -292.027828) (xy 380.496357 -292.07236) (xy 380.466981 -292.112793)
			(xy 380.431641 -292.148133) (xy 380.391208 -292.177509) (xy 380.346676 -292.200199) (xy 380.299144 -292.215643)
			(xy 380.249781 -292.223462) (xy 380.199803 -292.223462) (xy 380.15044 -292.215643) (xy 380.102908 -292.200199)
			(xy 380.058376 -292.177509) (xy 380.017943 -292.148133) (xy 379.982603 -292.112793) (xy 379.953227 -292.07236)
			(xy 379.930537 -292.027828) (xy 379.915093 -291.980296) (xy 379.907274 -291.930933) (xy 379.599957 -291.930933)
			(xy 379.599948 -291.93139) (xy 379.591784 -291.981624) (xy 379.575668 -292.029898) (xy 379.552017 -292.074961)
			(xy 379.521444 -292.115647) (xy 379.48474 -292.150902) (xy 379.442856 -292.179812) (xy 379.396877 -292.201629)
			(xy 379.347993 -292.215789) (xy 379.297472 -292.221923) (xy 379.24662 -292.219874) (xy 379.196756 -292.209694)
			(xy 379.14917 -292.191647) (xy 379.105096 -292.166201) (xy 379.065674 -292.134014) (xy 379.031926 -292.09592)
			(xy 379.004725 -292.052906) (xy 378.984777 -292.006086) (xy 378.972598 -291.956672) (xy 378.968503 -291.905944)
			(xy 378.662946 -291.905944) (xy 378.662456 -291.930933) (xy 378.654637 -291.980296) (xy 378.639193 -292.027828)
			(xy 378.616503 -292.07236) (xy 378.587127 -292.112793) (xy 378.551787 -292.148133) (xy 378.511354 -292.177509)
			(xy 378.466822 -292.200199) (xy 378.41929 -292.215643) (xy 378.369927 -292.223462) (xy 378.319949 -292.223462)
			(xy 378.270586 -292.215643) (xy 378.223054 -292.200199) (xy 378.178522 -292.177509) (xy 378.138089 -292.148133)
			(xy 378.102749 -292.112793) (xy 378.073373 -292.07236) (xy 378.050683 -292.027828) (xy 378.035239 -291.980296)
			(xy 378.02742 -291.930933) (xy 377.720103 -291.930933) (xy 377.720094 -291.93139) (xy 377.71193 -291.981624)
			(xy 377.695814 -292.029898) (xy 377.672163 -292.074961) (xy 377.64159 -292.115647) (xy 377.604886 -292.150902)
			(xy 377.563002 -292.179812) (xy 377.517023 -292.201629) (xy 377.468139 -292.215789) (xy 377.417618 -292.221923)
			(xy 377.366766 -292.219874) (xy 377.316902 -292.209694) (xy 377.269316 -292.191647) (xy 377.225242 -292.166201)
			(xy 377.18582 -292.134014) (xy 377.152072 -292.09592) (xy 377.124871 -292.052906) (xy 377.104923 -292.006086)
			(xy 377.092744 -291.956672) (xy 377.088649 -291.905944) (xy 376.782274 -291.905944) (xy 376.782274 -291.930884)
			(xy 376.774458 -291.980238) (xy 376.759017 -292.027761) (xy 376.736333 -292.072284) (xy 376.706964 -292.11271)
			(xy 376.671633 -292.148045) (xy 376.631209 -292.177418) (xy 376.586688 -292.200106) (xy 376.539167 -292.215551)
			(xy 376.489814 -292.223372) (xy 376.46483 -292.223952) (xy 376.440417 -292.223487) (xy 376.392168 -292.215991)
			(xy 376.34563 -292.201215) (xy 376.301893 -292.179507) (xy 376.281696 -292.165786) (xy 376.278394 -292.163754)
			(xy 376.270824 -292.159667) (xy 376.253967 -292.156285) (xy 376.236935 -292.158636) (xy 376.229118 -292.16223)
			(xy 376.150886 -292.202616) (xy 376.1428 -292.207241) (xy 376.130399 -292.221118) (xy 376.123802 -292.238521)
			(xy 376.123454 -292.247828) (xy 376.123454 -292.386766) (xy 376.123921 -292.39664) (xy 376.131372 -292.414931)
			(xy 376.137932 -292.422326) (xy 376.138186 -292.42258) (xy 376.159268 -292.443662) (xy 376.164094 -292.44671)
			(xy 376.184019 -292.459732) (xy 376.220092 -292.490786) (xy 376.251133 -292.52687) (xy 376.26417 -292.546786)
			(xy 376.267218 -292.551612) (xy 376.448828 -292.733222) (xy 376.455814 -292.739709) (xy 376.473245 -292.747398)
			(xy 376.49228 -292.748171) (xy 376.501406 -292.745414) (xy 376.599196 -292.711886) (xy 376.617484 -292.689534)
			(xy 376.619262 -292.675056) (xy 376.623031 -292.649835) (xy 376.637557 -292.600957) (xy 376.6597 -292.555024)
			(xy 376.688891 -292.513216) (xy 376.724383 -292.476604) (xy 376.765265 -292.446127) (xy 376.810487 -292.422568)
			(xy 376.858891 -292.406531) (xy 376.909234 -292.398427) (xy 376.93473 -292.397942) (xy 376.959718 -292.398409)
			(xy 377.009079 -292.406232) (xy 377.056607 -292.421681) (xy 377.101134 -292.444375) (xy 377.141563 -292.473755)
			(xy 377.176897 -292.509098) (xy 377.206267 -292.549534) (xy 377.22895 -292.594067) (xy 377.244386 -292.641599)
			(xy 377.252197 -292.690962) (xy 377.252738 -292.71595) (xy 377.252102 -292.745403) (xy 377.241272 -292.803306)
			(xy 377.219973 -292.858227) (xy 377.204986 -292.88359) (xy 377.19762 -292.895274) (xy 377.197112 -292.92296)
			(xy 377.24588 -293.01059) (xy 377.250583 -293.01833) (xy 377.264309 -293.030126) (xy 377.281281 -293.036411)
			(xy 377.29033 -293.036752)
		)
		(stroke
			(width 0)
			(type solid)
		)
		(fill yes)
		(layer "B.Cu")
		(net "PVDD11_S3_P0")
	)
	(gr_poly
		(pts
			(xy 429.193452 -397.53794) (xy 429.202979 -397.537552) (xy 429.220722 -397.530607) (xy 429.234701 -397.517659)
			(xy 429.239172 -397.509238) (xy 429.2854 -397.41348) (xy 429.282098 -397.384778) (xy 429.272954 -397.373094)
			(xy 429.257292 -397.352774) (xy 429.230987 -397.308728) (xy 429.210829 -397.261551) (xy 429.197185 -397.212095)
			(xy 429.1903 -397.161256) (xy 429.189896 -397.135604) (xy 429.190382 -397.108353) (xy 429.198138 -397.054405)
			(xy 429.213493 -397.00211) (xy 429.236135 -396.952533) (xy 429.265601 -396.906683) (xy 429.301292 -396.865492)
			(xy 429.342483 -396.829801) (xy 429.388333 -396.800335) (xy 429.43791 -396.777693) (xy 429.490205 -396.762338)
			(xy 429.544153 -396.754582) (xy 429.598655 -396.754582) (xy 429.652603 -396.762338) (xy 429.704898 -396.777693)
			(xy 429.754475 -396.800335) (xy 429.800325 -396.829801) (xy 429.841516 -396.865492) (xy 429.877207 -396.906683)
			(xy 429.906673 -396.952533) (xy 429.929315 -397.00211) (xy 429.94467 -397.054405) (xy 429.952426 -397.108353)
			(xy 429.952912 -397.135604) (xy 429.952477 -397.161253) (xy 429.945571 -397.212085) (xy 429.931925 -397.261535)
			(xy 429.911784 -397.308714) (xy 429.885511 -397.352774) (xy 429.869854 -397.373094) (xy 429.86071 -397.384778)
			(xy 429.857408 -397.41348) (xy 429.903636 -397.509238) (xy 429.908136 -397.517638) (xy 429.922107 -397.530579)
			(xy 429.939835 -397.537536) (xy 429.949356 -397.53794) (xy 430.430178 -397.53794) (xy 430.440241 -397.537501)
			(xy 430.458819 -397.52976) (xy 430.466246 -397.522954) (xy 430.649634 -397.339566) (xy 430.656482 -397.332169)
			(xy 430.664215 -397.31357) (xy 430.66462 -397.303498) (xy 430.66462 -392.888724) (xy 430.63922 -392.860276)
			(xy 430.619662 -392.85799) (xy 430.592169 -392.854243) (xy 430.538588 -392.839827) (xy 430.48766 -392.817804)
			(xy 430.440459 -392.788637) (xy 430.397978 -392.752942) (xy 430.361115 -392.711472) (xy 430.330646 -392.6651)
			(xy 430.307214 -392.614805) (xy 430.291312 -392.561646) (xy 430.283277 -392.506746) (xy 430.283276 -392.45126)
			(xy 430.291311 -392.396359) (xy 430.307212 -392.3432) (xy 430.330644 -392.292904) (xy 430.361112 -392.246532)
			(xy 430.397975 -392.205061) (xy 430.440455 -392.169366) (xy 430.487656 -392.140199) (xy 430.538583 -392.118175)
			(xy 430.592164 -392.103758) (xy 430.619662 -392.100054) (xy 430.63922 -392.097768) (xy 430.66462 -392.06932)
			(xy 430.66462 -389.118602) (xy 430.664198 -389.108531) (xy 430.656486 -389.089924) (xy 430.649634 -389.082534)
			(xy 429.015906 -387.448806) (xy 429.009058 -387.441408) (xy 429.00132 -387.42281) (xy 429.00092 -387.412738)
			(xy 429.00092 -380.787402) (xy 429.000498 -380.777331) (xy 428.992786 -380.758724) (xy 428.985934 -380.751334)
			(xy 425.97324 -377.73864) (xy 425.964473 -377.730763) (xy 425.94215 -377.723282) (xy 425.918824 -377.726465)
			(xy 425.908724 -377.732544) (xy 425.884834 -377.748177) (xy 425.833393 -377.772937) (xy 425.778837 -377.789759)
			(xy 425.722385 -377.798268) (xy 425.69384 -377.798838) (xy 425.665138 -377.797822) (xy 425.65193 -377.796806)
			(xy 425.628308 -377.807728) (xy 425.561506 -377.898406) (xy 425.558204 -377.924314) (xy 425.563284 -377.93676)
			(xy 425.571824 -377.959269) (xy 425.583819 -378.005895) (xy 425.589863 -378.053658) (xy 425.590208 -378.07773)
			(xy 425.589722 -378.104981) (xy 425.581966 -378.158929) (xy 425.566611 -378.211224) (xy 425.543969 -378.260801)
			(xy 425.514503 -378.306651) (xy 425.478812 -378.347842) (xy 425.437621 -378.383533) (xy 425.391771 -378.412999)
			(xy 425.342194 -378.435641) (xy 425.289899 -378.450996) (xy 425.235951 -378.458752) (xy 425.181449 -378.458752)
			(xy 425.127501 -378.450996) (xy 425.075206 -378.435641) (xy 425.025629 -378.412999) (xy 424.979779 -378.383533)
			(xy 424.938588 -378.347842) (xy 424.902897 -378.306651) (xy 424.873431 -378.260801) (xy 424.850789 -378.211224)
			(xy 424.835434 -378.158929) (xy 424.827678 -378.104981) (xy 424.827192 -378.07773) (xy 424.827895 -378.045199)
			(xy 424.839005 -377.981092) (xy 424.84929 -377.950222) (xy 424.852338 -377.941586) (xy 424.852084 -377.923806)
			(xy 424.82262 -377.84532) (xy 424.81119 -377.832112) (xy 424.803062 -377.82754) (xy 424.770804 -377.807728)
			(xy 424.764369 -377.803759) (xy 424.749911 -377.799363) (xy 424.742356 -377.799092) (xy 424.460924 -377.799092)
			(xy 424.453355 -377.79929) (xy 424.438871 -377.803676) (xy 424.432476 -377.807728) (xy 424.400218 -377.82754)
			(xy 424.39209 -377.832112) (xy 424.38066 -377.84532) (xy 424.351196 -377.923806) (xy 424.350942 -377.941586)
			(xy 424.35399 -377.950222) (xy 424.364291 -377.981088) (xy 424.37541 -378.045198) (xy 424.376088 -378.07773)
			(xy 424.375602 -378.104981) (xy 424.367846 -378.158929) (xy 424.352491 -378.211224) (xy 424.329849 -378.260801)
			(xy 424.300383 -378.306651) (xy 424.264692 -378.347842) (xy 424.223501 -378.383533) (xy 424.177651 -378.412999)
			(xy 424.128074 -378.435641) (xy 424.075779 -378.450996) (xy 424.021831 -378.458752) (xy 423.967329 -378.458752)
			(xy 423.913381 -378.450996) (xy 423.861086 -378.435641) (xy 423.811509 -378.412999) (xy 423.765659 -378.383533)
			(xy 423.724468 -378.347842) (xy 423.688777 -378.306651) (xy 423.659311 -378.260801) (xy 423.636669 -378.211224)
			(xy 423.621314 -378.158929) (xy 423.613558 -378.104981) (xy 423.613072 -378.07773) (xy 423.61342 -378.053657)
			(xy 423.619447 -378.005891) (xy 423.631446 -377.959266) (xy 423.639996 -377.93676) (xy 423.645076 -377.924314)
			(xy 423.641774 -377.898406) (xy 423.574972 -377.807728) (xy 423.55135 -377.796806) (xy 423.538142 -377.797822)
			(xy 423.50944 -377.798838) (xy 423.482183 -377.798378) (xy 423.428224 -377.790625) (xy 423.375917 -377.775271)
			(xy 423.326328 -377.752629) (xy 423.280466 -377.72316) (xy 423.239265 -377.687463) (xy 423.203564 -377.646266)
			(xy 423.17409 -377.600408) (xy 423.151443 -377.550821) (xy 423.136084 -377.498516) (xy 423.128325 -377.444557)
			(xy 423.128325 -377.390043) (xy 423.136084 -377.336084) (xy 423.151443 -377.283779) (xy 423.17409 -377.234192)
			(xy 423.203564 -377.188334) (xy 423.239265 -377.147137) (xy 423.280466 -377.11144) (xy 423.326328 -377.081971)
			(xy 423.375917 -377.059329) (xy 423.428224 -377.043975) (xy 423.482183 -377.036222) (xy 423.50944 -377.035822)
			(xy 423.538142 -377.036838) (xy 423.55135 -377.037854) (xy 423.574972 -377.026932) (xy 423.641774 -376.936254)
			(xy 423.645076 -376.910346) (xy 423.639996 -376.8979) (xy 423.631459 -376.87539) (xy 423.619469 -376.828764)
			(xy 423.613431 -376.781002) (xy 423.613072 -376.75693) (xy 423.614596 -376.721878) (xy 423.615612 -376.71121)
			(xy 423.609008 -376.69089) (xy 423.551096 -376.62739) (xy 423.543598 -376.619843) (xy 423.524134 -376.611302)
			(xy 423.513504 -376.61088) (xy 422.286176 -376.61088) (xy 422.275575 -376.611427) (xy 422.256161 -376.619955)
			(xy 422.248584 -376.62739) (xy 422.190672 -376.69089) (xy 422.184068 -376.71121) (xy 422.185084 -376.721878)
			(xy 422.186608 -376.75693) (xy 422.186256 -376.781002) (xy 422.180222 -376.828766) (xy 422.168216 -376.875388)
			(xy 422.159684 -376.8979) (xy 422.154604 -376.910346) (xy 422.157906 -376.936254) (xy 422.224708 -377.026932)
			(xy 422.24833 -377.037854) (xy 422.261538 -377.036838) (xy 422.29024 -377.035822) (xy 422.317487 -377.036311)
			(xy 422.371426 -377.044071) (xy 422.423712 -377.059429) (xy 422.47328 -377.08207) (xy 422.519122 -377.111535)
			(xy 422.560304 -377.147224) (xy 422.595989 -377.18841) (xy 422.625449 -377.234255) (xy 422.648085 -377.283825)
			(xy 422.663437 -377.336113) (xy 422.671192 -377.390053) (xy 422.671192 -377.444547) (xy 422.663437 -377.498487)
			(xy 422.648085 -377.550775) (xy 422.625449 -377.600345) (xy 422.595989 -377.64619) (xy 422.560304 -377.687376)
			(xy 422.519122 -377.723065) (xy 422.47328 -377.75253) (xy 422.423712 -377.775171) (xy 422.371426 -377.790529)
			(xy 422.317487 -377.798289) (xy 422.29024 -377.798838) (xy 422.261538 -377.797822) (xy 422.24833 -377.796806)
			(xy 422.224708 -377.807728) (xy 422.157906 -377.898406) (xy 422.154604 -377.924314) (xy 422.159684 -377.93676)
			(xy 422.168224 -377.959269) (xy 422.180219 -378.005895) (xy 422.186263 -378.053658) (xy 422.186608 -378.07773)
			(xy 422.186122 -378.104981) (xy 422.178366 -378.158929) (xy 422.163011 -378.211224) (xy 422.140369 -378.260801)
			(xy 422.110903 -378.306651) (xy 422.075212 -378.347842) (xy 422.034021 -378.383533) (xy 421.988171 -378.412999)
			(xy 421.938594 -378.435641) (xy 421.886299 -378.450996) (xy 421.832351 -378.458752) (xy 421.777849 -378.458752)
			(xy 421.723901 -378.450996) (xy 421.671606 -378.435641) (xy 421.622029 -378.412999) (xy 421.576179 -378.383533)
			(xy 421.534988 -378.347842) (xy 421.499297 -378.306651) (xy 421.469831 -378.260801) (xy 421.447189 -378.211224)
			(xy 421.431834 -378.158929) (xy 421.424078 -378.104981) (xy 421.423592 -378.07773) (xy 421.424295 -378.045199)
			(xy 421.435405 -377.981092) (xy 421.44569 -377.950222) (xy 421.448738 -377.941586) (xy 421.448484 -377.923806)
			(xy 421.41902 -377.84532) (xy 421.40759 -377.832112) (xy 421.399462 -377.82754) (xy 421.367204 -377.807728)
			(xy 421.360769 -377.803759) (xy 421.346311 -377.799363) (xy 421.338756 -377.799092) (xy 421.057324 -377.799092)
			(xy 421.049755 -377.79929) (xy 421.035271 -377.803676) (xy 421.028876 -377.807728) (xy 420.996618 -377.82754)
			(xy 420.98849 -377.832112) (xy 420.97706 -377.84532) (xy 420.947596 -377.923806) (xy 420.947342 -377.941586)
			(xy 420.95039 -377.950222) (xy 420.960691 -377.981088) (xy 420.97181 -378.045198) (xy 420.972488 -378.07773)
			(xy 420.972002 -378.104981) (xy 420.964246 -378.158929) (xy 420.948891 -378.211224) (xy 420.926249 -378.260801)
			(xy 420.896783 -378.306651) (xy 420.861092 -378.347842) (xy 420.819901 -378.383533) (xy 420.774051 -378.412999)
			(xy 420.724474 -378.435641) (xy 420.672179 -378.450996) (xy 420.618231 -378.458752) (xy 420.563729 -378.458752)
			(xy 420.509781 -378.450996) (xy 420.457486 -378.435641) (xy 420.407909 -378.412999) (xy 420.362059 -378.383533)
			(xy 420.320868 -378.347842) (xy 420.285177 -378.306651) (xy 420.255711 -378.260801) (xy 420.233069 -378.211224)
			(xy 420.217714 -378.158929) (xy 420.209958 -378.104981) (xy 420.209472 -378.07773) (xy 420.20982 -378.053657)
			(xy 420.215847 -378.005891) (xy 420.227846 -377.959266) (xy 420.236396 -377.93676) (xy 420.241476 -377.924314)
			(xy 420.238174 -377.898406) (xy 420.171372 -377.807728) (xy 420.14775 -377.796806) (xy 420.134542 -377.797822)
			(xy 420.10584 -377.798838) (xy 420.078583 -377.798378) (xy 420.024624 -377.790625) (xy 419.972317 -377.775271)
			(xy 419.922728 -377.752629) (xy 419.876866 -377.72316) (xy 419.835665 -377.687463) (xy 419.799964 -377.646266)
			(xy 419.77049 -377.600408) (xy 419.747843 -377.550821) (xy 419.732484 -377.498516) (xy 419.724725 -377.444557)
			(xy 419.724725 -377.390043) (xy 419.732484 -377.336084) (xy 419.747843 -377.283779) (xy 419.77049 -377.234192)
			(xy 419.799964 -377.188334) (xy 419.835665 -377.147137) (xy 419.876866 -377.11144) (xy 419.922728 -377.081971)
			(xy 419.972317 -377.059329) (xy 420.024624 -377.043975) (xy 420.078583 -377.036222) (xy 420.10584 -377.035822)
			(xy 420.134542 -377.036838) (xy 420.14775 -377.037854) (xy 420.171372 -377.026932) (xy 420.238174 -376.936254)
			(xy 420.241476 -376.910346) (xy 420.236396 -376.8979) (xy 420.227859 -376.87539) (xy 420.215869 -376.828764)
			(xy 420.209831 -376.781002) (xy 420.209472 -376.75693) (xy 420.210996 -376.721878) (xy 420.212012 -376.71121)
			(xy 420.205408 -376.69089) (xy 420.147496 -376.62739) (xy 420.139998 -376.619843) (xy 420.120534 -376.611302)
			(xy 420.109904 -376.61088) (xy 415.478976 -376.61088) (xy 415.468375 -376.611427) (xy 415.448961 -376.619955)
			(xy 415.441384 -376.62739) (xy 415.383472 -376.69089) (xy 415.376868 -376.71121) (xy 415.377884 -376.721878)
			(xy 415.379408 -376.75693) (xy 415.379056 -376.781002) (xy 415.373022 -376.828766) (xy 415.361016 -376.875388)
			(xy 415.352484 -376.8979) (xy 415.347404 -376.910346) (xy 415.350706 -376.936254) (xy 415.417508 -377.026932)
			(xy 415.44113 -377.037854) (xy 415.454338 -377.036838) (xy 415.48304 -377.035822) (xy 415.510287 -377.036311)
			(xy 415.564226 -377.044071) (xy 415.616512 -377.059429) (xy 415.66608 -377.08207) (xy 415.711922 -377.111535)
			(xy 415.753104 -377.147224) (xy 415.788789 -377.18841) (xy 415.818249 -377.234255) (xy 415.840885 -377.283825)
			(xy 415.856237 -377.336113) (xy 415.863992 -377.390053) (xy 415.863992 -377.444547) (xy 415.856237 -377.498487)
			(xy 415.840885 -377.550775) (xy 415.818249 -377.600345) (xy 415.788789 -377.64619) (xy 415.753104 -377.687376)
			(xy 415.711922 -377.723065) (xy 415.66608 -377.75253) (xy 415.616512 -377.775171) (xy 415.564226 -377.790529)
			(xy 415.510287 -377.798289) (xy 415.48304 -377.798838) (xy 415.454338 -377.797822) (xy 415.44113 -377.796806)
			(xy 415.417508 -377.807728) (xy 415.350706 -377.898406) (xy 415.347404 -377.924314) (xy 415.352484 -377.93676)
			(xy 415.361024 -377.959269) (xy 415.373019 -378.005895) (xy 415.379063 -378.053658) (xy 415.379408 -378.07773)
			(xy 415.378922 -378.104981) (xy 415.371166 -378.158929) (xy 415.355811 -378.211224) (xy 415.333169 -378.260801)
			(xy 415.303703 -378.306651) (xy 415.268012 -378.347842) (xy 415.226821 -378.383533) (xy 415.180971 -378.412999)
			(xy 415.131394 -378.435641) (xy 415.079099 -378.450996) (xy 415.025151 -378.458752) (xy 414.970649 -378.458752)
			(xy 414.916701 -378.450996) (xy 414.864406 -378.435641) (xy 414.814829 -378.412999) (xy 414.768979 -378.383533)
			(xy 414.727788 -378.347842) (xy 414.692097 -378.306651) (xy 414.662631 -378.260801) (xy 414.639989 -378.211224)
			(xy 414.624634 -378.158929) (xy 414.616878 -378.104981) (xy 414.616392 -378.07773) (xy 414.617095 -378.045199)
			(xy 414.628205 -377.981092) (xy 414.63849 -377.950222) (xy 414.641538 -377.941586) (xy 414.641284 -377.923806)
			(xy 414.61182 -377.84532) (xy 414.60039 -377.832112) (xy 414.592262 -377.82754) (xy 414.560004 -377.807728)
			(xy 414.553569 -377.803759) (xy 414.539111 -377.799363) (xy 414.531556 -377.799092) (xy 414.250124 -377.799092)
			(xy 414.242555 -377.79929) (xy 414.228071 -377.803676) (xy 414.221676 -377.807728) (xy 414.189418 -377.82754)
			(xy 414.18129 -377.832112) (xy 414.16986 -377.84532) (xy 414.140396 -377.923806) (xy 414.140142 -377.941586)
			(xy 414.14319 -377.950222) (xy 414.153491 -377.981088) (xy 414.16461 -378.045198) (xy 414.165288 -378.07773)
			(xy 414.164802 -378.104981) (xy 414.157046 -378.158929) (xy 414.141691 -378.211224) (xy 414.119049 -378.260801)
			(xy 414.089583 -378.306651) (xy 414.053892 -378.347842) (xy 414.012701 -378.383533) (xy 413.966851 -378.412999)
			(xy 413.917274 -378.435641) (xy 413.864979 -378.450996) (xy 413.811031 -378.458752) (xy 413.756529 -378.458752)
			(xy 413.702581 -378.450996) (xy 413.650286 -378.435641) (xy 413.600709 -378.412999) (xy 413.554859 -378.383533)
			(xy 413.513668 -378.347842) (xy 413.477977 -378.306651) (xy 413.448511 -378.260801) (xy 413.425869 -378.211224)
			(xy 413.410514 -378.158929) (xy 413.402758 -378.104981) (xy 413.402272 -378.07773) (xy 413.40262 -378.053657)
			(xy 413.408647 -378.005891) (xy 413.420646 -377.959266) (xy 413.429196 -377.93676) (xy 413.434276 -377.924314)
			(xy 413.430974 -377.898406) (xy 413.364172 -377.807728) (xy 413.34055 -377.796806) (xy 413.327342 -377.797822)
			(xy 413.29864 -377.798838) (xy 413.271383 -377.798378) (xy 413.217424 -377.790625) (xy 413.165117 -377.775271)
			(xy 413.115528 -377.752629) (xy 413.069666 -377.72316) (xy 413.028465 -377.687463) (xy 412.992764 -377.646266)
			(xy 412.96329 -377.600408) (xy 412.940643 -377.550821) (xy 412.925284 -377.498516) (xy 412.917525 -377.444557)
			(xy 412.917525 -377.390043) (xy 412.925284 -377.336084) (xy 412.940643 -377.283779) (xy 412.96329 -377.234192)
			(xy 412.992764 -377.188334) (xy 413.028465 -377.147137) (xy 413.069666 -377.11144) (xy 413.115528 -377.081971)
			(xy 413.165117 -377.059329) (xy 413.217424 -377.043975) (xy 413.271383 -377.036222) (xy 413.29864 -377.035822)
			(xy 413.327342 -377.036838) (xy 413.34055 -377.037854) (xy 413.364172 -377.026932) (xy 413.430974 -376.936254)
			(xy 413.434276 -376.910346) (xy 413.429196 -376.8979) (xy 413.420659 -376.87539) (xy 413.408669 -376.828764)
			(xy 413.402631 -376.781002) (xy 413.402272 -376.75693) (xy 413.403796 -376.721878) (xy 413.404812 -376.71121)
			(xy 413.398208 -376.69089) (xy 413.340296 -376.62739) (xy 413.332798 -376.619843) (xy 413.313334 -376.611302)
			(xy 413.302704 -376.61088) (xy 408.671776 -376.61088) (xy 408.661175 -376.611427) (xy 408.641761 -376.619955)
			(xy 408.634184 -376.62739) (xy 408.576272 -376.69089) (xy 408.569668 -376.71121) (xy 408.570684 -376.721878)
			(xy 408.572208 -376.75693) (xy 408.571856 -376.781002) (xy 408.565822 -376.828766) (xy 408.553816 -376.875388)
			(xy 408.545284 -376.8979) (xy 408.540204 -376.910346) (xy 408.543506 -376.936254) (xy 408.610308 -377.026932)
			(xy 408.63393 -377.037854) (xy 408.647138 -377.036838) (xy 408.67584 -377.035822) (xy 408.703087 -377.036311)
			(xy 408.757026 -377.044071) (xy 408.809312 -377.059429) (xy 408.85888 -377.08207) (xy 408.904722 -377.111535)
			(xy 408.945904 -377.147224) (xy 408.981589 -377.18841) (xy 409.011049 -377.234255) (xy 409.033685 -377.283825)
			(xy 409.049037 -377.336113) (xy 409.056792 -377.390053) (xy 409.056792 -377.444547) (xy 409.049037 -377.498487)
			(xy 409.033685 -377.550775) (xy 409.011049 -377.600345) (xy 408.981589 -377.64619) (xy 408.945904 -377.687376)
			(xy 408.904722 -377.723065) (xy 408.85888 -377.75253) (xy 408.809312 -377.775171) (xy 408.757026 -377.790529)
			(xy 408.703087 -377.798289) (xy 408.67584 -377.798838) (xy 408.647138 -377.797822) (xy 408.63393 -377.796806)
			(xy 408.610308 -377.807728) (xy 408.543506 -377.898406) (xy 408.540204 -377.924314) (xy 408.545284 -377.93676)
			(xy 408.553824 -377.959269) (xy 408.565819 -378.005895) (xy 408.571863 -378.053658) (xy 408.572208 -378.07773)
			(xy 408.571722 -378.104981) (xy 408.563966 -378.158929) (xy 408.548611 -378.211224) (xy 408.525969 -378.260801)
			(xy 408.496503 -378.306651) (xy 408.460812 -378.347842) (xy 408.419621 -378.383533) (xy 408.373771 -378.412999)
			(xy 408.324194 -378.435641) (xy 408.271899 -378.450996) (xy 408.217951 -378.458752) (xy 408.163449 -378.458752)
			(xy 408.109501 -378.450996) (xy 408.057206 -378.435641) (xy 408.007629 -378.412999) (xy 407.961779 -378.383533)
			(xy 407.920588 -378.347842) (xy 407.884897 -378.306651) (xy 407.855431 -378.260801) (xy 407.832789 -378.211224)
			(xy 407.817434 -378.158929) (xy 407.809678 -378.104981) (xy 407.809192 -378.07773) (xy 407.809895 -378.045199)
			(xy 407.821005 -377.981092) (xy 407.83129 -377.950222) (xy 407.834338 -377.941586) (xy 407.834084 -377.923806)
			(xy 407.80462 -377.84532) (xy 407.79319 -377.832112) (xy 407.785062 -377.82754) (xy 407.752804 -377.807728)
			(xy 407.746369 -377.803759) (xy 407.731911 -377.799363) (xy 407.724356 -377.799092) (xy 407.442924 -377.799092)
			(xy 407.435355 -377.79929) (xy 407.420871 -377.803676) (xy 407.414476 -377.807728) (xy 407.382218 -377.82754)
			(xy 407.37409 -377.832112) (xy 407.36266 -377.84532) (xy 407.333196 -377.923806) (xy 407.332942 -377.941586)
			(xy 407.33599 -377.950222) (xy 407.346291 -377.981088) (xy 407.35741 -378.045198) (xy 407.358088 -378.07773)
			(xy 407.357602 -378.104981) (xy 407.349846 -378.158929) (xy 407.334491 -378.211224) (xy 407.311849 -378.260801)
			(xy 407.282383 -378.306651) (xy 407.246692 -378.347842) (xy 407.205501 -378.383533) (xy 407.159651 -378.412999)
			(xy 407.110074 -378.435641) (xy 407.057779 -378.450996) (xy 407.003831 -378.458752) (xy 406.949329 -378.458752)
			(xy 406.895381 -378.450996) (xy 406.843086 -378.435641) (xy 406.793509 -378.412999) (xy 406.747659 -378.383533)
			(xy 406.706468 -378.347842) (xy 406.670777 -378.306651) (xy 406.641311 -378.260801) (xy 406.618669 -378.211224)
			(xy 406.603314 -378.158929) (xy 406.595558 -378.104981) (xy 406.595072 -378.07773) (xy 406.59542 -378.053657)
			(xy 406.601447 -378.005891) (xy 406.613446 -377.959266) (xy 406.621996 -377.93676) (xy 406.627076 -377.924314)
			(xy 406.623774 -377.898406) (xy 406.556972 -377.807728) (xy 406.53335 -377.796806) (xy 406.520142 -377.797822)
			(xy 406.49144 -377.798838) (xy 406.464183 -377.798378) (xy 406.410224 -377.790625) (xy 406.357917 -377.775271)
			(xy 406.308328 -377.752629) (xy 406.262466 -377.72316) (xy 406.221265 -377.687463) (xy 406.185564 -377.646266)
			(xy 406.15609 -377.600408) (xy 406.133443 -377.550821) (xy 406.118084 -377.498516) (xy 406.110325 -377.444557)
			(xy 406.110325 -377.390043) (xy 406.118084 -377.336084) (xy 406.133443 -377.283779) (xy 406.15609 -377.234192)
			(xy 406.185564 -377.188334) (xy 406.221265 -377.147137) (xy 406.262466 -377.11144) (xy 406.308328 -377.081971)
			(xy 406.357917 -377.059329) (xy 406.410224 -377.043975) (xy 406.464183 -377.036222) (xy 406.49144 -377.035822)
			(xy 406.520142 -377.036838) (xy 406.53335 -377.037854) (xy 406.556972 -377.026932) (xy 406.623774 -376.936254)
			(xy 406.627076 -376.910346) (xy 406.621996 -376.8979) (xy 406.613459 -376.87539) (xy 406.601469 -376.828764)
			(xy 406.595431 -376.781002) (xy 406.595072 -376.75693) (xy 406.596596 -376.721878) (xy 406.597612 -376.71121)
			(xy 406.591008 -376.69089) (xy 406.533096 -376.62739) (xy 406.525598 -376.619843) (xy 406.506134 -376.611302)
			(xy 406.495504 -376.61088) (xy 401.864576 -376.61088) (xy 401.853975 -376.611427) (xy 401.834561 -376.619955)
			(xy 401.826984 -376.62739) (xy 401.769072 -376.69089) (xy 401.762468 -376.71121) (xy 401.763484 -376.721878)
			(xy 401.765008 -376.75693) (xy 401.764656 -376.781002) (xy 401.758622 -376.828766) (xy 401.746616 -376.875388)
			(xy 401.738084 -376.8979) (xy 401.733004 -376.910346) (xy 401.736306 -376.936254) (xy 401.803108 -377.026932)
			(xy 401.82673 -377.037854) (xy 401.839938 -377.036838) (xy 401.86864 -377.035822) (xy 401.895887 -377.036311)
			(xy 401.949826 -377.044071) (xy 402.002112 -377.059429) (xy 402.05168 -377.08207) (xy 402.097522 -377.111535)
			(xy 402.138704 -377.147224) (xy 402.174389 -377.18841) (xy 402.203849 -377.234255) (xy 402.226485 -377.283825)
			(xy 402.241837 -377.336113) (xy 402.249592 -377.390053) (xy 402.249592 -377.444547) (xy 402.241837 -377.498487)
			(xy 402.226485 -377.550775) (xy 402.203849 -377.600345) (xy 402.174389 -377.64619) (xy 402.138704 -377.687376)
			(xy 402.097522 -377.723065) (xy 402.05168 -377.75253) (xy 402.002112 -377.775171) (xy 401.949826 -377.790529)
			(xy 401.895887 -377.798289) (xy 401.86864 -377.798838) (xy 401.839938 -377.797822) (xy 401.82673 -377.796806)
			(xy 401.803108 -377.807728) (xy 401.736306 -377.898406) (xy 401.733004 -377.924314) (xy 401.738084 -377.93676)
			(xy 401.746624 -377.959269) (xy 401.758619 -378.005895) (xy 401.764663 -378.053658) (xy 401.765008 -378.07773)
			(xy 401.764522 -378.104981) (xy 401.756766 -378.158929) (xy 401.741411 -378.211224) (xy 401.718769 -378.260801)
			(xy 401.689303 -378.306651) (xy 401.653612 -378.347842) (xy 401.612421 -378.383533) (xy 401.566571 -378.412999)
			(xy 401.516994 -378.435641) (xy 401.464699 -378.450996) (xy 401.410751 -378.458752) (xy 401.356249 -378.458752)
			(xy 401.302301 -378.450996) (xy 401.250006 -378.435641) (xy 401.200429 -378.412999) (xy 401.154579 -378.383533)
			(xy 401.113388 -378.347842) (xy 401.077697 -378.306651) (xy 401.048231 -378.260801) (xy 401.025589 -378.211224)
			(xy 401.010234 -378.158929) (xy 401.002478 -378.104981) (xy 401.001992 -378.07773) (xy 401.002695 -378.045199)
			(xy 401.013805 -377.981092) (xy 401.02409 -377.950222) (xy 401.027138 -377.941586) (xy 401.026884 -377.923806)
			(xy 400.99742 -377.84532) (xy 400.98599 -377.832112) (xy 400.977862 -377.82754) (xy 400.945604 -377.807728)
			(xy 400.939169 -377.803759) (xy 400.924711 -377.799363) (xy 400.917156 -377.799092) (xy 400.635724 -377.799092)
			(xy 400.628155 -377.79929) (xy 400.613671 -377.803676) (xy 400.607276 -377.807728) (xy 400.575018 -377.82754)
			(xy 400.56689 -377.832112) (xy 400.55546 -377.84532) (xy 400.525996 -377.923806) (xy 400.525742 -377.941586)
			(xy 400.52879 -377.950222) (xy 400.539091 -377.981088) (xy 400.55021 -378.045198) (xy 400.550888 -378.07773)
			(xy 400.550402 -378.104981) (xy 400.542646 -378.158929) (xy 400.527291 -378.211224) (xy 400.504649 -378.260801)
			(xy 400.475183 -378.306651) (xy 400.439492 -378.347842) (xy 400.398301 -378.383533) (xy 400.352451 -378.412999)
			(xy 400.302874 -378.435641) (xy 400.250579 -378.450996) (xy 400.196631 -378.458752) (xy 400.142129 -378.458752)
			(xy 400.088181 -378.450996) (xy 400.035886 -378.435641) (xy 399.986309 -378.412999) (xy 399.940459 -378.383533)
			(xy 399.899268 -378.347842) (xy 399.863577 -378.306651) (xy 399.834111 -378.260801) (xy 399.811469 -378.211224)
			(xy 399.796114 -378.158929) (xy 399.788358 -378.104981) (xy 399.787872 -378.07773) (xy 399.78822 -378.053657)
			(xy 399.794247 -378.005891) (xy 399.806246 -377.959266) (xy 399.814796 -377.93676) (xy 399.819876 -377.924314)
			(xy 399.816574 -377.898406) (xy 399.749772 -377.807728) (xy 399.72615 -377.796806) (xy 399.712942 -377.797822)
			(xy 399.68424 -377.798838) (xy 399.656983 -377.798378) (xy 399.603024 -377.790625) (xy 399.550717 -377.775271)
			(xy 399.501128 -377.752629) (xy 399.455266 -377.72316) (xy 399.414065 -377.687463) (xy 399.378364 -377.646266)
			(xy 399.34889 -377.600408) (xy 399.326243 -377.550821) (xy 399.310884 -377.498516) (xy 399.303125 -377.444557)
			(xy 399.303125 -377.390043) (xy 399.310884 -377.336084) (xy 399.326243 -377.283779) (xy 399.34889 -377.234192)
			(xy 399.378364 -377.188334) (xy 399.414065 -377.147137) (xy 399.455266 -377.11144) (xy 399.501128 -377.081971)
			(xy 399.550717 -377.059329) (xy 399.603024 -377.043975) (xy 399.656983 -377.036222) (xy 399.68424 -377.035822)
			(xy 399.712942 -377.036838) (xy 399.72615 -377.037854) (xy 399.749772 -377.026932) (xy 399.816574 -376.936254)
			(xy 399.819876 -376.910346) (xy 399.814796 -376.8979) (xy 399.806259 -376.87539) (xy 399.794269 -376.828764)
			(xy 399.788231 -376.781002) (xy 399.787872 -376.75693) (xy 399.789396 -376.721878) (xy 399.790412 -376.71121)
			(xy 399.783808 -376.69089) (xy 399.725896 -376.62739) (xy 399.718398 -376.619843) (xy 399.698934 -376.611302)
			(xy 399.688304 -376.61088) (xy 393.147042 -376.61088) (xy 393.13993 -376.613166) (xy 393.114022 -376.620024)
			(xy 393.104891 -376.622687) (xy 393.089362 -376.633648) (xy 393.083796 -376.64136) (xy 393.066524 -376.667014)
			(xy 393.06174 -376.675043) (xy 393.057696 -376.693277) (xy 393.05865 -376.702574) (xy 393.060455 -376.71609)
			(xy 393.062359 -376.743294) (xy 393.06246 -376.75693) (xy 393.062108 -376.781002) (xy 393.056075 -376.828766)
			(xy 393.04407 -376.875389) (xy 393.035536 -376.8979) (xy 393.030456 -376.910346) (xy 393.033758 -376.936254)
			(xy 393.10056 -377.026932) (xy 393.124182 -377.037854) (xy 393.13739 -377.036838) (xy 393.166092 -377.035822)
			(xy 393.193343 -377.036285) (xy 393.247291 -377.04404) (xy 393.299585 -377.059394) (xy 393.349163 -377.082035)
			(xy 393.395013 -377.1115) (xy 393.436203 -377.147191) (xy 393.471895 -377.18838) (xy 393.501362 -377.23423)
			(xy 393.524003 -377.283807) (xy 393.539358 -377.336102) (xy 393.547115 -377.390049) (xy 393.547115 -377.444551)
			(xy 393.539358 -377.498498) (xy 393.524003 -377.550793) (xy 393.501362 -377.60037) (xy 393.471895 -377.64622)
			(xy 393.436203 -377.687409) (xy 393.395013 -377.7231) (xy 393.349163 -377.752565) (xy 393.299585 -377.775206)
			(xy 393.247291 -377.79056) (xy 393.193343 -377.798315) (xy 393.166092 -377.798838) (xy 393.13739 -377.797822)
			(xy 393.124182 -377.796806) (xy 393.10056 -377.807728) (xy 393.033758 -377.898406) (xy 393.030456 -377.924314)
			(xy 393.035536 -377.93676) (xy 393.044074 -377.95927) (xy 393.056068 -378.005895) (xy 393.062111 -378.053658)
			(xy 393.06246 -378.07773) (xy 393.061974 -378.104981) (xy 393.054218 -378.158929) (xy 393.038863 -378.211224)
			(xy 393.016221 -378.260801) (xy 392.986755 -378.306651) (xy 392.951064 -378.347842) (xy 392.909873 -378.383533)
			(xy 392.864023 -378.412999) (xy 392.814446 -378.435641) (xy 392.762151 -378.450996) (xy 392.708203 -378.458752)
			(xy 392.653701 -378.458752) (xy 392.599753 -378.450996) (xy 392.547458 -378.435641) (xy 392.497881 -378.412999)
			(xy 392.452031 -378.383533) (xy 392.41084 -378.347842) (xy 392.375149 -378.306651) (xy 392.345683 -378.260801)
			(xy 392.323041 -378.211224) (xy 392.307686 -378.158929) (xy 392.29993 -378.104981) (xy 392.299444 -378.07773)
			(xy 392.300147 -378.0452) (xy 392.311259 -377.981092) (xy 392.321542 -377.950222) (xy 392.32459 -377.941586)
			(xy 392.324336 -377.923806) (xy 392.294872 -377.84532) (xy 392.283442 -377.832112) (xy 392.275314 -377.82754)
			(xy 392.243056 -377.807728) (xy 392.23662 -377.803765) (xy 392.222161 -377.799382) (xy 392.214608 -377.799092)
			(xy 391.933176 -377.799092) (xy 391.925609 -377.799297) (xy 391.911133 -377.803694) (xy 391.904728 -377.807728)
			(xy 391.87247 -377.82754) (xy 391.864342 -377.832112) (xy 391.852912 -377.84532) (xy 391.823448 -377.923806)
			(xy 391.823194 -377.941586) (xy 391.826242 -377.950222) (xy 391.836542 -377.981088) (xy 391.847659 -378.045198)
			(xy 391.84834 -378.07773) (xy 391.847854 -378.104981) (xy 391.840098 -378.158929) (xy 391.824743 -378.211224)
			(xy 391.802101 -378.260801) (xy 391.772635 -378.306651) (xy 391.736944 -378.347842) (xy 391.695753 -378.383533)
			(xy 391.649903 -378.412999) (xy 391.600326 -378.435641) (xy 391.548031 -378.450996) (xy 391.494083 -378.458752)
			(xy 391.439581 -378.458752) (xy 391.385633 -378.450996) (xy 391.333338 -378.435641) (xy 391.283761 -378.412999)
			(xy 391.237911 -378.383533) (xy 391.19672 -378.347842) (xy 391.161029 -378.306651) (xy 391.131563 -378.260801)
			(xy 391.108921 -378.211224) (xy 391.093566 -378.158929) (xy 391.08581 -378.104981) (xy 391.085324 -378.07773)
			(xy 391.085672 -378.053657) (xy 391.091698 -378.005891) (xy 391.103696 -377.959265) (xy 391.112248 -377.93676)
			(xy 391.117328 -377.924314) (xy 391.114026 -377.898406) (xy 391.047224 -377.807728) (xy 391.023602 -377.796806)
			(xy 391.010394 -377.797822) (xy 390.981692 -377.798838) (xy 390.954439 -377.798352) (xy 390.900488 -377.790594)
			(xy 390.84819 -377.775237) (xy 390.79861 -377.752593) (xy 390.752757 -377.723124) (xy 390.711564 -377.68743)
			(xy 390.675871 -377.646237) (xy 390.646403 -377.600383) (xy 390.623761 -377.550803) (xy 390.608405 -377.498504)
			(xy 390.600648 -377.444553) (xy 390.600648 -377.390047) (xy 390.608405 -377.336096) (xy 390.623761 -377.283797)
			(xy 390.646403 -377.234217) (xy 390.675871 -377.188363) (xy 390.711564 -377.14717) (xy 390.752757 -377.111476)
			(xy 390.79861 -377.082007) (xy 390.84819 -377.059363) (xy 390.900488 -377.044006) (xy 390.954439 -377.036248)
			(xy 390.981692 -377.035822) (xy 391.010394 -377.036838) (xy 391.023602 -377.037854) (xy 391.047224 -377.026932)
			(xy 391.114026 -376.936254) (xy 391.117328 -376.910346) (xy 391.112248 -376.8979) (xy 391.103712 -376.87539)
			(xy 391.091724 -376.828764) (xy 391.085686 -376.781001) (xy 391.085324 -376.75693) (xy 391.086848 -376.721878)
			(xy 391.087864 -376.71121) (xy 391.08126 -376.69089) (xy 391.023348 -376.62739) (xy 391.015853 -376.619835)
			(xy 390.99639 -376.611273) (xy 390.985756 -376.61088) (xy 389.758428 -376.61088) (xy 389.747822 -376.611417)
			(xy 389.728394 -376.619932) (xy 389.720836 -376.62739) (xy 389.662924 -376.69089) (xy 389.65632 -376.71121)
			(xy 389.657336 -376.721878) (xy 389.65886 -376.75693) (xy 389.658508 -376.781002) (xy 389.652475 -376.828766)
			(xy 389.64047 -376.875389) (xy 389.631936 -376.8979) (xy 389.626856 -376.910346) (xy 389.630158 -376.936254)
			(xy 389.69696 -377.026932) (xy 389.720582 -377.037854) (xy 389.73379 -377.036838) (xy 389.762492 -377.035822)
			(xy 389.789743 -377.036285) (xy 389.843691 -377.04404) (xy 389.895985 -377.059394) (xy 389.945563 -377.082035)
			(xy 389.991413 -377.1115) (xy 390.032603 -377.147191) (xy 390.068295 -377.18838) (xy 390.097762 -377.23423)
			(xy 390.120403 -377.283807) (xy 390.135758 -377.336102) (xy 390.143515 -377.390049) (xy 390.143515 -377.444551)
			(xy 390.135758 -377.498498) (xy 390.120403 -377.550793) (xy 390.097762 -377.60037) (xy 390.068295 -377.64622)
			(xy 390.032603 -377.687409) (xy 389.991413 -377.7231) (xy 389.945563 -377.752565) (xy 389.895985 -377.775206)
			(xy 389.843691 -377.79056) (xy 389.789743 -377.798315) (xy 389.762492 -377.798838) (xy 389.73379 -377.797822)
			(xy 389.720582 -377.796806) (xy 389.69696 -377.807728) (xy 389.630158 -377.898406) (xy 389.626856 -377.924314)
			(xy 389.631936 -377.93676) (xy 389.640474 -377.95927) (xy 389.652468 -378.005895) (xy 389.658511 -378.053658)
			(xy 389.65886 -378.07773) (xy 389.658374 -378.104981) (xy 389.650618 -378.158929) (xy 389.635263 -378.211224)
			(xy 389.612621 -378.260801) (xy 389.583155 -378.306651) (xy 389.547464 -378.347842) (xy 389.506273 -378.383533)
			(xy 389.460423 -378.412999) (xy 389.410846 -378.435641) (xy 389.358551 -378.450996) (xy 389.304603 -378.458752)
			(xy 389.250101 -378.458752) (xy 389.196153 -378.450996) (xy 389.143858 -378.435641) (xy 389.094281 -378.412999)
			(xy 389.048431 -378.383533) (xy 389.00724 -378.347842) (xy 388.971549 -378.306651) (xy 388.942083 -378.260801)
			(xy 388.919441 -378.211224) (xy 388.904086 -378.158929) (xy 388.89633 -378.104981) (xy 388.895844 -378.07773)
			(xy 388.896547 -378.0452) (xy 388.907659 -377.981092) (xy 388.917942 -377.950222) (xy 388.92099 -377.941586)
			(xy 388.920736 -377.923806) (xy 388.891272 -377.84532) (xy 388.879842 -377.832112) (xy 388.871714 -377.82754)
			(xy 388.839456 -377.807728) (xy 388.83302 -377.803765) (xy 388.818561 -377.799382) (xy 388.811008 -377.799092)
			(xy 388.529576 -377.799092) (xy 388.522009 -377.799297) (xy 388.507533 -377.803694) (xy 388.501128 -377.807728)
			(xy 388.46887 -377.82754) (xy 388.460742 -377.832112) (xy 388.449312 -377.84532) (xy 388.419848 -377.923806)
			(xy 388.419594 -377.941586) (xy 388.422642 -377.950222) (xy 388.432942 -377.981088) (xy 388.444059 -378.045198)
			(xy 388.44474 -378.07773) (xy 388.444254 -378.104981) (xy 388.436498 -378.158929) (xy 388.421143 -378.211224)
			(xy 388.398501 -378.260801) (xy 388.369035 -378.306651) (xy 388.333344 -378.347842) (xy 388.292153 -378.383533)
			(xy 388.246303 -378.412999) (xy 388.196726 -378.435641) (xy 388.144431 -378.450996) (xy 388.090483 -378.458752)
			(xy 388.035981 -378.458752) (xy 387.982033 -378.450996) (xy 387.929738 -378.435641) (xy 387.880161 -378.412999)
			(xy 387.834311 -378.383533) (xy 387.79312 -378.347842) (xy 387.757429 -378.306651) (xy 387.727963 -378.260801)
			(xy 387.705321 -378.211224) (xy 387.689966 -378.158929) (xy 387.68221 -378.104981) (xy 387.681724 -378.07773)
			(xy 387.682072 -378.053657) (xy 387.688098 -378.005891) (xy 387.700096 -377.959265) (xy 387.708648 -377.93676)
			(xy 387.713728 -377.924314) (xy 387.710426 -377.898406) (xy 387.643624 -377.807728) (xy 387.620002 -377.796806)
			(xy 387.606794 -377.797822) (xy 387.578092 -377.798838) (xy 387.550839 -377.798352) (xy 387.496888 -377.790594)
			(xy 387.44459 -377.775237) (xy 387.39501 -377.752593) (xy 387.349157 -377.723124) (xy 387.307964 -377.68743)
			(xy 387.272271 -377.646237) (xy 387.242803 -377.600383) (xy 387.220161 -377.550803) (xy 387.204805 -377.498504)
			(xy 387.197048 -377.444553) (xy 387.197048 -377.390047) (xy 387.204805 -377.336096) (xy 387.220161 -377.283797)
			(xy 387.242803 -377.234217) (xy 387.272271 -377.188363) (xy 387.307964 -377.14717) (xy 387.349157 -377.111476)
			(xy 387.39501 -377.082007) (xy 387.44459 -377.059363) (xy 387.496888 -377.044006) (xy 387.550839 -377.036248)
			(xy 387.578092 -377.035822) (xy 387.606794 -377.036838) (xy 387.620002 -377.037854) (xy 387.643624 -377.026932)
			(xy 387.710426 -376.936254) (xy 387.713728 -376.910346) (xy 387.708648 -376.8979) (xy 387.700112 -376.87539)
			(xy 387.688124 -376.828764) (xy 387.682086 -376.781001) (xy 387.681724 -376.75693) (xy 387.683248 -376.721878)
			(xy 387.684264 -376.71121) (xy 387.67766 -376.69089) (xy 387.619748 -376.62739) (xy 387.612253 -376.619835)
			(xy 387.59279 -376.611273) (xy 387.582156 -376.61088) (xy 382.951228 -376.61088) (xy 382.940622 -376.611417)
			(xy 382.921194 -376.619932) (xy 382.913636 -376.62739) (xy 382.855724 -376.69089) (xy 382.84912 -376.71121)
			(xy 382.850136 -376.721878) (xy 382.85166 -376.75693) (xy 382.851308 -376.781002) (xy 382.845275 -376.828766)
			(xy 382.83327 -376.875389) (xy 382.824736 -376.8979) (xy 382.819656 -376.910346) (xy 382.822958 -376.936254)
			(xy 382.88976 -377.026932) (xy 382.913382 -377.037854) (xy 382.92659 -377.036838) (xy 382.955292 -377.035822)
			(xy 382.982543 -377.036285) (xy 383.036491 -377.04404) (xy 383.088785 -377.059394) (xy 383.138363 -377.082035)
			(xy 383.184213 -377.1115) (xy 383.225403 -377.147191) (xy 383.261095 -377.18838) (xy 383.290562 -377.23423)
			(xy 383.313203 -377.283807) (xy 383.328558 -377.336102) (xy 383.336315 -377.390049) (xy 383.336315 -377.444551)
			(xy 383.328558 -377.498498) (xy 383.313203 -377.550793) (xy 383.290562 -377.60037) (xy 383.261095 -377.64622)
			(xy 383.225403 -377.687409) (xy 383.184213 -377.7231) (xy 383.138363 -377.752565) (xy 383.088785 -377.775206)
			(xy 383.036491 -377.79056) (xy 382.982543 -377.798315) (xy 382.955292 -377.798838) (xy 382.92659 -377.797822)
			(xy 382.913382 -377.796806) (xy 382.88976 -377.807728) (xy 382.822958 -377.898406) (xy 382.819656 -377.924314)
			(xy 382.824736 -377.93676) (xy 382.833274 -377.95927) (xy 382.845268 -378.005895) (xy 382.851311 -378.053658)
			(xy 382.85166 -378.07773) (xy 382.851174 -378.104981) (xy 382.843418 -378.158929) (xy 382.828063 -378.211224)
			(xy 382.805421 -378.260801) (xy 382.775955 -378.306651) (xy 382.740264 -378.347842) (xy 382.699073 -378.383533)
			(xy 382.653223 -378.412999) (xy 382.603646 -378.435641) (xy 382.551351 -378.450996) (xy 382.497403 -378.458752)
			(xy 382.442901 -378.458752) (xy 382.388953 -378.450996) (xy 382.336658 -378.435641) (xy 382.287081 -378.412999)
			(xy 382.241231 -378.383533) (xy 382.20004 -378.347842) (xy 382.164349 -378.306651) (xy 382.134883 -378.260801)
			(xy 382.112241 -378.211224) (xy 382.096886 -378.158929) (xy 382.08913 -378.104981) (xy 382.088644 -378.07773)
			(xy 382.089347 -378.0452) (xy 382.100459 -377.981092) (xy 382.110742 -377.950222) (xy 382.11379 -377.941586)
			(xy 382.113536 -377.923806) (xy 382.084072 -377.84532) (xy 382.072642 -377.832112) (xy 382.064514 -377.82754)
			(xy 382.032256 -377.807728) (xy 382.02582 -377.803765) (xy 382.011361 -377.799382) (xy 382.003808 -377.799092)
			(xy 381.722376 -377.799092) (xy 381.714809 -377.799297) (xy 381.700333 -377.803694) (xy 381.693928 -377.807728)
			(xy 381.66167 -377.82754) (xy 381.653542 -377.832112) (xy 381.642112 -377.84532) (xy 381.612648 -377.923806)
			(xy 381.612394 -377.941586) (xy 381.615442 -377.950222) (xy 381.625742 -377.981088) (xy 381.636859 -378.045198)
			(xy 381.63754 -378.07773) (xy 381.637054 -378.104981) (xy 381.629298 -378.158929) (xy 381.613943 -378.211224)
			(xy 381.591301 -378.260801) (xy 381.561835 -378.306651) (xy 381.526144 -378.347842) (xy 381.484953 -378.383533)
			(xy 381.439103 -378.412999) (xy 381.389526 -378.435641) (xy 381.337231 -378.450996) (xy 381.283283 -378.458752)
			(xy 381.228781 -378.458752) (xy 381.174833 -378.450996) (xy 381.122538 -378.435641) (xy 381.072961 -378.412999)
			(xy 381.027111 -378.383533) (xy 380.98592 -378.347842) (xy 380.950229 -378.306651) (xy 380.920763 -378.260801)
			(xy 380.898121 -378.211224) (xy 380.882766 -378.158929) (xy 380.87501 -378.104981) (xy 380.874524 -378.07773)
			(xy 380.874872 -378.053657) (xy 380.880898 -378.005891) (xy 380.892896 -377.959265) (xy 380.901448 -377.93676)
			(xy 380.906528 -377.924314) (xy 380.903226 -377.898406) (xy 380.836424 -377.807728) (xy 380.812802 -377.796806)
			(xy 380.799594 -377.797822) (xy 380.770892 -377.798838) (xy 380.743639 -377.798352) (xy 380.689688 -377.790594)
			(xy 380.63739 -377.775237) (xy 380.58781 -377.752593) (xy 380.541957 -377.723124) (xy 380.500764 -377.68743)
			(xy 380.465071 -377.646237) (xy 380.435603 -377.600383) (xy 380.412961 -377.550803) (xy 380.397605 -377.498504)
			(xy 380.389848 -377.444553) (xy 380.389848 -377.390047) (xy 380.397605 -377.336096) (xy 380.412961 -377.283797)
			(xy 380.435603 -377.234217) (xy 380.465071 -377.188363) (xy 380.500764 -377.14717) (xy 380.541957 -377.111476)
			(xy 380.58781 -377.082007) (xy 380.63739 -377.059363) (xy 380.689688 -377.044006) (xy 380.743639 -377.036248)
			(xy 380.770892 -377.035822) (xy 380.799594 -377.036838) (xy 380.812802 -377.037854) (xy 380.836424 -377.026932)
			(xy 380.903226 -376.936254) (xy 380.906528 -376.910346) (xy 380.901448 -376.8979) (xy 380.892912 -376.87539)
			(xy 380.880924 -376.828764) (xy 380.874886 -376.781001) (xy 380.874524 -376.75693) (xy 380.876048 -376.721878)
			(xy 380.877064 -376.71121) (xy 380.87046 -376.69089) (xy 380.812548 -376.62739) (xy 380.805053 -376.619835)
			(xy 380.78559 -376.611273) (xy 380.774956 -376.61088) (xy 376.144028 -376.61088) (xy 376.133422 -376.611417)
			(xy 376.113994 -376.619932) (xy 376.106436 -376.62739) (xy 376.048524 -376.69089) (xy 376.04192 -376.71121)
			(xy 376.042936 -376.721878) (xy 376.04446 -376.75693) (xy 376.044108 -376.781002) (xy 376.038075 -376.828766)
			(xy 376.02607 -376.875389) (xy 376.017536 -376.8979) (xy 376.012456 -376.910346) (xy 376.015758 -376.936254)
			(xy 376.08256 -377.026932) (xy 376.106182 -377.037854) (xy 376.11939 -377.036838) (xy 376.148092 -377.035822)
			(xy 376.175343 -377.036285) (xy 376.229291 -377.04404) (xy 376.281585 -377.059394) (xy 376.331163 -377.082035)
			(xy 376.377013 -377.1115) (xy 376.418203 -377.147191) (xy 376.453895 -377.18838) (xy 376.483362 -377.23423)
			(xy 376.506003 -377.283807) (xy 376.521358 -377.336102) (xy 376.529115 -377.390049) (xy 376.529115 -377.444551)
			(xy 376.521358 -377.498498) (xy 376.506003 -377.550793) (xy 376.483362 -377.60037) (xy 376.453895 -377.64622)
			(xy 376.418203 -377.687409) (xy 376.377013 -377.7231) (xy 376.331163 -377.752565) (xy 376.281585 -377.775206)
			(xy 376.229291 -377.79056) (xy 376.175343 -377.798315) (xy 376.148092 -377.798838) (xy 376.11939 -377.797822)
			(xy 376.106182 -377.796806) (xy 376.08256 -377.807728) (xy 376.015758 -377.898406) (xy 376.012456 -377.924314)
			(xy 376.017536 -377.93676) (xy 376.026074 -377.95927) (xy 376.038068 -378.005895) (xy 376.044111 -378.053658)
			(xy 376.04446 -378.07773) (xy 376.043974 -378.104981) (xy 376.036218 -378.158929) (xy 376.020863 -378.211224)
			(xy 375.998221 -378.260801) (xy 375.968755 -378.306651) (xy 375.933064 -378.347842) (xy 375.891873 -378.383533)
			(xy 375.846023 -378.412999) (xy 375.796446 -378.435641) (xy 375.744151 -378.450996) (xy 375.690203 -378.458752)
			(xy 375.635701 -378.458752) (xy 375.581753 -378.450996) (xy 375.529458 -378.435641) (xy 375.479881 -378.412999)
			(xy 375.434031 -378.383533) (xy 375.39284 -378.347842) (xy 375.357149 -378.306651) (xy 375.327683 -378.260801)
			(xy 375.305041 -378.211224) (xy 375.289686 -378.158929) (xy 375.28193 -378.104981) (xy 375.281444 -378.07773)
			(xy 375.282147 -378.0452) (xy 375.293259 -377.981092) (xy 375.303542 -377.950222) (xy 375.30659 -377.941586)
			(xy 375.306336 -377.923806) (xy 375.276872 -377.84532) (xy 375.265442 -377.832112) (xy 375.257314 -377.82754)
			(xy 375.225056 -377.807728) (xy 375.21862 -377.803765) (xy 375.204161 -377.799382) (xy 375.196608 -377.799092)
			(xy 374.915176 -377.799092) (xy 374.907609 -377.799297) (xy 374.893133 -377.803694) (xy 374.886728 -377.807728)
			(xy 374.85447 -377.82754) (xy 374.846342 -377.832112) (xy 374.834912 -377.84532) (xy 374.805448 -377.923806)
			(xy 374.805194 -377.941586) (xy 374.808242 -377.950222) (xy 374.818542 -377.981088) (xy 374.829659 -378.045198)
			(xy 374.83034 -378.07773) (xy 374.829854 -378.104981) (xy 374.822098 -378.158929) (xy 374.806743 -378.211224)
			(xy 374.784101 -378.260801) (xy 374.754635 -378.306651) (xy 374.718944 -378.347842) (xy 374.677753 -378.383533)
			(xy 374.631903 -378.412999) (xy 374.582326 -378.435641) (xy 374.530031 -378.450996) (xy 374.476083 -378.458752)
			(xy 374.421581 -378.458752) (xy 374.367633 -378.450996) (xy 374.315338 -378.435641) (xy 374.265761 -378.412999)
			(xy 374.219911 -378.383533) (xy 374.17872 -378.347842) (xy 374.143029 -378.306651) (xy 374.113563 -378.260801)
			(xy 374.090921 -378.211224) (xy 374.075566 -378.158929) (xy 374.06781 -378.104981) (xy 374.067324 -378.07773)
			(xy 374.067672 -378.053657) (xy 374.073698 -378.005891) (xy 374.085696 -377.959265) (xy 374.094248 -377.93676)
			(xy 374.099328 -377.924314) (xy 374.096026 -377.898406) (xy 374.029224 -377.807728) (xy 374.005602 -377.796806)
			(xy 373.992394 -377.797822) (xy 373.963692 -377.798838) (xy 373.936439 -377.798352) (xy 373.882488 -377.790594)
			(xy 373.83019 -377.775237) (xy 373.78061 -377.752593) (xy 373.734757 -377.723124) (xy 373.693564 -377.68743)
			(xy 373.657871 -377.646237) (xy 373.628403 -377.600383) (xy 373.605761 -377.550803) (xy 373.590405 -377.498504)
			(xy 373.582648 -377.444553) (xy 373.582648 -377.390047) (xy 373.590405 -377.336096) (xy 373.605761 -377.283797)
			(xy 373.628403 -377.234217) (xy 373.657871 -377.188363) (xy 373.693564 -377.14717) (xy 373.734757 -377.111476)
			(xy 373.78061 -377.082007) (xy 373.83019 -377.059363) (xy 373.882488 -377.044006) (xy 373.936439 -377.036248)
			(xy 373.963692 -377.035822) (xy 373.992394 -377.036838) (xy 374.005602 -377.037854) (xy 374.029224 -377.026932)
			(xy 374.096026 -376.936254) (xy 374.099328 -376.910346) (xy 374.094248 -376.8979) (xy 374.085712 -376.87539)
			(xy 374.073724 -376.828764) (xy 374.067686 -376.781001) (xy 374.067324 -376.75693) (xy 374.068848 -376.721878)
			(xy 374.069864 -376.71121) (xy 374.06326 -376.69089) (xy 374.005348 -376.62739) (xy 373.997853 -376.619835)
			(xy 373.97839 -376.611273) (xy 373.967756 -376.61088) (xy 369.336828 -376.61088) (xy 369.326222 -376.611417)
			(xy 369.306794 -376.619932) (xy 369.299236 -376.62739) (xy 369.241324 -376.69089) (xy 369.23472 -376.71121)
			(xy 369.235736 -376.721878) (xy 369.23726 -376.75693) (xy 369.236908 -376.781002) (xy 369.230875 -376.828766)
			(xy 369.21887 -376.875389) (xy 369.210336 -376.8979) (xy 369.205256 -376.910346) (xy 369.208558 -376.936254)
			(xy 369.27536 -377.026932) (xy 369.298982 -377.037854) (xy 369.31219 -377.036838) (xy 369.340892 -377.035822)
			(xy 369.368143 -377.036285) (xy 369.422091 -377.04404) (xy 369.474385 -377.059394) (xy 369.523963 -377.082035)
			(xy 369.569813 -377.1115) (xy 369.611003 -377.147191) (xy 369.646695 -377.18838) (xy 369.676162 -377.23423)
			(xy 369.698803 -377.283807) (xy 369.714158 -377.336102) (xy 369.721915 -377.390049) (xy 369.721915 -377.444551)
			(xy 369.714158 -377.498498) (xy 369.698803 -377.550793) (xy 369.676162 -377.60037) (xy 369.646695 -377.64622)
			(xy 369.611003 -377.687409) (xy 369.569813 -377.7231) (xy 369.523963 -377.752565) (xy 369.474385 -377.775206)
			(xy 369.422091 -377.79056) (xy 369.368143 -377.798315) (xy 369.340892 -377.798838) (xy 369.31219 -377.797822)
			(xy 369.298982 -377.796806) (xy 369.27536 -377.807728) (xy 369.208558 -377.898406) (xy 369.205256 -377.924314)
			(xy 369.210336 -377.93676) (xy 369.218874 -377.95927) (xy 369.230868 -378.005895) (xy 369.236911 -378.053658)
			(xy 369.23726 -378.07773) (xy 369.236774 -378.104981) (xy 369.229018 -378.158929) (xy 369.213663 -378.211224)
			(xy 369.191021 -378.260801) (xy 369.161555 -378.306651) (xy 369.125864 -378.347842) (xy 369.084673 -378.383533)
			(xy 369.038823 -378.412999) (xy 368.989246 -378.435641) (xy 368.936951 -378.450996) (xy 368.883003 -378.458752)
			(xy 368.828501 -378.458752) (xy 368.774553 -378.450996) (xy 368.722258 -378.435641) (xy 368.672681 -378.412999)
			(xy 368.626831 -378.383533) (xy 368.58564 -378.347842) (xy 368.549949 -378.306651) (xy 368.520483 -378.260801)
			(xy 368.497841 -378.211224) (xy 368.482486 -378.158929) (xy 368.47473 -378.104981) (xy 368.474244 -378.07773)
			(xy 368.474947 -378.0452) (xy 368.486059 -377.981092) (xy 368.496342 -377.950222) (xy 368.49939 -377.941586)
			(xy 368.499136 -377.923806) (xy 368.469672 -377.84532) (xy 368.458242 -377.832112) (xy 368.450114 -377.82754)
			(xy 368.417856 -377.807728) (xy 368.41142 -377.803765) (xy 368.396961 -377.799382) (xy 368.389408 -377.799092)
			(xy 368.107976 -377.799092) (xy 368.100409 -377.799297) (xy 368.085933 -377.803694) (xy 368.079528 -377.807728)
			(xy 368.04727 -377.82754) (xy 368.039142 -377.832112) (xy 368.027712 -377.84532) (xy 367.998248 -377.923806)
			(xy 367.997994 -377.941586) (xy 368.001042 -377.950222) (xy 368.011342 -377.981088) (xy 368.022459 -378.045198)
			(xy 368.02314 -378.07773) (xy 368.022654 -378.104981) (xy 368.014898 -378.158929) (xy 367.999543 -378.211224)
			(xy 367.976901 -378.260801) (xy 367.947435 -378.306651) (xy 367.911744 -378.347842) (xy 367.870553 -378.383533)
			(xy 367.824703 -378.412999) (xy 367.775126 -378.435641) (xy 367.722831 -378.450996) (xy 367.668883 -378.458752)
			(xy 367.614381 -378.458752) (xy 367.560433 -378.450996) (xy 367.508138 -378.435641) (xy 367.458561 -378.412999)
			(xy 367.412711 -378.383533) (xy 367.37152 -378.347842) (xy 367.335829 -378.306651) (xy 367.306363 -378.260801)
			(xy 367.283721 -378.211224) (xy 367.268366 -378.158929) (xy 367.26061 -378.104981) (xy 367.260124 -378.07773)
			(xy 367.260472 -378.053657) (xy 367.266498 -378.005891) (xy 367.278496 -377.959265) (xy 367.287048 -377.93676)
			(xy 367.292128 -377.924314) (xy 367.288826 -377.898406) (xy 367.222024 -377.807728) (xy 367.198402 -377.796806)
			(xy 367.185194 -377.797822) (xy 367.156492 -377.798838) (xy 367.129239 -377.798352) (xy 367.075288 -377.790594)
			(xy 367.02299 -377.775237) (xy 366.97341 -377.752593) (xy 366.927557 -377.723124) (xy 366.886364 -377.68743)
			(xy 366.850671 -377.646237) (xy 366.821203 -377.600383) (xy 366.798561 -377.550803) (xy 366.783205 -377.498504)
			(xy 366.775448 -377.444553) (xy 366.775448 -377.390047) (xy 366.783205 -377.336096) (xy 366.798561 -377.283797)
			(xy 366.821203 -377.234217) (xy 366.850671 -377.188363) (xy 366.886364 -377.14717) (xy 366.927557 -377.111476)
			(xy 366.97341 -377.082007) (xy 367.02299 -377.059363) (xy 367.075288 -377.044006) (xy 367.129239 -377.036248)
			(xy 367.156492 -377.035822) (xy 367.185194 -377.036838) (xy 367.198402 -377.037854) (xy 367.222024 -377.026932)
			(xy 367.288826 -376.936254) (xy 367.292128 -376.910346) (xy 367.287048 -376.8979) (xy 367.278512 -376.87539)
			(xy 367.266524 -376.828764) (xy 367.260486 -376.781001) (xy 367.260124 -376.75693) (xy 367.261648 -376.721878)
			(xy 367.262664 -376.71121) (xy 367.25606 -376.69089) (xy 367.198148 -376.62739) (xy 367.190653 -376.619835)
			(xy 367.17119 -376.611273) (xy 367.160556 -376.61088) (xy 358.58958 -376.61088) (xy 358.578979 -376.611426)
			(xy 358.559564 -376.619954) (xy 358.551988 -376.62739) (xy 358.494076 -376.69089) (xy 358.487472 -376.71121)
			(xy 358.488488 -376.721878) (xy 358.490012 -376.75693) (xy 358.48966 -376.781002) (xy 358.483626 -376.828766)
			(xy 358.47162 -376.875388) (xy 358.463088 -376.8979) (xy 358.458008 -376.910346) (xy 358.46131 -376.936254)
			(xy 358.528112 -377.026932) (xy 358.551734 -377.037854) (xy 358.564942 -377.036838) (xy 358.593644 -377.035822)
			(xy 358.620891 -377.036311) (xy 358.67483 -377.044072) (xy 358.727115 -377.05943) (xy 358.776683 -377.082072)
			(xy 358.822524 -377.111537) (xy 358.863706 -377.147226) (xy 358.89939 -377.188411) (xy 358.928849 -377.234256)
			(xy 358.951486 -377.283826) (xy 358.966837 -377.336113) (xy 358.974592 -377.390053) (xy 358.974592 -377.444547)
			(xy 358.966837 -377.498487) (xy 358.951486 -377.550774) (xy 358.928849 -377.600344) (xy 358.89939 -377.646189)
			(xy 358.863706 -377.687374) (xy 358.822524 -377.723063) (xy 358.776683 -377.752528) (xy 358.727115 -377.77517)
			(xy 358.67483 -377.790528) (xy 358.620891 -377.798289) (xy 358.593644 -377.798838) (xy 358.564942 -377.797822)
			(xy 358.551734 -377.796806) (xy 358.528112 -377.807728) (xy 358.46131 -377.898406) (xy 358.458008 -377.924314)
			(xy 358.463088 -377.93676) (xy 358.471627 -377.959269) (xy 358.483623 -378.005895) (xy 358.489666 -378.053658)
			(xy 358.490012 -378.07773) (xy 358.489526 -378.104981) (xy 358.48177 -378.158929) (xy 358.466415 -378.211224)
			(xy 358.443773 -378.260801) (xy 358.414307 -378.306651) (xy 358.378616 -378.347842) (xy 358.337425 -378.383533)
			(xy 358.291575 -378.412999) (xy 358.241998 -378.435641) (xy 358.189703 -378.450996) (xy 358.135755 -378.458752)
			(xy 358.081253 -378.458752) (xy 358.027305 -378.450996) (xy 357.97501 -378.435641) (xy 357.925433 -378.412999)
			(xy 357.879583 -378.383533) (xy 357.838392 -378.347842) (xy 357.802701 -378.306651) (xy 357.773235 -378.260801)
			(xy 357.750593 -378.211224) (xy 357.735238 -378.158929) (xy 357.727482 -378.104981) (xy 357.726996 -378.07773)
			(xy 357.727699 -378.045199) (xy 357.738809 -377.981092) (xy 357.749094 -377.950222) (xy 357.752142 -377.941586)
			(xy 357.751888 -377.923806) (xy 357.722424 -377.84532) (xy 357.710994 -377.832112) (xy 357.702866 -377.82754)
			(xy 357.670608 -377.807728) (xy 357.664173 -377.803758) (xy 357.649715 -377.799361) (xy 357.64216 -377.799092)
			(xy 357.360728 -377.799092) (xy 357.353159 -377.799289) (xy 357.338674 -377.803674) (xy 357.33228 -377.807728)
			(xy 357.300022 -377.82754) (xy 357.291894 -377.832112) (xy 357.280464 -377.84532) (xy 357.251 -377.923806)
			(xy 357.250746 -377.941586) (xy 357.253794 -377.950222) (xy 357.264095 -377.981088) (xy 357.275213 -378.045198)
			(xy 357.275892 -378.07773) (xy 357.275406 -378.104981) (xy 357.26765 -378.158929) (xy 357.252295 -378.211224)
			(xy 357.229653 -378.260801) (xy 357.200187 -378.306651) (xy 357.164496 -378.347842) (xy 357.123305 -378.383533)
			(xy 357.077455 -378.412999) (xy 357.027878 -378.435641) (xy 356.975583 -378.450996) (xy 356.921635 -378.458752)
			(xy 356.867133 -378.458752) (xy 356.813185 -378.450996) (xy 356.76089 -378.435641) (xy 356.711313 -378.412999)
			(xy 356.665463 -378.383533) (xy 356.624272 -378.347842) (xy 356.588581 -378.306651) (xy 356.559115 -378.260801)
			(xy 356.536473 -378.211224) (xy 356.521118 -378.158929) (xy 356.513362 -378.104981) (xy 356.512876 -378.07773)
			(xy 356.513224 -378.053657) (xy 356.519251 -378.005891) (xy 356.53125 -377.959266) (xy 356.5398 -377.93676)
			(xy 356.54488 -377.924314) (xy 356.541578 -377.898406) (xy 356.474776 -377.807728) (xy 356.451154 -377.796806)
			(xy 356.437946 -377.797822) (xy 356.409244 -377.798838) (xy 356.381987 -377.798378) (xy 356.328027 -377.790626)
			(xy 356.27572 -377.775272) (xy 356.22613 -377.75263) (xy 356.180268 -377.723161) (xy 356.139066 -377.687465)
			(xy 356.103365 -377.646268) (xy 356.073891 -377.600409) (xy 356.051243 -377.550822) (xy 356.035884 -377.498516)
			(xy 356.028125 -377.444557) (xy 356.028125 -377.390043) (xy 356.035884 -377.336084) (xy 356.051243 -377.283778)
			(xy 356.073891 -377.234191) (xy 356.103365 -377.188332) (xy 356.139066 -377.147135) (xy 356.180268 -377.111439)
			(xy 356.22613 -377.08197) (xy 356.27572 -377.059328) (xy 356.328027 -377.043974) (xy 356.381987 -377.036222)
			(xy 356.409244 -377.035822) (xy 356.437946 -377.036838) (xy 356.451154 -377.037854) (xy 356.474776 -377.026932)
			(xy 356.541578 -376.936254) (xy 356.54488 -376.910346) (xy 356.5398 -376.8979) (xy 356.531263 -376.87539)
			(xy 356.519273 -376.828764) (xy 356.513235 -376.781002) (xy 356.512876 -376.75693) (xy 356.5144 -376.721878)
			(xy 356.515416 -376.71121) (xy 356.508812 -376.69089) (xy 356.4509 -376.62739) (xy 356.443403 -376.619842)
			(xy 356.423939 -376.6113) (xy 356.413308 -376.61088) (xy 355.18598 -376.61088) (xy 355.175379 -376.611426)
			(xy 355.155964 -376.619954) (xy 355.148388 -376.62739) (xy 355.090476 -376.69089) (xy 355.083872 -376.71121)
			(xy 355.084888 -376.721878) (xy 355.086412 -376.75693) (xy 355.08606 -376.781002) (xy 355.080026 -376.828766)
			(xy 355.06802 -376.875388) (xy 355.059488 -376.8979) (xy 355.054408 -376.910346) (xy 355.05771 -376.936254)
			(xy 355.124512 -377.026932) (xy 355.148134 -377.037854) (xy 355.161342 -377.036838) (xy 355.190044 -377.035822)
			(xy 355.217291 -377.036311) (xy 355.27123 -377.044072) (xy 355.323515 -377.05943) (xy 355.373083 -377.082072)
			(xy 355.418924 -377.111537) (xy 355.460106 -377.147226) (xy 355.49579 -377.188411) (xy 355.525249 -377.234256)
			(xy 355.547886 -377.283826) (xy 355.563237 -377.336113) (xy 355.570992 -377.390053) (xy 355.570992 -377.444547)
			(xy 355.563237 -377.498487) (xy 355.547886 -377.550774) (xy 355.525249 -377.600344) (xy 355.49579 -377.646189)
			(xy 355.460106 -377.687374) (xy 355.418924 -377.723063) (xy 355.373083 -377.752528) (xy 355.323515 -377.77517)
			(xy 355.27123 -377.790528) (xy 355.217291 -377.798289) (xy 355.190044 -377.798838) (xy 355.161342 -377.797822)
			(xy 355.148134 -377.796806) (xy 355.124512 -377.807728) (xy 355.05771 -377.898406) (xy 355.054408 -377.924314)
			(xy 355.059488 -377.93676) (xy 355.068027 -377.959269) (xy 355.080023 -378.005895) (xy 355.086066 -378.053658)
			(xy 355.086412 -378.07773) (xy 355.085926 -378.104981) (xy 355.07817 -378.158929) (xy 355.062815 -378.211224)
			(xy 355.040173 -378.260801) (xy 355.010707 -378.306651) (xy 354.975016 -378.347842) (xy 354.933825 -378.383533)
			(xy 354.887975 -378.412999) (xy 354.838398 -378.435641) (xy 354.786103 -378.450996) (xy 354.732155 -378.458752)
			(xy 354.677653 -378.458752) (xy 354.623705 -378.450996) (xy 354.57141 -378.435641) (xy 354.521833 -378.412999)
			(xy 354.475983 -378.383533) (xy 354.434792 -378.347842) (xy 354.399101 -378.306651) (xy 354.369635 -378.260801)
			(xy 354.346993 -378.211224) (xy 354.331638 -378.158929) (xy 354.323882 -378.104981) (xy 354.323396 -378.07773)
			(xy 354.324099 -378.045199) (xy 354.335209 -377.981092) (xy 354.345494 -377.950222) (xy 354.348542 -377.941586)
			(xy 354.348288 -377.923806) (xy 354.318824 -377.84532) (xy 354.307394 -377.832112) (xy 354.299266 -377.82754)
			(xy 354.267008 -377.807728) (xy 354.260573 -377.803758) (xy 354.246115 -377.799361) (xy 354.23856 -377.799092)
			(xy 353.957128 -377.799092) (xy 353.949559 -377.799289) (xy 353.935074 -377.803674) (xy 353.92868 -377.807728)
			(xy 353.896422 -377.82754) (xy 353.888294 -377.832112) (xy 353.876864 -377.84532) (xy 353.8474 -377.923806)
			(xy 353.847146 -377.941586) (xy 353.850194 -377.950222) (xy 353.860495 -377.981088) (xy 353.871613 -378.045198)
			(xy 353.872292 -378.07773) (xy 353.871806 -378.104981) (xy 353.86405 -378.158929) (xy 353.848695 -378.211224)
			(xy 353.826053 -378.260801) (xy 353.796587 -378.306651) (xy 353.760896 -378.347842) (xy 353.719705 -378.383533)
			(xy 353.673855 -378.412999) (xy 353.624278 -378.435641) (xy 353.571983 -378.450996) (xy 353.518035 -378.458752)
			(xy 353.463533 -378.458752) (xy 353.409585 -378.450996) (xy 353.35729 -378.435641) (xy 353.307713 -378.412999)
			(xy 353.261863 -378.383533) (xy 353.220672 -378.347842) (xy 353.184981 -378.306651) (xy 353.155515 -378.260801)
			(xy 353.132873 -378.211224) (xy 353.117518 -378.158929) (xy 353.109762 -378.104981) (xy 353.109276 -378.07773)
			(xy 353.109624 -378.053657) (xy 353.115651 -378.005891) (xy 353.12765 -377.959266) (xy 353.1362 -377.93676)
			(xy 353.14128 -377.924314) (xy 353.137978 -377.898406) (xy 353.071176 -377.807728) (xy 353.047554 -377.796806)
			(xy 353.034346 -377.797822) (xy 353.005644 -377.798838) (xy 352.978387 -377.798378) (xy 352.924427 -377.790626)
			(xy 352.87212 -377.775272) (xy 352.82253 -377.75263) (xy 352.776668 -377.723161) (xy 352.735466 -377.687465)
			(xy 352.699765 -377.646268) (xy 352.670291 -377.600409) (xy 352.647643 -377.550822) (xy 352.632284 -377.498516)
			(xy 352.624525 -377.444557) (xy 352.624525 -377.390043) (xy 352.632284 -377.336084) (xy 352.647643 -377.283778)
			(xy 352.670291 -377.234191) (xy 352.699765 -377.188332) (xy 352.735466 -377.147135) (xy 352.776668 -377.111439)
			(xy 352.82253 -377.08197) (xy 352.87212 -377.059328) (xy 352.924427 -377.043974) (xy 352.978387 -377.036222)
			(xy 353.005644 -377.035822) (xy 353.034346 -377.036838) (xy 353.047554 -377.037854) (xy 353.071176 -377.026932)
			(xy 353.137978 -376.936254) (xy 353.14128 -376.910346) (xy 353.1362 -376.8979) (xy 353.127663 -376.87539)
			(xy 353.115673 -376.828764) (xy 353.109635 -376.781002) (xy 353.109276 -376.75693) (xy 353.1108 -376.721878)
			(xy 353.111816 -376.71121) (xy 353.105212 -376.69089) (xy 353.0473 -376.62739) (xy 353.039803 -376.619842)
			(xy 353.020339 -376.6113) (xy 353.009708 -376.61088) (xy 348.37878 -376.61088) (xy 348.368179 -376.611426)
			(xy 348.348764 -376.619954) (xy 348.341188 -376.62739) (xy 348.283276 -376.69089) (xy 348.276672 -376.71121)
			(xy 348.277688 -376.721878) (xy 348.279212 -376.75693) (xy 348.27886 -376.781002) (xy 348.272826 -376.828766)
			(xy 348.26082 -376.875388) (xy 348.252288 -376.8979) (xy 348.247208 -376.910346) (xy 348.25051 -376.936254)
			(xy 348.317312 -377.026932) (xy 348.340934 -377.037854) (xy 348.354142 -377.036838) (xy 348.382844 -377.035822)
			(xy 348.410091 -377.036311) (xy 348.46403 -377.044072) (xy 348.516315 -377.05943) (xy 348.565883 -377.082072)
			(xy 348.611724 -377.111537) (xy 348.652906 -377.147226) (xy 348.68859 -377.188411) (xy 348.718049 -377.234256)
			(xy 348.740686 -377.283826) (xy 348.756037 -377.336113) (xy 348.763792 -377.390053) (xy 348.763792 -377.444547)
			(xy 348.756037 -377.498487) (xy 348.740686 -377.550774) (xy 348.718049 -377.600344) (xy 348.68859 -377.646189)
			(xy 348.652906 -377.687374) (xy 348.611724 -377.723063) (xy 348.565883 -377.752528) (xy 348.516315 -377.77517)
			(xy 348.46403 -377.790528) (xy 348.410091 -377.798289) (xy 348.382844 -377.798838) (xy 348.354142 -377.797822)
			(xy 348.340934 -377.796806) (xy 348.317312 -377.807728) (xy 348.25051 -377.898406) (xy 348.247208 -377.924314)
			(xy 348.252288 -377.93676) (xy 348.260827 -377.959269) (xy 348.272823 -378.005895) (xy 348.278866 -378.053658)
			(xy 348.279212 -378.07773) (xy 348.278726 -378.104981) (xy 348.27097 -378.158929) (xy 348.255615 -378.211224)
			(xy 348.232973 -378.260801) (xy 348.203507 -378.306651) (xy 348.167816 -378.347842) (xy 348.126625 -378.383533)
			(xy 348.080775 -378.412999) (xy 348.031198 -378.435641) (xy 347.978903 -378.450996) (xy 347.924955 -378.458752)
			(xy 347.870453 -378.458752) (xy 347.816505 -378.450996) (xy 347.76421 -378.435641) (xy 347.714633 -378.412999)
			(xy 347.668783 -378.383533) (xy 347.627592 -378.347842) (xy 347.591901 -378.306651) (xy 347.562435 -378.260801)
			(xy 347.539793 -378.211224) (xy 347.524438 -378.158929) (xy 347.516682 -378.104981) (xy 347.516196 -378.07773)
			(xy 347.516899 -378.045199) (xy 347.528009 -377.981092) (xy 347.538294 -377.950222) (xy 347.541342 -377.941586)
			(xy 347.541088 -377.923806) (xy 347.511624 -377.84532) (xy 347.500194 -377.832112) (xy 347.492066 -377.82754)
			(xy 347.459808 -377.807728) (xy 347.453373 -377.803758) (xy 347.438915 -377.799361) (xy 347.43136 -377.799092)
			(xy 347.149928 -377.799092) (xy 347.142359 -377.799289) (xy 347.127874 -377.803674) (xy 347.12148 -377.807728)
			(xy 347.089222 -377.82754) (xy 347.081094 -377.832112) (xy 347.069664 -377.84532) (xy 347.0402 -377.923806)
			(xy 347.039946 -377.941586) (xy 347.042994 -377.950222) (xy 347.053295 -377.981088) (xy 347.064413 -378.045198)
			(xy 347.065092 -378.07773) (xy 347.064606 -378.104981) (xy 347.05685 -378.158929) (xy 347.041495 -378.211224)
			(xy 347.018853 -378.260801) (xy 346.989387 -378.306651) (xy 346.953696 -378.347842) (xy 346.912505 -378.383533)
			(xy 346.866655 -378.412999) (xy 346.817078 -378.435641) (xy 346.764783 -378.450996) (xy 346.710835 -378.458752)
			(xy 346.656333 -378.458752) (xy 346.602385 -378.450996) (xy 346.55009 -378.435641) (xy 346.500513 -378.412999)
			(xy 346.454663 -378.383533) (xy 346.413472 -378.347842) (xy 346.377781 -378.306651) (xy 346.348315 -378.260801)
			(xy 346.325673 -378.211224) (xy 346.310318 -378.158929) (xy 346.302562 -378.104981) (xy 346.302076 -378.07773)
			(xy 346.302424 -378.053657) (xy 346.308451 -378.005891) (xy 346.32045 -377.959266) (xy 346.329 -377.93676)
			(xy 346.33408 -377.924314) (xy 346.330778 -377.898406) (xy 346.263976 -377.807728) (xy 346.240354 -377.796806)
			(xy 346.227146 -377.797822) (xy 346.198444 -377.798838) (xy 346.171187 -377.798378) (xy 346.117227 -377.790626)
			(xy 346.06492 -377.775272) (xy 346.01533 -377.75263) (xy 345.969468 -377.723161) (xy 345.928266 -377.687465)
			(xy 345.892565 -377.646268) (xy 345.863091 -377.600409) (xy 345.840443 -377.550822) (xy 345.825084 -377.498516)
			(xy 345.817325 -377.444557) (xy 345.817325 -377.390043) (xy 345.825084 -377.336084) (xy 345.840443 -377.283778)
			(xy 345.863091 -377.234191) (xy 345.892565 -377.188332) (xy 345.928266 -377.147135) (xy 345.969468 -377.111439)
			(xy 346.01533 -377.08197) (xy 346.06492 -377.059328) (xy 346.117227 -377.043974) (xy 346.171187 -377.036222)
			(xy 346.198444 -377.035822) (xy 346.227146 -377.036838) (xy 346.240354 -377.037854) (xy 346.263976 -377.026932)
			(xy 346.330778 -376.936254) (xy 346.33408 -376.910346) (xy 346.329 -376.8979) (xy 346.320463 -376.87539)
			(xy 346.308473 -376.828764) (xy 346.302435 -376.781002) (xy 346.302076 -376.75693) (xy 346.3036 -376.721878)
			(xy 346.304616 -376.71121) (xy 346.298012 -376.69089) (xy 346.2401 -376.62739) (xy 346.232603 -376.619842)
			(xy 346.213139 -376.6113) (xy 346.202508 -376.61088) (xy 341.57158 -376.61088) (xy 341.560979 -376.611426)
			(xy 341.541564 -376.619954) (xy 341.533988 -376.62739) (xy 341.476076 -376.69089) (xy 341.469472 -376.71121)
			(xy 341.470488 -376.721878) (xy 341.472012 -376.75693) (xy 341.47166 -376.781002) (xy 341.465626 -376.828766)
			(xy 341.45362 -376.875388) (xy 341.445088 -376.8979) (xy 341.440008 -376.910346) (xy 341.44331 -376.936254)
			(xy 341.510112 -377.026932) (xy 341.533734 -377.037854) (xy 341.546942 -377.036838) (xy 341.575644 -377.035822)
			(xy 341.602891 -377.036311) (xy 341.65683 -377.044072) (xy 341.709115 -377.05943) (xy 341.758683 -377.082072)
			(xy 341.804524 -377.111537) (xy 341.845706 -377.147226) (xy 341.88139 -377.188411) (xy 341.910849 -377.234256)
			(xy 341.933486 -377.283826) (xy 341.948837 -377.336113) (xy 341.956592 -377.390053) (xy 341.956592 -377.444547)
			(xy 341.948837 -377.498487) (xy 341.933486 -377.550774) (xy 341.910849 -377.600344) (xy 341.88139 -377.646189)
			(xy 341.845706 -377.687374) (xy 341.804524 -377.723063) (xy 341.758683 -377.752528) (xy 341.709115 -377.77517)
			(xy 341.65683 -377.790528) (xy 341.602891 -377.798289) (xy 341.575644 -377.798838) (xy 341.546942 -377.797822)
			(xy 341.533734 -377.796806) (xy 341.510112 -377.807728) (xy 341.44331 -377.898406) (xy 341.440008 -377.924314)
			(xy 341.445088 -377.93676) (xy 341.453627 -377.959269) (xy 341.465623 -378.005895) (xy 341.471666 -378.053658)
			(xy 341.472012 -378.07773) (xy 341.471526 -378.104981) (xy 341.46377 -378.158929) (xy 341.448415 -378.211224)
			(xy 341.425773 -378.260801) (xy 341.396307 -378.306651) (xy 341.360616 -378.347842) (xy 341.319425 -378.383533)
			(xy 341.273575 -378.412999) (xy 341.223998 -378.435641) (xy 341.171703 -378.450996) (xy 341.117755 -378.458752)
			(xy 341.063253 -378.458752) (xy 341.009305 -378.450996) (xy 340.95701 -378.435641) (xy 340.907433 -378.412999)
			(xy 340.861583 -378.383533) (xy 340.820392 -378.347842) (xy 340.784701 -378.306651) (xy 340.755235 -378.260801)
			(xy 340.732593 -378.211224) (xy 340.717238 -378.158929) (xy 340.709482 -378.104981) (xy 340.708996 -378.07773)
			(xy 340.709699 -378.045199) (xy 340.720809 -377.981092) (xy 340.731094 -377.950222) (xy 340.734142 -377.941586)
			(xy 340.733888 -377.923806) (xy 340.704424 -377.84532) (xy 340.692994 -377.832112) (xy 340.684866 -377.82754)
			(xy 340.652608 -377.807728) (xy 340.646173 -377.803758) (xy 340.631715 -377.799361) (xy 340.62416 -377.799092)
			(xy 340.342728 -377.799092) (xy 340.335159 -377.799289) (xy 340.320674 -377.803674) (xy 340.31428 -377.807728)
			(xy 340.282022 -377.82754) (xy 340.273894 -377.832112) (xy 340.262464 -377.84532) (xy 340.233 -377.923806)
			(xy 340.232746 -377.941586) (xy 340.235794 -377.950222) (xy 340.246095 -377.981088) (xy 340.257213 -378.045198)
			(xy 340.257892 -378.07773) (xy 340.257406 -378.104981) (xy 340.24965 -378.158929) (xy 340.234295 -378.211224)
			(xy 340.211653 -378.260801) (xy 340.182187 -378.306651) (xy 340.146496 -378.347842) (xy 340.105305 -378.383533)
			(xy 340.059455 -378.412999) (xy 340.009878 -378.435641) (xy 339.957583 -378.450996) (xy 339.903635 -378.458752)
			(xy 339.849133 -378.458752) (xy 339.795185 -378.450996) (xy 339.74289 -378.435641) (xy 339.693313 -378.412999)
			(xy 339.647463 -378.383533) (xy 339.606272 -378.347842) (xy 339.570581 -378.306651) (xy 339.541115 -378.260801)
			(xy 339.518473 -378.211224) (xy 339.503118 -378.158929) (xy 339.495362 -378.104981) (xy 339.494876 -378.07773)
			(xy 339.495224 -378.053657) (xy 339.501251 -378.005891) (xy 339.51325 -377.959266) (xy 339.5218 -377.93676)
			(xy 339.52688 -377.924314) (xy 339.523578 -377.898406) (xy 339.456776 -377.807728) (xy 339.433154 -377.796806)
			(xy 339.419946 -377.797822) (xy 339.391244 -377.798838) (xy 339.363987 -377.798378) (xy 339.310027 -377.790626)
			(xy 339.25772 -377.775272) (xy 339.20813 -377.75263) (xy 339.162268 -377.723161) (xy 339.121066 -377.687465)
			(xy 339.085365 -377.646268) (xy 339.055891 -377.600409) (xy 339.033243 -377.550822) (xy 339.017884 -377.498516)
			(xy 339.010125 -377.444557) (xy 339.010125 -377.390043) (xy 339.017884 -377.336084) (xy 339.033243 -377.283778)
			(xy 339.055891 -377.234191) (xy 339.085365 -377.188332) (xy 339.121066 -377.147135) (xy 339.162268 -377.111439)
			(xy 339.20813 -377.08197) (xy 339.25772 -377.059328) (xy 339.310027 -377.043974) (xy 339.363987 -377.036222)
			(xy 339.391244 -377.035822) (xy 339.419946 -377.036838) (xy 339.433154 -377.037854) (xy 339.456776 -377.026932)
			(xy 339.523578 -376.936254) (xy 339.52688 -376.910346) (xy 339.5218 -376.8979) (xy 339.513263 -376.87539)
			(xy 339.501273 -376.828764) (xy 339.495235 -376.781002) (xy 339.494876 -376.75693) (xy 339.4964 -376.721878)
			(xy 339.497416 -376.71121) (xy 339.490812 -376.69089) (xy 339.4329 -376.62739) (xy 339.425403 -376.619842)
			(xy 339.405939 -376.6113) (xy 339.395308 -376.61088) (xy 334.76438 -376.61088) (xy 334.753779 -376.611426)
			(xy 334.734364 -376.619954) (xy 334.726788 -376.62739) (xy 334.668876 -376.69089) (xy 334.662272 -376.71121)
			(xy 334.663288 -376.721878) (xy 334.664812 -376.75693) (xy 334.66446 -376.781002) (xy 334.658426 -376.828766)
			(xy 334.64642 -376.875388) (xy 334.637888 -376.8979) (xy 334.632808 -376.910346) (xy 334.63611 -376.936254)
			(xy 334.702912 -377.026932) (xy 334.726534 -377.037854) (xy 334.739742 -377.036838) (xy 334.768444 -377.035822)
			(xy 334.795691 -377.036311) (xy 334.84963 -377.044072) (xy 334.901915 -377.05943) (xy 334.951483 -377.082072)
			(xy 334.997324 -377.111537) (xy 335.038506 -377.147226) (xy 335.07419 -377.188411) (xy 335.103649 -377.234256)
			(xy 335.126286 -377.283826) (xy 335.141637 -377.336113) (xy 335.149392 -377.390053) (xy 335.149392 -377.444547)
			(xy 335.141637 -377.498487) (xy 335.126286 -377.550774) (xy 335.103649 -377.600344) (xy 335.07419 -377.646189)
			(xy 335.038506 -377.687374) (xy 334.997324 -377.723063) (xy 334.951483 -377.752528) (xy 334.901915 -377.77517)
			(xy 334.84963 -377.790528) (xy 334.795691 -377.798289) (xy 334.768444 -377.798838) (xy 334.739742 -377.797822)
			(xy 334.726534 -377.796806) (xy 334.702912 -377.807728) (xy 334.63611 -377.898406) (xy 334.632808 -377.924314)
			(xy 334.637888 -377.93676) (xy 334.646427 -377.959269) (xy 334.658423 -378.005895) (xy 334.664466 -378.053658)
			(xy 334.664812 -378.07773) (xy 334.664326 -378.104981) (xy 334.65657 -378.158929) (xy 334.641215 -378.211224)
			(xy 334.618573 -378.260801) (xy 334.589107 -378.306651) (xy 334.553416 -378.347842) (xy 334.512225 -378.383533)
			(xy 334.466375 -378.412999) (xy 334.416798 -378.435641) (xy 334.364503 -378.450996) (xy 334.310555 -378.458752)
			(xy 334.256053 -378.458752) (xy 334.202105 -378.450996) (xy 334.14981 -378.435641) (xy 334.100233 -378.412999)
			(xy 334.054383 -378.383533) (xy 334.013192 -378.347842) (xy 333.977501 -378.306651) (xy 333.948035 -378.260801)
			(xy 333.925393 -378.211224) (xy 333.910038 -378.158929) (xy 333.902282 -378.104981) (xy 333.901796 -378.07773)
			(xy 333.902499 -378.045199) (xy 333.913609 -377.981092) (xy 333.923894 -377.950222) (xy 333.926942 -377.941586)
			(xy 333.926688 -377.923806) (xy 333.897224 -377.84532) (xy 333.885794 -377.832112) (xy 333.877666 -377.82754)
			(xy 333.845408 -377.807728) (xy 333.838973 -377.803758) (xy 333.824515 -377.799361) (xy 333.81696 -377.799092)
			(xy 333.535528 -377.799092) (xy 333.527959 -377.799289) (xy 333.513474 -377.803674) (xy 333.50708 -377.807728)
			(xy 333.474822 -377.82754) (xy 333.466694 -377.832112) (xy 333.455264 -377.84532) (xy 333.4258 -377.923806)
			(xy 333.425546 -377.941586) (xy 333.428594 -377.950222) (xy 333.438895 -377.981088) (xy 333.450013 -378.045198)
			(xy 333.450692 -378.07773) (xy 333.450206 -378.104981) (xy 333.44245 -378.158929) (xy 333.427095 -378.211224)
			(xy 333.404453 -378.260801) (xy 333.374987 -378.306651) (xy 333.339296 -378.347842) (xy 333.298105 -378.383533)
			(xy 333.252255 -378.412999) (xy 333.202678 -378.435641) (xy 333.150383 -378.450996) (xy 333.096435 -378.458752)
			(xy 333.041933 -378.458752) (xy 332.987985 -378.450996) (xy 332.93569 -378.435641) (xy 332.886113 -378.412999)
			(xy 332.840263 -378.383533) (xy 332.799072 -378.347842) (xy 332.763381 -378.306651) (xy 332.733915 -378.260801)
			(xy 332.711273 -378.211224) (xy 332.695918 -378.158929) (xy 332.688162 -378.104981) (xy 332.687676 -378.07773)
			(xy 332.688024 -378.053657) (xy 332.694051 -378.005891) (xy 332.70605 -377.959266) (xy 332.7146 -377.93676)
			(xy 332.71968 -377.924314) (xy 332.716378 -377.898406) (xy 332.649576 -377.807728) (xy 332.625954 -377.796806)
			(xy 332.612746 -377.797822) (xy 332.584044 -377.798838) (xy 332.556787 -377.798378) (xy 332.502827 -377.790626)
			(xy 332.45052 -377.775272) (xy 332.40093 -377.75263) (xy 332.355068 -377.723161) (xy 332.313866 -377.687465)
			(xy 332.278165 -377.646268) (xy 332.248691 -377.600409) (xy 332.226043 -377.550822) (xy 332.210684 -377.498516)
			(xy 332.202925 -377.444557) (xy 332.202925 -377.390043) (xy 332.210684 -377.336084) (xy 332.226043 -377.283778)
			(xy 332.248691 -377.234191) (xy 332.278165 -377.188332) (xy 332.313866 -377.147135) (xy 332.355068 -377.111439)
			(xy 332.40093 -377.08197) (xy 332.45052 -377.059328) (xy 332.502827 -377.043974) (xy 332.556787 -377.036222)
			(xy 332.584044 -377.035822) (xy 332.612746 -377.036838) (xy 332.625954 -377.037854) (xy 332.649576 -377.026932)
			(xy 332.716378 -376.936254) (xy 332.71968 -376.910346) (xy 332.7146 -376.8979) (xy 332.706063 -376.87539)
			(xy 332.694073 -376.828764) (xy 332.688035 -376.781002) (xy 332.687676 -376.75693) (xy 332.6892 -376.721878)
			(xy 332.690216 -376.71121) (xy 332.683612 -376.69089) (xy 332.6257 -376.62739) (xy 332.618203 -376.619842)
			(xy 332.598739 -376.6113) (xy 332.588108 -376.61088) (xy 326.061832 -376.61088) (xy 326.051226 -376.611416)
			(xy 326.031796 -376.619931) (xy 326.02424 -376.62739) (xy 325.966328 -376.69089) (xy 325.959724 -376.71121)
			(xy 325.96074 -376.721878) (xy 325.962264 -376.75693) (xy 325.961912 -376.781002) (xy 325.955879 -376.828766)
			(xy 325.943874 -376.875389) (xy 325.93534 -376.8979) (xy 325.93026 -376.910346) (xy 325.933562 -376.936254)
			(xy 326.000364 -377.026932) (xy 326.023986 -377.037854) (xy 326.037194 -377.036838) (xy 326.065896 -377.035822)
			(xy 326.093147 -377.036285) (xy 326.147094 -377.044041) (xy 326.199388 -377.059395) (xy 326.248965 -377.082036)
			(xy 326.294815 -377.111501) (xy 326.336005 -377.147192) (xy 326.371696 -377.188382) (xy 326.401162 -377.234232)
			(xy 326.423803 -377.283808) (xy 326.439158 -377.336102) (xy 326.446915 -377.390049) (xy 326.446915 -377.444551)
			(xy 326.439158 -377.498498) (xy 326.423803 -377.550792) (xy 326.401162 -377.600368) (xy 326.371696 -377.646218)
			(xy 326.336005 -377.687408) (xy 326.294815 -377.723099) (xy 326.248965 -377.752564) (xy 326.199388 -377.775205)
			(xy 326.147094 -377.790559) (xy 326.093147 -377.798315) (xy 326.065896 -377.798838) (xy 326.037194 -377.797822)
			(xy 326.023986 -377.796806) (xy 326.000364 -377.807728) (xy 325.933562 -377.898406) (xy 325.93026 -377.924314)
			(xy 325.93534 -377.93676) (xy 325.943878 -377.95927) (xy 325.955872 -378.005895) (xy 325.961915 -378.053658)
			(xy 325.962264 -378.07773) (xy 325.961778 -378.104981) (xy 325.954022 -378.158929) (xy 325.938667 -378.211224)
			(xy 325.916025 -378.260801) (xy 325.886559 -378.306651) (xy 325.850868 -378.347842) (xy 325.809677 -378.383533)
			(xy 325.763827 -378.412999) (xy 325.71425 -378.435641) (xy 325.661955 -378.450996) (xy 325.608007 -378.458752)
			(xy 325.553505 -378.458752) (xy 325.499557 -378.450996) (xy 325.447262 -378.435641) (xy 325.397685 -378.412999)
			(xy 325.351835 -378.383533) (xy 325.310644 -378.347842) (xy 325.274953 -378.306651) (xy 325.245487 -378.260801)
			(xy 325.222845 -378.211224) (xy 325.20749 -378.158929) (xy 325.199734 -378.104981) (xy 325.199248 -378.07773)
			(xy 325.199951 -378.0452) (xy 325.211063 -377.981092) (xy 325.221346 -377.950222) (xy 325.224394 -377.941586)
			(xy 325.22414 -377.923806) (xy 325.194676 -377.84532) (xy 325.183246 -377.832112) (xy 325.175118 -377.82754)
			(xy 325.14286 -377.807728) (xy 325.136424 -377.803764) (xy 325.121966 -377.799381) (xy 325.114412 -377.799092)
			(xy 324.83298 -377.799092) (xy 324.825413 -377.799296) (xy 324.810936 -377.803692) (xy 324.804532 -377.807728)
			(xy 324.772274 -377.82754) (xy 324.764146 -377.832112) (xy 324.752716 -377.84532) (xy 324.723252 -377.923806)
			(xy 324.722998 -377.941586) (xy 324.726046 -377.950222) (xy 324.736346 -377.981089) (xy 324.747463 -378.045198)
			(xy 324.748144 -378.07773) (xy 324.747658 -378.104981) (xy 324.739902 -378.158929) (xy 324.724547 -378.211224)
			(xy 324.701905 -378.260801) (xy 324.672439 -378.306651) (xy 324.636748 -378.347842) (xy 324.595557 -378.383533)
			(xy 324.549707 -378.412999) (xy 324.50013 -378.435641) (xy 324.447835 -378.450996) (xy 324.393887 -378.458752)
			(xy 324.339385 -378.458752) (xy 324.285437 -378.450996) (xy 324.233142 -378.435641) (xy 324.183565 -378.412999)
			(xy 324.137715 -378.383533) (xy 324.096524 -378.347842) (xy 324.060833 -378.306651) (xy 324.031367 -378.260801)
			(xy 324.008725 -378.211224) (xy 323.99337 -378.158929) (xy 323.985614 -378.104981) (xy 323.985128 -378.07773)
			(xy 323.985476 -378.053657) (xy 323.991502 -378.005891) (xy 324.0035 -377.959265) (xy 324.012052 -377.93676)
			(xy 324.017132 -377.924314) (xy 324.01383 -377.898406) (xy 323.947028 -377.807728) (xy 323.923406 -377.796806)
			(xy 323.910198 -377.797822) (xy 323.881496 -377.798838) (xy 323.854243 -377.798352) (xy 323.800291 -377.790594)
			(xy 323.747993 -377.775238) (xy 323.698412 -377.752594) (xy 323.652559 -377.723126) (xy 323.611366 -377.687431)
			(xy 323.575672 -377.646238) (xy 323.546204 -377.600384) (xy 323.523561 -377.550803) (xy 323.508205 -377.498505)
			(xy 323.500448 -377.444553) (xy 323.500448 -377.390047) (xy 323.508205 -377.336095) (xy 323.523561 -377.283797)
			(xy 323.546204 -377.234216) (xy 323.575672 -377.188362) (xy 323.611366 -377.147169) (xy 323.652559 -377.111474)
			(xy 323.698412 -377.082006) (xy 323.747993 -377.059362) (xy 323.800291 -377.044006) (xy 323.854243 -377.036248)
			(xy 323.881496 -377.035822) (xy 323.910198 -377.036838) (xy 323.923406 -377.037854) (xy 323.947028 -377.026932)
			(xy 324.01383 -376.936254) (xy 324.017132 -376.910346) (xy 324.012052 -376.8979) (xy 324.003516 -376.87539)
			(xy 323.991528 -376.828764) (xy 323.98549 -376.781001) (xy 323.985128 -376.75693) (xy 323.986652 -376.721878)
			(xy 323.987668 -376.71121) (xy 323.981064 -376.69089) (xy 323.923152 -376.62739) (xy 323.915658 -376.619834)
			(xy 323.896194 -376.611271) (xy 323.88556 -376.61088) (xy 322.658232 -376.61088) (xy 322.647626 -376.611416)
			(xy 322.628196 -376.619931) (xy 322.62064 -376.62739) (xy 322.562728 -376.69089) (xy 322.556124 -376.71121)
			(xy 322.55714 -376.721878) (xy 322.558664 -376.75693) (xy 322.558312 -376.781002) (xy 322.552279 -376.828766)
			(xy 322.540274 -376.875389) (xy 322.53174 -376.8979) (xy 322.52666 -376.910346) (xy 322.529962 -376.936254)
			(xy 322.596764 -377.026932) (xy 322.620386 -377.037854) (xy 322.633594 -377.036838) (xy 322.662296 -377.035822)
			(xy 322.689547 -377.036285) (xy 322.743494 -377.044041) (xy 322.795788 -377.059395) (xy 322.845365 -377.082036)
			(xy 322.891215 -377.111501) (xy 322.932405 -377.147192) (xy 322.968096 -377.188382) (xy 322.997562 -377.234232)
			(xy 323.020203 -377.283808) (xy 323.035558 -377.336102) (xy 323.043315 -377.390049) (xy 323.043315 -377.444551)
			(xy 323.035558 -377.498498) (xy 323.020203 -377.550792) (xy 322.997562 -377.600368) (xy 322.968096 -377.646218)
			(xy 322.932405 -377.687408) (xy 322.891215 -377.723099) (xy 322.845365 -377.752564) (xy 322.795788 -377.775205)
			(xy 322.743494 -377.790559) (xy 322.689547 -377.798315) (xy 322.662296 -377.798838) (xy 322.633594 -377.797822)
			(xy 322.620386 -377.796806) (xy 322.596764 -377.807728) (xy 322.529962 -377.898406) (xy 322.52666 -377.924314)
			(xy 322.53174 -377.93676) (xy 322.540278 -377.95927) (xy 322.552272 -378.005895) (xy 322.558315 -378.053658)
			(xy 322.558664 -378.07773) (xy 322.558178 -378.104981) (xy 322.550422 -378.158929) (xy 322.535067 -378.211224)
			(xy 322.512425 -378.260801) (xy 322.482959 -378.306651) (xy 322.447268 -378.347842) (xy 322.406077 -378.383533)
			(xy 322.360227 -378.412999) (xy 322.31065 -378.435641) (xy 322.258355 -378.450996) (xy 322.204407 -378.458752)
			(xy 322.149905 -378.458752) (xy 322.095957 -378.450996) (xy 322.043662 -378.435641) (xy 321.994085 -378.412999)
			(xy 321.948235 -378.383533) (xy 321.907044 -378.347842) (xy 321.871353 -378.306651) (xy 321.841887 -378.260801)
			(xy 321.819245 -378.211224) (xy 321.80389 -378.158929) (xy 321.796134 -378.104981) (xy 321.795648 -378.07773)
			(xy 321.796351 -378.0452) (xy 321.807463 -377.981092) (xy 321.817746 -377.950222) (xy 321.820794 -377.941586)
			(xy 321.82054 -377.923806) (xy 321.791076 -377.84532) (xy 321.779646 -377.832112) (xy 321.771518 -377.82754)
			(xy 321.73926 -377.807728) (xy 321.732824 -377.803764) (xy 321.718366 -377.799381) (xy 321.710812 -377.799092)
			(xy 321.42938 -377.799092) (xy 321.421813 -377.799296) (xy 321.407336 -377.803692) (xy 321.400932 -377.807728)
			(xy 321.368674 -377.82754) (xy 321.360546 -377.832112) (xy 321.349116 -377.84532) (xy 321.319652 -377.923806)
			(xy 321.319398 -377.941586) (xy 321.322446 -377.950222) (xy 321.332746 -377.981089) (xy 321.343863 -378.045198)
			(xy 321.344544 -378.07773) (xy 321.344058 -378.104981) (xy 321.336302 -378.158929) (xy 321.320947 -378.211224)
			(xy 321.298305 -378.260801) (xy 321.268839 -378.306651) (xy 321.233148 -378.347842) (xy 321.191957 -378.383533)
			(xy 321.146107 -378.412999) (xy 321.09653 -378.435641) (xy 321.044235 -378.450996) (xy 320.990287 -378.458752)
			(xy 320.935785 -378.458752) (xy 320.881837 -378.450996) (xy 320.829542 -378.435641) (xy 320.779965 -378.412999)
			(xy 320.734115 -378.383533) (xy 320.692924 -378.347842) (xy 320.657233 -378.306651) (xy 320.627767 -378.260801)
			(xy 320.605125 -378.211224) (xy 320.58977 -378.158929) (xy 320.582014 -378.104981) (xy 320.581528 -378.07773)
			(xy 320.581876 -378.053657) (xy 320.587902 -378.005891) (xy 320.5999 -377.959265) (xy 320.608452 -377.93676)
			(xy 320.613532 -377.924314) (xy 320.61023 -377.898406) (xy 320.543428 -377.807728) (xy 320.519806 -377.796806)
			(xy 320.506598 -377.797822) (xy 320.477896 -377.798838) (xy 320.450643 -377.798352) (xy 320.396691 -377.790594)
			(xy 320.344393 -377.775238) (xy 320.294812 -377.752594) (xy 320.248959 -377.723126) (xy 320.207766 -377.687431)
			(xy 320.172072 -377.646238) (xy 320.142604 -377.600384) (xy 320.119961 -377.550803) (xy 320.104605 -377.498505)
			(xy 320.096848 -377.444553) (xy 320.096848 -377.390047) (xy 320.104605 -377.336095) (xy 320.119961 -377.283797)
			(xy 320.142604 -377.234216) (xy 320.172072 -377.188362) (xy 320.207766 -377.147169) (xy 320.248959 -377.111474)
			(xy 320.294812 -377.082006) (xy 320.344393 -377.059362) (xy 320.396691 -377.044006) (xy 320.450643 -377.036248)
			(xy 320.477896 -377.035822) (xy 320.506598 -377.036838) (xy 320.519806 -377.037854) (xy 320.543428 -377.026932)
			(xy 320.61023 -376.936254) (xy 320.613532 -376.910346) (xy 320.608452 -376.8979) (xy 320.599916 -376.87539)
			(xy 320.587928 -376.828764) (xy 320.58189 -376.781001) (xy 320.581528 -376.75693) (xy 320.583052 -376.721878)
			(xy 320.584068 -376.71121) (xy 320.577464 -376.69089) (xy 320.519552 -376.62739) (xy 320.512058 -376.619834)
			(xy 320.492594 -376.611271) (xy 320.48196 -376.61088) (xy 315.851032 -376.61088) (xy 315.840426 -376.611416)
			(xy 315.820996 -376.619931) (xy 315.81344 -376.62739) (xy 315.755528 -376.69089) (xy 315.748924 -376.71121)
			(xy 315.74994 -376.721878) (xy 315.751464 -376.75693) (xy 315.751112 -376.781002) (xy 315.745079 -376.828766)
			(xy 315.733074 -376.875389) (xy 315.72454 -376.8979) (xy 315.71946 -376.910346) (xy 315.722762 -376.936254)
			(xy 315.789564 -377.026932) (xy 315.813186 -377.037854) (xy 315.826394 -377.036838) (xy 315.855096 -377.035822)
			(xy 315.882347 -377.036285) (xy 315.936294 -377.044041) (xy 315.988588 -377.059395) (xy 316.038165 -377.082036)
			(xy 316.084015 -377.111501) (xy 316.125205 -377.147192) (xy 316.160896 -377.188382) (xy 316.190362 -377.234232)
			(xy 316.213003 -377.283808) (xy 316.228358 -377.336102) (xy 316.236115 -377.390049) (xy 316.236115 -377.444551)
			(xy 316.228358 -377.498498) (xy 316.213003 -377.550792) (xy 316.190362 -377.600368) (xy 316.160896 -377.646218)
			(xy 316.125205 -377.687408) (xy 316.084015 -377.723099) (xy 316.038165 -377.752564) (xy 315.988588 -377.775205)
			(xy 315.936294 -377.790559) (xy 315.882347 -377.798315) (xy 315.855096 -377.798838) (xy 315.826394 -377.797822)
			(xy 315.813186 -377.796806) (xy 315.789564 -377.807728) (xy 315.722762 -377.898406) (xy 315.71946 -377.924314)
			(xy 315.72454 -377.93676) (xy 315.733078 -377.95927) (xy 315.745072 -378.005895) (xy 315.751115 -378.053658)
			(xy 315.751464 -378.07773) (xy 315.750978 -378.104981) (xy 315.743222 -378.158929) (xy 315.727867 -378.211224)
			(xy 315.705225 -378.260801) (xy 315.675759 -378.306651) (xy 315.640068 -378.347842) (xy 315.598877 -378.383533)
			(xy 315.553027 -378.412999) (xy 315.50345 -378.435641) (xy 315.451155 -378.450996) (xy 315.397207 -378.458752)
			(xy 315.342705 -378.458752) (xy 315.288757 -378.450996) (xy 315.236462 -378.435641) (xy 315.186885 -378.412999)
			(xy 315.141035 -378.383533) (xy 315.099844 -378.347842) (xy 315.064153 -378.306651) (xy 315.034687 -378.260801)
			(xy 315.012045 -378.211224) (xy 314.99669 -378.158929) (xy 314.988934 -378.104981) (xy 314.988448 -378.07773)
			(xy 314.989151 -378.0452) (xy 315.000263 -377.981092) (xy 315.010546 -377.950222) (xy 315.013594 -377.941586)
			(xy 315.01334 -377.923806) (xy 314.983876 -377.84532) (xy 314.972446 -377.832112) (xy 314.964318 -377.82754)
			(xy 314.93206 -377.807728) (xy 314.925624 -377.803764) (xy 314.911166 -377.799381) (xy 314.903612 -377.799092)
			(xy 314.62218 -377.799092) (xy 314.614613 -377.799296) (xy 314.600136 -377.803692) (xy 314.593732 -377.807728)
			(xy 314.561474 -377.82754) (xy 314.553346 -377.832112) (xy 314.541916 -377.84532) (xy 314.512452 -377.923806)
			(xy 314.512198 -377.941586) (xy 314.515246 -377.950222) (xy 314.525546 -377.981089) (xy 314.536663 -378.045198)
			(xy 314.537344 -378.07773) (xy 314.536858 -378.104981) (xy 314.529102 -378.158929) (xy 314.513747 -378.211224)
			(xy 314.491105 -378.260801) (xy 314.461639 -378.306651) (xy 314.425948 -378.347842) (xy 314.384757 -378.383533)
			(xy 314.338907 -378.412999) (xy 314.28933 -378.435641) (xy 314.237035 -378.450996) (xy 314.183087 -378.458752)
			(xy 314.128585 -378.458752) (xy 314.074637 -378.450996) (xy 314.022342 -378.435641) (xy 313.972765 -378.412999)
			(xy 313.926915 -378.383533) (xy 313.885724 -378.347842) (xy 313.850033 -378.306651) (xy 313.820567 -378.260801)
			(xy 313.797925 -378.211224) (xy 313.78257 -378.158929) (xy 313.774814 -378.104981) (xy 313.774328 -378.07773)
			(xy 313.774676 -378.053657) (xy 313.780702 -378.005891) (xy 313.7927 -377.959265) (xy 313.801252 -377.93676)
			(xy 313.806332 -377.924314) (xy 313.80303 -377.898406) (xy 313.736228 -377.807728) (xy 313.712606 -377.796806)
			(xy 313.699398 -377.797822) (xy 313.670696 -377.798838) (xy 313.643443 -377.798352) (xy 313.589491 -377.790594)
			(xy 313.537193 -377.775238) (xy 313.487612 -377.752594) (xy 313.441759 -377.723126) (xy 313.400566 -377.687431)
			(xy 313.364872 -377.646238) (xy 313.335404 -377.600384) (xy 313.312761 -377.550803) (xy 313.297405 -377.498505)
			(xy 313.289648 -377.444553) (xy 313.289648 -377.390047) (xy 313.297405 -377.336095) (xy 313.312761 -377.283797)
			(xy 313.335404 -377.234216) (xy 313.364872 -377.188362) (xy 313.400566 -377.147169) (xy 313.441759 -377.111474)
			(xy 313.487612 -377.082006) (xy 313.537193 -377.059362) (xy 313.589491 -377.044006) (xy 313.643443 -377.036248)
			(xy 313.670696 -377.035822) (xy 313.699398 -377.036838) (xy 313.712606 -377.037854) (xy 313.736228 -377.026932)
			(xy 313.80303 -376.936254) (xy 313.806332 -376.910346) (xy 313.801252 -376.8979) (xy 313.792716 -376.87539)
			(xy 313.780728 -376.828764) (xy 313.77469 -376.781001) (xy 313.774328 -376.75693) (xy 313.775852 -376.721878)
			(xy 313.776868 -376.71121) (xy 313.770264 -376.69089) (xy 313.712352 -376.62739) (xy 313.704858 -376.619834)
			(xy 313.685394 -376.611271) (xy 313.67476 -376.61088) (xy 309.043832 -376.61088) (xy 309.033226 -376.611416)
			(xy 309.013796 -376.619931) (xy 309.00624 -376.62739) (xy 308.948328 -376.69089) (xy 308.941724 -376.71121)
			(xy 308.94274 -376.721878) (xy 308.944264 -376.75693) (xy 308.943912 -376.781002) (xy 308.937879 -376.828766)
			(xy 308.925874 -376.875389) (xy 308.91734 -376.8979) (xy 308.91226 -376.910346) (xy 308.915562 -376.936254)
			(xy 308.982364 -377.026932) (xy 309.005986 -377.037854) (xy 309.019194 -377.036838) (xy 309.047896 -377.035822)
			(xy 309.075147 -377.036285) (xy 309.129094 -377.044041) (xy 309.181388 -377.059395) (xy 309.230965 -377.082036)
			(xy 309.276815 -377.111501) (xy 309.318005 -377.147192) (xy 309.353696 -377.188382) (xy 309.383162 -377.234232)
			(xy 309.405803 -377.283808) (xy 309.421158 -377.336102) (xy 309.428915 -377.390049) (xy 309.428915 -377.444551)
			(xy 309.421158 -377.498498) (xy 309.405803 -377.550792) (xy 309.383162 -377.600368) (xy 309.353696 -377.646218)
			(xy 309.318005 -377.687408) (xy 309.276815 -377.723099) (xy 309.230965 -377.752564) (xy 309.181388 -377.775205)
			(xy 309.129094 -377.790559) (xy 309.075147 -377.798315) (xy 309.047896 -377.798838) (xy 309.019194 -377.797822)
			(xy 309.005986 -377.796806) (xy 308.982364 -377.807728) (xy 308.915562 -377.898406) (xy 308.91226 -377.924314)
			(xy 308.91734 -377.93676) (xy 308.925878 -377.95927) (xy 308.937872 -378.005895) (xy 308.943915 -378.053658)
			(xy 308.944264 -378.07773) (xy 308.943778 -378.104981) (xy 308.936022 -378.158929) (xy 308.920667 -378.211224)
			(xy 308.898025 -378.260801) (xy 308.868559 -378.306651) (xy 308.832868 -378.347842) (xy 308.791677 -378.383533)
			(xy 308.745827 -378.412999) (xy 308.69625 -378.435641) (xy 308.643955 -378.450996) (xy 308.590007 -378.458752)
			(xy 308.535505 -378.458752) (xy 308.481557 -378.450996) (xy 308.429262 -378.435641) (xy 308.379685 -378.412999)
			(xy 308.333835 -378.383533) (xy 308.292644 -378.347842) (xy 308.256953 -378.306651) (xy 308.227487 -378.260801)
			(xy 308.204845 -378.211224) (xy 308.18949 -378.158929) (xy 308.181734 -378.104981) (xy 308.181248 -378.07773)
			(xy 308.181951 -378.0452) (xy 308.193063 -377.981092) (xy 308.203346 -377.950222) (xy 308.206394 -377.941586)
			(xy 308.20614 -377.923806) (xy 308.176676 -377.84532) (xy 308.165246 -377.832112) (xy 308.157118 -377.82754)
			(xy 308.12486 -377.807728) (xy 308.118424 -377.803764) (xy 308.103966 -377.799381) (xy 308.096412 -377.799092)
			(xy 307.81498 -377.799092) (xy 307.807413 -377.799296) (xy 307.792936 -377.803692) (xy 307.786532 -377.807728)
			(xy 307.754274 -377.82754) (xy 307.746146 -377.832112) (xy 307.734716 -377.84532) (xy 307.705252 -377.923806)
			(xy 307.704998 -377.941586) (xy 307.708046 -377.950222) (xy 307.718346 -377.981089) (xy 307.729463 -378.045198)
			(xy 307.730144 -378.07773) (xy 307.729658 -378.104981) (xy 307.721902 -378.158929) (xy 307.706547 -378.211224)
			(xy 307.683905 -378.260801) (xy 307.654439 -378.306651) (xy 307.618748 -378.347842) (xy 307.577557 -378.383533)
			(xy 307.531707 -378.412999) (xy 307.48213 -378.435641) (xy 307.429835 -378.450996) (xy 307.375887 -378.458752)
			(xy 307.321385 -378.458752) (xy 307.267437 -378.450996) (xy 307.215142 -378.435641) (xy 307.165565 -378.412999)
			(xy 307.119715 -378.383533) (xy 307.078524 -378.347842) (xy 307.042833 -378.306651) (xy 307.013367 -378.260801)
			(xy 306.990725 -378.211224) (xy 306.97537 -378.158929) (xy 306.967614 -378.104981) (xy 306.967128 -378.07773)
			(xy 306.967476 -378.053657) (xy 306.973502 -378.005891) (xy 306.9855 -377.959265) (xy 306.994052 -377.93676)
			(xy 306.999132 -377.924314) (xy 306.99583 -377.898406) (xy 306.929028 -377.807728) (xy 306.905406 -377.796806)
			(xy 306.892198 -377.797822) (xy 306.863496 -377.798838) (xy 306.836243 -377.798352) (xy 306.782291 -377.790594)
			(xy 306.729993 -377.775238) (xy 306.680412 -377.752594) (xy 306.634559 -377.723126) (xy 306.593366 -377.687431)
			(xy 306.557672 -377.646238) (xy 306.528204 -377.600384) (xy 306.505561 -377.550803) (xy 306.490205 -377.498505)
			(xy 306.482448 -377.444553) (xy 306.482448 -377.390047) (xy 306.490205 -377.336095) (xy 306.505561 -377.283797)
			(xy 306.528204 -377.234216) (xy 306.557672 -377.188362) (xy 306.593366 -377.147169) (xy 306.634559 -377.111474)
			(xy 306.680412 -377.082006) (xy 306.729993 -377.059362) (xy 306.782291 -377.044006) (xy 306.836243 -377.036248)
			(xy 306.863496 -377.035822) (xy 306.892198 -377.036838) (xy 306.905406 -377.037854) (xy 306.929028 -377.026932)
			(xy 306.99583 -376.936254) (xy 306.999132 -376.910346) (xy 306.994052 -376.8979) (xy 306.985516 -376.87539)
			(xy 306.973528 -376.828764) (xy 306.96749 -376.781001) (xy 306.967128 -376.75693) (xy 306.968652 -376.721878)
			(xy 306.969668 -376.71121) (xy 306.963064 -376.69089) (xy 306.905152 -376.62739) (xy 306.897658 -376.619834)
			(xy 306.878194 -376.611271) (xy 306.86756 -376.61088) (xy 304.308002 -376.61088) (xy 304.297931 -376.611302)
			(xy 304.279324 -376.619014) (xy 304.271934 -376.625866) (xy 303.671986 -377.225814) (xy 303.665132 -377.233209)
			(xy 303.65739 -377.251808) (xy 303.657 -377.261882) (xy 303.657 -378.769118) (xy 303.656573 -378.779187)
			(xy 303.648854 -378.797786) (xy 303.642014 -378.805186) (xy 303.222406 -379.224794) (xy 303.215008 -379.231642)
			(xy 303.19641 -379.23938) (xy 303.186338 -379.23978) (xy 300.46168 -379.23978) (xy 300.433232 -379.26391)
			(xy 300.430184 -379.282452) (xy 300.426611 -379.302738) (xy 300.41567 -379.34245) (xy 300.40834 -379.3617)
			(xy 300.40326 -379.374146) (xy 300.406562 -379.400054) (xy 300.473364 -379.490732) (xy 300.496986 -379.501654)
			(xy 300.510194 -379.500638) (xy 300.538896 -379.499622) (xy 300.566147 -379.500085) (xy 300.620094 -379.507841)
			(xy 300.672388 -379.523195) (xy 300.721965 -379.545836) (xy 300.767815 -379.575301) (xy 300.809005 -379.610992)
			(xy 300.844696 -379.652182) (xy 300.874162 -379.698032) (xy 300.896803 -379.747608) (xy 300.912158 -379.799902)
			(xy 300.919915 -379.853849) (xy 300.919915 -379.908349) (xy 304.780708 -379.908349) (xy 304.780708 -379.853851)
			(xy 304.788464 -379.799908) (xy 304.803818 -379.747618) (xy 304.826457 -379.698045) (xy 304.85592 -379.652198)
			(xy 304.891609 -379.611011) (xy 304.932795 -379.575323) (xy 304.978641 -379.545859) (xy 305.028214 -379.523219)
			(xy 305.080504 -379.507865) (xy 305.134447 -379.500108) (xy 305.161696 -379.499622) (xy 305.190398 -379.500638)
			(xy 305.203606 -379.501654) (xy 305.227228 -379.490732) (xy 305.29403 -379.400054) (xy 305.297332 -379.374146)
			(xy 305.292252 -379.3617) (xy 305.283717 -379.339189) (xy 305.271713 -379.292566) (xy 305.26568 -379.244802)
			(xy 305.265328 -379.22073) (xy 305.265814 -379.193479) (xy 305.27357 -379.139531) (xy 305.288925 -379.087236)
			(xy 305.311567 -379.037659) (xy 305.341033 -378.991809) (xy 305.376724 -378.950618) (xy 305.417915 -378.914927)
			(xy 305.463765 -378.885461) (xy 305.513342 -378.862819) (xy 305.565637 -378.847464) (xy 305.619585 -378.839708)
			(xy 305.674087 -378.839708) (xy 305.728035 -378.847464) (xy 305.78033 -378.862819) (xy 305.829907 -378.885461)
			(xy 305.875757 -378.914927) (xy 305.916948 -378.950618) (xy 305.952639 -378.991809) (xy 305.982105 -379.037659)
			(xy 306.004747 -379.087236) (xy 306.020102 -379.139531) (xy 306.027858 -379.193479) (xy 306.028344 -379.22073)
			(xy 306.027653 -379.253262) (xy 306.016543 -379.317371) (xy 306.006246 -379.348238) (xy 306.003198 -379.356874)
			(xy 306.003452 -379.374654) (xy 306.032916 -379.45314) (xy 306.044346 -379.466348) (xy 306.052474 -379.47092)
			(xy 306.084732 -379.490732) (xy 306.091133 -379.494773) (xy 306.105613 -379.499165) (xy 306.11318 -379.499368)
			(xy 306.394612 -379.499368) (xy 306.402165 -379.49907) (xy 306.416623 -379.494692) (xy 306.42306 -379.490732)
			(xy 306.455318 -379.47092) (xy 306.463446 -379.466348) (xy 306.474876 -379.45314) (xy 306.50434 -379.374654)
			(xy 306.504594 -379.356874) (xy 306.501546 -379.348238) (xy 306.491253 -379.31737) (xy 306.480148 -379.253261)
			(xy 306.479448 -379.22073) (xy 306.479934 -379.193479) (xy 306.48769 -379.139531) (xy 306.503045 -379.087236)
			(xy 306.525687 -379.037659) (xy 306.555153 -378.991809) (xy 306.590844 -378.950618) (xy 306.632035 -378.914927)
			(xy 306.677885 -378.885461) (xy 306.727462 -378.862819) (xy 306.779757 -378.847464) (xy 306.833705 -378.839708)
			(xy 306.888207 -378.839708) (xy 306.942155 -378.847464) (xy 306.99445 -378.862819) (xy 307.044027 -378.885461)
			(xy 307.089877 -378.914927) (xy 307.131068 -378.950618) (xy 307.166759 -378.991809) (xy 307.196225 -379.037659)
			(xy 307.218867 -379.087236) (xy 307.234222 -379.139531) (xy 307.241978 -379.193479) (xy 307.242464 -379.22073)
			(xy 307.242102 -379.244801) (xy 307.236065 -379.292564) (xy 307.224076 -379.33919) (xy 307.21554 -379.3617)
			(xy 307.21046 -379.374146) (xy 307.213762 -379.400054) (xy 307.280564 -379.490732) (xy 307.304186 -379.501654)
			(xy 307.317394 -379.500638) (xy 307.346096 -379.499622) (xy 307.373351 -379.500025) (xy 307.427307 -379.507782)
			(xy 307.479609 -379.523139) (xy 307.529194 -379.545783) (xy 307.575051 -379.575253) (xy 307.616248 -379.610949)
			(xy 307.651945 -379.652146) (xy 307.681415 -379.698003) (xy 307.70406 -379.747587) (xy 307.719417 -379.799889)
			(xy 307.727175 -379.853845) (xy 307.727175 -379.908349) (xy 311.587908 -379.908349) (xy 311.587908 -379.853851)
			(xy 311.595664 -379.799908) (xy 311.611018 -379.747618) (xy 311.633657 -379.698045) (xy 311.66312 -379.652198)
			(xy 311.698809 -379.611011) (xy 311.739995 -379.575323) (xy 311.785841 -379.545859) (xy 311.835414 -379.523219)
			(xy 311.887704 -379.507865) (xy 311.941647 -379.500108) (xy 311.968896 -379.499622) (xy 311.997598 -379.500638)
			(xy 312.010806 -379.501654) (xy 312.034428 -379.490732) (xy 312.10123 -379.400054) (xy 312.104532 -379.374146)
			(xy 312.099452 -379.3617) (xy 312.090917 -379.339189) (xy 312.078913 -379.292566) (xy 312.07288 -379.244802)
			(xy 312.072528 -379.22073) (xy 312.073014 -379.193479) (xy 312.08077 -379.139531) (xy 312.096125 -379.087236)
			(xy 312.118767 -379.037659) (xy 312.148233 -378.991809) (xy 312.183924 -378.950618) (xy 312.225115 -378.914927)
			(xy 312.270965 -378.885461) (xy 312.320542 -378.862819) (xy 312.372837 -378.847464) (xy 312.426785 -378.839708)
			(xy 312.481287 -378.839708) (xy 312.535235 -378.847464) (xy 312.58753 -378.862819) (xy 312.637107 -378.885461)
			(xy 312.682957 -378.914927) (xy 312.724148 -378.950618) (xy 312.759839 -378.991809) (xy 312.789305 -379.037659)
			(xy 312.811947 -379.087236) (xy 312.827302 -379.139531) (xy 312.835058 -379.193479) (xy 312.835544 -379.22073)
			(xy 312.834853 -379.253262) (xy 312.823743 -379.317371) (xy 312.813446 -379.348238) (xy 312.810398 -379.356874)
			(xy 312.810652 -379.374654) (xy 312.840116 -379.45314) (xy 312.851546 -379.466348) (xy 312.859674 -379.47092)
			(xy 312.891932 -379.490732) (xy 312.898333 -379.494773) (xy 312.912813 -379.499165) (xy 312.92038 -379.499368)
			(xy 313.201812 -379.499368) (xy 313.209365 -379.49907) (xy 313.223823 -379.494692) (xy 313.23026 -379.490732)
			(xy 313.262518 -379.47092) (xy 313.270646 -379.466348) (xy 313.282076 -379.45314) (xy 313.31154 -379.374654)
			(xy 313.311794 -379.356874) (xy 313.308746 -379.348238) (xy 313.298453 -379.31737) (xy 313.287348 -379.253261)
			(xy 313.286648 -379.22073) (xy 313.287134 -379.193479) (xy 313.29489 -379.139531) (xy 313.310245 -379.087236)
			(xy 313.332887 -379.037659) (xy 313.362353 -378.991809) (xy 313.398044 -378.950618) (xy 313.439235 -378.914927)
			(xy 313.485085 -378.885461) (xy 313.534662 -378.862819) (xy 313.586957 -378.847464) (xy 313.640905 -378.839708)
			(xy 313.695407 -378.839708) (xy 313.749355 -378.847464) (xy 313.80165 -378.862819) (xy 313.851227 -378.885461)
			(xy 313.897077 -378.914927) (xy 313.938268 -378.950618) (xy 313.973959 -378.991809) (xy 314.003425 -379.037659)
			(xy 314.026067 -379.087236) (xy 314.041422 -379.139531) (xy 314.049178 -379.193479) (xy 314.049664 -379.22073)
			(xy 314.049302 -379.244801) (xy 314.043265 -379.292564) (xy 314.031276 -379.33919) (xy 314.02274 -379.3617)
			(xy 314.01766 -379.374146) (xy 314.020962 -379.400054) (xy 314.087764 -379.490732) (xy 314.111386 -379.501654)
			(xy 314.124594 -379.500638) (xy 314.153296 -379.499622) (xy 314.180551 -379.500025) (xy 314.234507 -379.507782)
			(xy 314.286809 -379.523139) (xy 314.336394 -379.545783) (xy 314.382251 -379.575253) (xy 314.423448 -379.610949)
			(xy 314.459145 -379.652146) (xy 314.488615 -379.698003) (xy 314.51126 -379.747587) (xy 314.526617 -379.799889)
			(xy 314.534375 -379.853845) (xy 314.534375 -379.908349) (xy 318.395108 -379.908349) (xy 318.395108 -379.853851)
			(xy 318.402864 -379.799908) (xy 318.418218 -379.747618) (xy 318.440857 -379.698045) (xy 318.47032 -379.652198)
			(xy 318.506009 -379.611011) (xy 318.547195 -379.575323) (xy 318.593041 -379.545859) (xy 318.642614 -379.523219)
			(xy 318.694904 -379.507865) (xy 318.748847 -379.500108) (xy 318.776096 -379.499622) (xy 318.804798 -379.500638)
			(xy 318.818006 -379.501654) (xy 318.841628 -379.490732) (xy 318.90843 -379.400054) (xy 318.911732 -379.374146)
			(xy 318.906652 -379.3617) (xy 318.898117 -379.339189) (xy 318.886113 -379.292566) (xy 318.88008 -379.244802)
			(xy 318.879728 -379.22073) (xy 318.880214 -379.193479) (xy 318.88797 -379.139531) (xy 318.903325 -379.087236)
			(xy 318.925967 -379.037659) (xy 318.955433 -378.991809) (xy 318.991124 -378.950618) (xy 319.032315 -378.914927)
			(xy 319.078165 -378.885461) (xy 319.127742 -378.862819) (xy 319.180037 -378.847464) (xy 319.233985 -378.839708)
			(xy 319.288487 -378.839708) (xy 319.342435 -378.847464) (xy 319.39473 -378.862819) (xy 319.444307 -378.885461)
			(xy 319.490157 -378.914927) (xy 319.531348 -378.950618) (xy 319.567039 -378.991809) (xy 319.596505 -379.037659)
			(xy 319.619147 -379.087236) (xy 319.634502 -379.139531) (xy 319.642258 -379.193479) (xy 319.642744 -379.22073)
			(xy 319.642053 -379.253262) (xy 319.630943 -379.317371) (xy 319.620646 -379.348238) (xy 319.617598 -379.356874)
			(xy 319.617852 -379.374654) (xy 319.647316 -379.45314) (xy 319.658746 -379.466348) (xy 319.666874 -379.47092)
			(xy 319.699132 -379.490732) (xy 319.705533 -379.494773) (xy 319.720013 -379.499165) (xy 319.72758 -379.499368)
			(xy 320.009012 -379.499368) (xy 320.016565 -379.49907) (xy 320.031023 -379.494692) (xy 320.03746 -379.490732)
			(xy 320.069718 -379.47092) (xy 320.077846 -379.466348) (xy 320.089276 -379.45314) (xy 320.11874 -379.374654)
			(xy 320.118994 -379.356874) (xy 320.115946 -379.348238) (xy 320.105653 -379.31737) (xy 320.094548 -379.253261)
			(xy 320.093848 -379.22073) (xy 320.094334 -379.193479) (xy 320.10209 -379.139531) (xy 320.117445 -379.087236)
			(xy 320.140087 -379.037659) (xy 320.169553 -378.991809) (xy 320.205244 -378.950618) (xy 320.246435 -378.914927)
			(xy 320.292285 -378.885461) (xy 320.341862 -378.862819) (xy 320.394157 -378.847464) (xy 320.448105 -378.839708)
			(xy 320.502607 -378.839708) (xy 320.556555 -378.847464) (xy 320.60885 -378.862819) (xy 320.658427 -378.885461)
			(xy 320.704277 -378.914927) (xy 320.745468 -378.950618) (xy 320.781159 -378.991809) (xy 320.810625 -379.037659)
			(xy 320.833267 -379.087236) (xy 320.848622 -379.139531) (xy 320.856378 -379.193479) (xy 320.856864 -379.22073)
			(xy 320.856502 -379.244801) (xy 320.850465 -379.292564) (xy 320.838476 -379.33919) (xy 320.82994 -379.3617)
			(xy 320.82486 -379.374146) (xy 320.828162 -379.400054) (xy 320.894964 -379.490732) (xy 320.918586 -379.501654)
			(xy 320.931794 -379.500638) (xy 320.960496 -379.499622) (xy 320.987751 -379.500025) (xy 321.041707 -379.507782)
			(xy 321.094009 -379.523139) (xy 321.143594 -379.545783) (xy 321.189451 -379.575253) (xy 321.230648 -379.610949)
			(xy 321.266345 -379.652146) (xy 321.295815 -379.698003) (xy 321.31846 -379.747587) (xy 321.333817 -379.799889)
			(xy 321.341575 -379.853845) (xy 321.341575 -379.908353) (xy 330.501185 -379.908353) (xy 330.501185 -379.853847)
			(xy 330.508943 -379.799897) (xy 330.5243 -379.747599) (xy 330.546944 -379.69802) (xy 330.576414 -379.652169)
			(xy 330.612109 -379.610978) (xy 330.653304 -379.575287) (xy 330.699159 -379.545823) (xy 330.748741 -379.523185)
			(xy 330.80104 -379.507834) (xy 330.854991 -379.500082) (xy 330.882244 -379.499622) (xy 330.910946 -379.500638)
			(xy 330.924154 -379.501654) (xy 330.947776 -379.490732) (xy 331.014578 -379.400054) (xy 331.01788 -379.374146)
			(xy 331.0128 -379.3617) (xy 331.004267 -379.339188) (xy 330.992262 -379.292566) (xy 330.986228 -379.244802)
			(xy 330.985876 -379.22073) (xy 330.986362 -379.193479) (xy 330.994118 -379.139531) (xy 331.009473 -379.087236)
			(xy 331.032115 -379.037659) (xy 331.061581 -378.991809) (xy 331.097272 -378.950618) (xy 331.138463 -378.914927)
			(xy 331.184313 -378.885461) (xy 331.23389 -378.862819) (xy 331.286185 -378.847464) (xy 331.340133 -378.839708)
			(xy 331.394635 -378.839708) (xy 331.448583 -378.847464) (xy 331.500878 -378.862819) (xy 331.550455 -378.885461)
			(xy 331.596305 -378.914927) (xy 331.637496 -378.950618) (xy 331.673187 -378.991809) (xy 331.702653 -379.037659)
			(xy 331.725295 -379.087236) (xy 331.74065 -379.139531) (xy 331.748406 -379.193479) (xy 331.748892 -379.22073)
			(xy 331.748203 -379.253262) (xy 331.737092 -379.317371) (xy 331.726794 -379.348238) (xy 331.723746 -379.356874)
			(xy 331.724 -379.374654) (xy 331.753464 -379.45314) (xy 331.764894 -379.466348) (xy 331.773022 -379.47092)
			(xy 331.80528 -379.490732) (xy 331.811671 -379.494791) (xy 331.826158 -379.499172) (xy 331.833728 -379.499368)
			(xy 332.11516 -379.499368) (xy 332.122714 -379.49909) (xy 332.137172 -379.494698) (xy 332.143608 -379.490732)
			(xy 332.175866 -379.47092) (xy 332.183994 -379.466348) (xy 332.195424 -379.45314) (xy 332.224888 -379.374654)
			(xy 332.225142 -379.356874) (xy 332.222094 -379.348238) (xy 332.211799 -379.317371) (xy 332.200695 -379.253261)
			(xy 332.199996 -379.22073) (xy 332.200482 -379.193479) (xy 332.208238 -379.139531) (xy 332.223593 -379.087236)
			(xy 332.246235 -379.037659) (xy 332.275701 -378.991809) (xy 332.311392 -378.950618) (xy 332.352583 -378.914927)
			(xy 332.398433 -378.885461) (xy 332.44801 -378.862819) (xy 332.500305 -378.847464) (xy 332.554253 -378.839708)
			(xy 332.608755 -378.839708) (xy 332.662703 -378.847464) (xy 332.714998 -378.862819) (xy 332.764575 -378.885461)
			(xy 332.810425 -378.914927) (xy 332.851616 -378.950618) (xy 332.887307 -378.991809) (xy 332.916773 -379.037659)
			(xy 332.939415 -379.087236) (xy 332.95477 -379.139531) (xy 332.962526 -379.193479) (xy 332.963012 -379.22073)
			(xy 332.962654 -379.244802) (xy 332.956615 -379.292564) (xy 332.944625 -379.33919) (xy 332.936088 -379.3617)
			(xy 332.931008 -379.374146) (xy 332.93431 -379.400054) (xy 333.001112 -379.490732) (xy 333.024734 -379.501654)
			(xy 333.037942 -379.500638) (xy 333.066644 -379.499622) (xy 333.093895 -379.500051) (xy 333.147843 -379.507813)
			(xy 333.200136 -379.523173) (xy 333.249712 -379.545819) (xy 333.29556 -379.575288) (xy 333.336748 -379.610983)
			(xy 333.372438 -379.652175) (xy 333.401902 -379.698027) (xy 333.424542 -379.747605) (xy 333.439896 -379.799901)
			(xy 333.447652 -379.853849) (xy 333.447652 -379.908351) (xy 333.447652 -379.908353) (xy 337.308385 -379.908353)
			(xy 337.308385 -379.853847) (xy 337.316143 -379.799897) (xy 337.3315 -379.747599) (xy 337.354144 -379.69802)
			(xy 337.383614 -379.652169) (xy 337.419309 -379.610978) (xy 337.460504 -379.575287) (xy 337.506359 -379.545823)
			(xy 337.555941 -379.523185) (xy 337.60824 -379.507834) (xy 337.662191 -379.500082) (xy 337.689444 -379.499622)
			(xy 337.718146 -379.500638) (xy 337.731354 -379.501654) (xy 337.754976 -379.490732) (xy 337.821778 -379.400054)
			(xy 337.82508 -379.374146) (xy 337.82 -379.3617) (xy 337.811467 -379.339188) (xy 337.799462 -379.292566)
			(xy 337.793428 -379.244802) (xy 337.793076 -379.22073) (xy 337.793562 -379.193479) (xy 337.801318 -379.139531)
			(xy 337.816673 -379.087236) (xy 337.839315 -379.037659) (xy 337.868781 -378.991809) (xy 337.904472 -378.950618)
			(xy 337.945663 -378.914927) (xy 337.991513 -378.885461) (xy 338.04109 -378.862819) (xy 338.093385 -378.847464)
			(xy 338.147333 -378.839708) (xy 338.201835 -378.839708) (xy 338.255783 -378.847464) (xy 338.308078 -378.862819)
			(xy 338.357655 -378.885461) (xy 338.403505 -378.914927) (xy 338.444696 -378.950618) (xy 338.480387 -378.991809)
			(xy 338.509853 -379.037659) (xy 338.532495 -379.087236) (xy 338.54785 -379.139531) (xy 338.555606 -379.193479)
			(xy 338.556092 -379.22073) (xy 338.555403 -379.253262) (xy 338.544292 -379.317371) (xy 338.533994 -379.348238)
			(xy 338.530946 -379.356874) (xy 338.5312 -379.374654) (xy 338.560664 -379.45314) (xy 338.572094 -379.466348)
			(xy 338.580222 -379.47092) (xy 338.61248 -379.490732) (xy 338.618871 -379.494791) (xy 338.633358 -379.499172)
			(xy 338.640928 -379.499368) (xy 338.92236 -379.499368) (xy 338.929914 -379.49909) (xy 338.944372 -379.494698)
			(xy 338.950808 -379.490732) (xy 338.983066 -379.47092) (xy 338.991194 -379.466348) (xy 339.002624 -379.45314)
			(xy 339.032088 -379.374654) (xy 339.032342 -379.356874) (xy 339.029294 -379.348238) (xy 339.018999 -379.317371)
			(xy 339.007895 -379.253261) (xy 339.007196 -379.22073) (xy 339.007682 -379.193479) (xy 339.015438 -379.139531)
			(xy 339.030793 -379.087236) (xy 339.053435 -379.037659) (xy 339.082901 -378.991809) (xy 339.118592 -378.950618)
			(xy 339.159783 -378.914927) (xy 339.205633 -378.885461) (xy 339.25521 -378.862819) (xy 339.307505 -378.847464)
			(xy 339.361453 -378.839708) (xy 339.415955 -378.839708) (xy 339.469903 -378.847464) (xy 339.522198 -378.862819)
			(xy 339.571775 -378.885461) (xy 339.617625 -378.914927) (xy 339.658816 -378.950618) (xy 339.694507 -378.991809)
			(xy 339.723973 -379.037659) (xy 339.746615 -379.087236) (xy 339.76197 -379.139531) (xy 339.769726 -379.193479)
			(xy 339.770212 -379.22073) (xy 339.769854 -379.244802) (xy 339.763815 -379.292564) (xy 339.751825 -379.33919)
			(xy 339.743288 -379.3617) (xy 339.738208 -379.374146) (xy 339.74151 -379.400054) (xy 339.808312 -379.490732)
			(xy 339.831934 -379.501654) (xy 339.845142 -379.500638) (xy 339.873844 -379.499622) (xy 339.901095 -379.500051)
			(xy 339.955043 -379.507813) (xy 340.007336 -379.523173) (xy 340.056912 -379.545819) (xy 340.10276 -379.575288)
			(xy 340.143948 -379.610983) (xy 340.179638 -379.652175) (xy 340.209102 -379.698027) (xy 340.231742 -379.747605)
			(xy 340.247096 -379.799901) (xy 340.254852 -379.853849) (xy 340.254852 -379.908351) (xy 340.254852 -379.908353)
			(xy 344.115585 -379.908353) (xy 344.115585 -379.853847) (xy 344.123343 -379.799897) (xy 344.1387 -379.747599)
			(xy 344.161344 -379.69802) (xy 344.190814 -379.652169) (xy 344.226509 -379.610978) (xy 344.267704 -379.575287)
			(xy 344.313559 -379.545823) (xy 344.363141 -379.523185) (xy 344.41544 -379.507834) (xy 344.469391 -379.500082)
			(xy 344.496644 -379.499622) (xy 344.525346 -379.500638) (xy 344.538554 -379.501654) (xy 344.562176 -379.490732)
			(xy 344.628978 -379.400054) (xy 344.63228 -379.374146) (xy 344.6272 -379.3617) (xy 344.618667 -379.339188)
			(xy 344.606662 -379.292566) (xy 344.600628 -379.244802) (xy 344.600276 -379.22073) (xy 344.600762 -379.193479)
			(xy 344.608518 -379.139531) (xy 344.623873 -379.087236) (xy 344.646515 -379.037659) (xy 344.675981 -378.991809)
			(xy 344.711672 -378.950618) (xy 344.752863 -378.914927) (xy 344.798713 -378.885461) (xy 344.84829 -378.862819)
			(xy 344.900585 -378.847464) (xy 344.954533 -378.839708) (xy 345.009035 -378.839708) (xy 345.062983 -378.847464)
			(xy 345.115278 -378.862819) (xy 345.164855 -378.885461) (xy 345.210705 -378.914927) (xy 345.251896 -378.950618)
			(xy 345.287587 -378.991809) (xy 345.317053 -379.037659) (xy 345.339695 -379.087236) (xy 345.35505 -379.139531)
			(xy 345.362806 -379.193479) (xy 345.363292 -379.22073) (xy 345.362603 -379.253262) (xy 345.351492 -379.317371)
			(xy 345.341194 -379.348238) (xy 345.338146 -379.356874) (xy 345.3384 -379.374654) (xy 345.367864 -379.45314)
			(xy 345.379294 -379.466348) (xy 345.387422 -379.47092) (xy 345.41968 -379.490732) (xy 345.426071 -379.494791)
			(xy 345.440558 -379.499172) (xy 345.448128 -379.499368) (xy 345.72956 -379.499368) (xy 345.737114 -379.49909)
			(xy 345.751572 -379.494698) (xy 345.758008 -379.490732) (xy 345.790266 -379.47092) (xy 345.798394 -379.466348)
			(xy 345.809824 -379.45314) (xy 345.839288 -379.374654) (xy 345.839542 -379.356874) (xy 345.836494 -379.348238)
			(xy 345.826199 -379.317371) (xy 345.815095 -379.253261) (xy 345.814396 -379.22073) (xy 345.814882 -379.193479)
			(xy 345.822638 -379.139531) (xy 345.837993 -379.087236) (xy 345.860635 -379.037659) (xy 345.890101 -378.991809)
			(xy 345.925792 -378.950618) (xy 345.966983 -378.914927) (xy 346.012833 -378.885461) (xy 346.06241 -378.862819)
			(xy 346.114705 -378.847464) (xy 346.168653 -378.839708) (xy 346.223155 -378.839708) (xy 346.277103 -378.847464)
			(xy 346.329398 -378.862819) (xy 346.378975 -378.885461) (xy 346.424825 -378.914927) (xy 346.466016 -378.950618)
			(xy 346.501707 -378.991809) (xy 346.531173 -379.037659) (xy 346.553815 -379.087236) (xy 346.56917 -379.139531)
			(xy 346.576926 -379.193479) (xy 346.577412 -379.22073) (xy 346.577054 -379.244802) (xy 346.571015 -379.292564)
			(xy 346.559025 -379.33919) (xy 346.550488 -379.3617) (xy 346.545408 -379.374146) (xy 346.54871 -379.400054)
			(xy 346.615512 -379.490732) (xy 346.639134 -379.501654) (xy 346.652342 -379.500638) (xy 346.681044 -379.499622)
			(xy 346.708295 -379.500051) (xy 346.762243 -379.507813) (xy 346.814536 -379.523173) (xy 346.864112 -379.545819)
			(xy 346.90996 -379.575288) (xy 346.951148 -379.610983) (xy 346.986838 -379.652175) (xy 347.016302 -379.698027)
			(xy 347.038942 -379.747605) (xy 347.054296 -379.799901) (xy 347.062052 -379.853849) (xy 347.062052 -379.908351)
			(xy 347.062052 -379.908353) (xy 350.922785 -379.908353) (xy 350.922785 -379.853847) (xy 350.930543 -379.799897)
			(xy 350.9459 -379.747599) (xy 350.968544 -379.69802) (xy 350.998014 -379.652169) (xy 351.033709 -379.610978)
			(xy 351.074904 -379.575287) (xy 351.120759 -379.545823) (xy 351.170341 -379.523185) (xy 351.22264 -379.507834)
			(xy 351.276591 -379.500082) (xy 351.303844 -379.499622) (xy 351.332546 -379.500638) (xy 351.345754 -379.501654)
			(xy 351.369376 -379.490732) (xy 351.436178 -379.400054) (xy 351.43948 -379.374146) (xy 351.4344 -379.3617)
			(xy 351.425867 -379.339188) (xy 351.413862 -379.292566) (xy 351.407828 -379.244802) (xy 351.407476 -379.22073)
			(xy 351.407962 -379.193479) (xy 351.415718 -379.139531) (xy 351.431073 -379.087236) (xy 351.453715 -379.037659)
			(xy 351.483181 -378.991809) (xy 351.518872 -378.950618) (xy 351.560063 -378.914927) (xy 351.605913 -378.885461)
			(xy 351.65549 -378.862819) (xy 351.707785 -378.847464) (xy 351.761733 -378.839708) (xy 351.816235 -378.839708)
			(xy 351.870183 -378.847464) (xy 351.922478 -378.862819) (xy 351.972055 -378.885461) (xy 352.017905 -378.914927)
			(xy 352.059096 -378.950618) (xy 352.094787 -378.991809) (xy 352.124253 -379.037659) (xy 352.146895 -379.087236)
			(xy 352.16225 -379.139531) (xy 352.170006 -379.193479) (xy 352.170492 -379.22073) (xy 352.169803 -379.253262)
			(xy 352.158692 -379.317371) (xy 352.148394 -379.348238) (xy 352.145346 -379.356874) (xy 352.1456 -379.374654)
			(xy 352.175064 -379.45314) (xy 352.186494 -379.466348) (xy 352.194622 -379.47092) (xy 352.22688 -379.490732)
			(xy 352.233271 -379.494791) (xy 352.247758 -379.499172) (xy 352.255328 -379.499368) (xy 352.53676 -379.499368)
			(xy 352.544314 -379.49909) (xy 352.558772 -379.494698) (xy 352.565208 -379.490732) (xy 352.597466 -379.47092)
			(xy 352.605594 -379.466348) (xy 352.617024 -379.45314) (xy 352.646488 -379.374654) (xy 352.646742 -379.356874)
			(xy 352.643694 -379.348238) (xy 352.633399 -379.317371) (xy 352.622295 -379.253261) (xy 352.621596 -379.22073)
			(xy 352.622082 -379.193479) (xy 352.629838 -379.139531) (xy 352.645193 -379.087236) (xy 352.667835 -379.037659)
			(xy 352.697301 -378.991809) (xy 352.732992 -378.950618) (xy 352.774183 -378.914927) (xy 352.820033 -378.885461)
			(xy 352.86961 -378.862819) (xy 352.921905 -378.847464) (xy 352.975853 -378.839708) (xy 353.030355 -378.839708)
			(xy 353.084303 -378.847464) (xy 353.136598 -378.862819) (xy 353.186175 -378.885461) (xy 353.232025 -378.914927)
			(xy 353.273216 -378.950618) (xy 353.308907 -378.991809) (xy 353.338373 -379.037659) (xy 353.361015 -379.087236)
			(xy 353.37637 -379.139531) (xy 353.384126 -379.193479) (xy 353.384612 -379.22073) (xy 353.384254 -379.244802)
			(xy 353.378215 -379.292564) (xy 353.366225 -379.33919) (xy 353.357688 -379.3617) (xy 353.352608 -379.374146)
			(xy 353.35591 -379.400054) (xy 353.422712 -379.490732) (xy 353.446334 -379.501654) (xy 353.459542 -379.500638)
			(xy 353.488244 -379.499622) (xy 353.515495 -379.500051) (xy 353.569443 -379.507813) (xy 353.621736 -379.523173)
			(xy 353.671312 -379.545819) (xy 353.71716 -379.575288) (xy 353.758348 -379.610983) (xy 353.794038 -379.652175)
			(xy 353.823502 -379.698027) (xy 353.846142 -379.747605) (xy 353.861496 -379.799901) (xy 353.869252 -379.853849)
			(xy 353.869252 -379.908349) (xy 365.073708 -379.908349) (xy 365.073708 -379.853851) (xy 365.081464 -379.799909)
			(xy 365.096817 -379.747619) (xy 365.119456 -379.698046) (xy 365.148919 -379.6522) (xy 365.184607 -379.611013)
			(xy 365.225793 -379.575324) (xy 365.271639 -379.54586) (xy 365.321211 -379.52322) (xy 365.373501 -379.507866)
			(xy 365.427443 -379.500109) (xy 365.454692 -379.499622) (xy 365.483394 -379.500638) (xy 365.496602 -379.501654)
			(xy 365.520224 -379.490732) (xy 365.587026 -379.400054) (xy 365.590328 -379.374146) (xy 365.585248 -379.3617)
			(xy 365.576713 -379.339189) (xy 365.564709 -379.292566) (xy 365.558676 -379.244802) (xy 365.558324 -379.22073)
			(xy 365.55881 -379.193479) (xy 365.566566 -379.139531) (xy 365.581921 -379.087236) (xy 365.604563 -379.037659)
			(xy 365.634029 -378.991809) (xy 365.66972 -378.950618) (xy 365.710911 -378.914927) (xy 365.756761 -378.885461)
			(xy 365.806338 -378.862819) (xy 365.858633 -378.847464) (xy 365.912581 -378.839708) (xy 365.967083 -378.839708)
			(xy 366.021031 -378.847464) (xy 366.073326 -378.862819) (xy 366.122903 -378.885461) (xy 366.168753 -378.914927)
			(xy 366.209944 -378.950618) (xy 366.245635 -378.991809) (xy 366.275101 -379.037659) (xy 366.297743 -379.087236)
			(xy 366.313098 -379.139531) (xy 366.320854 -379.193479) (xy 366.32134 -379.22073) (xy 366.320649 -379.253262)
			(xy 366.309539 -379.317371) (xy 366.299242 -379.348238) (xy 366.296194 -379.356874) (xy 366.296448 -379.374654)
			(xy 366.325912 -379.45314) (xy 366.337342 -379.466348) (xy 366.34547 -379.47092) (xy 366.377728 -379.490732)
			(xy 366.38413 -379.494771) (xy 366.398609 -379.499164) (xy 366.406176 -379.499368) (xy 366.687608 -379.499368)
			(xy 366.69516 -379.499068) (xy 366.709618 -379.494691) (xy 366.716056 -379.490732) (xy 366.748314 -379.47092)
			(xy 366.756442 -379.466348) (xy 366.767872 -379.45314) (xy 366.797336 -379.374654) (xy 366.79759 -379.356874)
			(xy 366.794542 -379.348238) (xy 366.784249 -379.31737) (xy 366.773144 -379.253261) (xy 366.772444 -379.22073)
			(xy 366.77293 -379.193479) (xy 366.780686 -379.139531) (xy 366.796041 -379.087236) (xy 366.818683 -379.037659)
			(xy 366.848149 -378.991809) (xy 366.88384 -378.950618) (xy 366.925031 -378.914927) (xy 366.970881 -378.885461)
			(xy 367.020458 -378.862819) (xy 367.072753 -378.847464) (xy 367.126701 -378.839708) (xy 367.181203 -378.839708)
			(xy 367.235151 -378.847464) (xy 367.287446 -378.862819) (xy 367.337023 -378.885461) (xy 367.382873 -378.914927)
			(xy 367.424064 -378.950618) (xy 367.459755 -378.991809) (xy 367.489221 -379.037659) (xy 367.511863 -379.087236)
			(xy 367.527218 -379.139531) (xy 367.534974 -379.193479) (xy 367.53546 -379.22073) (xy 367.535099 -379.244801)
			(xy 367.529061 -379.292564) (xy 367.517072 -379.33919) (xy 367.508536 -379.3617) (xy 367.503456 -379.374146)
			(xy 367.506758 -379.400054) (xy 367.57356 -379.490732) (xy 367.597182 -379.501654) (xy 367.61039 -379.500638)
			(xy 367.639092 -379.499622) (xy 367.666347 -379.500024) (xy 367.720303 -379.507781) (xy 367.772606 -379.523138)
			(xy 367.822192 -379.545781) (xy 367.868049 -379.575252) (xy 367.909246 -379.610948) (xy 367.944944 -379.652144)
			(xy 367.974415 -379.698001) (xy 367.99706 -379.747586) (xy 368.012417 -379.799889) (xy 368.020175 -379.853845)
			(xy 368.020175 -379.908349) (xy 371.880908 -379.908349) (xy 371.880908 -379.853851) (xy 371.888664 -379.799909)
			(xy 371.904017 -379.747619) (xy 371.926656 -379.698046) (xy 371.956119 -379.6522) (xy 371.991807 -379.611013)
			(xy 372.032993 -379.575324) (xy 372.078839 -379.54586) (xy 372.128411 -379.52322) (xy 372.180701 -379.507866)
			(xy 372.234643 -379.500109) (xy 372.261892 -379.499622) (xy 372.290594 -379.500638) (xy 372.303802 -379.501654)
			(xy 372.327424 -379.490732) (xy 372.394226 -379.400054) (xy 372.397528 -379.374146) (xy 372.392448 -379.3617)
			(xy 372.383913 -379.339189) (xy 372.371909 -379.292566) (xy 372.365876 -379.244802) (xy 372.365524 -379.22073)
			(xy 372.36601 -379.193479) (xy 372.373766 -379.139531) (xy 372.389121 -379.087236) (xy 372.411763 -379.037659)
			(xy 372.441229 -378.991809) (xy 372.47692 -378.950618) (xy 372.518111 -378.914927) (xy 372.563961 -378.885461)
			(xy 372.613538 -378.862819) (xy 372.665833 -378.847464) (xy 372.719781 -378.839708) (xy 372.774283 -378.839708)
			(xy 372.828231 -378.847464) (xy 372.880526 -378.862819) (xy 372.930103 -378.885461) (xy 372.975953 -378.914927)
			(xy 373.017144 -378.950618) (xy 373.052835 -378.991809) (xy 373.082301 -379.037659) (xy 373.104943 -379.087236)
			(xy 373.120298 -379.139531) (xy 373.128054 -379.193479) (xy 373.12854 -379.22073) (xy 373.127849 -379.253262)
			(xy 373.116739 -379.317371) (xy 373.106442 -379.348238) (xy 373.103394 -379.356874) (xy 373.103648 -379.374654)
			(xy 373.133112 -379.45314) (xy 373.144542 -379.466348) (xy 373.15267 -379.47092) (xy 373.184928 -379.490732)
			(xy 373.19133 -379.494771) (xy 373.205809 -379.499164) (xy 373.213376 -379.499368) (xy 373.494808 -379.499368)
			(xy 373.50236 -379.499068) (xy 373.516818 -379.494691) (xy 373.523256 -379.490732) (xy 373.555514 -379.47092)
			(xy 373.563642 -379.466348) (xy 373.575072 -379.45314) (xy 373.604536 -379.374654) (xy 373.60479 -379.356874)
			(xy 373.601742 -379.348238) (xy 373.591449 -379.31737) (xy 373.580344 -379.253261) (xy 373.579644 -379.22073)
			(xy 373.58013 -379.193479) (xy 373.587886 -379.139531) (xy 373.603241 -379.087236) (xy 373.625883 -379.037659)
			(xy 373.655349 -378.991809) (xy 373.69104 -378.950618) (xy 373.732231 -378.914927) (xy 373.778081 -378.885461)
			(xy 373.827658 -378.862819) (xy 373.879953 -378.847464) (xy 373.933901 -378.839708) (xy 373.988403 -378.839708)
			(xy 374.042351 -378.847464) (xy 374.094646 -378.862819) (xy 374.144223 -378.885461) (xy 374.190073 -378.914927)
			(xy 374.231264 -378.950618) (xy 374.266955 -378.991809) (xy 374.296421 -379.037659) (xy 374.319063 -379.087236)
			(xy 374.334418 -379.139531) (xy 374.342174 -379.193479) (xy 374.34266 -379.22073) (xy 374.342299 -379.244801)
			(xy 374.336261 -379.292564) (xy 374.324272 -379.33919) (xy 374.315736 -379.3617) (xy 374.310656 -379.374146)
			(xy 374.313958 -379.400054) (xy 374.38076 -379.490732) (xy 374.404382 -379.501654) (xy 374.41759 -379.500638)
			(xy 374.446292 -379.499622) (xy 374.473547 -379.500024) (xy 374.527503 -379.507781) (xy 374.579806 -379.523138)
			(xy 374.629392 -379.545781) (xy 374.675249 -379.575252) (xy 374.716446 -379.610948) (xy 374.752144 -379.652144)
			(xy 374.781615 -379.698001) (xy 374.80426 -379.747586) (xy 374.819617 -379.799889) (xy 374.827375 -379.853845)
			(xy 374.827375 -379.908349) (xy 378.688108 -379.908349) (xy 378.688108 -379.853851) (xy 378.695864 -379.799909)
			(xy 378.711217 -379.747619) (xy 378.733856 -379.698046) (xy 378.763319 -379.6522) (xy 378.799007 -379.611013)
			(xy 378.840193 -379.575324) (xy 378.886039 -379.54586) (xy 378.935611 -379.52322) (xy 378.987901 -379.507866)
			(xy 379.041843 -379.500109) (xy 379.069092 -379.499622) (xy 379.097794 -379.500638) (xy 379.111002 -379.501654)
			(xy 379.134624 -379.490732) (xy 379.201426 -379.400054) (xy 379.204728 -379.374146) (xy 379.199648 -379.3617)
			(xy 379.191113 -379.339189) (xy 379.179109 -379.292566) (xy 379.173076 -379.244802) (xy 379.172724 -379.22073)
			(xy 379.17321 -379.193479) (xy 379.180966 -379.139531) (xy 379.196321 -379.087236) (xy 379.218963 -379.037659)
			(xy 379.248429 -378.991809) (xy 379.28412 -378.950618) (xy 379.325311 -378.914927) (xy 379.371161 -378.885461)
			(xy 379.420738 -378.862819) (xy 379.473033 -378.847464) (xy 379.526981 -378.839708) (xy 379.581483 -378.839708)
			(xy 379.635431 -378.847464) (xy 379.687726 -378.862819) (xy 379.737303 -378.885461) (xy 379.783153 -378.914927)
			(xy 379.824344 -378.950618) (xy 379.860035 -378.991809) (xy 379.889501 -379.037659) (xy 379.912143 -379.087236)
			(xy 379.927498 -379.139531) (xy 379.935254 -379.193479) (xy 379.93574 -379.22073) (xy 379.935049 -379.253262)
			(xy 379.923939 -379.317371) (xy 379.913642 -379.348238) (xy 379.910594 -379.356874) (xy 379.910848 -379.374654)
			(xy 379.940312 -379.45314) (xy 379.951742 -379.466348) (xy 379.95987 -379.47092) (xy 379.992128 -379.490732)
			(xy 379.99853 -379.494771) (xy 380.013009 -379.499164) (xy 380.020576 -379.499368) (xy 380.302008 -379.499368)
			(xy 380.30956 -379.499068) (xy 380.324018 -379.494691) (xy 380.330456 -379.490732) (xy 380.362714 -379.47092)
			(xy 380.370842 -379.466348) (xy 380.382272 -379.45314) (xy 380.411736 -379.374654) (xy 380.41199 -379.356874)
			(xy 380.408942 -379.348238) (xy 380.398649 -379.31737) (xy 380.387544 -379.253261) (xy 380.386844 -379.22073)
			(xy 380.38733 -379.193479) (xy 380.395086 -379.139531) (xy 380.410441 -379.087236) (xy 380.433083 -379.037659)
			(xy 380.462549 -378.991809) (xy 380.49824 -378.950618) (xy 380.539431 -378.914927) (xy 380.585281 -378.885461)
			(xy 380.634858 -378.862819) (xy 380.687153 -378.847464) (xy 380.741101 -378.839708) (xy 380.795603 -378.839708)
			(xy 380.849551 -378.847464) (xy 380.901846 -378.862819) (xy 380.951423 -378.885461) (xy 380.997273 -378.914927)
			(xy 381.038464 -378.950618) (xy 381.074155 -378.991809) (xy 381.103621 -379.037659) (xy 381.126263 -379.087236)
			(xy 381.141618 -379.139531) (xy 381.149374 -379.193479) (xy 381.14986 -379.22073) (xy 381.149499 -379.244801)
			(xy 381.143461 -379.292564) (xy 381.131472 -379.33919) (xy 381.122936 -379.3617) (xy 381.117856 -379.374146)
			(xy 381.121158 -379.400054) (xy 381.18796 -379.490732) (xy 381.211582 -379.501654) (xy 381.22479 -379.500638)
			(xy 381.253492 -379.499622) (xy 381.280747 -379.500024) (xy 381.334703 -379.507781) (xy 381.387006 -379.523138)
			(xy 381.436592 -379.545781) (xy 381.482449 -379.575252) (xy 381.523646 -379.610948) (xy 381.559344 -379.652144)
			(xy 381.588815 -379.698001) (xy 381.61146 -379.747586) (xy 381.626817 -379.799889) (xy 381.634575 -379.853845)
			(xy 381.634575 -379.908349) (xy 385.495308 -379.908349) (xy 385.495308 -379.853851) (xy 385.503064 -379.799909)
			(xy 385.518417 -379.747619) (xy 385.541056 -379.698046) (xy 385.570519 -379.6522) (xy 385.606207 -379.611013)
			(xy 385.647393 -379.575324) (xy 385.693239 -379.54586) (xy 385.742811 -379.52322) (xy 385.795101 -379.507866)
			(xy 385.849043 -379.500109) (xy 385.876292 -379.499622) (xy 385.904994 -379.500638) (xy 385.918202 -379.501654)
			(xy 385.941824 -379.490732) (xy 386.008626 -379.400054) (xy 386.011928 -379.374146) (xy 386.006848 -379.3617)
			(xy 385.998313 -379.339189) (xy 385.986309 -379.292566) (xy 385.980276 -379.244802) (xy 385.979924 -379.22073)
			(xy 385.98041 -379.193479) (xy 385.988166 -379.139531) (xy 386.003521 -379.087236) (xy 386.026163 -379.037659)
			(xy 386.055629 -378.991809) (xy 386.09132 -378.950618) (xy 386.132511 -378.914927) (xy 386.178361 -378.885461)
			(xy 386.227938 -378.862819) (xy 386.280233 -378.847464) (xy 386.334181 -378.839708) (xy 386.388683 -378.839708)
			(xy 386.442631 -378.847464) (xy 386.494926 -378.862819) (xy 386.544503 -378.885461) (xy 386.590353 -378.914927)
			(xy 386.631544 -378.950618) (xy 386.667235 -378.991809) (xy 386.696701 -379.037659) (xy 386.719343 -379.087236)
			(xy 386.734698 -379.139531) (xy 386.742454 -379.193479) (xy 386.74294 -379.22073) (xy 386.742249 -379.253262)
			(xy 386.731139 -379.317371) (xy 386.720842 -379.348238) (xy 386.717794 -379.356874) (xy 386.718048 -379.374654)
			(xy 386.747512 -379.45314) (xy 386.758942 -379.466348) (xy 386.76707 -379.47092) (xy 386.799328 -379.490732)
			(xy 386.80573 -379.494771) (xy 386.820209 -379.499164) (xy 386.827776 -379.499368) (xy 387.109208 -379.499368)
			(xy 387.11676 -379.499068) (xy 387.131218 -379.494691) (xy 387.137656 -379.490732) (xy 387.169914 -379.47092)
			(xy 387.178042 -379.466348) (xy 387.189472 -379.45314) (xy 387.218936 -379.374654) (xy 387.21919 -379.356874)
			(xy 387.216142 -379.348238) (xy 387.205849 -379.31737) (xy 387.194744 -379.253261) (xy 387.194044 -379.22073)
			(xy 387.19453 -379.193479) (xy 387.202286 -379.139531) (xy 387.217641 -379.087236) (xy 387.240283 -379.037659)
			(xy 387.269749 -378.991809) (xy 387.30544 -378.950618) (xy 387.346631 -378.914927) (xy 387.392481 -378.885461)
			(xy 387.442058 -378.862819) (xy 387.494353 -378.847464) (xy 387.548301 -378.839708) (xy 387.602803 -378.839708)
			(xy 387.656751 -378.847464) (xy 387.709046 -378.862819) (xy 387.758623 -378.885461) (xy 387.804473 -378.914927)
			(xy 387.845664 -378.950618) (xy 387.881355 -378.991809) (xy 387.910821 -379.037659) (xy 387.933463 -379.087236)
			(xy 387.948818 -379.139531) (xy 387.956574 -379.193479) (xy 387.95706 -379.22073) (xy 387.956699 -379.244801)
			(xy 387.950661 -379.292564) (xy 387.938672 -379.33919) (xy 387.930136 -379.3617) (xy 387.925056 -379.374146)
			(xy 387.928358 -379.400054) (xy 387.99516 -379.490732) (xy 388.018782 -379.501654) (xy 388.03199 -379.500638)
			(xy 388.060692 -379.499622) (xy 388.087947 -379.500024) (xy 388.141903 -379.507781) (xy 388.194206 -379.523138)
			(xy 388.243792 -379.545781) (xy 388.289649 -379.575252) (xy 388.330846 -379.610948) (xy 388.366544 -379.652144)
			(xy 388.396015 -379.698001) (xy 388.41866 -379.747586) (xy 388.434017 -379.799889) (xy 388.441775 -379.853845)
			(xy 388.441775 -379.908353) (xy 397.601385 -379.908353) (xy 397.601385 -379.853847) (xy 397.609143 -379.799897)
			(xy 397.6245 -379.7476) (xy 397.647143 -379.698021) (xy 397.676613 -379.65217) (xy 397.712308 -379.61098)
			(xy 397.753502 -379.575289) (xy 397.799357 -379.545824) (xy 397.848938 -379.523186) (xy 397.901236 -379.507834)
			(xy 397.955187 -379.500083) (xy 397.98244 -379.499622) (xy 398.011142 -379.500638) (xy 398.02435 -379.501654)
			(xy 398.047972 -379.490732) (xy 398.114774 -379.400054) (xy 398.118076 -379.374146) (xy 398.112996 -379.3617)
			(xy 398.104463 -379.339188) (xy 398.092458 -379.292566) (xy 398.086424 -379.244802) (xy 398.086072 -379.22073)
			(xy 398.086558 -379.193479) (xy 398.094314 -379.139531) (xy 398.109669 -379.087236) (xy 398.132311 -379.037659)
			(xy 398.161777 -378.991809) (xy 398.197468 -378.950618) (xy 398.238659 -378.914927) (xy 398.284509 -378.885461)
			(xy 398.334086 -378.862819) (xy 398.386381 -378.847464) (xy 398.440329 -378.839708) (xy 398.494831 -378.839708)
			(xy 398.548779 -378.847464) (xy 398.601074 -378.862819) (xy 398.650651 -378.885461) (xy 398.696501 -378.914927)
			(xy 398.737692 -378.950618) (xy 398.773383 -378.991809) (xy 398.802849 -379.037659) (xy 398.825491 -379.087236)
			(xy 398.840846 -379.139531) (xy 398.848602 -379.193479) (xy 398.849088 -379.22073) (xy 398.8484 -379.253262)
			(xy 398.837288 -379.317371) (xy 398.82699 -379.348238) (xy 398.823942 -379.356874) (xy 398.824196 -379.374654)
			(xy 398.85366 -379.45314) (xy 398.86509 -379.466348) (xy 398.873218 -379.47092) (xy 398.905476 -379.490732)
			(xy 398.911868 -379.49479) (xy 398.926355 -379.499171) (xy 398.933924 -379.499368) (xy 399.215356 -379.499368)
			(xy 399.22291 -379.499088) (xy 399.237368 -379.494698) (xy 399.243804 -379.490732) (xy 399.276062 -379.47092)
			(xy 399.28419 -379.466348) (xy 399.29562 -379.45314) (xy 399.325084 -379.374654) (xy 399.325338 -379.356874)
			(xy 399.32229 -379.348238) (xy 399.311995 -379.317371) (xy 399.300891 -379.253261) (xy 399.300192 -379.22073)
			(xy 399.300678 -379.193479) (xy 399.308434 -379.139531) (xy 399.323789 -379.087236) (xy 399.346431 -379.037659)
			(xy 399.375897 -378.991809) (xy 399.411588 -378.950618) (xy 399.452779 -378.914927) (xy 399.498629 -378.885461)
			(xy 399.548206 -378.862819) (xy 399.600501 -378.847464) (xy 399.654449 -378.839708) (xy 399.708951 -378.839708)
			(xy 399.762899 -378.847464) (xy 399.815194 -378.862819) (xy 399.864771 -378.885461) (xy 399.910621 -378.914927)
			(xy 399.951812 -378.950618) (xy 399.987503 -378.991809) (xy 400.016969 -379.037659) (xy 400.039611 -379.087236)
			(xy 400.054966 -379.139531) (xy 400.062722 -379.193479) (xy 400.063208 -379.22073) (xy 400.06285 -379.244802)
			(xy 400.056812 -379.292564) (xy 400.044821 -379.33919) (xy 400.036284 -379.3617) (xy 400.031204 -379.374146)
			(xy 400.034506 -379.400054) (xy 400.101308 -379.490732) (xy 400.12493 -379.501654) (xy 400.138138 -379.500638)
			(xy 400.16684 -379.499622) (xy 400.194092 -379.500051) (xy 400.248039 -379.507812) (xy 400.300333 -379.523172)
			(xy 400.349909 -379.545817) (xy 400.395758 -379.575287) (xy 400.436947 -379.610981) (xy 400.472637 -379.652174)
			(xy 400.502102 -379.698026) (xy 400.524742 -379.747604) (xy 400.540096 -379.7999) (xy 400.547852 -379.853848)
			(xy 400.547852 -379.908352) (xy 400.547852 -379.908353) (xy 404.408585 -379.908353) (xy 404.408585 -379.853847)
			(xy 404.416343 -379.799897) (xy 404.4317 -379.7476) (xy 404.454343 -379.698021) (xy 404.483813 -379.65217)
			(xy 404.519508 -379.61098) (xy 404.560702 -379.575289) (xy 404.606557 -379.545824) (xy 404.656138 -379.523186)
			(xy 404.708436 -379.507834) (xy 404.762387 -379.500083) (xy 404.78964 -379.499622) (xy 404.818342 -379.500638)
			(xy 404.83155 -379.501654) (xy 404.855172 -379.490732) (xy 404.921974 -379.400054) (xy 404.925276 -379.374146)
			(xy 404.920196 -379.3617) (xy 404.911663 -379.339188) (xy 404.899658 -379.292566) (xy 404.893624 -379.244802)
			(xy 404.893272 -379.22073) (xy 404.893758 -379.193479) (xy 404.901514 -379.139531) (xy 404.916869 -379.087236)
			(xy 404.939511 -379.037659) (xy 404.968977 -378.991809) (xy 405.004668 -378.950618) (xy 405.045859 -378.914927)
			(xy 405.091709 -378.885461) (xy 405.141286 -378.862819) (xy 405.193581 -378.847464) (xy 405.247529 -378.839708)
			(xy 405.302031 -378.839708) (xy 405.355979 -378.847464) (xy 405.408274 -378.862819) (xy 405.457851 -378.885461)
			(xy 405.503701 -378.914927) (xy 405.544892 -378.950618) (xy 405.580583 -378.991809) (xy 405.610049 -379.037659)
			(xy 405.632691 -379.087236) (xy 405.648046 -379.139531) (xy 405.655802 -379.193479) (xy 405.656288 -379.22073)
			(xy 405.6556 -379.253262) (xy 405.644488 -379.317371) (xy 405.63419 -379.348238) (xy 405.631142 -379.356874)
			(xy 405.631396 -379.374654) (xy 405.66086 -379.45314) (xy 405.67229 -379.466348) (xy 405.680418 -379.47092)
			(xy 405.712676 -379.490732) (xy 405.719068 -379.49479) (xy 405.733555 -379.499171) (xy 405.741124 -379.499368)
			(xy 406.022556 -379.499368) (xy 406.03011 -379.499088) (xy 406.044568 -379.494698) (xy 406.051004 -379.490732)
			(xy 406.083262 -379.47092) (xy 406.09139 -379.466348) (xy 406.10282 -379.45314) (xy 406.132284 -379.374654)
			(xy 406.132538 -379.356874) (xy 406.12949 -379.348238) (xy 406.119195 -379.317371) (xy 406.108091 -379.253261)
			(xy 406.107392 -379.22073) (xy 406.107878 -379.193479) (xy 406.115634 -379.139531) (xy 406.130989 -379.087236)
			(xy 406.153631 -379.037659) (xy 406.183097 -378.991809) (xy 406.218788 -378.950618) (xy 406.259979 -378.914927)
			(xy 406.305829 -378.885461) (xy 406.355406 -378.862819) (xy 406.407701 -378.847464) (xy 406.461649 -378.839708)
			(xy 406.516151 -378.839708) (xy 406.570099 -378.847464) (xy 406.622394 -378.862819) (xy 406.671971 -378.885461)
			(xy 406.717821 -378.914927) (xy 406.759012 -378.950618) (xy 406.794703 -378.991809) (xy 406.824169 -379.037659)
			(xy 406.846811 -379.087236) (xy 406.862166 -379.139531) (xy 406.869922 -379.193479) (xy 406.870408 -379.22073)
			(xy 406.87005 -379.244802) (xy 406.864012 -379.292564) (xy 406.852021 -379.33919) (xy 406.843484 -379.3617)
			(xy 406.838404 -379.374146) (xy 406.841706 -379.400054) (xy 406.908508 -379.490732) (xy 406.93213 -379.501654)
			(xy 406.945338 -379.500638) (xy 406.97404 -379.499622) (xy 407.001292 -379.500051) (xy 407.055239 -379.507812)
			(xy 407.107533 -379.523172) (xy 407.157109 -379.545817) (xy 407.202958 -379.575287) (xy 407.244147 -379.610981)
			(xy 407.279837 -379.652174) (xy 407.309302 -379.698026) (xy 407.331942 -379.747604) (xy 407.347296 -379.7999)
			(xy 407.355052 -379.853848) (xy 407.355052 -379.908352) (xy 407.355052 -379.908353) (xy 411.215785 -379.908353)
			(xy 411.215785 -379.853847) (xy 411.223543 -379.799897) (xy 411.2389 -379.7476) (xy 411.261543 -379.698021)
			(xy 411.291013 -379.65217) (xy 411.326708 -379.61098) (xy 411.367902 -379.575289) (xy 411.413757 -379.545824)
			(xy 411.463338 -379.523186) (xy 411.515636 -379.507834) (xy 411.569587 -379.500083) (xy 411.59684 -379.499622)
			(xy 411.625542 -379.500638) (xy 411.63875 -379.501654) (xy 411.662372 -379.490732) (xy 411.729174 -379.400054)
			(xy 411.732476 -379.374146) (xy 411.727396 -379.3617) (xy 411.718863 -379.339188) (xy 411.706858 -379.292566)
			(xy 411.700824 -379.244802) (xy 411.700472 -379.22073) (xy 411.700958 -379.193479) (xy 411.708714 -379.139531)
			(xy 411.724069 -379.087236) (xy 411.746711 -379.037659) (xy 411.776177 -378.991809) (xy 411.811868 -378.950618)
			(xy 411.853059 -378.914927) (xy 411.898909 -378.885461) (xy 411.948486 -378.862819) (xy 412.000781 -378.847464)
			(xy 412.054729 -378.839708) (xy 412.109231 -378.839708) (xy 412.163179 -378.847464) (xy 412.215474 -378.862819)
			(xy 412.265051 -378.885461) (xy 412.310901 -378.914927) (xy 412.352092 -378.950618) (xy 412.387783 -378.991809)
			(xy 412.417249 -379.037659) (xy 412.439891 -379.087236) (xy 412.455246 -379.139531) (xy 412.463002 -379.193479)
			(xy 412.463488 -379.22073) (xy 412.4628 -379.253262) (xy 412.451688 -379.317371) (xy 412.44139 -379.348238)
			(xy 412.438342 -379.356874) (xy 412.438596 -379.374654) (xy 412.46806 -379.45314) (xy 412.47949 -379.466348)
			(xy 412.487618 -379.47092) (xy 412.519876 -379.490732) (xy 412.526268 -379.49479) (xy 412.540755 -379.499171)
			(xy 412.548324 -379.499368) (xy 412.829756 -379.499368) (xy 412.83731 -379.499088) (xy 412.851768 -379.494698)
			(xy 412.858204 -379.490732) (xy 412.890462 -379.47092) (xy 412.89859 -379.466348) (xy 412.91002 -379.45314)
			(xy 412.939484 -379.374654) (xy 412.939738 -379.356874) (xy 412.93669 -379.348238) (xy 412.926395 -379.317371)
			(xy 412.915291 -379.253261) (xy 412.914592 -379.22073) (xy 412.915078 -379.193479) (xy 412.922834 -379.139531)
			(xy 412.938189 -379.087236) (xy 412.960831 -379.037659) (xy 412.990297 -378.991809) (xy 413.025988 -378.950618)
			(xy 413.067179 -378.914927) (xy 413.113029 -378.885461) (xy 413.162606 -378.862819) (xy 413.214901 -378.847464)
			(xy 413.268849 -378.839708) (xy 413.323351 -378.839708) (xy 413.377299 -378.847464) (xy 413.429594 -378.862819)
			(xy 413.479171 -378.885461) (xy 413.525021 -378.914927) (xy 413.566212 -378.950618) (xy 413.601903 -378.991809)
			(xy 413.631369 -379.037659) (xy 413.654011 -379.087236) (xy 413.669366 -379.139531) (xy 413.677122 -379.193479)
			(xy 413.677608 -379.22073) (xy 413.67725 -379.244802) (xy 413.671212 -379.292564) (xy 413.659221 -379.33919)
			(xy 413.650684 -379.3617) (xy 413.645604 -379.374146) (xy 413.648906 -379.400054) (xy 413.715708 -379.490732)
			(xy 413.73933 -379.501654) (xy 413.752538 -379.500638) (xy 413.78124 -379.499622) (xy 413.808492 -379.500051)
			(xy 413.862439 -379.507812) (xy 413.914733 -379.523172) (xy 413.964309 -379.545817) (xy 414.010158 -379.575287)
			(xy 414.051347 -379.610981) (xy 414.087037 -379.652174) (xy 414.116502 -379.698026) (xy 414.139142 -379.747604)
			(xy 414.154496 -379.7999) (xy 414.162252 -379.853848) (xy 414.162252 -379.908352) (xy 414.162252 -379.908353)
			(xy 418.022985 -379.908353) (xy 418.022985 -379.853847) (xy 418.030743 -379.799897) (xy 418.0461 -379.7476)
			(xy 418.068743 -379.698021) (xy 418.098213 -379.65217) (xy 418.133908 -379.61098) (xy 418.175102 -379.575289)
			(xy 418.220957 -379.545824) (xy 418.270538 -379.523186) (xy 418.322836 -379.507834) (xy 418.376787 -379.500083)
			(xy 418.40404 -379.499622) (xy 418.432742 -379.500638) (xy 418.44595 -379.501654) (xy 418.469572 -379.490732)
			(xy 418.536374 -379.400054) (xy 418.539676 -379.374146) (xy 418.534596 -379.3617) (xy 418.526063 -379.339188)
			(xy 418.514058 -379.292566) (xy 418.508024 -379.244802) (xy 418.507672 -379.22073) (xy 418.508158 -379.193479)
			(xy 418.515914 -379.139531) (xy 418.531269 -379.087236) (xy 418.553911 -379.037659) (xy 418.583377 -378.991809)
			(xy 418.619068 -378.950618) (xy 418.660259 -378.914927) (xy 418.706109 -378.885461) (xy 418.755686 -378.862819)
			(xy 418.807981 -378.847464) (xy 418.861929 -378.839708) (xy 418.916431 -378.839708) (xy 418.970379 -378.847464)
			(xy 419.022674 -378.862819) (xy 419.072251 -378.885461) (xy 419.118101 -378.914927) (xy 419.159292 -378.950618)
			(xy 419.194983 -378.991809) (xy 419.224449 -379.037659) (xy 419.247091 -379.087236) (xy 419.262446 -379.139531)
			(xy 419.270202 -379.193479) (xy 419.270688 -379.22073) (xy 419.27 -379.253262) (xy 419.258888 -379.317371)
			(xy 419.24859 -379.348238) (xy 419.245542 -379.356874) (xy 419.245796 -379.374654) (xy 419.27526 -379.45314)
			(xy 419.28669 -379.466348) (xy 419.294818 -379.47092) (xy 419.327076 -379.490732) (xy 419.333468 -379.49479)
			(xy 419.347955 -379.499171) (xy 419.355524 -379.499368) (xy 419.636956 -379.499368) (xy 419.64451 -379.499088)
			(xy 419.658968 -379.494698) (xy 419.665404 -379.490732) (xy 419.697662 -379.47092) (xy 419.70579 -379.466348)
			(xy 419.71722 -379.45314) (xy 419.746684 -379.374654) (xy 419.746938 -379.356874) (xy 419.74389 -379.348238)
			(xy 419.733595 -379.317371) (xy 419.722491 -379.253261) (xy 419.721792 -379.22073) (xy 419.722278 -379.193479)
			(xy 419.730034 -379.139531) (xy 419.745389 -379.087236) (xy 419.768031 -379.037659) (xy 419.797497 -378.991809)
			(xy 419.833188 -378.950618) (xy 419.874379 -378.914927) (xy 419.920229 -378.885461) (xy 419.969806 -378.862819)
			(xy 420.022101 -378.847464) (xy 420.076049 -378.839708) (xy 420.130551 -378.839708) (xy 420.184499 -378.847464)
			(xy 420.236794 -378.862819) (xy 420.286371 -378.885461) (xy 420.332221 -378.914927) (xy 420.373412 -378.950618)
			(xy 420.409103 -378.991809) (xy 420.438569 -379.037659) (xy 420.461211 -379.087236) (xy 420.476566 -379.139531)
			(xy 420.484322 -379.193479) (xy 420.484808 -379.22073) (xy 420.48445 -379.244802) (xy 420.478412 -379.292564)
			(xy 420.466421 -379.33919) (xy 420.457884 -379.3617) (xy 420.452804 -379.374146) (xy 420.456106 -379.400054)
			(xy 420.522908 -379.490732) (xy 420.54653 -379.501654) (xy 420.559738 -379.500638) (xy 420.58844 -379.499622)
			(xy 420.615692 -379.500051) (xy 420.669639 -379.507812) (xy 420.721933 -379.523172) (xy 420.771509 -379.545817)
			(xy 420.817358 -379.575287) (xy 420.858547 -379.610981) (xy 420.894237 -379.652174) (xy 420.923702 -379.698026)
			(xy 420.946342 -379.747604) (xy 420.961696 -379.7999) (xy 420.969452 -379.853848) (xy 420.969452 -379.908352)
			(xy 420.961696 -379.9623) (xy 420.946342 -380.014596) (xy 420.923702 -380.064174) (xy 420.894237 -380.110026)
			(xy 420.858547 -380.151219) (xy 420.817358 -380.186913) (xy 420.771509 -380.216383) (xy 420.721933 -380.239028)
			(xy 420.669639 -380.254388) (xy 420.615692 -380.262149) (xy 420.58844 -380.262638) (xy 420.559738 -380.261622)
			(xy 420.54653 -380.260606) (xy 420.522908 -380.271528) (xy 420.456106 -380.362206) (xy 420.452804 -380.388114)
			(xy 420.457884 -380.40056) (xy 420.466433 -380.423066) (xy 420.478433 -380.469691) (xy 420.48446 -380.517457)
			(xy 420.484808 -380.54153) (xy 420.484322 -380.568781) (xy 420.476566 -380.622729) (xy 420.461211 -380.675024)
			(xy 420.438569 -380.724601) (xy 420.409103 -380.770451) (xy 420.373412 -380.811642) (xy 420.332221 -380.847333)
			(xy 420.286371 -380.876799) (xy 420.236794 -380.899441) (xy 420.184499 -380.914796) (xy 420.130551 -380.922552)
			(xy 420.076049 -380.922552) (xy 420.022101 -380.914796) (xy 419.969806 -380.899441) (xy 419.920229 -380.876799)
			(xy 419.874379 -380.847333) (xy 419.833188 -380.811642) (xy 419.797497 -380.770451) (xy 419.768031 -380.724601)
			(xy 419.745389 -380.675024) (xy 419.730034 -380.622729) (xy 419.722278 -380.568781) (xy 419.721792 -380.54153)
			(xy 419.722471 -380.508998) (xy 419.733589 -380.444888) (xy 419.74389 -380.414022) (xy 419.746938 -380.405386)
			(xy 419.746684 -380.387606) (xy 419.71722 -380.30912) (xy 419.70579 -380.295912) (xy 419.697662 -380.29134)
			(xy 419.665404 -380.271528) (xy 419.658992 -380.267506) (xy 419.644521 -380.263102) (xy 419.636956 -380.262892)
			(xy 419.355524 -380.262892) (xy 419.347968 -380.263155) (xy 419.33351 -380.267556) (xy 419.327076 -380.271528)
			(xy 419.294818 -380.29134) (xy 419.28669 -380.295912) (xy 419.27526 -380.30912) (xy 419.245796 -380.387606)
			(xy 419.245542 -380.405386) (xy 419.24859 -380.414022) (xy 419.258874 -380.444892) (xy 419.269985 -380.508999)
			(xy 419.270688 -380.54153) (xy 419.270202 -380.568781) (xy 419.262446 -380.622729) (xy 419.247091 -380.675024)
			(xy 419.224449 -380.724601) (xy 419.194983 -380.770451) (xy 419.159292 -380.811642) (xy 419.118101 -380.847333)
			(xy 419.072251 -380.876799) (xy 419.022674 -380.899441) (xy 418.970379 -380.914796) (xy 418.916431 -380.922552)
			(xy 418.861929 -380.922552) (xy 418.807981 -380.914796) (xy 418.755686 -380.899441) (xy 418.706109 -380.876799)
			(xy 418.660259 -380.847333) (xy 418.619068 -380.811642) (xy 418.583377 -380.770451) (xy 418.553911 -380.724601)
			(xy 418.531269 -380.675024) (xy 418.515914 -380.622729) (xy 418.508158 -380.568781) (xy 418.507672 -380.54153)
			(xy 418.508019 -380.517458) (xy 418.514062 -380.469695) (xy 418.526057 -380.423069) (xy 418.534596 -380.40056)
			(xy 418.539676 -380.388114) (xy 418.536374 -380.362206) (xy 418.469572 -380.271528) (xy 418.44595 -380.260606)
			(xy 418.432742 -380.261622) (xy 418.40404 -380.262638) (xy 418.376787 -380.262117) (xy 418.322836 -380.254366)
			(xy 418.270538 -380.239014) (xy 418.220957 -380.216376) (xy 418.175102 -380.186911) (xy 418.133908 -380.15122)
			(xy 418.098213 -380.11003) (xy 418.068743 -380.064179) (xy 418.0461 -380.0146) (xy 418.030743 -379.962303)
			(xy 418.022985 -379.908353) (xy 414.162252 -379.908353) (xy 414.154496 -379.9623) (xy 414.139142 -380.014596)
			(xy 414.116502 -380.064174) (xy 414.087037 -380.110026) (xy 414.051347 -380.151219) (xy 414.010158 -380.186913)
			(xy 413.964309 -380.216383) (xy 413.914733 -380.239028) (xy 413.862439 -380.254388) (xy 413.808492 -380.262149)
			(xy 413.78124 -380.262638) (xy 413.752538 -380.261622) (xy 413.73933 -380.260606) (xy 413.715708 -380.271528)
			(xy 413.648906 -380.362206) (xy 413.645604 -380.388114) (xy 413.650684 -380.40056) (xy 413.659233 -380.423066)
			(xy 413.671233 -380.469691) (xy 413.67726 -380.517457) (xy 413.677608 -380.54153) (xy 413.677122 -380.568781)
			(xy 413.669366 -380.622729) (xy 413.654011 -380.675024) (xy 413.631369 -380.724601) (xy 413.601903 -380.770451)
			(xy 413.566212 -380.811642) (xy 413.525021 -380.847333) (xy 413.479171 -380.876799) (xy 413.429594 -380.899441)
			(xy 413.377299 -380.914796) (xy 413.323351 -380.922552) (xy 413.268849 -380.922552) (xy 413.214901 -380.914796)
			(xy 413.162606 -380.899441) (xy 413.113029 -380.876799) (xy 413.067179 -380.847333) (xy 413.025988 -380.811642)
			(xy 412.990297 -380.770451) (xy 412.960831 -380.724601) (xy 412.938189 -380.675024) (xy 412.922834 -380.622729)
			(xy 412.915078 -380.568781) (xy 412.914592 -380.54153) (xy 412.915271 -380.508998) (xy 412.926389 -380.444888)
			(xy 412.93669 -380.414022) (xy 412.939738 -380.405386) (xy 412.939484 -380.387606) (xy 412.91002 -380.30912)
			(xy 412.89859 -380.295912) (xy 412.890462 -380.29134) (xy 412.858204 -380.271528) (xy 412.851792 -380.267506)
			(xy 412.837321 -380.263102) (xy 412.829756 -380.262892) (xy 412.548324 -380.262892) (xy 412.540768 -380.263155)
			(xy 412.52631 -380.267556) (xy 412.519876 -380.271528) (xy 412.487618 -380.29134) (xy 412.47949 -380.295912)
			(xy 412.46806 -380.30912) (xy 412.438596 -380.387606) (xy 412.438342 -380.405386) (xy 412.44139 -380.414022)
			(xy 412.451674 -380.444892) (xy 412.462785 -380.508999) (xy 412.463488 -380.54153) (xy 412.463002 -380.568781)
			(xy 412.455246 -380.622729) (xy 412.439891 -380.675024) (xy 412.417249 -380.724601) (xy 412.387783 -380.770451)
			(xy 412.352092 -380.811642) (xy 412.310901 -380.847333) (xy 412.265051 -380.876799) (xy 412.215474 -380.899441)
			(xy 412.163179 -380.914796) (xy 412.109231 -380.922552) (xy 412.054729 -380.922552) (xy 412.000781 -380.914796)
			(xy 411.948486 -380.899441) (xy 411.898909 -380.876799) (xy 411.853059 -380.847333) (xy 411.811868 -380.811642)
			(xy 411.776177 -380.770451) (xy 411.746711 -380.724601) (xy 411.724069 -380.675024) (xy 411.708714 -380.622729)
			(xy 411.700958 -380.568781) (xy 411.700472 -380.54153) (xy 411.700819 -380.517458) (xy 411.706862 -380.469695)
			(xy 411.718857 -380.423069) (xy 411.727396 -380.40056) (xy 411.732476 -380.388114) (xy 411.729174 -380.362206)
			(xy 411.662372 -380.271528) (xy 411.63875 -380.260606) (xy 411.625542 -380.261622) (xy 411.59684 -380.262638)
			(xy 411.569587 -380.262117) (xy 411.515636 -380.254366) (xy 411.463338 -380.239014) (xy 411.413757 -380.216376)
			(xy 411.367902 -380.186911) (xy 411.326708 -380.15122) (xy 411.291013 -380.11003) (xy 411.261543 -380.064179)
			(xy 411.2389 -380.0146) (xy 411.223543 -379.962303) (xy 411.215785 -379.908353) (xy 407.355052 -379.908353)
			(xy 407.347296 -379.9623) (xy 407.331942 -380.014596) (xy 407.309302 -380.064174) (xy 407.279837 -380.110026)
			(xy 407.244147 -380.151219) (xy 407.202958 -380.186913) (xy 407.157109 -380.216383) (xy 407.107533 -380.239028)
			(xy 407.055239 -380.254388) (xy 407.001292 -380.262149) (xy 406.97404 -380.262638) (xy 406.945338 -380.261622)
			(xy 406.93213 -380.260606) (xy 406.908508 -380.271528) (xy 406.841706 -380.362206) (xy 406.838404 -380.388114)
			(xy 406.843484 -380.40056) (xy 406.852033 -380.423066) (xy 406.864033 -380.469691) (xy 406.87006 -380.517457)
			(xy 406.870408 -380.54153) (xy 406.869922 -380.568781) (xy 406.862166 -380.622729) (xy 406.846811 -380.675024)
			(xy 406.824169 -380.724601) (xy 406.794703 -380.770451) (xy 406.759012 -380.811642) (xy 406.717821 -380.847333)
			(xy 406.671971 -380.876799) (xy 406.622394 -380.899441) (xy 406.570099 -380.914796) (xy 406.516151 -380.922552)
			(xy 406.461649 -380.922552) (xy 406.407701 -380.914796) (xy 406.355406 -380.899441) (xy 406.305829 -380.876799)
			(xy 406.259979 -380.847333) (xy 406.218788 -380.811642) (xy 406.183097 -380.770451) (xy 406.153631 -380.724601)
			(xy 406.130989 -380.675024) (xy 406.115634 -380.622729) (xy 406.107878 -380.568781) (xy 406.107392 -380.54153)
			(xy 406.108071 -380.508998) (xy 406.119189 -380.444888) (xy 406.12949 -380.414022) (xy 406.132538 -380.405386)
			(xy 406.132284 -380.387606) (xy 406.10282 -380.30912) (xy 406.09139 -380.295912) (xy 406.083262 -380.29134)
			(xy 406.051004 -380.271528) (xy 406.044592 -380.267506) (xy 406.030121 -380.263102) (xy 406.022556 -380.262892)
			(xy 405.741124 -380.262892) (xy 405.733568 -380.263155) (xy 405.71911 -380.267556) (xy 405.712676 -380.271528)
			(xy 405.680418 -380.29134) (xy 405.67229 -380.295912) (xy 405.66086 -380.30912) (xy 405.631396 -380.387606)
			(xy 405.631142 -380.405386) (xy 405.63419 -380.414022) (xy 405.644474 -380.444892) (xy 405.655585 -380.508999)
			(xy 405.656288 -380.54153) (xy 405.655802 -380.568781) (xy 405.648046 -380.622729) (xy 405.632691 -380.675024)
			(xy 405.610049 -380.724601) (xy 405.580583 -380.770451) (xy 405.544892 -380.811642) (xy 405.503701 -380.847333)
			(xy 405.457851 -380.876799) (xy 405.408274 -380.899441) (xy 405.355979 -380.914796) (xy 405.302031 -380.922552)
			(xy 405.247529 -380.922552) (xy 405.193581 -380.914796) (xy 405.141286 -380.899441) (xy 405.091709 -380.876799)
			(xy 405.045859 -380.847333) (xy 405.004668 -380.811642) (xy 404.968977 -380.770451) (xy 404.939511 -380.724601)
			(xy 404.916869 -380.675024) (xy 404.901514 -380.622729) (xy 404.893758 -380.568781) (xy 404.893272 -380.54153)
			(xy 404.893619 -380.517458) (xy 404.899662 -380.469695) (xy 404.911657 -380.423069) (xy 404.920196 -380.40056)
			(xy 404.925276 -380.388114) (xy 404.921974 -380.362206) (xy 404.855172 -380.271528) (xy 404.83155 -380.260606)
			(xy 404.818342 -380.261622) (xy 404.78964 -380.262638) (xy 404.762387 -380.262117) (xy 404.708436 -380.254366)
			(xy 404.656138 -380.239014) (xy 404.606557 -380.216376) (xy 404.560702 -380.186911) (xy 404.519508 -380.15122)
			(xy 404.483813 -380.11003) (xy 404.454343 -380.064179) (xy 404.4317 -380.0146) (xy 404.416343 -379.962303)
			(xy 404.408585 -379.908353) (xy 400.547852 -379.908353) (xy 400.540096 -379.9623) (xy 400.524742 -380.014596)
			(xy 400.502102 -380.064174) (xy 400.472637 -380.110026) (xy 400.436947 -380.151219) (xy 400.395758 -380.186913)
			(xy 400.349909 -380.216383) (xy 400.300333 -380.239028) (xy 400.248039 -380.254388) (xy 400.194092 -380.262149)
			(xy 400.16684 -380.262638) (xy 400.138138 -380.261622) (xy 400.12493 -380.260606) (xy 400.101308 -380.271528)
			(xy 400.034506 -380.362206) (xy 400.031204 -380.388114) (xy 400.036284 -380.40056) (xy 400.044833 -380.423066)
			(xy 400.056833 -380.469691) (xy 400.06286 -380.517457) (xy 400.063208 -380.54153) (xy 400.062722 -380.568781)
			(xy 400.054966 -380.622729) (xy 400.039611 -380.675024) (xy 400.016969 -380.724601) (xy 399.987503 -380.770451)
			(xy 399.951812 -380.811642) (xy 399.910621 -380.847333) (xy 399.864771 -380.876799) (xy 399.815194 -380.899441)
			(xy 399.762899 -380.914796) (xy 399.708951 -380.922552) (xy 399.654449 -380.922552) (xy 399.600501 -380.914796)
			(xy 399.548206 -380.899441) (xy 399.498629 -380.876799) (xy 399.452779 -380.847333) (xy 399.411588 -380.811642)
			(xy 399.375897 -380.770451) (xy 399.346431 -380.724601) (xy 399.323789 -380.675024) (xy 399.308434 -380.622729)
			(xy 399.300678 -380.568781) (xy 399.300192 -380.54153) (xy 399.300871 -380.508998) (xy 399.311989 -380.444888)
			(xy 399.32229 -380.414022) (xy 399.325338 -380.405386) (xy 399.325084 -380.387606) (xy 399.29562 -380.30912)
			(xy 399.28419 -380.295912) (xy 399.276062 -380.29134) (xy 399.243804 -380.271528) (xy 399.237392 -380.267506)
			(xy 399.222921 -380.263102) (xy 399.215356 -380.262892) (xy 398.933924 -380.262892) (xy 398.926368 -380.263155)
			(xy 398.91191 -380.267556) (xy 398.905476 -380.271528) (xy 398.873218 -380.29134) (xy 398.86509 -380.295912)
			(xy 398.85366 -380.30912) (xy 398.824196 -380.387606) (xy 398.823942 -380.405386) (xy 398.82699 -380.414022)
			(xy 398.837274 -380.444892) (xy 398.848385 -380.508999) (xy 398.849088 -380.54153) (xy 398.848602 -380.568781)
			(xy 398.840846 -380.622729) (xy 398.825491 -380.675024) (xy 398.802849 -380.724601) (xy 398.773383 -380.770451)
			(xy 398.737692 -380.811642) (xy 398.696501 -380.847333) (xy 398.650651 -380.876799) (xy 398.601074 -380.899441)
			(xy 398.548779 -380.914796) (xy 398.494831 -380.922552) (xy 398.440329 -380.922552) (xy 398.386381 -380.914796)
			(xy 398.334086 -380.899441) (xy 398.284509 -380.876799) (xy 398.238659 -380.847333) (xy 398.197468 -380.811642)
			(xy 398.161777 -380.770451) (xy 398.132311 -380.724601) (xy 398.109669 -380.675024) (xy 398.094314 -380.622729)
			(xy 398.086558 -380.568781) (xy 398.086072 -380.54153) (xy 398.086419 -380.517458) (xy 398.092462 -380.469695)
			(xy 398.104457 -380.423069) (xy 398.112996 -380.40056) (xy 398.118076 -380.388114) (xy 398.114774 -380.362206)
			(xy 398.047972 -380.271528) (xy 398.02435 -380.260606) (xy 398.011142 -380.261622) (xy 397.98244 -380.262638)
			(xy 397.955187 -380.262117) (xy 397.901236 -380.254366) (xy 397.848938 -380.239014) (xy 397.799357 -380.216376)
			(xy 397.753502 -380.186911) (xy 397.712308 -380.15122) (xy 397.676613 -380.11003) (xy 397.647143 -380.064179)
			(xy 397.6245 -380.0146) (xy 397.609143 -379.962303) (xy 397.601385 -379.908353) (xy 388.441775 -379.908353)
			(xy 388.441775 -379.908355) (xy 388.434017 -379.962311) (xy 388.41866 -380.014614) (xy 388.396015 -380.064199)
			(xy 388.366544 -380.110056) (xy 388.330846 -380.151252) (xy 388.289649 -380.186948) (xy 388.243792 -380.216419)
			(xy 388.194206 -380.239062) (xy 388.141903 -380.254419) (xy 388.087947 -380.262176) (xy 388.060692 -380.262638)
			(xy 388.03199 -380.261622) (xy 388.018782 -380.260606) (xy 387.99516 -380.271528) (xy 387.928358 -380.362206)
			(xy 387.925056 -380.388114) (xy 387.930136 -380.40056) (xy 387.938688 -380.423065) (xy 387.950686 -380.469691)
			(xy 387.956712 -380.517457) (xy 387.95706 -380.54153) (xy 387.956574 -380.568781) (xy 387.948818 -380.622729)
			(xy 387.933463 -380.675024) (xy 387.910821 -380.724601) (xy 387.881355 -380.770451) (xy 387.845664 -380.811642)
			(xy 387.804473 -380.847333) (xy 387.758623 -380.876799) (xy 387.709046 -380.899441) (xy 387.656751 -380.914796)
			(xy 387.602803 -380.922552) (xy 387.548301 -380.922552) (xy 387.494353 -380.914796) (xy 387.442058 -380.899441)
			(xy 387.392481 -380.876799) (xy 387.346631 -380.847333) (xy 387.30544 -380.811642) (xy 387.269749 -380.770451)
			(xy 387.240283 -380.724601) (xy 387.217641 -380.675024) (xy 387.202286 -380.622729) (xy 387.19453 -380.568781)
			(xy 387.194044 -380.54153) (xy 387.194726 -380.508998) (xy 387.205842 -380.444889) (xy 387.216142 -380.414022)
			(xy 387.21919 -380.405386) (xy 387.218936 -380.387606) (xy 387.189472 -380.30912) (xy 387.178042 -380.295912)
			(xy 387.169914 -380.29134) (xy 387.137656 -380.271528) (xy 387.131254 -380.267488) (xy 387.116775 -380.263095)
			(xy 387.109208 -380.262892) (xy 386.827776 -380.262892) (xy 386.820222 -380.263176) (xy 386.805764 -380.267563)
			(xy 386.799328 -380.271528) (xy 386.76707 -380.29134) (xy 386.758942 -380.295912) (xy 386.747512 -380.30912)
			(xy 386.718048 -380.387606) (xy 386.717794 -380.405386) (xy 386.720842 -380.414022) (xy 386.731128 -380.444892)
			(xy 386.742237 -380.508999) (xy 386.74294 -380.54153) (xy 386.742454 -380.568781) (xy 386.734698 -380.622729)
			(xy 386.719343 -380.675024) (xy 386.696701 -380.724601) (xy 386.667235 -380.770451) (xy 386.631544 -380.811642)
			(xy 386.590353 -380.847333) (xy 386.544503 -380.876799) (xy 386.494926 -380.899441) (xy 386.442631 -380.914796)
			(xy 386.388683 -380.922552) (xy 386.334181 -380.922552) (xy 386.280233 -380.914796) (xy 386.227938 -380.899441)
			(xy 386.178361 -380.876799) (xy 386.132511 -380.847333) (xy 386.09132 -380.811642) (xy 386.055629 -380.770451)
			(xy 386.026163 -380.724601) (xy 386.003521 -380.675024) (xy 385.988166 -380.622729) (xy 385.98041 -380.568781)
			(xy 385.979924 -380.54153) (xy 385.980274 -380.517458) (xy 385.986317 -380.469695) (xy 385.99831 -380.42307)
			(xy 386.006848 -380.40056) (xy 386.011928 -380.388114) (xy 386.008626 -380.362206) (xy 385.941824 -380.271528)
			(xy 385.918202 -380.260606) (xy 385.904994 -380.261622) (xy 385.876292 -380.262638) (xy 385.849043 -380.262091)
			(xy 385.795101 -380.254334) (xy 385.742811 -380.23898) (xy 385.693239 -380.21634) (xy 385.647393 -380.186876)
			(xy 385.606207 -380.151187) (xy 385.570519 -380.11) (xy 385.541056 -380.064154) (xy 385.518417 -380.014581)
			(xy 385.503064 -379.962291) (xy 385.495308 -379.908349) (xy 381.634575 -379.908349) (xy 381.634575 -379.908355)
			(xy 381.626817 -379.962311) (xy 381.61146 -380.014614) (xy 381.588815 -380.064199) (xy 381.559344 -380.110056)
			(xy 381.523646 -380.151252) (xy 381.482449 -380.186948) (xy 381.436592 -380.216419) (xy 381.387006 -380.239062)
			(xy 381.334703 -380.254419) (xy 381.280747 -380.262176) (xy 381.253492 -380.262638) (xy 381.22479 -380.261622)
			(xy 381.211582 -380.260606) (xy 381.18796 -380.271528) (xy 381.121158 -380.362206) (xy 381.117856 -380.388114)
			(xy 381.122936 -380.40056) (xy 381.131488 -380.423065) (xy 381.143486 -380.469691) (xy 381.149512 -380.517457)
			(xy 381.14986 -380.54153) (xy 381.149374 -380.568781) (xy 381.141618 -380.622729) (xy 381.126263 -380.675024)
			(xy 381.103621 -380.724601) (xy 381.074155 -380.770451) (xy 381.038464 -380.811642) (xy 380.997273 -380.847333)
			(xy 380.951423 -380.876799) (xy 380.901846 -380.899441) (xy 380.849551 -380.914796) (xy 380.795603 -380.922552)
			(xy 380.741101 -380.922552) (xy 380.687153 -380.914796) (xy 380.634858 -380.899441) (xy 380.585281 -380.876799)
			(xy 380.539431 -380.847333) (xy 380.49824 -380.811642) (xy 380.462549 -380.770451) (xy 380.433083 -380.724601)
			(xy 380.410441 -380.675024) (xy 380.395086 -380.622729) (xy 380.38733 -380.568781) (xy 380.386844 -380.54153)
			(xy 380.387526 -380.508998) (xy 380.398642 -380.444889) (xy 380.408942 -380.414022) (xy 380.41199 -380.405386)
			(xy 380.411736 -380.387606) (xy 380.382272 -380.30912) (xy 380.370842 -380.295912) (xy 380.362714 -380.29134)
			(xy 380.330456 -380.271528) (xy 380.324054 -380.267488) (xy 380.309575 -380.263095) (xy 380.302008 -380.262892)
			(xy 380.020576 -380.262892) (xy 380.013022 -380.263176) (xy 379.998564 -380.267563) (xy 379.992128 -380.271528)
			(xy 379.95987 -380.29134) (xy 379.951742 -380.295912) (xy 379.940312 -380.30912) (xy 379.910848 -380.387606)
			(xy 379.910594 -380.405386) (xy 379.913642 -380.414022) (xy 379.923928 -380.444892) (xy 379.935037 -380.508999)
			(xy 379.93574 -380.54153) (xy 379.935254 -380.568781) (xy 379.927498 -380.622729) (xy 379.912143 -380.675024)
			(xy 379.889501 -380.724601) (xy 379.860035 -380.770451) (xy 379.824344 -380.811642) (xy 379.783153 -380.847333)
			(xy 379.737303 -380.876799) (xy 379.687726 -380.899441) (xy 379.635431 -380.914796) (xy 379.581483 -380.922552)
			(xy 379.526981 -380.922552) (xy 379.473033 -380.914796) (xy 379.420738 -380.899441) (xy 379.371161 -380.876799)
			(xy 379.325311 -380.847333) (xy 379.28412 -380.811642) (xy 379.248429 -380.770451) (xy 379.218963 -380.724601)
			(xy 379.196321 -380.675024) (xy 379.180966 -380.622729) (xy 379.17321 -380.568781) (xy 379.172724 -380.54153)
			(xy 379.173074 -380.517458) (xy 379.179117 -380.469695) (xy 379.19111 -380.42307) (xy 379.199648 -380.40056)
			(xy 379.204728 -380.388114) (xy 379.201426 -380.362206) (xy 379.134624 -380.271528) (xy 379.111002 -380.260606)
			(xy 379.097794 -380.261622) (xy 379.069092 -380.262638) (xy 379.041843 -380.262091) (xy 378.987901 -380.254334)
			(xy 378.935611 -380.23898) (xy 378.886039 -380.21634) (xy 378.840193 -380.186876) (xy 378.799007 -380.151187)
			(xy 378.763319 -380.11) (xy 378.733856 -380.064154) (xy 378.711217 -380.014581) (xy 378.695864 -379.962291)
			(xy 378.688108 -379.908349) (xy 374.827375 -379.908349) (xy 374.827375 -379.908355) (xy 374.819617 -379.962311)
			(xy 374.80426 -380.014614) (xy 374.781615 -380.064199) (xy 374.752144 -380.110056) (xy 374.716446 -380.151252)
			(xy 374.675249 -380.186948) (xy 374.629392 -380.216419) (xy 374.579806 -380.239062) (xy 374.527503 -380.254419)
			(xy 374.473547 -380.262176) (xy 374.446292 -380.262638) (xy 374.41759 -380.261622) (xy 374.404382 -380.260606)
			(xy 374.38076 -380.271528) (xy 374.313958 -380.362206) (xy 374.310656 -380.388114) (xy 374.315736 -380.40056)
			(xy 374.324288 -380.423065) (xy 374.336286 -380.469691) (xy 374.342312 -380.517457) (xy 374.34266 -380.54153)
			(xy 374.342174 -380.568781) (xy 374.334418 -380.622729) (xy 374.319063 -380.675024) (xy 374.296421 -380.724601)
			(xy 374.266955 -380.770451) (xy 374.231264 -380.811642) (xy 374.190073 -380.847333) (xy 374.144223 -380.876799)
			(xy 374.094646 -380.899441) (xy 374.042351 -380.914796) (xy 373.988403 -380.922552) (xy 373.933901 -380.922552)
			(xy 373.879953 -380.914796) (xy 373.827658 -380.899441) (xy 373.778081 -380.876799) (xy 373.732231 -380.847333)
			(xy 373.69104 -380.811642) (xy 373.655349 -380.770451) (xy 373.625883 -380.724601) (xy 373.603241 -380.675024)
			(xy 373.587886 -380.622729) (xy 373.58013 -380.568781) (xy 373.579644 -380.54153) (xy 373.580326 -380.508998)
			(xy 373.591442 -380.444889) (xy 373.601742 -380.414022) (xy 373.60479 -380.405386) (xy 373.604536 -380.387606)
			(xy 373.575072 -380.30912) (xy 373.563642 -380.295912) (xy 373.555514 -380.29134) (xy 373.523256 -380.271528)
			(xy 373.516854 -380.267488) (xy 373.502375 -380.263095) (xy 373.494808 -380.262892) (xy 373.213376 -380.262892)
			(xy 373.205822 -380.263176) (xy 373.191364 -380.267563) (xy 373.184928 -380.271528) (xy 373.15267 -380.29134)
			(xy 373.144542 -380.295912) (xy 373.133112 -380.30912) (xy 373.103648 -380.387606) (xy 373.103394 -380.405386)
			(xy 373.106442 -380.414022) (xy 373.116728 -380.444892) (xy 373.127837 -380.508999) (xy 373.12854 -380.54153)
			(xy 373.128054 -380.568781) (xy 373.120298 -380.622729) (xy 373.104943 -380.675024) (xy 373.082301 -380.724601)
			(xy 373.052835 -380.770451) (xy 373.017144 -380.811642) (xy 372.975953 -380.847333) (xy 372.930103 -380.876799)
			(xy 372.880526 -380.899441) (xy 372.828231 -380.914796) (xy 372.774283 -380.922552) (xy 372.719781 -380.922552)
			(xy 372.665833 -380.914796) (xy 372.613538 -380.899441) (xy 372.563961 -380.876799) (xy 372.518111 -380.847333)
			(xy 372.47692 -380.811642) (xy 372.441229 -380.770451) (xy 372.411763 -380.724601) (xy 372.389121 -380.675024)
			(xy 372.373766 -380.622729) (xy 372.36601 -380.568781) (xy 372.365524 -380.54153) (xy 372.365874 -380.517458)
			(xy 372.371917 -380.469695) (xy 372.38391 -380.42307) (xy 372.392448 -380.40056) (xy 372.397528 -380.388114)
			(xy 372.394226 -380.362206) (xy 372.327424 -380.271528) (xy 372.303802 -380.260606) (xy 372.290594 -380.261622)
			(xy 372.261892 -380.262638) (xy 372.234643 -380.262091) (xy 372.180701 -380.254334) (xy 372.128411 -380.23898)
			(xy 372.078839 -380.21634) (xy 372.032993 -380.186876) (xy 371.991807 -380.151187) (xy 371.956119 -380.11)
			(xy 371.926656 -380.064154) (xy 371.904017 -380.014581) (xy 371.888664 -379.962291) (xy 371.880908 -379.908349)
			(xy 368.020175 -379.908349) (xy 368.020175 -379.908355) (xy 368.012417 -379.962311) (xy 367.99706 -380.014614)
			(xy 367.974415 -380.064199) (xy 367.944944 -380.110056) (xy 367.909246 -380.151252) (xy 367.868049 -380.186948)
			(xy 367.822192 -380.216419) (xy 367.772606 -380.239062) (xy 367.720303 -380.254419) (xy 367.666347 -380.262176)
			(xy 367.639092 -380.262638) (xy 367.61039 -380.261622) (xy 367.597182 -380.260606) (xy 367.57356 -380.271528)
			(xy 367.506758 -380.362206) (xy 367.503456 -380.388114) (xy 367.508536 -380.40056) (xy 367.517088 -380.423065)
			(xy 367.529086 -380.469691) (xy 367.535112 -380.517457) (xy 367.53546 -380.54153) (xy 367.534974 -380.568781)
			(xy 367.527218 -380.622729) (xy 367.511863 -380.675024) (xy 367.489221 -380.724601) (xy 367.459755 -380.770451)
			(xy 367.424064 -380.811642) (xy 367.382873 -380.847333) (xy 367.337023 -380.876799) (xy 367.287446 -380.899441)
			(xy 367.235151 -380.914796) (xy 367.181203 -380.922552) (xy 367.126701 -380.922552) (xy 367.072753 -380.914796)
			(xy 367.020458 -380.899441) (xy 366.970881 -380.876799) (xy 366.925031 -380.847333) (xy 366.88384 -380.811642)
			(xy 366.848149 -380.770451) (xy 366.818683 -380.724601) (xy 366.796041 -380.675024) (xy 366.780686 -380.622729)
			(xy 366.77293 -380.568781) (xy 366.772444 -380.54153) (xy 366.773126 -380.508998) (xy 366.784242 -380.444889)
			(xy 366.794542 -380.414022) (xy 366.79759 -380.405386) (xy 366.797336 -380.387606) (xy 366.767872 -380.30912)
			(xy 366.756442 -380.295912) (xy 366.748314 -380.29134) (xy 366.716056 -380.271528) (xy 366.709654 -380.267488)
			(xy 366.695175 -380.263095) (xy 366.687608 -380.262892) (xy 366.406176 -380.262892) (xy 366.398622 -380.263176)
			(xy 366.384164 -380.267563) (xy 366.377728 -380.271528) (xy 366.34547 -380.29134) (xy 366.337342 -380.295912)
			(xy 366.325912 -380.30912) (xy 366.296448 -380.387606) (xy 366.296194 -380.405386) (xy 366.299242 -380.414022)
			(xy 366.309528 -380.444892) (xy 366.320637 -380.508999) (xy 366.32134 -380.54153) (xy 366.320854 -380.568781)
			(xy 366.313098 -380.622729) (xy 366.297743 -380.675024) (xy 366.275101 -380.724601) (xy 366.245635 -380.770451)
			(xy 366.209944 -380.811642) (xy 366.168753 -380.847333) (xy 366.122903 -380.876799) (xy 366.073326 -380.899441)
			(xy 366.021031 -380.914796) (xy 365.967083 -380.922552) (xy 365.912581 -380.922552) (xy 365.858633 -380.914796)
			(xy 365.806338 -380.899441) (xy 365.756761 -380.876799) (xy 365.710911 -380.847333) (xy 365.66972 -380.811642)
			(xy 365.634029 -380.770451) (xy 365.604563 -380.724601) (xy 365.581921 -380.675024) (xy 365.566566 -380.622729)
			(xy 365.55881 -380.568781) (xy 365.558324 -380.54153) (xy 365.558674 -380.517458) (xy 365.564717 -380.469695)
			(xy 365.57671 -380.42307) (xy 365.585248 -380.40056) (xy 365.590328 -380.388114) (xy 365.587026 -380.362206)
			(xy 365.520224 -380.271528) (xy 365.496602 -380.260606) (xy 365.483394 -380.261622) (xy 365.454692 -380.262638)
			(xy 365.427443 -380.262091) (xy 365.373501 -380.254334) (xy 365.321211 -380.23898) (xy 365.271639 -380.21634)
			(xy 365.225793 -380.186876) (xy 365.184607 -380.151187) (xy 365.148919 -380.11) (xy 365.119456 -380.064154)
			(xy 365.096817 -380.014581) (xy 365.081464 -379.962291) (xy 365.073708 -379.908349) (xy 353.869252 -379.908349)
			(xy 353.869252 -379.908351) (xy 353.861496 -379.962299) (xy 353.846142 -380.014595) (xy 353.823502 -380.064173)
			(xy 353.794038 -380.110025) (xy 353.758348 -380.151217) (xy 353.71716 -380.186912) (xy 353.671312 -380.216381)
			(xy 353.621736 -380.239027) (xy 353.569443 -380.254387) (xy 353.515495 -380.262149) (xy 353.488244 -380.262638)
			(xy 353.459542 -380.261622) (xy 353.446334 -380.260606) (xy 353.422712 -380.271528) (xy 353.35591 -380.362206)
			(xy 353.352608 -380.388114) (xy 353.357688 -380.40056) (xy 353.366238 -380.423066) (xy 353.378237 -380.469691)
			(xy 353.384264 -380.517457) (xy 353.384612 -380.54153) (xy 353.384126 -380.568781) (xy 353.37637 -380.622729)
			(xy 353.361015 -380.675024) (xy 353.338373 -380.724601) (xy 353.308907 -380.770451) (xy 353.273216 -380.811642)
			(xy 353.232025 -380.847333) (xy 353.186175 -380.876799) (xy 353.136598 -380.899441) (xy 353.084303 -380.914796)
			(xy 353.030355 -380.922552) (xy 352.975853 -380.922552) (xy 352.921905 -380.914796) (xy 352.86961 -380.899441)
			(xy 352.820033 -380.876799) (xy 352.774183 -380.847333) (xy 352.732992 -380.811642) (xy 352.697301 -380.770451)
			(xy 352.667835 -380.724601) (xy 352.645193 -380.675024) (xy 352.629838 -380.622729) (xy 352.622082 -380.568781)
			(xy 352.621596 -380.54153) (xy 352.622275 -380.508998) (xy 352.633393 -380.444888) (xy 352.643694 -380.414022)
			(xy 352.646742 -380.405386) (xy 352.646488 -380.387606) (xy 352.617024 -380.30912) (xy 352.605594 -380.295912)
			(xy 352.597466 -380.29134) (xy 352.565208 -380.271528) (xy 352.558795 -380.267508) (xy 352.544325 -380.263102)
			(xy 352.53676 -380.262892) (xy 352.255328 -380.262892) (xy 352.247772 -380.263156) (xy 352.233314 -380.267557)
			(xy 352.22688 -380.271528) (xy 352.194622 -380.29134) (xy 352.186494 -380.295912) (xy 352.175064 -380.30912)
			(xy 352.1456 -380.387606) (xy 352.145346 -380.405386) (xy 352.148394 -380.414022) (xy 352.158678 -380.444892)
			(xy 352.169789 -380.508999) (xy 352.170492 -380.54153) (xy 352.170006 -380.568781) (xy 352.16225 -380.622729)
			(xy 352.146895 -380.675024) (xy 352.124253 -380.724601) (xy 352.094787 -380.770451) (xy 352.059096 -380.811642)
			(xy 352.017905 -380.847333) (xy 351.972055 -380.876799) (xy 351.922478 -380.899441) (xy 351.870183 -380.914796)
			(xy 351.816235 -380.922552) (xy 351.761733 -380.922552) (xy 351.707785 -380.914796) (xy 351.65549 -380.899441)
			(xy 351.605913 -380.876799) (xy 351.560063 -380.847333) (xy 351.518872 -380.811642) (xy 351.483181 -380.770451)
			(xy 351.453715 -380.724601) (xy 351.431073 -380.675024) (xy 351.415718 -380.622729) (xy 351.407962 -380.568781)
			(xy 351.407476 -380.54153) (xy 351.407823 -380.517458) (xy 351.413866 -380.469695) (xy 351.425861 -380.423069)
			(xy 351.4344 -380.40056) (xy 351.43948 -380.388114) (xy 351.436178 -380.362206) (xy 351.369376 -380.271528)
			(xy 351.345754 -380.260606) (xy 351.332546 -380.261622) (xy 351.303844 -380.262638) (xy 351.276591 -380.262118)
			(xy 351.22264 -380.254366) (xy 351.170341 -380.239015) (xy 351.120759 -380.216377) (xy 351.074904 -380.186913)
			(xy 351.033709 -380.151222) (xy 350.998014 -380.110031) (xy 350.968544 -380.06418) (xy 350.9459 -380.014601)
			(xy 350.930543 -379.962303) (xy 350.922785 -379.908353) (xy 347.062052 -379.908353) (xy 347.054296 -379.962299)
			(xy 347.038942 -380.014595) (xy 347.016302 -380.064173) (xy 346.986838 -380.110025) (xy 346.951148 -380.151217)
			(xy 346.90996 -380.186912) (xy 346.864112 -380.216381) (xy 346.814536 -380.239027) (xy 346.762243 -380.254387)
			(xy 346.708295 -380.262149) (xy 346.681044 -380.262638) (xy 346.652342 -380.261622) (xy 346.639134 -380.260606)
			(xy 346.615512 -380.271528) (xy 346.54871 -380.362206) (xy 346.545408 -380.388114) (xy 346.550488 -380.40056)
			(xy 346.559038 -380.423066) (xy 346.571037 -380.469691) (xy 346.577064 -380.517457) (xy 346.577412 -380.54153)
			(xy 346.576926 -380.568781) (xy 346.56917 -380.622729) (xy 346.553815 -380.675024) (xy 346.531173 -380.724601)
			(xy 346.501707 -380.770451) (xy 346.466016 -380.811642) (xy 346.424825 -380.847333) (xy 346.378975 -380.876799)
			(xy 346.329398 -380.899441) (xy 346.277103 -380.914796) (xy 346.223155 -380.922552) (xy 346.168653 -380.922552)
			(xy 346.114705 -380.914796) (xy 346.06241 -380.899441) (xy 346.012833 -380.876799) (xy 345.966983 -380.847333)
			(xy 345.925792 -380.811642) (xy 345.890101 -380.770451) (xy 345.860635 -380.724601) (xy 345.837993 -380.675024)
			(xy 345.822638 -380.622729) (xy 345.814882 -380.568781) (xy 345.814396 -380.54153) (xy 345.815075 -380.508998)
			(xy 345.826193 -380.444888) (xy 345.836494 -380.414022) (xy 345.839542 -380.405386) (xy 345.839288 -380.387606)
			(xy 345.809824 -380.30912) (xy 345.798394 -380.295912) (xy 345.790266 -380.29134) (xy 345.758008 -380.271528)
			(xy 345.751595 -380.267508) (xy 345.737125 -380.263102) (xy 345.72956 -380.262892) (xy 345.448128 -380.262892)
			(xy 345.440572 -380.263156) (xy 345.426114 -380.267557) (xy 345.41968 -380.271528) (xy 345.387422 -380.29134)
			(xy 345.379294 -380.295912) (xy 345.367864 -380.30912) (xy 345.3384 -380.387606) (xy 345.338146 -380.405386)
			(xy 345.341194 -380.414022) (xy 345.351478 -380.444892) (xy 345.362589 -380.508999) (xy 345.363292 -380.54153)
			(xy 345.362806 -380.568781) (xy 345.35505 -380.622729) (xy 345.339695 -380.675024) (xy 345.317053 -380.724601)
			(xy 345.287587 -380.770451) (xy 345.251896 -380.811642) (xy 345.210705 -380.847333) (xy 345.164855 -380.876799)
			(xy 345.115278 -380.899441) (xy 345.062983 -380.914796) (xy 345.009035 -380.922552) (xy 344.954533 -380.922552)
			(xy 344.900585 -380.914796) (xy 344.84829 -380.899441) (xy 344.798713 -380.876799) (xy 344.752863 -380.847333)
			(xy 344.711672 -380.811642) (xy 344.675981 -380.770451) (xy 344.646515 -380.724601) (xy 344.623873 -380.675024)
			(xy 344.608518 -380.622729) (xy 344.600762 -380.568781) (xy 344.600276 -380.54153) (xy 344.600623 -380.517458)
			(xy 344.606666 -380.469695) (xy 344.618661 -380.423069) (xy 344.6272 -380.40056) (xy 344.63228 -380.388114)
			(xy 344.628978 -380.362206) (xy 344.562176 -380.271528) (xy 344.538554 -380.260606) (xy 344.525346 -380.261622)
			(xy 344.496644 -380.262638) (xy 344.469391 -380.262118) (xy 344.41544 -380.254366) (xy 344.363141 -380.239015)
			(xy 344.313559 -380.216377) (xy 344.267704 -380.186913) (xy 344.226509 -380.151222) (xy 344.190814 -380.110031)
			(xy 344.161344 -380.06418) (xy 344.1387 -380.014601) (xy 344.123343 -379.962303) (xy 344.115585 -379.908353)
			(xy 340.254852 -379.908353) (xy 340.247096 -379.962299) (xy 340.231742 -380.014595) (xy 340.209102 -380.064173)
			(xy 340.179638 -380.110025) (xy 340.143948 -380.151217) (xy 340.10276 -380.186912) (xy 340.056912 -380.216381)
			(xy 340.007336 -380.239027) (xy 339.955043 -380.254387) (xy 339.901095 -380.262149) (xy 339.873844 -380.262638)
			(xy 339.845142 -380.261622) (xy 339.831934 -380.260606) (xy 339.808312 -380.271528) (xy 339.74151 -380.362206)
			(xy 339.738208 -380.388114) (xy 339.743288 -380.40056) (xy 339.751838 -380.423066) (xy 339.763837 -380.469691)
			(xy 339.769864 -380.517457) (xy 339.770212 -380.54153) (xy 339.769726 -380.568781) (xy 339.76197 -380.622729)
			(xy 339.746615 -380.675024) (xy 339.723973 -380.724601) (xy 339.694507 -380.770451) (xy 339.658816 -380.811642)
			(xy 339.617625 -380.847333) (xy 339.571775 -380.876799) (xy 339.522198 -380.899441) (xy 339.469903 -380.914796)
			(xy 339.415955 -380.922552) (xy 339.361453 -380.922552) (xy 339.307505 -380.914796) (xy 339.25521 -380.899441)
			(xy 339.205633 -380.876799) (xy 339.159783 -380.847333) (xy 339.118592 -380.811642) (xy 339.082901 -380.770451)
			(xy 339.053435 -380.724601) (xy 339.030793 -380.675024) (xy 339.015438 -380.622729) (xy 339.007682 -380.568781)
			(xy 339.007196 -380.54153) (xy 339.007875 -380.508998) (xy 339.018993 -380.444888) (xy 339.029294 -380.414022)
			(xy 339.032342 -380.405386) (xy 339.032088 -380.387606) (xy 339.002624 -380.30912) (xy 338.991194 -380.295912)
			(xy 338.983066 -380.29134) (xy 338.950808 -380.271528) (xy 338.944395 -380.267508) (xy 338.929925 -380.263102)
			(xy 338.92236 -380.262892) (xy 338.640928 -380.262892) (xy 338.633372 -380.263156) (xy 338.618914 -380.267557)
			(xy 338.61248 -380.271528) (xy 338.580222 -380.29134) (xy 338.572094 -380.295912) (xy 338.560664 -380.30912)
			(xy 338.5312 -380.387606) (xy 338.530946 -380.405386) (xy 338.533994 -380.414022) (xy 338.544278 -380.444892)
			(xy 338.555389 -380.508999) (xy 338.556092 -380.54153) (xy 338.555606 -380.568781) (xy 338.54785 -380.622729)
			(xy 338.532495 -380.675024) (xy 338.509853 -380.724601) (xy 338.480387 -380.770451) (xy 338.444696 -380.811642)
			(xy 338.403505 -380.847333) (xy 338.357655 -380.876799) (xy 338.308078 -380.899441) (xy 338.255783 -380.914796)
			(xy 338.201835 -380.922552) (xy 338.147333 -380.922552) (xy 338.093385 -380.914796) (xy 338.04109 -380.899441)
			(xy 337.991513 -380.876799) (xy 337.945663 -380.847333) (xy 337.904472 -380.811642) (xy 337.868781 -380.770451)
			(xy 337.839315 -380.724601) (xy 337.816673 -380.675024) (xy 337.801318 -380.622729) (xy 337.793562 -380.568781)
			(xy 337.793076 -380.54153) (xy 337.793423 -380.517458) (xy 337.799466 -380.469695) (xy 337.811461 -380.423069)
			(xy 337.82 -380.40056) (xy 337.82508 -380.388114) (xy 337.821778 -380.362206) (xy 337.754976 -380.271528)
			(xy 337.731354 -380.260606) (xy 337.718146 -380.261622) (xy 337.689444 -380.262638) (xy 337.662191 -380.262118)
			(xy 337.60824 -380.254366) (xy 337.555941 -380.239015) (xy 337.506359 -380.216377) (xy 337.460504 -380.186913)
			(xy 337.419309 -380.151222) (xy 337.383614 -380.110031) (xy 337.354144 -380.06418) (xy 337.3315 -380.014601)
			(xy 337.316143 -379.962303) (xy 337.308385 -379.908353) (xy 333.447652 -379.908353) (xy 333.439896 -379.962299)
			(xy 333.424542 -380.014595) (xy 333.401902 -380.064173) (xy 333.372438 -380.110025) (xy 333.336748 -380.151217)
			(xy 333.29556 -380.186912) (xy 333.249712 -380.216381) (xy 333.200136 -380.239027) (xy 333.147843 -380.254387)
			(xy 333.093895 -380.262149) (xy 333.066644 -380.262638) (xy 333.037942 -380.261622) (xy 333.024734 -380.260606)
			(xy 333.001112 -380.271528) (xy 332.93431 -380.362206) (xy 332.931008 -380.388114) (xy 332.936088 -380.40056)
			(xy 332.944638 -380.423066) (xy 332.956637 -380.469691) (xy 332.962664 -380.517457) (xy 332.963012 -380.54153)
			(xy 332.962526 -380.568781) (xy 332.95477 -380.622729) (xy 332.939415 -380.675024) (xy 332.916773 -380.724601)
			(xy 332.887307 -380.770451) (xy 332.851616 -380.811642) (xy 332.810425 -380.847333) (xy 332.764575 -380.876799)
			(xy 332.714998 -380.899441) (xy 332.662703 -380.914796) (xy 332.608755 -380.922552) (xy 332.554253 -380.922552)
			(xy 332.500305 -380.914796) (xy 332.44801 -380.899441) (xy 332.398433 -380.876799) (xy 332.352583 -380.847333)
			(xy 332.311392 -380.811642) (xy 332.275701 -380.770451) (xy 332.246235 -380.724601) (xy 332.223593 -380.675024)
			(xy 332.208238 -380.622729) (xy 332.200482 -380.568781) (xy 332.199996 -380.54153) (xy 332.200675 -380.508998)
			(xy 332.211793 -380.444888) (xy 332.222094 -380.414022) (xy 332.225142 -380.405386) (xy 332.224888 -380.387606)
			(xy 332.195424 -380.30912) (xy 332.183994 -380.295912) (xy 332.175866 -380.29134) (xy 332.143608 -380.271528)
			(xy 332.137195 -380.267508) (xy 332.122725 -380.263102) (xy 332.11516 -380.262892) (xy 331.833728 -380.262892)
			(xy 331.826172 -380.263156) (xy 331.811714 -380.267557) (xy 331.80528 -380.271528) (xy 331.773022 -380.29134)
			(xy 331.764894 -380.295912) (xy 331.753464 -380.30912) (xy 331.724 -380.387606) (xy 331.723746 -380.405386)
			(xy 331.726794 -380.414022) (xy 331.737078 -380.444892) (xy 331.748189 -380.508999) (xy 331.748892 -380.54153)
			(xy 331.748406 -380.568781) (xy 331.74065 -380.622729) (xy 331.725295 -380.675024) (xy 331.702653 -380.724601)
			(xy 331.673187 -380.770451) (xy 331.637496 -380.811642) (xy 331.596305 -380.847333) (xy 331.550455 -380.876799)
			(xy 331.500878 -380.899441) (xy 331.448583 -380.914796) (xy 331.394635 -380.922552) (xy 331.340133 -380.922552)
			(xy 331.286185 -380.914796) (xy 331.23389 -380.899441) (xy 331.184313 -380.876799) (xy 331.138463 -380.847333)
			(xy 331.097272 -380.811642) (xy 331.061581 -380.770451) (xy 331.032115 -380.724601) (xy 331.009473 -380.675024)
			(xy 330.994118 -380.622729) (xy 330.986362 -380.568781) (xy 330.985876 -380.54153) (xy 330.986223 -380.517458)
			(xy 330.992266 -380.469695) (xy 331.004261 -380.423069) (xy 331.0128 -380.40056) (xy 331.01788 -380.388114)
			(xy 331.014578 -380.362206) (xy 330.947776 -380.271528) (xy 330.924154 -380.260606) (xy 330.910946 -380.261622)
			(xy 330.882244 -380.262638) (xy 330.854991 -380.262118) (xy 330.80104 -380.254366) (xy 330.748741 -380.239015)
			(xy 330.699159 -380.216377) (xy 330.653304 -380.186913) (xy 330.612109 -380.151222) (xy 330.576414 -380.110031)
			(xy 330.546944 -380.06418) (xy 330.5243 -380.014601) (xy 330.508943 -379.962303) (xy 330.501185 -379.908353)
			(xy 321.341575 -379.908353) (xy 321.341575 -379.908355) (xy 321.333817 -379.962311) (xy 321.31846 -380.014613)
			(xy 321.295815 -380.064197) (xy 321.266345 -380.110054) (xy 321.230648 -380.151251) (xy 321.189451 -380.186947)
			(xy 321.143594 -380.216417) (xy 321.094009 -380.239061) (xy 321.041707 -380.254418) (xy 320.987751 -380.262175)
			(xy 320.960496 -380.262638) (xy 320.931794 -380.261622) (xy 320.918586 -380.260606) (xy 320.894964 -380.271528)
			(xy 320.828162 -380.362206) (xy 320.82486 -380.388114) (xy 320.82994 -380.40056) (xy 320.838492 -380.423065)
			(xy 320.85049 -380.469691) (xy 320.856516 -380.517457) (xy 320.856864 -380.54153) (xy 320.856378 -380.568781)
			(xy 320.848622 -380.622729) (xy 320.833267 -380.675024) (xy 320.810625 -380.724601) (xy 320.781159 -380.770451)
			(xy 320.745468 -380.811642) (xy 320.704277 -380.847333) (xy 320.658427 -380.876799) (xy 320.60885 -380.899441)
			(xy 320.556555 -380.914796) (xy 320.502607 -380.922552) (xy 320.448105 -380.922552) (xy 320.394157 -380.914796)
			(xy 320.341862 -380.899441) (xy 320.292285 -380.876799) (xy 320.246435 -380.847333) (xy 320.205244 -380.811642)
			(xy 320.169553 -380.770451) (xy 320.140087 -380.724601) (xy 320.117445 -380.675024) (xy 320.10209 -380.622729)
			(xy 320.094334 -380.568781) (xy 320.093848 -380.54153) (xy 320.09453 -380.508998) (xy 320.105646 -380.444889)
			(xy 320.115946 -380.414022) (xy 320.118994 -380.405386) (xy 320.11874 -380.387606) (xy 320.089276 -380.30912)
			(xy 320.077846 -380.295912) (xy 320.069718 -380.29134) (xy 320.03746 -380.271528) (xy 320.031058 -380.267489)
			(xy 320.016579 -380.263095) (xy 320.009012 -380.262892) (xy 319.72758 -380.262892) (xy 319.720026 -380.263177)
			(xy 319.705568 -380.267563) (xy 319.699132 -380.271528) (xy 319.666874 -380.29134) (xy 319.658746 -380.295912)
			(xy 319.647316 -380.30912) (xy 319.617852 -380.387606) (xy 319.617598 -380.405386) (xy 319.620646 -380.414022)
			(xy 319.630932 -380.444892) (xy 319.642041 -380.508999) (xy 319.642744 -380.54153) (xy 319.642258 -380.568781)
			(xy 319.634502 -380.622729) (xy 319.619147 -380.675024) (xy 319.596505 -380.724601) (xy 319.567039 -380.770451)
			(xy 319.531348 -380.811642) (xy 319.490157 -380.847333) (xy 319.444307 -380.876799) (xy 319.39473 -380.899441)
			(xy 319.342435 -380.914796) (xy 319.288487 -380.922552) (xy 319.233985 -380.922552) (xy 319.180037 -380.914796)
			(xy 319.127742 -380.899441) (xy 319.078165 -380.876799) (xy 319.032315 -380.847333) (xy 318.991124 -380.811642)
			(xy 318.955433 -380.770451) (xy 318.925967 -380.724601) (xy 318.903325 -380.675024) (xy 318.88797 -380.622729)
			(xy 318.880214 -380.568781) (xy 318.879728 -380.54153) (xy 318.880078 -380.517458) (xy 318.88612 -380.469695)
			(xy 318.898114 -380.42307) (xy 318.906652 -380.40056) (xy 318.911732 -380.388114) (xy 318.90843 -380.362206)
			(xy 318.841628 -380.271528) (xy 318.818006 -380.260606) (xy 318.804798 -380.261622) (xy 318.776096 -380.262638)
			(xy 318.748847 -380.262092) (xy 318.694904 -380.254335) (xy 318.642614 -380.238981) (xy 318.593041 -380.216341)
			(xy 318.547195 -380.186877) (xy 318.506009 -380.151189) (xy 318.47032 -380.110002) (xy 318.440857 -380.064155)
			(xy 318.418218 -380.014582) (xy 318.402864 -379.962292) (xy 318.395108 -379.908349) (xy 314.534375 -379.908349)
			(xy 314.534375 -379.908355) (xy 314.526617 -379.962311) (xy 314.51126 -380.014613) (xy 314.488615 -380.064197)
			(xy 314.459145 -380.110054) (xy 314.423448 -380.151251) (xy 314.382251 -380.186947) (xy 314.336394 -380.216417)
			(xy 314.286809 -380.239061) (xy 314.234507 -380.254418) (xy 314.180551 -380.262175) (xy 314.153296 -380.262638)
			(xy 314.124594 -380.261622) (xy 314.111386 -380.260606) (xy 314.087764 -380.271528) (xy 314.020962 -380.362206)
			(xy 314.01766 -380.388114) (xy 314.02274 -380.40056) (xy 314.031292 -380.423065) (xy 314.04329 -380.469691)
			(xy 314.049316 -380.517457) (xy 314.049664 -380.54153) (xy 314.049178 -380.568781) (xy 314.041422 -380.622729)
			(xy 314.026067 -380.675024) (xy 314.003425 -380.724601) (xy 313.973959 -380.770451) (xy 313.938268 -380.811642)
			(xy 313.897077 -380.847333) (xy 313.851227 -380.876799) (xy 313.80165 -380.899441) (xy 313.749355 -380.914796)
			(xy 313.695407 -380.922552) (xy 313.640905 -380.922552) (xy 313.586957 -380.914796) (xy 313.534662 -380.899441)
			(xy 313.485085 -380.876799) (xy 313.439235 -380.847333) (xy 313.398044 -380.811642) (xy 313.362353 -380.770451)
			(xy 313.332887 -380.724601) (xy 313.310245 -380.675024) (xy 313.29489 -380.622729) (xy 313.287134 -380.568781)
			(xy 313.286648 -380.54153) (xy 313.28733 -380.508998) (xy 313.298446 -380.444889) (xy 313.308746 -380.414022)
			(xy 313.311794 -380.405386) (xy 313.31154 -380.387606) (xy 313.282076 -380.30912) (xy 313.270646 -380.295912)
			(xy 313.262518 -380.29134) (xy 313.23026 -380.271528) (xy 313.223858 -380.267489) (xy 313.209379 -380.263095)
			(xy 313.201812 -380.262892) (xy 312.92038 -380.262892) (xy 312.912826 -380.263177) (xy 312.898368 -380.267563)
			(xy 312.891932 -380.271528) (xy 312.859674 -380.29134) (xy 312.851546 -380.295912) (xy 312.840116 -380.30912)
			(xy 312.810652 -380.387606) (xy 312.810398 -380.405386) (xy 312.813446 -380.414022) (xy 312.823732 -380.444892)
			(xy 312.834841 -380.508999) (xy 312.835544 -380.54153) (xy 312.835058 -380.568781) (xy 312.827302 -380.622729)
			(xy 312.811947 -380.675024) (xy 312.789305 -380.724601) (xy 312.759839 -380.770451) (xy 312.724148 -380.811642)
			(xy 312.682957 -380.847333) (xy 312.637107 -380.876799) (xy 312.58753 -380.899441) (xy 312.535235 -380.914796)
			(xy 312.481287 -380.922552) (xy 312.426785 -380.922552) (xy 312.372837 -380.914796) (xy 312.320542 -380.899441)
			(xy 312.270965 -380.876799) (xy 312.225115 -380.847333) (xy 312.183924 -380.811642) (xy 312.148233 -380.770451)
			(xy 312.118767 -380.724601) (xy 312.096125 -380.675024) (xy 312.08077 -380.622729) (xy 312.073014 -380.568781)
			(xy 312.072528 -380.54153) (xy 312.072878 -380.517458) (xy 312.07892 -380.469695) (xy 312.090914 -380.42307)
			(xy 312.099452 -380.40056) (xy 312.104532 -380.388114) (xy 312.10123 -380.362206) (xy 312.034428 -380.271528)
			(xy 312.010806 -380.260606) (xy 311.997598 -380.261622) (xy 311.968896 -380.262638) (xy 311.941647 -380.262092)
			(xy 311.887704 -380.254335) (xy 311.835414 -380.238981) (xy 311.785841 -380.216341) (xy 311.739995 -380.186877)
			(xy 311.698809 -380.151189) (xy 311.66312 -380.110002) (xy 311.633657 -380.064155) (xy 311.611018 -380.014582)
			(xy 311.595664 -379.962292) (xy 311.587908 -379.908349) (xy 307.727175 -379.908349) (xy 307.727175 -379.908355)
			(xy 307.719417 -379.962311) (xy 307.70406 -380.014613) (xy 307.681415 -380.064197) (xy 307.651945 -380.110054)
			(xy 307.616248 -380.151251) (xy 307.575051 -380.186947) (xy 307.529194 -380.216417) (xy 307.479609 -380.239061)
			(xy 307.427307 -380.254418) (xy 307.373351 -380.262175) (xy 307.346096 -380.262638) (xy 307.317394 -380.261622)
			(xy 307.304186 -380.260606) (xy 307.280564 -380.271528) (xy 307.213762 -380.362206) (xy 307.21046 -380.388114)
			(xy 307.21554 -380.40056) (xy 307.224092 -380.423065) (xy 307.23609 -380.469691) (xy 307.242116 -380.517457)
			(xy 307.242464 -380.54153) (xy 307.241978 -380.568781) (xy 307.234222 -380.622729) (xy 307.218867 -380.675024)
			(xy 307.196225 -380.724601) (xy 307.166759 -380.770451) (xy 307.131068 -380.811642) (xy 307.089877 -380.847333)
			(xy 307.044027 -380.876799) (xy 306.99445 -380.899441) (xy 306.942155 -380.914796) (xy 306.888207 -380.922552)
			(xy 306.833705 -380.922552) (xy 306.779757 -380.914796) (xy 306.727462 -380.899441) (xy 306.677885 -380.876799)
			(xy 306.632035 -380.847333) (xy 306.590844 -380.811642) (xy 306.555153 -380.770451) (xy 306.525687 -380.724601)
			(xy 306.503045 -380.675024) (xy 306.48769 -380.622729) (xy 306.479934 -380.568781) (xy 306.479448 -380.54153)
			(xy 306.48013 -380.508998) (xy 306.491246 -380.444889) (xy 306.501546 -380.414022) (xy 306.504594 -380.405386)
			(xy 306.50434 -380.387606) (xy 306.474876 -380.30912) (xy 306.463446 -380.295912) (xy 306.455318 -380.29134)
			(xy 306.42306 -380.271528) (xy 306.416658 -380.267489) (xy 306.402179 -380.263095) (xy 306.394612 -380.262892)
			(xy 306.11318 -380.262892) (xy 306.105626 -380.263177) (xy 306.091168 -380.267563) (xy 306.084732 -380.271528)
			(xy 306.052474 -380.29134) (xy 306.044346 -380.295912) (xy 306.032916 -380.30912) (xy 306.003452 -380.387606)
			(xy 306.003198 -380.405386) (xy 306.006246 -380.414022) (xy 306.016532 -380.444892) (xy 306.027641 -380.508999)
			(xy 306.028344 -380.54153) (xy 306.027858 -380.568781) (xy 306.020102 -380.622729) (xy 306.004747 -380.675024)
			(xy 305.982105 -380.724601) (xy 305.952639 -380.770451) (xy 305.916948 -380.811642) (xy 305.875757 -380.847333)
			(xy 305.829907 -380.876799) (xy 305.78033 -380.899441) (xy 305.728035 -380.914796) (xy 305.674087 -380.922552)
			(xy 305.619585 -380.922552) (xy 305.565637 -380.914796) (xy 305.513342 -380.899441) (xy 305.463765 -380.876799)
			(xy 305.417915 -380.847333) (xy 305.376724 -380.811642) (xy 305.341033 -380.770451) (xy 305.311567 -380.724601)
			(xy 305.288925 -380.675024) (xy 305.27357 -380.622729) (xy 305.265814 -380.568781) (xy 305.265328 -380.54153)
			(xy 305.265678 -380.517458) (xy 305.27172 -380.469695) (xy 305.283714 -380.42307) (xy 305.292252 -380.40056)
			(xy 305.297332 -380.388114) (xy 305.29403 -380.362206) (xy 305.227228 -380.271528) (xy 305.203606 -380.260606)
			(xy 305.190398 -380.261622) (xy 305.161696 -380.262638) (xy 305.134447 -380.262092) (xy 305.080504 -380.254335)
			(xy 305.028214 -380.238981) (xy 304.978641 -380.216341) (xy 304.932795 -380.186877) (xy 304.891609 -380.151189)
			(xy 304.85592 -380.110002) (xy 304.826457 -380.064155) (xy 304.803818 -380.014582) (xy 304.788464 -379.962292)
			(xy 304.780708 -379.908349) (xy 300.919915 -379.908349) (xy 300.919915 -379.908351) (xy 300.912158 -379.962298)
			(xy 300.896803 -380.014592) (xy 300.874162 -380.064168) (xy 300.844696 -380.110018) (xy 300.809005 -380.151208)
			(xy 300.767815 -380.186899) (xy 300.721965 -380.216364) (xy 300.672388 -380.239005) (xy 300.620094 -380.254359)
			(xy 300.566147 -380.262115) (xy 300.538896 -380.262638) (xy 300.510194 -380.261622) (xy 300.496986 -380.260606)
			(xy 300.473364 -380.271528) (xy 300.406562 -380.362206) (xy 300.40326 -380.388114) (xy 300.40834 -380.40056)
			(xy 300.416878 -380.42307) (xy 300.428872 -380.469695) (xy 300.434915 -380.517458) (xy 300.435264 -380.54153)
			(xy 300.434778 -380.568781) (xy 300.427022 -380.622729) (xy 300.411667 -380.675024) (xy 300.389025 -380.724601)
			(xy 300.359559 -380.770451) (xy 300.323868 -380.811642) (xy 300.282677 -380.847333) (xy 300.236827 -380.876799)
			(xy 300.18725 -380.899441) (xy 300.134955 -380.914796) (xy 300.081007 -380.922552) (xy 300.026505 -380.922552)
			(xy 299.972557 -380.914796) (xy 299.920262 -380.899441) (xy 299.870685 -380.876799) (xy 299.824835 -380.847333)
			(xy 299.783644 -380.811642) (xy 299.747953 -380.770451) (xy 299.718487 -380.724601) (xy 299.695845 -380.675024)
			(xy 299.68049 -380.622729) (xy 299.672734 -380.568781) (xy 299.672248 -380.54153) (xy 299.672951 -380.509)
			(xy 299.684063 -380.444892) (xy 299.694346 -380.414022) (xy 299.697394 -380.405386) (xy 299.69714 -380.387606)
			(xy 299.667676 -380.30912) (xy 299.656246 -380.295912) (xy 299.648118 -380.29134) (xy 299.61586 -380.271528)
			(xy 299.609424 -380.267564) (xy 299.594966 -380.263181) (xy 299.587412 -380.262892) (xy 299.30598 -380.262892)
			(xy 299.298413 -380.263096) (xy 299.283936 -380.267492) (xy 299.277532 -380.271528) (xy 299.245274 -380.29134)
			(xy 299.237146 -380.295912) (xy 299.225716 -380.30912) (xy 299.196252 -380.387606) (xy 299.195998 -380.405386)
			(xy 299.199046 -380.414022) (xy 299.209346 -380.444889) (xy 299.220463 -380.508998) (xy 299.221144 -380.54153)
			(xy 299.220658 -380.568781) (xy 299.212902 -380.622729) (xy 299.197547 -380.675024) (xy 299.174905 -380.724601)
			(xy 299.145439 -380.770451) (xy 299.109748 -380.811642) (xy 299.068557 -380.847333) (xy 299.022707 -380.876799)
			(xy 298.97313 -380.899441) (xy 298.920835 -380.914796) (xy 298.866887 -380.922552) (xy 298.812385 -380.922552)
			(xy 298.758437 -380.914796) (xy 298.706142 -380.899441) (xy 298.656565 -380.876799) (xy 298.610715 -380.847333)
			(xy 298.569524 -380.811642) (xy 298.533833 -380.770451) (xy 298.504367 -380.724601) (xy 298.481725 -380.675024)
			(xy 298.46637 -380.622729) (xy 298.458614 -380.568781) (xy 298.458128 -380.54153) (xy 298.458476 -380.517457)
			(xy 298.464502 -380.469691) (xy 298.4765 -380.423065) (xy 298.485052 -380.40056) (xy 298.490132 -380.388114)
			(xy 298.48683 -380.362206) (xy 298.420028 -380.271528) (xy 298.396406 -380.260606) (xy 298.383198 -380.261622)
			(xy 298.354496 -380.262638) (xy 298.324337 -380.262066) (xy 298.26477 -380.252569) (xy 298.207442 -380.233814)
			(xy 298.15378 -380.206268) (xy 298.105125 -380.170617) (xy 298.083478 -380.149608) (xy 298.076112 -380.142242)
			(xy 298.05757 -380.134622) (xy 297.975528 -380.134368) (xy 297.965497 -380.134809) (xy 297.946923 -380.142384)
			(xy 297.93946 -380.1491) (xy 295.716411 -382.372149) (xy 303.078908 -382.372149) (xy 303.078908 -382.317651)
			(xy 303.086664 -382.263708) (xy 303.102018 -382.211418) (xy 303.124657 -382.161845) (xy 303.15412 -382.115998)
			(xy 303.189809 -382.074811) (xy 303.230995 -382.039123) (xy 303.276841 -382.009659) (xy 303.326414 -381.987019)
			(xy 303.378704 -381.971665) (xy 303.432647 -381.963908) (xy 303.459896 -381.963422) (xy 303.488598 -381.964438)
			(xy 303.501806 -381.965454) (xy 303.525428 -381.954532) (xy 303.59223 -381.863854) (xy 303.595532 -381.837946)
			(xy 303.590452 -381.8255) (xy 303.581917 -381.802989) (xy 303.569913 -381.756366) (xy 303.56388 -381.708602)
			(xy 303.563528 -381.68453) (xy 303.564014 -381.657279) (xy 303.57177 -381.603331) (xy 303.587125 -381.551036)
			(xy 303.609767 -381.501459) (xy 303.639233 -381.455609) (xy 303.674924 -381.414418) (xy 303.716115 -381.378727)
			(xy 303.761965 -381.349261) (xy 303.811542 -381.326619) (xy 303.863837 -381.311264) (xy 303.917785 -381.303508)
			(xy 303.972287 -381.303508) (xy 304.026235 -381.311264) (xy 304.07853 -381.326619) (xy 304.128107 -381.349261)
			(xy 304.173957 -381.378727) (xy 304.215148 -381.414418) (xy 304.250839 -381.455609) (xy 304.280305 -381.501459)
			(xy 304.302947 -381.551036) (xy 304.318302 -381.603331) (xy 304.326058 -381.657279) (xy 304.326544 -381.68453)
			(xy 304.325853 -381.717062) (xy 304.314743 -381.781171) (xy 304.304446 -381.812038) (xy 304.301398 -381.820674)
			(xy 304.301652 -381.838454) (xy 304.331116 -381.91694) (xy 304.342546 -381.930148) (xy 304.350674 -381.93472)
			(xy 304.382932 -381.954532) (xy 304.389333 -381.958573) (xy 304.403813 -381.962965) (xy 304.41138 -381.963168)
			(xy 304.692812 -381.963168) (xy 304.700365 -381.96287) (xy 304.714823 -381.958492) (xy 304.72126 -381.954532)
			(xy 304.753518 -381.93472) (xy 304.761646 -381.930148) (xy 304.773076 -381.91694) (xy 304.80254 -381.838454)
			(xy 304.802794 -381.820674) (xy 304.799746 -381.812038) (xy 304.789453 -381.78117) (xy 304.778348 -381.717061)
			(xy 304.777648 -381.68453) (xy 304.778134 -381.657279) (xy 304.78589 -381.603331) (xy 304.801245 -381.551036)
			(xy 304.823887 -381.501459) (xy 304.853353 -381.455609) (xy 304.889044 -381.414418) (xy 304.930235 -381.378727)
			(xy 304.976085 -381.349261) (xy 305.025662 -381.326619) (xy 305.077957 -381.311264) (xy 305.131905 -381.303508)
			(xy 305.186407 -381.303508) (xy 305.240355 -381.311264) (xy 305.29265 -381.326619) (xy 305.342227 -381.349261)
			(xy 305.388077 -381.378727) (xy 305.429268 -381.414418) (xy 305.464959 -381.455609) (xy 305.494425 -381.501459)
			(xy 305.517067 -381.551036) (xy 305.532422 -381.603331) (xy 305.540178 -381.657279) (xy 305.540664 -381.68453)
			(xy 305.540302 -381.708601) (xy 305.534265 -381.756364) (xy 305.522276 -381.80299) (xy 305.51374 -381.8255)
			(xy 305.50866 -381.837946) (xy 305.511962 -381.863854) (xy 305.578764 -381.954532) (xy 305.602386 -381.965454)
			(xy 305.615594 -381.964438) (xy 305.644296 -381.963422) (xy 305.671551 -381.963825) (xy 305.725507 -381.971582)
			(xy 305.777809 -381.986939) (xy 305.827394 -382.009583) (xy 305.873251 -382.039053) (xy 305.914448 -382.074749)
			(xy 305.950145 -382.115946) (xy 305.979615 -382.161803) (xy 306.00226 -382.211387) (xy 306.017617 -382.263689)
			(xy 306.025375 -382.317645) (xy 306.025375 -382.372149) (xy 309.886108 -382.372149) (xy 309.886108 -382.317651)
			(xy 309.893864 -382.263708) (xy 309.909218 -382.211418) (xy 309.931857 -382.161845) (xy 309.96132 -382.115998)
			(xy 309.997009 -382.074811) (xy 310.038195 -382.039123) (xy 310.084041 -382.009659) (xy 310.133614 -381.987019)
			(xy 310.185904 -381.971665) (xy 310.239847 -381.963908) (xy 310.267096 -381.963422) (xy 310.295798 -381.964438)
			(xy 310.309006 -381.965454) (xy 310.332628 -381.954532) (xy 310.39943 -381.863854) (xy 310.402732 -381.837946)
			(xy 310.397652 -381.8255) (xy 310.389117 -381.802989) (xy 310.377113 -381.756366) (xy 310.37108 -381.708602)
			(xy 310.370728 -381.68453) (xy 310.371214 -381.657279) (xy 310.37897 -381.603331) (xy 310.394325 -381.551036)
			(xy 310.416967 -381.501459) (xy 310.446433 -381.455609) (xy 310.482124 -381.414418) (xy 310.523315 -381.378727)
			(xy 310.569165 -381.349261) (xy 310.618742 -381.326619) (xy 310.671037 -381.311264) (xy 310.724985 -381.303508)
			(xy 310.779487 -381.303508) (xy 310.833435 -381.311264) (xy 310.88573 -381.326619) (xy 310.935307 -381.349261)
			(xy 310.981157 -381.378727) (xy 311.022348 -381.414418) (xy 311.058039 -381.455609) (xy 311.087505 -381.501459)
			(xy 311.110147 -381.551036) (xy 311.125502 -381.603331) (xy 311.133258 -381.657279) (xy 311.133744 -381.68453)
			(xy 311.133053 -381.717062) (xy 311.121943 -381.781171) (xy 311.111646 -381.812038) (xy 311.108598 -381.820674)
			(xy 311.108852 -381.838454) (xy 311.138316 -381.91694) (xy 311.149746 -381.930148) (xy 311.157874 -381.93472)
			(xy 311.190132 -381.954532) (xy 311.196533 -381.958573) (xy 311.211013 -381.962965) (xy 311.21858 -381.963168)
			(xy 311.500012 -381.963168) (xy 311.507565 -381.96287) (xy 311.522023 -381.958492) (xy 311.52846 -381.954532)
			(xy 311.560718 -381.93472) (xy 311.568846 -381.930148) (xy 311.580276 -381.91694) (xy 311.60974 -381.838454)
			(xy 311.609994 -381.820674) (xy 311.606946 -381.812038) (xy 311.596653 -381.78117) (xy 311.585548 -381.717061)
			(xy 311.584848 -381.68453) (xy 311.585334 -381.657279) (xy 311.59309 -381.603331) (xy 311.608445 -381.551036)
			(xy 311.631087 -381.501459) (xy 311.660553 -381.455609) (xy 311.696244 -381.414418) (xy 311.737435 -381.378727)
			(xy 311.783285 -381.349261) (xy 311.832862 -381.326619) (xy 311.885157 -381.311264) (xy 311.939105 -381.303508)
			(xy 311.993607 -381.303508) (xy 312.047555 -381.311264) (xy 312.09985 -381.326619) (xy 312.149427 -381.349261)
			(xy 312.195277 -381.378727) (xy 312.236468 -381.414418) (xy 312.272159 -381.455609) (xy 312.301625 -381.501459)
			(xy 312.324267 -381.551036) (xy 312.339622 -381.603331) (xy 312.347378 -381.657279) (xy 312.347864 -381.68453)
			(xy 312.347502 -381.708601) (xy 312.341465 -381.756364) (xy 312.329476 -381.80299) (xy 312.32094 -381.8255)
			(xy 312.31586 -381.837946) (xy 312.319162 -381.863854) (xy 312.385964 -381.954532) (xy 312.409586 -381.965454)
			(xy 312.422794 -381.964438) (xy 312.451496 -381.963422) (xy 312.478751 -381.963825) (xy 312.532707 -381.971582)
			(xy 312.585009 -381.986939) (xy 312.634594 -382.009583) (xy 312.680451 -382.039053) (xy 312.721648 -382.074749)
			(xy 312.757345 -382.115946) (xy 312.786815 -382.161803) (xy 312.80946 -382.211387) (xy 312.824817 -382.263689)
			(xy 312.832575 -382.317645) (xy 312.832575 -382.372149) (xy 316.693308 -382.372149) (xy 316.693308 -382.317651)
			(xy 316.701064 -382.263708) (xy 316.716418 -382.211418) (xy 316.739057 -382.161845) (xy 316.76852 -382.115998)
			(xy 316.804209 -382.074811) (xy 316.845395 -382.039123) (xy 316.891241 -382.009659) (xy 316.940814 -381.987019)
			(xy 316.993104 -381.971665) (xy 317.047047 -381.963908) (xy 317.074296 -381.963422) (xy 317.102998 -381.964438)
			(xy 317.116206 -381.965454) (xy 317.139828 -381.954532) (xy 317.20663 -381.863854) (xy 317.209932 -381.837946)
			(xy 317.204852 -381.8255) (xy 317.196317 -381.802989) (xy 317.184313 -381.756366) (xy 317.17828 -381.708602)
			(xy 317.177928 -381.68453) (xy 317.178414 -381.657279) (xy 317.18617 -381.603331) (xy 317.201525 -381.551036)
			(xy 317.224167 -381.501459) (xy 317.253633 -381.455609) (xy 317.289324 -381.414418) (xy 317.330515 -381.378727)
			(xy 317.376365 -381.349261) (xy 317.425942 -381.326619) (xy 317.478237 -381.311264) (xy 317.532185 -381.303508)
			(xy 317.586687 -381.303508) (xy 317.640635 -381.311264) (xy 317.69293 -381.326619) (xy 317.742507 -381.349261)
			(xy 317.788357 -381.378727) (xy 317.829548 -381.414418) (xy 317.865239 -381.455609) (xy 317.894705 -381.501459)
			(xy 317.917347 -381.551036) (xy 317.932702 -381.603331) (xy 317.940458 -381.657279) (xy 317.940944 -381.68453)
			(xy 317.940253 -381.717062) (xy 317.929143 -381.781171) (xy 317.918846 -381.812038) (xy 317.915798 -381.820674)
			(xy 317.916052 -381.838454) (xy 317.945516 -381.91694) (xy 317.956946 -381.930148) (xy 317.965074 -381.93472)
			(xy 317.997332 -381.954532) (xy 318.003733 -381.958573) (xy 318.018213 -381.962965) (xy 318.02578 -381.963168)
			(xy 318.307212 -381.963168) (xy 318.314765 -381.96287) (xy 318.329223 -381.958492) (xy 318.33566 -381.954532)
			(xy 318.367918 -381.93472) (xy 318.376046 -381.930148) (xy 318.387476 -381.91694) (xy 318.41694 -381.838454)
			(xy 318.417194 -381.820674) (xy 318.414146 -381.812038) (xy 318.403853 -381.78117) (xy 318.392748 -381.717061)
			(xy 318.392048 -381.68453) (xy 318.392534 -381.657279) (xy 318.40029 -381.603331) (xy 318.415645 -381.551036)
			(xy 318.438287 -381.501459) (xy 318.467753 -381.455609) (xy 318.503444 -381.414418) (xy 318.544635 -381.378727)
			(xy 318.590485 -381.349261) (xy 318.640062 -381.326619) (xy 318.692357 -381.311264) (xy 318.746305 -381.303508)
			(xy 318.800807 -381.303508) (xy 318.854755 -381.311264) (xy 318.90705 -381.326619) (xy 318.956627 -381.349261)
			(xy 319.002477 -381.378727) (xy 319.043668 -381.414418) (xy 319.079359 -381.455609) (xy 319.108825 -381.501459)
			(xy 319.131467 -381.551036) (xy 319.146822 -381.603331) (xy 319.154578 -381.657279) (xy 319.155064 -381.68453)
			(xy 319.154702 -381.708601) (xy 319.148665 -381.756364) (xy 319.136676 -381.80299) (xy 319.12814 -381.8255)
			(xy 319.12306 -381.837946) (xy 319.126362 -381.863854) (xy 319.193164 -381.954532) (xy 319.216786 -381.965454)
			(xy 319.229994 -381.964438) (xy 319.258696 -381.963422) (xy 319.285951 -381.963825) (xy 319.339907 -381.971582)
			(xy 319.392209 -381.986939) (xy 319.441794 -382.009583) (xy 319.487651 -382.039053) (xy 319.528848 -382.074749)
			(xy 319.564545 -382.115946) (xy 319.594015 -382.161803) (xy 319.61666 -382.211387) (xy 319.632017 -382.263689)
			(xy 319.639775 -382.317645) (xy 319.639775 -382.372153) (xy 335.606585 -382.372153) (xy 335.606585 -382.317647)
			(xy 335.614343 -382.263697) (xy 335.6297 -382.211399) (xy 335.652344 -382.16182) (xy 335.681814 -382.115969)
			(xy 335.717509 -382.074778) (xy 335.758704 -382.039087) (xy 335.804559 -382.009623) (xy 335.854141 -381.986985)
			(xy 335.90644 -381.971634) (xy 335.960391 -381.963882) (xy 335.987644 -381.963422) (xy 336.016346 -381.964438)
			(xy 336.029554 -381.965454) (xy 336.053176 -381.954532) (xy 336.119978 -381.863854) (xy 336.12328 -381.837946)
			(xy 336.1182 -381.8255) (xy 336.109667 -381.802988) (xy 336.097662 -381.756366) (xy 336.091628 -381.708602)
			(xy 336.091276 -381.68453) (xy 336.091762 -381.657279) (xy 336.099518 -381.603331) (xy 336.114873 -381.551036)
			(xy 336.137515 -381.501459) (xy 336.166981 -381.455609) (xy 336.202672 -381.414418) (xy 336.243863 -381.378727)
			(xy 336.289713 -381.349261) (xy 336.33929 -381.326619) (xy 336.391585 -381.311264) (xy 336.445533 -381.303508)
			(xy 336.500035 -381.303508) (xy 336.553983 -381.311264) (xy 336.606278 -381.326619) (xy 336.655855 -381.349261)
			(xy 336.701705 -381.378727) (xy 336.742896 -381.414418) (xy 336.778587 -381.455609) (xy 336.808053 -381.501459)
			(xy 336.830695 -381.551036) (xy 336.84605 -381.603331) (xy 336.853806 -381.657279) (xy 336.854292 -381.68453)
			(xy 336.853603 -381.717062) (xy 336.842492 -381.781171) (xy 336.832194 -381.812038) (xy 336.829146 -381.820674)
			(xy 336.8294 -381.838454) (xy 336.858864 -381.91694) (xy 336.870294 -381.930148) (xy 336.878422 -381.93472)
			(xy 336.91068 -381.954532) (xy 336.917071 -381.958591) (xy 336.931558 -381.962972) (xy 336.939128 -381.963168)
			(xy 337.22056 -381.963168) (xy 337.228114 -381.96289) (xy 337.242572 -381.958498) (xy 337.249008 -381.954532)
			(xy 337.281266 -381.93472) (xy 337.289394 -381.930148) (xy 337.300824 -381.91694) (xy 337.330288 -381.838454)
			(xy 337.330542 -381.820674) (xy 337.327494 -381.812038) (xy 337.317199 -381.781171) (xy 337.306095 -381.717061)
			(xy 337.305396 -381.68453) (xy 337.305882 -381.657279) (xy 337.313638 -381.603331) (xy 337.328993 -381.551036)
			(xy 337.351635 -381.501459) (xy 337.381101 -381.455609) (xy 337.416792 -381.414418) (xy 337.457983 -381.378727)
			(xy 337.503833 -381.349261) (xy 337.55341 -381.326619) (xy 337.605705 -381.311264) (xy 337.659653 -381.303508)
			(xy 337.714155 -381.303508) (xy 337.768103 -381.311264) (xy 337.820398 -381.326619) (xy 337.869975 -381.349261)
			(xy 337.915825 -381.378727) (xy 337.957016 -381.414418) (xy 337.992707 -381.455609) (xy 338.022173 -381.501459)
			(xy 338.044815 -381.551036) (xy 338.06017 -381.603331) (xy 338.067926 -381.657279) (xy 338.068412 -381.68453)
			(xy 338.068054 -381.708602) (xy 338.062015 -381.756364) (xy 338.050025 -381.80299) (xy 338.041488 -381.8255)
			(xy 338.036408 -381.837946) (xy 338.03971 -381.863854) (xy 338.106512 -381.954532) (xy 338.130134 -381.965454)
			(xy 338.143342 -381.964438) (xy 338.172044 -381.963422) (xy 338.199295 -381.963851) (xy 338.253243 -381.971613)
			(xy 338.305536 -381.986973) (xy 338.355112 -382.009619) (xy 338.40096 -382.039088) (xy 338.442148 -382.074783)
			(xy 338.477838 -382.115975) (xy 338.507302 -382.161827) (xy 338.529942 -382.211405) (xy 338.545296 -382.263701)
			(xy 338.553052 -382.317649) (xy 338.553052 -382.372151) (xy 338.553052 -382.372153) (xy 342.413785 -382.372153)
			(xy 342.413785 -382.317647) (xy 342.421543 -382.263697) (xy 342.4369 -382.211399) (xy 342.459544 -382.16182)
			(xy 342.489014 -382.115969) (xy 342.524709 -382.074778) (xy 342.565904 -382.039087) (xy 342.611759 -382.009623)
			(xy 342.661341 -381.986985) (xy 342.71364 -381.971634) (xy 342.767591 -381.963882) (xy 342.794844 -381.963422)
			(xy 342.823546 -381.964438) (xy 342.836754 -381.965454) (xy 342.860376 -381.954532) (xy 342.927178 -381.863854)
			(xy 342.93048 -381.837946) (xy 342.9254 -381.8255) (xy 342.916867 -381.802988) (xy 342.904862 -381.756366)
			(xy 342.898828 -381.708602) (xy 342.898476 -381.68453) (xy 342.898962 -381.657279) (xy 342.906718 -381.603331)
			(xy 342.922073 -381.551036) (xy 342.944715 -381.501459) (xy 342.974181 -381.455609) (xy 343.009872 -381.414418)
			(xy 343.051063 -381.378727) (xy 343.096913 -381.349261) (xy 343.14649 -381.326619) (xy 343.198785 -381.311264)
			(xy 343.252733 -381.303508) (xy 343.307235 -381.303508) (xy 343.361183 -381.311264) (xy 343.413478 -381.326619)
			(xy 343.463055 -381.349261) (xy 343.508905 -381.378727) (xy 343.550096 -381.414418) (xy 343.585787 -381.455609)
			(xy 343.615253 -381.501459) (xy 343.637895 -381.551036) (xy 343.65325 -381.603331) (xy 343.661006 -381.657279)
			(xy 343.661492 -381.68453) (xy 343.660803 -381.717062) (xy 343.649692 -381.781171) (xy 343.639394 -381.812038)
			(xy 343.636346 -381.820674) (xy 343.6366 -381.838454) (xy 343.666064 -381.91694) (xy 343.677494 -381.930148)
			(xy 343.685622 -381.93472) (xy 343.71788 -381.954532) (xy 343.724271 -381.958591) (xy 343.738758 -381.962972)
			(xy 343.746328 -381.963168) (xy 344.02776 -381.963168) (xy 344.035314 -381.96289) (xy 344.049772 -381.958498)
			(xy 344.056208 -381.954532) (xy 344.088466 -381.93472) (xy 344.096594 -381.930148) (xy 344.108024 -381.91694)
			(xy 344.137488 -381.838454) (xy 344.137742 -381.820674) (xy 344.134694 -381.812038) (xy 344.124399 -381.781171)
			(xy 344.113295 -381.717061) (xy 344.112596 -381.68453) (xy 344.113082 -381.657279) (xy 344.120838 -381.603331)
			(xy 344.136193 -381.551036) (xy 344.158835 -381.501459) (xy 344.188301 -381.455609) (xy 344.223992 -381.414418)
			(xy 344.265183 -381.378727) (xy 344.311033 -381.349261) (xy 344.36061 -381.326619) (xy 344.412905 -381.311264)
			(xy 344.466853 -381.303508) (xy 344.521355 -381.303508) (xy 344.575303 -381.311264) (xy 344.627598 -381.326619)
			(xy 344.677175 -381.349261) (xy 344.723025 -381.378727) (xy 344.764216 -381.414418) (xy 344.799907 -381.455609)
			(xy 344.829373 -381.501459) (xy 344.852015 -381.551036) (xy 344.86737 -381.603331) (xy 344.875126 -381.657279)
			(xy 344.875612 -381.68453) (xy 344.875254 -381.708602) (xy 344.869215 -381.756364) (xy 344.857225 -381.80299)
			(xy 344.848688 -381.8255) (xy 344.843608 -381.837946) (xy 344.84691 -381.863854) (xy 344.913712 -381.954532)
			(xy 344.937334 -381.965454) (xy 344.950542 -381.964438) (xy 344.979244 -381.963422) (xy 345.006495 -381.963851)
			(xy 345.060443 -381.971613) (xy 345.112736 -381.986973) (xy 345.162312 -382.009619) (xy 345.20816 -382.039088)
			(xy 345.249348 -382.074783) (xy 345.285038 -382.115975) (xy 345.314502 -382.161827) (xy 345.337142 -382.211405)
			(xy 345.352496 -382.263701) (xy 345.360252 -382.317649) (xy 345.360252 -382.372151) (xy 345.360252 -382.372153)
			(xy 349.220985 -382.372153) (xy 349.220985 -382.317647) (xy 349.228743 -382.263697) (xy 349.2441 -382.211399)
			(xy 349.266744 -382.16182) (xy 349.296214 -382.115969) (xy 349.331909 -382.074778) (xy 349.373104 -382.039087)
			(xy 349.418959 -382.009623) (xy 349.468541 -381.986985) (xy 349.52084 -381.971634) (xy 349.574791 -381.963882)
			(xy 349.602044 -381.963422) (xy 349.630746 -381.964438) (xy 349.643954 -381.965454) (xy 349.667576 -381.954532)
			(xy 349.734378 -381.863854) (xy 349.73768 -381.837946) (xy 349.7326 -381.8255) (xy 349.724067 -381.802988)
			(xy 349.712062 -381.756366) (xy 349.706028 -381.708602) (xy 349.705676 -381.68453) (xy 349.706162 -381.657279)
			(xy 349.713918 -381.603331) (xy 349.729273 -381.551036) (xy 349.751915 -381.501459) (xy 349.781381 -381.455609)
			(xy 349.817072 -381.414418) (xy 349.858263 -381.378727) (xy 349.904113 -381.349261) (xy 349.95369 -381.326619)
			(xy 350.005985 -381.311264) (xy 350.059933 -381.303508) (xy 350.114435 -381.303508) (xy 350.168383 -381.311264)
			(xy 350.220678 -381.326619) (xy 350.270255 -381.349261) (xy 350.316105 -381.378727) (xy 350.357296 -381.414418)
			(xy 350.392987 -381.455609) (xy 350.422453 -381.501459) (xy 350.445095 -381.551036) (xy 350.46045 -381.603331)
			(xy 350.468206 -381.657279) (xy 350.468692 -381.68453) (xy 350.468003 -381.717062) (xy 350.456892 -381.781171)
			(xy 350.446594 -381.812038) (xy 350.443546 -381.820674) (xy 350.4438 -381.838454) (xy 350.473264 -381.91694)
			(xy 350.484694 -381.930148) (xy 350.492822 -381.93472) (xy 350.52508 -381.954532) (xy 350.531471 -381.958591)
			(xy 350.545958 -381.962972) (xy 350.553528 -381.963168) (xy 350.83496 -381.963168) (xy 350.842514 -381.96289)
			(xy 350.856972 -381.958498) (xy 350.863408 -381.954532) (xy 350.895666 -381.93472) (xy 350.903794 -381.930148)
			(xy 350.915224 -381.91694) (xy 350.944688 -381.838454) (xy 350.944942 -381.820674) (xy 350.941894 -381.812038)
			(xy 350.931599 -381.781171) (xy 350.920495 -381.717061) (xy 350.919796 -381.68453) (xy 350.920282 -381.657279)
			(xy 350.928038 -381.603331) (xy 350.943393 -381.551036) (xy 350.966035 -381.501459) (xy 350.995501 -381.455609)
			(xy 351.031192 -381.414418) (xy 351.072383 -381.378727) (xy 351.118233 -381.349261) (xy 351.16781 -381.326619)
			(xy 351.220105 -381.311264) (xy 351.274053 -381.303508) (xy 351.328555 -381.303508) (xy 351.382503 -381.311264)
			(xy 351.434798 -381.326619) (xy 351.484375 -381.349261) (xy 351.530225 -381.378727) (xy 351.571416 -381.414418)
			(xy 351.607107 -381.455609) (xy 351.636573 -381.501459) (xy 351.659215 -381.551036) (xy 351.67457 -381.603331)
			(xy 351.682326 -381.657279) (xy 351.682812 -381.68453) (xy 351.682454 -381.708602) (xy 351.676415 -381.756364)
			(xy 351.664425 -381.80299) (xy 351.655888 -381.8255) (xy 351.650808 -381.837946) (xy 351.65411 -381.863854)
			(xy 351.720912 -381.954532) (xy 351.744534 -381.965454) (xy 351.757742 -381.964438) (xy 351.786444 -381.963422)
			(xy 351.813695 -381.963851) (xy 351.867643 -381.971613) (xy 351.919936 -381.986973) (xy 351.969512 -382.009619)
			(xy 352.01536 -382.039088) (xy 352.056548 -382.074783) (xy 352.092238 -382.115975) (xy 352.121702 -382.161827)
			(xy 352.144342 -382.211405) (xy 352.159696 -382.263701) (xy 352.167452 -382.317649) (xy 352.167452 -382.372149)
			(xy 370.179108 -382.372149) (xy 370.179108 -382.317651) (xy 370.186864 -382.263709) (xy 370.202217 -382.211419)
			(xy 370.224856 -382.161846) (xy 370.254319 -382.116) (xy 370.290007 -382.074813) (xy 370.331193 -382.039124)
			(xy 370.377039 -382.00966) (xy 370.426611 -381.98702) (xy 370.478901 -381.971666) (xy 370.532843 -381.963909)
			(xy 370.560092 -381.963422) (xy 370.588794 -381.964438) (xy 370.602002 -381.965454) (xy 370.625624 -381.954532)
			(xy 370.692426 -381.863854) (xy 370.695728 -381.837946) (xy 370.690648 -381.8255) (xy 370.682113 -381.802989)
			(xy 370.670109 -381.756366) (xy 370.664076 -381.708602) (xy 370.663724 -381.68453) (xy 370.66421 -381.657279)
			(xy 370.671966 -381.603331) (xy 370.687321 -381.551036) (xy 370.709963 -381.501459) (xy 370.739429 -381.455609)
			(xy 370.77512 -381.414418) (xy 370.816311 -381.378727) (xy 370.862161 -381.349261) (xy 370.911738 -381.326619)
			(xy 370.964033 -381.311264) (xy 371.017981 -381.303508) (xy 371.072483 -381.303508) (xy 371.126431 -381.311264)
			(xy 371.178726 -381.326619) (xy 371.228303 -381.349261) (xy 371.274153 -381.378727) (xy 371.315344 -381.414418)
			(xy 371.351035 -381.455609) (xy 371.380501 -381.501459) (xy 371.403143 -381.551036) (xy 371.418498 -381.603331)
			(xy 371.426254 -381.657279) (xy 371.42674 -381.68453) (xy 371.426049 -381.717062) (xy 371.414939 -381.781171)
			(xy 371.404642 -381.812038) (xy 371.401594 -381.820674) (xy 371.401848 -381.838454) (xy 371.431312 -381.91694)
			(xy 371.442742 -381.930148) (xy 371.45087 -381.93472) (xy 371.483128 -381.954532) (xy 371.48953 -381.958571)
			(xy 371.504009 -381.962964) (xy 371.511576 -381.963168) (xy 371.793008 -381.963168) (xy 371.80056 -381.962868)
			(xy 371.815018 -381.958491) (xy 371.821456 -381.954532) (xy 371.853714 -381.93472) (xy 371.861842 -381.930148)
			(xy 371.873272 -381.91694) (xy 371.902736 -381.838454) (xy 371.90299 -381.820674) (xy 371.899942 -381.812038)
			(xy 371.889649 -381.78117) (xy 371.878544 -381.717061) (xy 371.877844 -381.68453) (xy 371.87833 -381.657279)
			(xy 371.886086 -381.603331) (xy 371.901441 -381.551036) (xy 371.924083 -381.501459) (xy 371.953549 -381.455609)
			(xy 371.98924 -381.414418) (xy 372.030431 -381.378727) (xy 372.076281 -381.349261) (xy 372.125858 -381.326619)
			(xy 372.178153 -381.311264) (xy 372.232101 -381.303508) (xy 372.286603 -381.303508) (xy 372.340551 -381.311264)
			(xy 372.392846 -381.326619) (xy 372.442423 -381.349261) (xy 372.488273 -381.378727) (xy 372.529464 -381.414418)
			(xy 372.565155 -381.455609) (xy 372.594621 -381.501459) (xy 372.617263 -381.551036) (xy 372.632618 -381.603331)
			(xy 372.640374 -381.657279) (xy 372.64086 -381.68453) (xy 372.640499 -381.708601) (xy 372.634461 -381.756364)
			(xy 372.622472 -381.80299) (xy 372.613936 -381.8255) (xy 372.608856 -381.837946) (xy 372.612158 -381.863854)
			(xy 372.67896 -381.954532) (xy 372.702582 -381.965454) (xy 372.71579 -381.964438) (xy 372.744492 -381.963422)
			(xy 372.771747 -381.963824) (xy 372.825703 -381.971581) (xy 372.878006 -381.986938) (xy 372.927592 -382.009581)
			(xy 372.973449 -382.039052) (xy 373.014646 -382.074748) (xy 373.050344 -382.115944) (xy 373.079815 -382.161801)
			(xy 373.10246 -382.211386) (xy 373.117817 -382.263689) (xy 373.125575 -382.317645) (xy 373.125575 -382.372149)
			(xy 376.986308 -382.372149) (xy 376.986308 -382.317651) (xy 376.994064 -382.263709) (xy 377.009417 -382.211419)
			(xy 377.032056 -382.161846) (xy 377.061519 -382.116) (xy 377.097207 -382.074813) (xy 377.138393 -382.039124)
			(xy 377.184239 -382.00966) (xy 377.233811 -381.98702) (xy 377.286101 -381.971666) (xy 377.340043 -381.963909)
			(xy 377.367292 -381.963422) (xy 377.395994 -381.964438) (xy 377.409202 -381.965454) (xy 377.432824 -381.954532)
			(xy 377.499626 -381.863854) (xy 377.502928 -381.837946) (xy 377.497848 -381.8255) (xy 377.489313 -381.802989)
			(xy 377.477309 -381.756366) (xy 377.471276 -381.708602) (xy 377.470924 -381.68453) (xy 377.47141 -381.657279)
			(xy 377.479166 -381.603331) (xy 377.494521 -381.551036) (xy 377.517163 -381.501459) (xy 377.546629 -381.455609)
			(xy 377.58232 -381.414418) (xy 377.623511 -381.378727) (xy 377.669361 -381.349261) (xy 377.718938 -381.326619)
			(xy 377.771233 -381.311264) (xy 377.825181 -381.303508) (xy 377.879683 -381.303508) (xy 377.933631 -381.311264)
			(xy 377.985926 -381.326619) (xy 378.035503 -381.349261) (xy 378.081353 -381.378727) (xy 378.122544 -381.414418)
			(xy 378.158235 -381.455609) (xy 378.187701 -381.501459) (xy 378.210343 -381.551036) (xy 378.225698 -381.603331)
			(xy 378.233454 -381.657279) (xy 378.23394 -381.68453) (xy 378.233249 -381.717062) (xy 378.222139 -381.781171)
			(xy 378.211842 -381.812038) (xy 378.208794 -381.820674) (xy 378.209048 -381.838454) (xy 378.238512 -381.91694)
			(xy 378.249942 -381.930148) (xy 378.25807 -381.93472) (xy 378.290328 -381.954532) (xy 378.29673 -381.958571)
			(xy 378.311209 -381.962964) (xy 378.318776 -381.963168) (xy 378.600208 -381.963168) (xy 378.60776 -381.962868)
			(xy 378.622218 -381.958491) (xy 378.628656 -381.954532) (xy 378.660914 -381.93472) (xy 378.669042 -381.930148)
			(xy 378.680472 -381.91694) (xy 378.709936 -381.838454) (xy 378.71019 -381.820674) (xy 378.707142 -381.812038)
			(xy 378.696849 -381.78117) (xy 378.685744 -381.717061) (xy 378.685044 -381.68453) (xy 378.68553 -381.657279)
			(xy 378.693286 -381.603331) (xy 378.708641 -381.551036) (xy 378.731283 -381.501459) (xy 378.760749 -381.455609)
			(xy 378.79644 -381.414418) (xy 378.837631 -381.378727) (xy 378.883481 -381.349261) (xy 378.933058 -381.326619)
			(xy 378.985353 -381.311264) (xy 379.039301 -381.303508) (xy 379.093803 -381.303508) (xy 379.147751 -381.311264)
			(xy 379.200046 -381.326619) (xy 379.249623 -381.349261) (xy 379.295473 -381.378727) (xy 379.336664 -381.414418)
			(xy 379.372355 -381.455609) (xy 379.401821 -381.501459) (xy 379.424463 -381.551036) (xy 379.439818 -381.603331)
			(xy 379.447574 -381.657279) (xy 379.44806 -381.68453) (xy 379.447699 -381.708601) (xy 379.441661 -381.756364)
			(xy 379.429672 -381.80299) (xy 379.421136 -381.8255) (xy 379.416056 -381.837946) (xy 379.419358 -381.863854)
			(xy 379.48616 -381.954532) (xy 379.509782 -381.965454) (xy 379.52299 -381.964438) (xy 379.551692 -381.963422)
			(xy 379.578947 -381.963824) (xy 379.632903 -381.971581) (xy 379.685206 -381.986938) (xy 379.734792 -382.009581)
			(xy 379.780649 -382.039052) (xy 379.821846 -382.074748) (xy 379.857544 -382.115944) (xy 379.887015 -382.161801)
			(xy 379.90966 -382.211386) (xy 379.925017 -382.263689) (xy 379.932775 -382.317645) (xy 379.932775 -382.372149)
			(xy 383.793508 -382.372149) (xy 383.793508 -382.317651) (xy 383.801264 -382.263709) (xy 383.816617 -382.211419)
			(xy 383.839256 -382.161846) (xy 383.868719 -382.116) (xy 383.904407 -382.074813) (xy 383.945593 -382.039124)
			(xy 383.991439 -382.00966) (xy 384.041011 -381.98702) (xy 384.093301 -381.971666) (xy 384.147243 -381.963909)
			(xy 384.174492 -381.963422) (xy 384.203194 -381.964438) (xy 384.216402 -381.965454) (xy 384.240024 -381.954532)
			(xy 384.306826 -381.863854) (xy 384.310128 -381.837946) (xy 384.305048 -381.8255) (xy 384.296513 -381.802989)
			(xy 384.284509 -381.756366) (xy 384.278476 -381.708602) (xy 384.278124 -381.68453) (xy 384.27861 -381.657279)
			(xy 384.286366 -381.603331) (xy 384.301721 -381.551036) (xy 384.324363 -381.501459) (xy 384.353829 -381.455609)
			(xy 384.38952 -381.414418) (xy 384.430711 -381.378727) (xy 384.476561 -381.349261) (xy 384.526138 -381.326619)
			(xy 384.578433 -381.311264) (xy 384.632381 -381.303508) (xy 384.686883 -381.303508) (xy 384.740831 -381.311264)
			(xy 384.793126 -381.326619) (xy 384.842703 -381.349261) (xy 384.888553 -381.378727) (xy 384.929744 -381.414418)
			(xy 384.965435 -381.455609) (xy 384.994901 -381.501459) (xy 385.017543 -381.551036) (xy 385.032898 -381.603331)
			(xy 385.040654 -381.657279) (xy 385.04114 -381.68453) (xy 385.040449 -381.717062) (xy 385.029339 -381.781171)
			(xy 385.019042 -381.812038) (xy 385.015994 -381.820674) (xy 385.016248 -381.838454) (xy 385.045712 -381.91694)
			(xy 385.057142 -381.930148) (xy 385.06527 -381.93472) (xy 385.097528 -381.954532) (xy 385.10393 -381.958571)
			(xy 385.118409 -381.962964) (xy 385.125976 -381.963168) (xy 385.407408 -381.963168) (xy 385.41496 -381.962868)
			(xy 385.429418 -381.958491) (xy 385.435856 -381.954532) (xy 385.468114 -381.93472) (xy 385.476242 -381.930148)
			(xy 385.487672 -381.91694) (xy 385.517136 -381.838454) (xy 385.51739 -381.820674) (xy 385.514342 -381.812038)
			(xy 385.504049 -381.78117) (xy 385.492944 -381.717061) (xy 385.492244 -381.68453) (xy 385.49273 -381.657279)
			(xy 385.500486 -381.603331) (xy 385.515841 -381.551036) (xy 385.538483 -381.501459) (xy 385.567949 -381.455609)
			(xy 385.60364 -381.414418) (xy 385.644831 -381.378727) (xy 385.690681 -381.349261) (xy 385.740258 -381.326619)
			(xy 385.792553 -381.311264) (xy 385.846501 -381.303508) (xy 385.901003 -381.303508) (xy 385.954951 -381.311264)
			(xy 386.007246 -381.326619) (xy 386.056823 -381.349261) (xy 386.102673 -381.378727) (xy 386.143864 -381.414418)
			(xy 386.179555 -381.455609) (xy 386.209021 -381.501459) (xy 386.231663 -381.551036) (xy 386.247018 -381.603331)
			(xy 386.254774 -381.657279) (xy 386.25526 -381.68453) (xy 386.254899 -381.708601) (xy 386.248861 -381.756364)
			(xy 386.236872 -381.80299) (xy 386.228336 -381.8255) (xy 386.223256 -381.837946) (xy 386.226558 -381.863854)
			(xy 386.29336 -381.954532) (xy 386.316982 -381.965454) (xy 386.33019 -381.964438) (xy 386.358892 -381.963422)
			(xy 386.386147 -381.963824) (xy 386.440103 -381.971581) (xy 386.492406 -381.986938) (xy 386.541992 -382.009581)
			(xy 386.587849 -382.039052) (xy 386.629046 -382.074748) (xy 386.664744 -382.115944) (xy 386.694215 -382.161801)
			(xy 386.71686 -382.211386) (xy 386.732217 -382.263689) (xy 386.739975 -382.317645) (xy 386.739975 -382.372144)
			(xy 387.197108 -382.372144) (xy 387.197108 -382.317647) (xy 387.204865 -382.263705) (xy 387.220219 -382.211415)
			(xy 387.242858 -382.161843) (xy 387.272321 -382.115997) (xy 387.308009 -382.074811) (xy 387.349195 -382.039123)
			(xy 387.39504 -382.009659) (xy 387.444612 -381.98702) (xy 387.496901 -381.971665) (xy 387.550844 -381.963909)
			(xy 387.578092 -381.963422) (xy 387.606794 -381.964438) (xy 387.621505 -381.96507) (xy 387.650258 -381.958761)
			(xy 387.676021 -381.944521) (xy 387.696658 -381.92353) (xy 387.710459 -381.897529) (xy 387.716279 -381.868674)
			(xy 387.713636 -381.839356) (xy 387.708648 -381.8255) (xy 387.700113 -381.802989) (xy 387.688109 -381.756366)
			(xy 387.682076 -381.708602) (xy 387.681724 -381.68453) (xy 387.682146 -381.657277) (xy 387.689899 -381.603324)
			(xy 387.705251 -381.551024) (xy 387.72789 -381.501441) (xy 387.757355 -381.455585) (xy 387.793046 -381.414389)
			(xy 387.834236 -381.378691) (xy 387.880088 -381.349219) (xy 387.929667 -381.326572) (xy 387.981965 -381.311211)
			(xy 388.035916 -381.30345) (xy 388.090423 -381.303446) (xy 388.144375 -381.311198) (xy 388.196675 -381.326551)
			(xy 388.246258 -381.349189) (xy 388.292115 -381.378654) (xy 388.333311 -381.414345) (xy 388.369009 -381.455536)
			(xy 388.398481 -381.501387) (xy 388.421128 -381.550967) (xy 388.436488 -381.603264) (xy 388.44425 -381.657215)
			(xy 388.444254 -381.711722) (xy 388.436502 -381.765675) (xy 388.42115 -381.817975) (xy 388.398511 -381.867558)
			(xy 388.369046 -381.913414) (xy 388.333355 -381.95461) (xy 388.292165 -381.990308) (xy 388.246313 -382.019781)
			(xy 388.196734 -382.042428) (xy 388.144437 -382.057788) (xy 388.090485 -382.06555) (xy 388.063232 -382.066038)
			(xy 388.03453 -382.065022) (xy 388.019819 -382.064466) (xy 387.991076 -382.070766) (xy 387.96532 -382.084994)
			(xy 387.944686 -382.105972) (xy 387.930884 -382.131959) (xy 387.925059 -382.160801) (xy 387.927694 -382.190108)
			(xy 387.932676 -382.20396) (xy 387.94123 -382.226464) (xy 387.953227 -382.273091) (xy 387.959252 -382.320857)
			(xy 387.9596 -382.34493) (xy 387.95909 -382.372153) (xy 402.706785 -382.372153) (xy 402.706785 -382.317647)
			(xy 402.714543 -382.263697) (xy 402.7299 -382.2114) (xy 402.752543 -382.161821) (xy 402.782013 -382.11597)
			(xy 402.817708 -382.07478) (xy 402.858902 -382.039089) (xy 402.904757 -382.009624) (xy 402.954338 -381.986986)
			(xy 403.006636 -381.971634) (xy 403.060587 -381.963883) (xy 403.08784 -381.963422) (xy 403.116542 -381.964438)
			(xy 403.12975 -381.965454) (xy 403.153372 -381.954532) (xy 403.220174 -381.863854) (xy 403.223476 -381.837946)
			(xy 403.218396 -381.8255) (xy 403.209863 -381.802988) (xy 403.197858 -381.756366) (xy 403.191824 -381.708602)
			(xy 403.191472 -381.68453) (xy 403.191958 -381.657279) (xy 403.199714 -381.603331) (xy 403.215069 -381.551036)
			(xy 403.237711 -381.501459) (xy 403.267177 -381.455609) (xy 403.302868 -381.414418) (xy 403.344059 -381.378727)
			(xy 403.389909 -381.349261) (xy 403.439486 -381.326619) (xy 403.491781 -381.311264) (xy 403.545729 -381.303508)
			(xy 403.600231 -381.303508) (xy 403.654179 -381.311264) (xy 403.706474 -381.326619) (xy 403.756051 -381.349261)
			(xy 403.801901 -381.378727) (xy 403.843092 -381.414418) (xy 403.878783 -381.455609) (xy 403.908249 -381.501459)
			(xy 403.930891 -381.551036) (xy 403.946246 -381.603331) (xy 403.954002 -381.657279) (xy 403.954488 -381.68453)
			(xy 403.9538 -381.717062) (xy 403.942688 -381.781171) (xy 403.93239 -381.812038) (xy 403.929342 -381.820674)
			(xy 403.929596 -381.838454) (xy 403.95906 -381.91694) (xy 403.97049 -381.930148) (xy 403.978618 -381.93472)
			(xy 404.010876 -381.954532) (xy 404.017268 -381.95859) (xy 404.031755 -381.962971) (xy 404.039324 -381.963168)
			(xy 404.320756 -381.963168) (xy 404.32831 -381.962888) (xy 404.342768 -381.958498) (xy 404.349204 -381.954532)
			(xy 404.381462 -381.93472) (xy 404.38959 -381.930148) (xy 404.40102 -381.91694) (xy 404.430484 -381.838454)
			(xy 404.430738 -381.820674) (xy 404.42769 -381.812038) (xy 404.417395 -381.781171) (xy 404.406291 -381.717061)
			(xy 404.405592 -381.68453) (xy 404.406078 -381.657279) (xy 404.413834 -381.603331) (xy 404.429189 -381.551036)
			(xy 404.451831 -381.501459) (xy 404.481297 -381.455609) (xy 404.516988 -381.414418) (xy 404.558179 -381.378727)
			(xy 404.604029 -381.349261) (xy 404.653606 -381.326619) (xy 404.705901 -381.311264) (xy 404.759849 -381.303508)
			(xy 404.814351 -381.303508) (xy 404.868299 -381.311264) (xy 404.920594 -381.326619) (xy 404.970171 -381.349261)
			(xy 405.016021 -381.378727) (xy 405.057212 -381.414418) (xy 405.092903 -381.455609) (xy 405.122369 -381.501459)
			(xy 405.145011 -381.551036) (xy 405.160366 -381.603331) (xy 405.168122 -381.657279) (xy 405.168608 -381.68453)
			(xy 405.16825 -381.708602) (xy 405.162212 -381.756364) (xy 405.150221 -381.80299) (xy 405.141684 -381.8255)
			(xy 405.136604 -381.837946) (xy 405.139906 -381.863854) (xy 405.206708 -381.954532) (xy 405.23033 -381.965454)
			(xy 405.243538 -381.964438) (xy 405.27224 -381.963422) (xy 405.299492 -381.963851) (xy 405.353439 -381.971612)
			(xy 405.405733 -381.986972) (xy 405.455309 -382.009617) (xy 405.501158 -382.039087) (xy 405.542347 -382.074781)
			(xy 405.578037 -382.115974) (xy 405.607502 -382.161826) (xy 405.630142 -382.211404) (xy 405.645496 -382.2637)
			(xy 405.653252 -382.317648) (xy 405.653252 -382.372152) (xy 405.653252 -382.372153) (xy 409.513985 -382.372153)
			(xy 409.513985 -382.317647) (xy 409.521743 -382.263697) (xy 409.5371 -382.2114) (xy 409.559743 -382.161821)
			(xy 409.589213 -382.11597) (xy 409.624908 -382.07478) (xy 409.666102 -382.039089) (xy 409.711957 -382.009624)
			(xy 409.761538 -381.986986) (xy 409.813836 -381.971634) (xy 409.867787 -381.963883) (xy 409.89504 -381.963422)
			(xy 409.923742 -381.964438) (xy 409.93695 -381.965454) (xy 409.960572 -381.954532) (xy 410.027374 -381.863854)
			(xy 410.030676 -381.837946) (xy 410.025596 -381.8255) (xy 410.017063 -381.802988) (xy 410.005058 -381.756366)
			(xy 409.999024 -381.708602) (xy 409.998672 -381.68453) (xy 409.999158 -381.657279) (xy 410.006914 -381.603331)
			(xy 410.022269 -381.551036) (xy 410.044911 -381.501459) (xy 410.074377 -381.455609) (xy 410.110068 -381.414418)
			(xy 410.151259 -381.378727) (xy 410.197109 -381.349261) (xy 410.246686 -381.326619) (xy 410.298981 -381.311264)
			(xy 410.352929 -381.303508) (xy 410.407431 -381.303508) (xy 410.461379 -381.311264) (xy 410.513674 -381.326619)
			(xy 410.563251 -381.349261) (xy 410.609101 -381.378727) (xy 410.650292 -381.414418) (xy 410.685983 -381.455609)
			(xy 410.715449 -381.501459) (xy 410.738091 -381.551036) (xy 410.753446 -381.603331) (xy 410.761202 -381.657279)
			(xy 410.761688 -381.68453) (xy 410.761 -381.717062) (xy 410.749888 -381.781171) (xy 410.73959 -381.812038)
			(xy 410.736542 -381.820674) (xy 410.736796 -381.838454) (xy 410.76626 -381.91694) (xy 410.77769 -381.930148)
			(xy 410.785818 -381.93472) (xy 410.818076 -381.954532) (xy 410.824468 -381.95859) (xy 410.838955 -381.962971)
			(xy 410.846524 -381.963168) (xy 411.127956 -381.963168) (xy 411.13551 -381.962888) (xy 411.149968 -381.958498)
			(xy 411.156404 -381.954532) (xy 411.188662 -381.93472) (xy 411.19679 -381.930148) (xy 411.20822 -381.91694)
			(xy 411.237684 -381.838454) (xy 411.237938 -381.820674) (xy 411.23489 -381.812038) (xy 411.224595 -381.781171)
			(xy 411.213491 -381.717061) (xy 411.212792 -381.68453) (xy 411.213278 -381.657279) (xy 411.221034 -381.603331)
			(xy 411.236389 -381.551036) (xy 411.259031 -381.501459) (xy 411.288497 -381.455609) (xy 411.324188 -381.414418)
			(xy 411.365379 -381.378727) (xy 411.411229 -381.349261) (xy 411.460806 -381.326619) (xy 411.513101 -381.311264)
			(xy 411.567049 -381.303508) (xy 411.621551 -381.303508) (xy 411.675499 -381.311264) (xy 411.727794 -381.326619)
			(xy 411.777371 -381.349261) (xy 411.823221 -381.378727) (xy 411.864412 -381.414418) (xy 411.900103 -381.455609)
			(xy 411.929569 -381.501459) (xy 411.952211 -381.551036) (xy 411.967566 -381.603331) (xy 411.975322 -381.657279)
			(xy 411.975808 -381.68453) (xy 411.97545 -381.708602) (xy 411.969412 -381.756364) (xy 411.957421 -381.80299)
			(xy 411.948884 -381.8255) (xy 411.943804 -381.837946) (xy 411.947106 -381.863854) (xy 412.013908 -381.954532)
			(xy 412.03753 -381.965454) (xy 412.050738 -381.964438) (xy 412.07944 -381.963422) (xy 412.106692 -381.963851)
			(xy 412.160639 -381.971612) (xy 412.212933 -381.986972) (xy 412.262509 -382.009617) (xy 412.308358 -382.039087)
			(xy 412.349547 -382.074781) (xy 412.385237 -382.115974) (xy 412.414702 -382.161826) (xy 412.437342 -382.211404)
			(xy 412.452696 -382.2637) (xy 412.460452 -382.317648) (xy 412.460452 -382.372152) (xy 412.460452 -382.372153)
			(xy 416.321185 -382.372153) (xy 416.321185 -382.317647) (xy 416.328943 -382.263697) (xy 416.3443 -382.2114)
			(xy 416.366943 -382.161821) (xy 416.396413 -382.11597) (xy 416.432108 -382.07478) (xy 416.473302 -382.039089)
			(xy 416.519157 -382.009624) (xy 416.568738 -381.986986) (xy 416.621036 -381.971634) (xy 416.674987 -381.963883)
			(xy 416.70224 -381.963422) (xy 416.730942 -381.964438) (xy 416.74415 -381.965454) (xy 416.767772 -381.954532)
			(xy 416.834574 -381.863854) (xy 416.837876 -381.837946) (xy 416.832796 -381.8255) (xy 416.824263 -381.802988)
			(xy 416.812258 -381.756366) (xy 416.806224 -381.708602) (xy 416.805872 -381.68453) (xy 416.806358 -381.657279)
			(xy 416.814114 -381.603331) (xy 416.829469 -381.551036) (xy 416.852111 -381.501459) (xy 416.881577 -381.455609)
			(xy 416.917268 -381.414418) (xy 416.958459 -381.378727) (xy 417.004309 -381.349261) (xy 417.053886 -381.326619)
			(xy 417.106181 -381.311264) (xy 417.160129 -381.303508) (xy 417.214631 -381.303508) (xy 417.268579 -381.311264)
			(xy 417.320874 -381.326619) (xy 417.370451 -381.349261) (xy 417.416301 -381.378727) (xy 417.457492 -381.414418)
			(xy 417.493183 -381.455609) (xy 417.522649 -381.501459) (xy 417.545291 -381.551036) (xy 417.560646 -381.603331)
			(xy 417.568402 -381.657279) (xy 417.568888 -381.68453) (xy 417.5682 -381.717062) (xy 417.557088 -381.781171)
			(xy 417.54679 -381.812038) (xy 417.543742 -381.820674) (xy 417.543996 -381.838454) (xy 417.57346 -381.91694)
			(xy 417.58489 -381.930148) (xy 417.593018 -381.93472) (xy 417.625276 -381.954532) (xy 417.631668 -381.95859)
			(xy 417.646155 -381.962971) (xy 417.653724 -381.963168) (xy 417.935156 -381.963168) (xy 417.94271 -381.962888)
			(xy 417.957168 -381.958498) (xy 417.963604 -381.954532) (xy 417.995862 -381.93472) (xy 418.00399 -381.930148)
			(xy 418.01542 -381.91694) (xy 418.044884 -381.838454) (xy 418.045138 -381.820674) (xy 418.04209 -381.812038)
			(xy 418.031795 -381.781171) (xy 418.020691 -381.717061) (xy 418.019992 -381.68453) (xy 418.020478 -381.657279)
			(xy 418.028234 -381.603331) (xy 418.043589 -381.551036) (xy 418.066231 -381.501459) (xy 418.095697 -381.455609)
			(xy 418.131388 -381.414418) (xy 418.172579 -381.378727) (xy 418.218429 -381.349261) (xy 418.268006 -381.326619)
			(xy 418.320301 -381.311264) (xy 418.374249 -381.303508) (xy 418.428751 -381.303508) (xy 418.482699 -381.311264)
			(xy 418.534994 -381.326619) (xy 418.584571 -381.349261) (xy 418.630421 -381.378727) (xy 418.671612 -381.414418)
			(xy 418.707303 -381.455609) (xy 418.736769 -381.501459) (xy 418.759411 -381.551036) (xy 418.774766 -381.603331)
			(xy 418.782522 -381.657279) (xy 418.783008 -381.68453) (xy 418.78265 -381.708602) (xy 418.776612 -381.756364)
			(xy 418.764621 -381.80299) (xy 418.756084 -381.8255) (xy 418.751004 -381.837946) (xy 418.754306 -381.863854)
			(xy 418.821108 -381.954532) (xy 418.84473 -381.965454) (xy 418.857938 -381.964438) (xy 418.88664 -381.963422)
			(xy 418.913892 -381.963851) (xy 418.967839 -381.971612) (xy 419.020133 -381.986972) (xy 419.069709 -382.009617)
			(xy 419.115558 -382.039087) (xy 419.156747 -382.074781) (xy 419.192437 -382.115974) (xy 419.221902 -382.161826)
			(xy 419.244542 -382.211404) (xy 419.259896 -382.2637) (xy 419.267652 -382.317648) (xy 419.267652 -382.372152)
			(xy 419.259896 -382.4261) (xy 419.244542 -382.478396) (xy 419.221902 -382.527974) (xy 419.192437 -382.573826)
			(xy 419.156747 -382.615019) (xy 419.115558 -382.650713) (xy 419.069709 -382.680183) (xy 419.020133 -382.702828)
			(xy 418.967839 -382.718188) (xy 418.913892 -382.725949) (xy 418.88664 -382.726438) (xy 418.857938 -382.725422)
			(xy 418.84473 -382.724406) (xy 418.821108 -382.735328) (xy 418.754306 -382.826006) (xy 418.751004 -382.851914)
			(xy 418.756084 -382.86436) (xy 418.764633 -382.886866) (xy 418.776633 -382.933491) (xy 418.78266 -382.981257)
			(xy 418.783008 -383.00533) (xy 418.782522 -383.032581) (xy 418.774766 -383.086529) (xy 418.759411 -383.138824)
			(xy 418.736769 -383.188401) (xy 418.707303 -383.234251) (xy 418.671612 -383.275442) (xy 418.630421 -383.311133)
			(xy 418.584571 -383.340599) (xy 418.534994 -383.363241) (xy 418.482699 -383.378596) (xy 418.428751 -383.386352)
			(xy 418.374249 -383.386352) (xy 418.320301 -383.378596) (xy 418.268006 -383.363241) (xy 418.218429 -383.340599)
			(xy 418.172579 -383.311133) (xy 418.131388 -383.275442) (xy 418.095697 -383.234251) (xy 418.066231 -383.188401)
			(xy 418.043589 -383.138824) (xy 418.028234 -383.086529) (xy 418.020478 -383.032581) (xy 418.019992 -383.00533)
			(xy 418.020671 -382.972798) (xy 418.031789 -382.908688) (xy 418.04209 -382.877822) (xy 418.045138 -382.869186)
			(xy 418.044884 -382.851406) (xy 418.01542 -382.77292) (xy 418.00399 -382.759712) (xy 417.995862 -382.75514)
			(xy 417.963604 -382.735328) (xy 417.957192 -382.731306) (xy 417.942721 -382.726902) (xy 417.935156 -382.726692)
			(xy 417.653724 -382.726692) (xy 417.646168 -382.726955) (xy 417.63171 -382.731356) (xy 417.625276 -382.735328)
			(xy 417.593018 -382.75514) (xy 417.58489 -382.759712) (xy 417.57346 -382.77292) (xy 417.543996 -382.851406)
			(xy 417.543742 -382.869186) (xy 417.54679 -382.877822) (xy 417.557074 -382.908692) (xy 417.568185 -382.972799)
			(xy 417.568888 -383.00533) (xy 417.568402 -383.032581) (xy 417.560646 -383.086529) (xy 417.545291 -383.138824)
			(xy 417.522649 -383.188401) (xy 417.493183 -383.234251) (xy 417.457492 -383.275442) (xy 417.416301 -383.311133)
			(xy 417.370451 -383.340599) (xy 417.320874 -383.363241) (xy 417.268579 -383.378596) (xy 417.214631 -383.386352)
			(xy 417.160129 -383.386352) (xy 417.106181 -383.378596) (xy 417.053886 -383.363241) (xy 417.004309 -383.340599)
			(xy 416.958459 -383.311133) (xy 416.917268 -383.275442) (xy 416.881577 -383.234251) (xy 416.852111 -383.188401)
			(xy 416.829469 -383.138824) (xy 416.814114 -383.086529) (xy 416.806358 -383.032581) (xy 416.805872 -383.00533)
			(xy 416.806219 -382.981258) (xy 416.812262 -382.933495) (xy 416.824257 -382.886869) (xy 416.832796 -382.86436)
			(xy 416.837876 -382.851914) (xy 416.834574 -382.826006) (xy 416.767772 -382.735328) (xy 416.74415 -382.724406)
			(xy 416.730942 -382.725422) (xy 416.70224 -382.726438) (xy 416.674987 -382.725917) (xy 416.621036 -382.718166)
			(xy 416.568738 -382.702814) (xy 416.519157 -382.680176) (xy 416.473302 -382.650711) (xy 416.432108 -382.61502)
			(xy 416.396413 -382.57383) (xy 416.366943 -382.527979) (xy 416.3443 -382.4784) (xy 416.328943 -382.426103)
			(xy 416.321185 -382.372153) (xy 412.460452 -382.372153) (xy 412.452696 -382.4261) (xy 412.437342 -382.478396)
			(xy 412.414702 -382.527974) (xy 412.385237 -382.573826) (xy 412.349547 -382.615019) (xy 412.308358 -382.650713)
			(xy 412.262509 -382.680183) (xy 412.212933 -382.702828) (xy 412.160639 -382.718188) (xy 412.106692 -382.725949)
			(xy 412.07944 -382.726438) (xy 412.050738 -382.725422) (xy 412.03753 -382.724406) (xy 412.013908 -382.735328)
			(xy 411.947106 -382.826006) (xy 411.943804 -382.851914) (xy 411.948884 -382.86436) (xy 411.957433 -382.886866)
			(xy 411.969433 -382.933491) (xy 411.97546 -382.981257) (xy 411.975808 -383.00533) (xy 411.975322 -383.032581)
			(xy 411.967566 -383.086529) (xy 411.952211 -383.138824) (xy 411.929569 -383.188401) (xy 411.900103 -383.234251)
			(xy 411.864412 -383.275442) (xy 411.823221 -383.311133) (xy 411.777371 -383.340599) (xy 411.727794 -383.363241)
			(xy 411.675499 -383.378596) (xy 411.621551 -383.386352) (xy 411.567049 -383.386352) (xy 411.513101 -383.378596)
			(xy 411.460806 -383.363241) (xy 411.411229 -383.340599) (xy 411.365379 -383.311133) (xy 411.324188 -383.275442)
			(xy 411.288497 -383.234251) (xy 411.259031 -383.188401) (xy 411.236389 -383.138824) (xy 411.221034 -383.086529)
			(xy 411.213278 -383.032581) (xy 411.212792 -383.00533) (xy 411.213471 -382.972798) (xy 411.224589 -382.908688)
			(xy 411.23489 -382.877822) (xy 411.237938 -382.869186) (xy 411.237684 -382.851406) (xy 411.20822 -382.77292)
			(xy 411.19679 -382.759712) (xy 411.188662 -382.75514) (xy 411.156404 -382.735328) (xy 411.149992 -382.731306)
			(xy 411.135521 -382.726902) (xy 411.127956 -382.726692) (xy 410.846524 -382.726692) (xy 410.838968 -382.726955)
			(xy 410.82451 -382.731356) (xy 410.818076 -382.735328) (xy 410.785818 -382.75514) (xy 410.77769 -382.759712)
			(xy 410.76626 -382.77292) (xy 410.736796 -382.851406) (xy 410.736542 -382.869186) (xy 410.73959 -382.877822)
			(xy 410.749874 -382.908692) (xy 410.760985 -382.972799) (xy 410.761688 -383.00533) (xy 410.761202 -383.032581)
			(xy 410.753446 -383.086529) (xy 410.738091 -383.138824) (xy 410.715449 -383.188401) (xy 410.685983 -383.234251)
			(xy 410.650292 -383.275442) (xy 410.609101 -383.311133) (xy 410.563251 -383.340599) (xy 410.513674 -383.363241)
			(xy 410.461379 -383.378596) (xy 410.407431 -383.386352) (xy 410.352929 -383.386352) (xy 410.298981 -383.378596)
			(xy 410.246686 -383.363241) (xy 410.197109 -383.340599) (xy 410.151259 -383.311133) (xy 410.110068 -383.275442)
			(xy 410.074377 -383.234251) (xy 410.044911 -383.188401) (xy 410.022269 -383.138824) (xy 410.006914 -383.086529)
			(xy 409.999158 -383.032581) (xy 409.998672 -383.00533) (xy 409.999019 -382.981258) (xy 410.005062 -382.933495)
			(xy 410.017057 -382.886869) (xy 410.025596 -382.86436) (xy 410.030676 -382.851914) (xy 410.027374 -382.826006)
			(xy 409.960572 -382.735328) (xy 409.93695 -382.724406) (xy 409.923742 -382.725422) (xy 409.89504 -382.726438)
			(xy 409.867787 -382.725917) (xy 409.813836 -382.718166) (xy 409.761538 -382.702814) (xy 409.711957 -382.680176)
			(xy 409.666102 -382.650711) (xy 409.624908 -382.61502) (xy 409.589213 -382.57383) (xy 409.559743 -382.527979)
			(xy 409.5371 -382.4784) (xy 409.521743 -382.426103) (xy 409.513985 -382.372153) (xy 405.653252 -382.372153)
			(xy 405.645496 -382.4261) (xy 405.630142 -382.478396) (xy 405.607502 -382.527974) (xy 405.578037 -382.573826)
			(xy 405.542347 -382.615019) (xy 405.501158 -382.650713) (xy 405.455309 -382.680183) (xy 405.405733 -382.702828)
			(xy 405.353439 -382.718188) (xy 405.299492 -382.725949) (xy 405.27224 -382.726438) (xy 405.243538 -382.725422)
			(xy 405.23033 -382.724406) (xy 405.206708 -382.735328) (xy 405.139906 -382.826006) (xy 405.136604 -382.851914)
			(xy 405.141684 -382.86436) (xy 405.150233 -382.886866) (xy 405.162233 -382.933491) (xy 405.16826 -382.981257)
			(xy 405.168608 -383.00533) (xy 405.168122 -383.032581) (xy 405.160366 -383.086529) (xy 405.145011 -383.138824)
			(xy 405.122369 -383.188401) (xy 405.092903 -383.234251) (xy 405.057212 -383.275442) (xy 405.016021 -383.311133)
			(xy 404.970171 -383.340599) (xy 404.920594 -383.363241) (xy 404.868299 -383.378596) (xy 404.814351 -383.386352)
			(xy 404.759849 -383.386352) (xy 404.705901 -383.378596) (xy 404.653606 -383.363241) (xy 404.604029 -383.340599)
			(xy 404.558179 -383.311133) (xy 404.516988 -383.275442) (xy 404.481297 -383.234251) (xy 404.451831 -383.188401)
			(xy 404.429189 -383.138824) (xy 404.413834 -383.086529) (xy 404.406078 -383.032581) (xy 404.405592 -383.00533)
			(xy 404.406271 -382.972798) (xy 404.417389 -382.908688) (xy 404.42769 -382.877822) (xy 404.430738 -382.869186)
			(xy 404.430484 -382.851406) (xy 404.40102 -382.77292) (xy 404.38959 -382.759712) (xy 404.381462 -382.75514)
			(xy 404.349204 -382.735328) (xy 404.342792 -382.731306) (xy 404.328321 -382.726902) (xy 404.320756 -382.726692)
			(xy 404.039324 -382.726692) (xy 404.031768 -382.726955) (xy 404.01731 -382.731356) (xy 404.010876 -382.735328)
			(xy 403.978618 -382.75514) (xy 403.97049 -382.759712) (xy 403.95906 -382.77292) (xy 403.929596 -382.851406)
			(xy 403.929342 -382.869186) (xy 403.93239 -382.877822) (xy 403.942674 -382.908692) (xy 403.953785 -382.972799)
			(xy 403.954488 -383.00533) (xy 403.954002 -383.032581) (xy 403.946246 -383.086529) (xy 403.930891 -383.138824)
			(xy 403.908249 -383.188401) (xy 403.878783 -383.234251) (xy 403.843092 -383.275442) (xy 403.801901 -383.311133)
			(xy 403.756051 -383.340599) (xy 403.706474 -383.363241) (xy 403.654179 -383.378596) (xy 403.600231 -383.386352)
			(xy 403.545729 -383.386352) (xy 403.491781 -383.378596) (xy 403.439486 -383.363241) (xy 403.389909 -383.340599)
			(xy 403.344059 -383.311133) (xy 403.302868 -383.275442) (xy 403.267177 -383.234251) (xy 403.237711 -383.188401)
			(xy 403.215069 -383.138824) (xy 403.199714 -383.086529) (xy 403.191958 -383.032581) (xy 403.191472 -383.00533)
			(xy 403.191819 -382.981258) (xy 403.197862 -382.933495) (xy 403.209857 -382.886869) (xy 403.218396 -382.86436)
			(xy 403.223476 -382.851914) (xy 403.220174 -382.826006) (xy 403.153372 -382.735328) (xy 403.12975 -382.724406)
			(xy 403.116542 -382.725422) (xy 403.08784 -382.726438) (xy 403.060587 -382.725917) (xy 403.006636 -382.718166)
			(xy 402.954338 -382.702814) (xy 402.904757 -382.680176) (xy 402.858902 -382.650711) (xy 402.817708 -382.61502)
			(xy 402.782013 -382.57383) (xy 402.752543 -382.527979) (xy 402.7299 -382.4784) (xy 402.714543 -382.426103)
			(xy 402.706785 -382.372153) (xy 387.95909 -382.372153) (xy 387.95909 -382.372178) (xy 387.95133 -382.42612)
			(xy 387.935973 -382.478409) (xy 387.91333 -382.527979) (xy 387.883864 -382.573823) (xy 387.848173 -382.615007)
			(xy 387.806985 -382.650692) (xy 387.761138 -382.680153) (xy 387.711564 -382.702789) (xy 387.659274 -382.71814)
			(xy 387.605331 -382.725893) (xy 387.550834 -382.725891) (xy 387.496892 -382.718133) (xy 387.444603 -382.702777)
			(xy 387.395032 -382.680136) (xy 387.349187 -382.650671) (xy 387.308002 -382.614982) (xy 387.272315 -382.573795)
			(xy 387.242853 -382.527949) (xy 387.220215 -382.478376) (xy 387.204863 -382.426086) (xy 387.197108 -382.372144)
			(xy 386.739975 -382.372144) (xy 386.739975 -382.372155) (xy 386.732217 -382.426111) (xy 386.71686 -382.478414)
			(xy 386.694215 -382.527999) (xy 386.664744 -382.573856) (xy 386.629046 -382.615052) (xy 386.587849 -382.650748)
			(xy 386.541992 -382.680219) (xy 386.492406 -382.702862) (xy 386.440103 -382.718219) (xy 386.386147 -382.725976)
			(xy 386.358892 -382.726438) (xy 386.33019 -382.725422) (xy 386.316982 -382.724406) (xy 386.29336 -382.735328)
			(xy 386.226558 -382.826006) (xy 386.223256 -382.851914) (xy 386.228336 -382.86436) (xy 386.236888 -382.886865)
			(xy 386.248886 -382.933491) (xy 386.254912 -382.981257) (xy 386.25526 -383.00533) (xy 386.254774 -383.032581)
			(xy 386.247018 -383.086529) (xy 386.231663 -383.138824) (xy 386.209021 -383.188401) (xy 386.179555 -383.234251)
			(xy 386.143864 -383.275442) (xy 386.102673 -383.311133) (xy 386.056823 -383.340599) (xy 386.007246 -383.363241)
			(xy 385.954951 -383.378596) (xy 385.901003 -383.386352) (xy 385.846501 -383.386352) (xy 385.792553 -383.378596)
			(xy 385.740258 -383.363241) (xy 385.690681 -383.340599) (xy 385.644831 -383.311133) (xy 385.60364 -383.275442)
			(xy 385.567949 -383.234251) (xy 385.538483 -383.188401) (xy 385.515841 -383.138824) (xy 385.500486 -383.086529)
			(xy 385.49273 -383.032581) (xy 385.492244 -383.00533) (xy 385.492926 -382.972798) (xy 385.504042 -382.908689)
			(xy 385.514342 -382.877822) (xy 385.51739 -382.869186) (xy 385.517136 -382.851406) (xy 385.487672 -382.77292)
			(xy 385.476242 -382.759712) (xy 385.468114 -382.75514) (xy 385.435856 -382.735328) (xy 385.429454 -382.731288)
			(xy 385.414975 -382.726895) (xy 385.407408 -382.726692) (xy 385.125976 -382.726692) (xy 385.118422 -382.726976)
			(xy 385.103964 -382.731363) (xy 385.097528 -382.735328) (xy 385.06527 -382.75514) (xy 385.057142 -382.759712)
			(xy 385.045712 -382.77292) (xy 385.016248 -382.851406) (xy 385.015994 -382.869186) (xy 385.019042 -382.877822)
			(xy 385.029328 -382.908692) (xy 385.040437 -382.972799) (xy 385.04114 -383.00533) (xy 385.040654 -383.032581)
			(xy 385.032898 -383.086529) (xy 385.017543 -383.138824) (xy 384.994901 -383.188401) (xy 384.965435 -383.234251)
			(xy 384.929744 -383.275442) (xy 384.888553 -383.311133) (xy 384.842703 -383.340599) (xy 384.793126 -383.363241)
			(xy 384.740831 -383.378596) (xy 384.686883 -383.386352) (xy 384.632381 -383.386352) (xy 384.578433 -383.378596)
			(xy 384.526138 -383.363241) (xy 384.476561 -383.340599) (xy 384.430711 -383.311133) (xy 384.38952 -383.275442)
			(xy 384.353829 -383.234251) (xy 384.324363 -383.188401) (xy 384.301721 -383.138824) (xy 384.286366 -383.086529)
			(xy 384.27861 -383.032581) (xy 384.278124 -383.00533) (xy 384.278474 -382.981258) (xy 384.284517 -382.933495)
			(xy 384.29651 -382.88687) (xy 384.305048 -382.86436) (xy 384.310128 -382.851914) (xy 384.306826 -382.826006)
			(xy 384.240024 -382.735328) (xy 384.216402 -382.724406) (xy 384.203194 -382.725422) (xy 384.174492 -382.726438)
			(xy 384.147243 -382.725891) (xy 384.093301 -382.718134) (xy 384.041011 -382.70278) (xy 383.991439 -382.68014)
			(xy 383.945593 -382.650676) (xy 383.904407 -382.614987) (xy 383.868719 -382.5738) (xy 383.839256 -382.527954)
			(xy 383.816617 -382.478381) (xy 383.801264 -382.426091) (xy 383.793508 -382.372149) (xy 379.932775 -382.372149)
			(xy 379.932775 -382.372155) (xy 379.925017 -382.426111) (xy 379.90966 -382.478414) (xy 379.887015 -382.527999)
			(xy 379.857544 -382.573856) (xy 379.821846 -382.615052) (xy 379.780649 -382.650748) (xy 379.734792 -382.680219)
			(xy 379.685206 -382.702862) (xy 379.632903 -382.718219) (xy 379.578947 -382.725976) (xy 379.551692 -382.726438)
			(xy 379.52299 -382.725422) (xy 379.509782 -382.724406) (xy 379.48616 -382.735328) (xy 379.419358 -382.826006)
			(xy 379.416056 -382.851914) (xy 379.421136 -382.86436) (xy 379.429688 -382.886865) (xy 379.441686 -382.933491)
			(xy 379.447712 -382.981257) (xy 379.44806 -383.00533) (xy 379.447574 -383.032581) (xy 379.439818 -383.086529)
			(xy 379.424463 -383.138824) (xy 379.401821 -383.188401) (xy 379.372355 -383.234251) (xy 379.336664 -383.275442)
			(xy 379.295473 -383.311133) (xy 379.249623 -383.340599) (xy 379.200046 -383.363241) (xy 379.147751 -383.378596)
			(xy 379.093803 -383.386352) (xy 379.039301 -383.386352) (xy 378.985353 -383.378596) (xy 378.933058 -383.363241)
			(xy 378.883481 -383.340599) (xy 378.837631 -383.311133) (xy 378.79644 -383.275442) (xy 378.760749 -383.234251)
			(xy 378.731283 -383.188401) (xy 378.708641 -383.138824) (xy 378.693286 -383.086529) (xy 378.68553 -383.032581)
			(xy 378.685044 -383.00533) (xy 378.685726 -382.972798) (xy 378.696842 -382.908689) (xy 378.707142 -382.877822)
			(xy 378.71019 -382.869186) (xy 378.709936 -382.851406) (xy 378.680472 -382.77292) (xy 378.669042 -382.759712)
			(xy 378.660914 -382.75514) (xy 378.628656 -382.735328) (xy 378.622254 -382.731288) (xy 378.607775 -382.726895)
			(xy 378.600208 -382.726692) (xy 378.318776 -382.726692) (xy 378.311222 -382.726976) (xy 378.296764 -382.731363)
			(xy 378.290328 -382.735328) (xy 378.25807 -382.75514) (xy 378.249942 -382.759712) (xy 378.238512 -382.77292)
			(xy 378.209048 -382.851406) (xy 378.208794 -382.869186) (xy 378.211842 -382.877822) (xy 378.222128 -382.908692)
			(xy 378.233237 -382.972799) (xy 378.23394 -383.00533) (xy 378.233454 -383.032581) (xy 378.225698 -383.086529)
			(xy 378.210343 -383.138824) (xy 378.187701 -383.188401) (xy 378.158235 -383.234251) (xy 378.122544 -383.275442)
			(xy 378.081353 -383.311133) (xy 378.035503 -383.340599) (xy 377.985926 -383.363241) (xy 377.933631 -383.378596)
			(xy 377.879683 -383.386352) (xy 377.825181 -383.386352) (xy 377.771233 -383.378596) (xy 377.718938 -383.363241)
			(xy 377.669361 -383.340599) (xy 377.623511 -383.311133) (xy 377.58232 -383.275442) (xy 377.546629 -383.234251)
			(xy 377.517163 -383.188401) (xy 377.494521 -383.138824) (xy 377.479166 -383.086529) (xy 377.47141 -383.032581)
			(xy 377.470924 -383.00533) (xy 377.471274 -382.981258) (xy 377.477317 -382.933495) (xy 377.48931 -382.88687)
			(xy 377.497848 -382.86436) (xy 377.502928 -382.851914) (xy 377.499626 -382.826006) (xy 377.432824 -382.735328)
			(xy 377.409202 -382.724406) (xy 377.395994 -382.725422) (xy 377.367292 -382.726438) (xy 377.340043 -382.725891)
			(xy 377.286101 -382.718134) (xy 377.233811 -382.70278) (xy 377.184239 -382.68014) (xy 377.138393 -382.650676)
			(xy 377.097207 -382.614987) (xy 377.061519 -382.5738) (xy 377.032056 -382.527954) (xy 377.009417 -382.478381)
			(xy 376.994064 -382.426091) (xy 376.986308 -382.372149) (xy 373.125575 -382.372149) (xy 373.125575 -382.372155)
			(xy 373.117817 -382.426111) (xy 373.10246 -382.478414) (xy 373.079815 -382.527999) (xy 373.050344 -382.573856)
			(xy 373.014646 -382.615052) (xy 372.973449 -382.650748) (xy 372.927592 -382.680219) (xy 372.878006 -382.702862)
			(xy 372.825703 -382.718219) (xy 372.771747 -382.725976) (xy 372.744492 -382.726438) (xy 372.71579 -382.725422)
			(xy 372.702582 -382.724406) (xy 372.67896 -382.735328) (xy 372.612158 -382.826006) (xy 372.608856 -382.851914)
			(xy 372.613936 -382.86436) (xy 372.622488 -382.886865) (xy 372.634486 -382.933491) (xy 372.640512 -382.981257)
			(xy 372.64086 -383.00533) (xy 372.640374 -383.032581) (xy 372.632618 -383.086529) (xy 372.617263 -383.138824)
			(xy 372.594621 -383.188401) (xy 372.565155 -383.234251) (xy 372.529464 -383.275442) (xy 372.488273 -383.311133)
			(xy 372.442423 -383.340599) (xy 372.392846 -383.363241) (xy 372.340551 -383.378596) (xy 372.286603 -383.386352)
			(xy 372.232101 -383.386352) (xy 372.178153 -383.378596) (xy 372.125858 -383.363241) (xy 372.076281 -383.340599)
			(xy 372.030431 -383.311133) (xy 371.98924 -383.275442) (xy 371.953549 -383.234251) (xy 371.924083 -383.188401)
			(xy 371.901441 -383.138824) (xy 371.886086 -383.086529) (xy 371.87833 -383.032581) (xy 371.877844 -383.00533)
			(xy 371.878526 -382.972798) (xy 371.889642 -382.908689) (xy 371.899942 -382.877822) (xy 371.90299 -382.869186)
			(xy 371.902736 -382.851406) (xy 371.873272 -382.77292) (xy 371.861842 -382.759712) (xy 371.853714 -382.75514)
			(xy 371.821456 -382.735328) (xy 371.815054 -382.731288) (xy 371.800575 -382.726895) (xy 371.793008 -382.726692)
			(xy 371.511576 -382.726692) (xy 371.504022 -382.726976) (xy 371.489564 -382.731363) (xy 371.483128 -382.735328)
			(xy 371.45087 -382.75514) (xy 371.442742 -382.759712) (xy 371.431312 -382.77292) (xy 371.401848 -382.851406)
			(xy 371.401594 -382.869186) (xy 371.404642 -382.877822) (xy 371.414928 -382.908692) (xy 371.426037 -382.972799)
			(xy 371.42674 -383.00533) (xy 371.426254 -383.032581) (xy 371.418498 -383.086529) (xy 371.403143 -383.138824)
			(xy 371.380501 -383.188401) (xy 371.351035 -383.234251) (xy 371.315344 -383.275442) (xy 371.274153 -383.311133)
			(xy 371.228303 -383.340599) (xy 371.178726 -383.363241) (xy 371.126431 -383.378596) (xy 371.072483 -383.386352)
			(xy 371.017981 -383.386352) (xy 370.964033 -383.378596) (xy 370.911738 -383.363241) (xy 370.862161 -383.340599)
			(xy 370.816311 -383.311133) (xy 370.77512 -383.275442) (xy 370.739429 -383.234251) (xy 370.709963 -383.188401)
			(xy 370.687321 -383.138824) (xy 370.671966 -383.086529) (xy 370.66421 -383.032581) (xy 370.663724 -383.00533)
			(xy 370.664074 -382.981258) (xy 370.670117 -382.933495) (xy 370.68211 -382.88687) (xy 370.690648 -382.86436)
			(xy 370.695728 -382.851914) (xy 370.692426 -382.826006) (xy 370.625624 -382.735328) (xy 370.602002 -382.724406)
			(xy 370.588794 -382.725422) (xy 370.560092 -382.726438) (xy 370.532843 -382.725891) (xy 370.478901 -382.718134)
			(xy 370.426611 -382.70278) (xy 370.377039 -382.68014) (xy 370.331193 -382.650676) (xy 370.290007 -382.614987)
			(xy 370.254319 -382.5738) (xy 370.224856 -382.527954) (xy 370.202217 -382.478381) (xy 370.186864 -382.426091)
			(xy 370.179108 -382.372149) (xy 352.167452 -382.372149) (xy 352.167452 -382.372151) (xy 352.159696 -382.426099)
			(xy 352.144342 -382.478395) (xy 352.121702 -382.527973) (xy 352.092238 -382.573825) (xy 352.056548 -382.615017)
			(xy 352.01536 -382.650712) (xy 351.969512 -382.680181) (xy 351.919936 -382.702827) (xy 351.867643 -382.718187)
			(xy 351.813695 -382.725949) (xy 351.786444 -382.726438) (xy 351.757742 -382.725422) (xy 351.744534 -382.724406)
			(xy 351.720912 -382.735328) (xy 351.65411 -382.826006) (xy 351.650808 -382.851914) (xy 351.655888 -382.86436)
			(xy 351.664438 -382.886866) (xy 351.676437 -382.933491) (xy 351.682464 -382.981257) (xy 351.682812 -383.00533)
			(xy 351.682326 -383.032581) (xy 351.67457 -383.086529) (xy 351.659215 -383.138824) (xy 351.636573 -383.188401)
			(xy 351.607107 -383.234251) (xy 351.571416 -383.275442) (xy 351.530225 -383.311133) (xy 351.484375 -383.340599)
			(xy 351.434798 -383.363241) (xy 351.382503 -383.378596) (xy 351.328555 -383.386352) (xy 351.274053 -383.386352)
			(xy 351.220105 -383.378596) (xy 351.16781 -383.363241) (xy 351.118233 -383.340599) (xy 351.072383 -383.311133)
			(xy 351.031192 -383.275442) (xy 350.995501 -383.234251) (xy 350.966035 -383.188401) (xy 350.943393 -383.138824)
			(xy 350.928038 -383.086529) (xy 350.920282 -383.032581) (xy 350.919796 -383.00533) (xy 350.920475 -382.972798)
			(xy 350.931593 -382.908688) (xy 350.941894 -382.877822) (xy 350.944942 -382.869186) (xy 350.944688 -382.851406)
			(xy 350.915224 -382.77292) (xy 350.903794 -382.759712) (xy 350.895666 -382.75514) (xy 350.863408 -382.735328)
			(xy 350.856995 -382.731308) (xy 350.842525 -382.726902) (xy 350.83496 -382.726692) (xy 350.553528 -382.726692)
			(xy 350.545972 -382.726956) (xy 350.531514 -382.731357) (xy 350.52508 -382.735328) (xy 350.492822 -382.75514)
			(xy 350.484694 -382.759712) (xy 350.473264 -382.77292) (xy 350.4438 -382.851406) (xy 350.443546 -382.869186)
			(xy 350.446594 -382.877822) (xy 350.456878 -382.908692) (xy 350.467989 -382.972799) (xy 350.468692 -383.00533)
			(xy 350.468206 -383.032581) (xy 350.46045 -383.086529) (xy 350.445095 -383.138824) (xy 350.422453 -383.188401)
			(xy 350.392987 -383.234251) (xy 350.357296 -383.275442) (xy 350.316105 -383.311133) (xy 350.270255 -383.340599)
			(xy 350.220678 -383.363241) (xy 350.168383 -383.378596) (xy 350.114435 -383.386352) (xy 350.059933 -383.386352)
			(xy 350.005985 -383.378596) (xy 349.95369 -383.363241) (xy 349.904113 -383.340599) (xy 349.858263 -383.311133)
			(xy 349.817072 -383.275442) (xy 349.781381 -383.234251) (xy 349.751915 -383.188401) (xy 349.729273 -383.138824)
			(xy 349.713918 -383.086529) (xy 349.706162 -383.032581) (xy 349.705676 -383.00533) (xy 349.706023 -382.981258)
			(xy 349.712066 -382.933495) (xy 349.724061 -382.886869) (xy 349.7326 -382.86436) (xy 349.73768 -382.851914)
			(xy 349.734378 -382.826006) (xy 349.667576 -382.735328) (xy 349.643954 -382.724406) (xy 349.630746 -382.725422)
			(xy 349.602044 -382.726438) (xy 349.574791 -382.725918) (xy 349.52084 -382.718166) (xy 349.468541 -382.702815)
			(xy 349.418959 -382.680177) (xy 349.373104 -382.650713) (xy 349.331909 -382.615022) (xy 349.296214 -382.573831)
			(xy 349.266744 -382.52798) (xy 349.2441 -382.478401) (xy 349.228743 -382.426103) (xy 349.220985 -382.372153)
			(xy 345.360252 -382.372153) (xy 345.352496 -382.426099) (xy 345.337142 -382.478395) (xy 345.314502 -382.527973)
			(xy 345.285038 -382.573825) (xy 345.249348 -382.615017) (xy 345.20816 -382.650712) (xy 345.162312 -382.680181)
			(xy 345.112736 -382.702827) (xy 345.060443 -382.718187) (xy 345.006495 -382.725949) (xy 344.979244 -382.726438)
			(xy 344.950542 -382.725422) (xy 344.937334 -382.724406) (xy 344.913712 -382.735328) (xy 344.84691 -382.826006)
			(xy 344.843608 -382.851914) (xy 344.848688 -382.86436) (xy 344.857238 -382.886866) (xy 344.869237 -382.933491)
			(xy 344.875264 -382.981257) (xy 344.875612 -383.00533) (xy 344.875126 -383.032581) (xy 344.86737 -383.086529)
			(xy 344.852015 -383.138824) (xy 344.829373 -383.188401) (xy 344.799907 -383.234251) (xy 344.764216 -383.275442)
			(xy 344.723025 -383.311133) (xy 344.677175 -383.340599) (xy 344.627598 -383.363241) (xy 344.575303 -383.378596)
			(xy 344.521355 -383.386352) (xy 344.466853 -383.386352) (xy 344.412905 -383.378596) (xy 344.36061 -383.363241)
			(xy 344.311033 -383.340599) (xy 344.265183 -383.311133) (xy 344.223992 -383.275442) (xy 344.188301 -383.234251)
			(xy 344.158835 -383.188401) (xy 344.136193 -383.138824) (xy 344.120838 -383.086529) (xy 344.113082 -383.032581)
			(xy 344.112596 -383.00533) (xy 344.113275 -382.972798) (xy 344.124393 -382.908688) (xy 344.134694 -382.877822)
			(xy 344.137742 -382.869186) (xy 344.137488 -382.851406) (xy 344.108024 -382.77292) (xy 344.096594 -382.759712)
			(xy 344.088466 -382.75514) (xy 344.056208 -382.735328) (xy 344.049795 -382.731308) (xy 344.035325 -382.726902)
			(xy 344.02776 -382.726692) (xy 343.746328 -382.726692) (xy 343.738772 -382.726956) (xy 343.724314 -382.731357)
			(xy 343.71788 -382.735328) (xy 343.685622 -382.75514) (xy 343.677494 -382.759712) (xy 343.666064 -382.77292)
			(xy 343.6366 -382.851406) (xy 343.636346 -382.869186) (xy 343.639394 -382.877822) (xy 343.649678 -382.908692)
			(xy 343.660789 -382.972799) (xy 343.661492 -383.00533) (xy 343.661006 -383.032581) (xy 343.65325 -383.086529)
			(xy 343.637895 -383.138824) (xy 343.615253 -383.188401) (xy 343.585787 -383.234251) (xy 343.550096 -383.275442)
			(xy 343.508905 -383.311133) (xy 343.463055 -383.340599) (xy 343.413478 -383.363241) (xy 343.361183 -383.378596)
			(xy 343.307235 -383.386352) (xy 343.252733 -383.386352) (xy 343.198785 -383.378596) (xy 343.14649 -383.363241)
			(xy 343.096913 -383.340599) (xy 343.051063 -383.311133) (xy 343.009872 -383.275442) (xy 342.974181 -383.234251)
			(xy 342.944715 -383.188401) (xy 342.922073 -383.138824) (xy 342.906718 -383.086529) (xy 342.898962 -383.032581)
			(xy 342.898476 -383.00533) (xy 342.898823 -382.981258) (xy 342.904866 -382.933495) (xy 342.916861 -382.886869)
			(xy 342.9254 -382.86436) (xy 342.93048 -382.851914) (xy 342.927178 -382.826006) (xy 342.860376 -382.735328)
			(xy 342.836754 -382.724406) (xy 342.823546 -382.725422) (xy 342.794844 -382.726438) (xy 342.767591 -382.725918)
			(xy 342.71364 -382.718166) (xy 342.661341 -382.702815) (xy 342.611759 -382.680177) (xy 342.565904 -382.650713)
			(xy 342.524709 -382.615022) (xy 342.489014 -382.573831) (xy 342.459544 -382.52798) (xy 342.4369 -382.478401)
			(xy 342.421543 -382.426103) (xy 342.413785 -382.372153) (xy 338.553052 -382.372153) (xy 338.545296 -382.426099)
			(xy 338.529942 -382.478395) (xy 338.507302 -382.527973) (xy 338.477838 -382.573825) (xy 338.442148 -382.615017)
			(xy 338.40096 -382.650712) (xy 338.355112 -382.680181) (xy 338.305536 -382.702827) (xy 338.253243 -382.718187)
			(xy 338.199295 -382.725949) (xy 338.172044 -382.726438) (xy 338.143342 -382.725422) (xy 338.130134 -382.724406)
			(xy 338.106512 -382.735328) (xy 338.03971 -382.826006) (xy 338.036408 -382.851914) (xy 338.041488 -382.86436)
			(xy 338.050038 -382.886866) (xy 338.062037 -382.933491) (xy 338.068064 -382.981257) (xy 338.068412 -383.00533)
			(xy 338.067926 -383.032581) (xy 338.06017 -383.086529) (xy 338.044815 -383.138824) (xy 338.022173 -383.188401)
			(xy 337.992707 -383.234251) (xy 337.957016 -383.275442) (xy 337.915825 -383.311133) (xy 337.869975 -383.340599)
			(xy 337.820398 -383.363241) (xy 337.768103 -383.378596) (xy 337.714155 -383.386352) (xy 337.659653 -383.386352)
			(xy 337.605705 -383.378596) (xy 337.55341 -383.363241) (xy 337.503833 -383.340599) (xy 337.457983 -383.311133)
			(xy 337.416792 -383.275442) (xy 337.381101 -383.234251) (xy 337.351635 -383.188401) (xy 337.328993 -383.138824)
			(xy 337.313638 -383.086529) (xy 337.305882 -383.032581) (xy 337.305396 -383.00533) (xy 337.306075 -382.972798)
			(xy 337.317193 -382.908688) (xy 337.327494 -382.877822) (xy 337.330542 -382.869186) (xy 337.330288 -382.851406)
			(xy 337.300824 -382.77292) (xy 337.289394 -382.759712) (xy 337.281266 -382.75514) (xy 337.249008 -382.735328)
			(xy 337.242595 -382.731308) (xy 337.228125 -382.726902) (xy 337.22056 -382.726692) (xy 336.939128 -382.726692)
			(xy 336.931572 -382.726956) (xy 336.917114 -382.731357) (xy 336.91068 -382.735328) (xy 336.878422 -382.75514)
			(xy 336.870294 -382.759712) (xy 336.858864 -382.77292) (xy 336.8294 -382.851406) (xy 336.829146 -382.869186)
			(xy 336.832194 -382.877822) (xy 336.842478 -382.908692) (xy 336.853589 -382.972799) (xy 336.854292 -383.00533)
			(xy 336.853806 -383.032581) (xy 336.84605 -383.086529) (xy 336.830695 -383.138824) (xy 336.808053 -383.188401)
			(xy 336.778587 -383.234251) (xy 336.742896 -383.275442) (xy 336.701705 -383.311133) (xy 336.655855 -383.340599)
			(xy 336.606278 -383.363241) (xy 336.553983 -383.378596) (xy 336.500035 -383.386352) (xy 336.445533 -383.386352)
			(xy 336.391585 -383.378596) (xy 336.33929 -383.363241) (xy 336.289713 -383.340599) (xy 336.243863 -383.311133)
			(xy 336.202672 -383.275442) (xy 336.166981 -383.234251) (xy 336.137515 -383.188401) (xy 336.114873 -383.138824)
			(xy 336.099518 -383.086529) (xy 336.091762 -383.032581) (xy 336.091276 -383.00533) (xy 336.091623 -382.981258)
			(xy 336.097666 -382.933495) (xy 336.109661 -382.886869) (xy 336.1182 -382.86436) (xy 336.12328 -382.851914)
			(xy 336.119978 -382.826006) (xy 336.053176 -382.735328) (xy 336.029554 -382.724406) (xy 336.016346 -382.725422)
			(xy 335.987644 -382.726438) (xy 335.960391 -382.725918) (xy 335.90644 -382.718166) (xy 335.854141 -382.702815)
			(xy 335.804559 -382.680177) (xy 335.758704 -382.650713) (xy 335.717509 -382.615022) (xy 335.681814 -382.573831)
			(xy 335.652344 -382.52798) (xy 335.6297 -382.478401) (xy 335.614343 -382.426103) (xy 335.606585 -382.372153)
			(xy 319.639775 -382.372153) (xy 319.639775 -382.372155) (xy 319.632017 -382.426111) (xy 319.61666 -382.478413)
			(xy 319.594015 -382.527997) (xy 319.564545 -382.573854) (xy 319.528848 -382.615051) (xy 319.487651 -382.650747)
			(xy 319.441794 -382.680217) (xy 319.392209 -382.702861) (xy 319.339907 -382.718218) (xy 319.285951 -382.725975)
			(xy 319.258696 -382.726438) (xy 319.229994 -382.725422) (xy 319.216786 -382.724406) (xy 319.193164 -382.735328)
			(xy 319.126362 -382.826006) (xy 319.12306 -382.851914) (xy 319.12814 -382.86436) (xy 319.136692 -382.886865)
			(xy 319.14869 -382.933491) (xy 319.154716 -382.981257) (xy 319.155064 -383.00533) (xy 319.154578 -383.032581)
			(xy 319.146822 -383.086529) (xy 319.131467 -383.138824) (xy 319.108825 -383.188401) (xy 319.079359 -383.234251)
			(xy 319.043668 -383.275442) (xy 319.002477 -383.311133) (xy 318.956627 -383.340599) (xy 318.90705 -383.363241)
			(xy 318.854755 -383.378596) (xy 318.800807 -383.386352) (xy 318.746305 -383.386352) (xy 318.692357 -383.378596)
			(xy 318.640062 -383.363241) (xy 318.590485 -383.340599) (xy 318.544635 -383.311133) (xy 318.503444 -383.275442)
			(xy 318.467753 -383.234251) (xy 318.438287 -383.188401) (xy 318.415645 -383.138824) (xy 318.40029 -383.086529)
			(xy 318.392534 -383.032581) (xy 318.392048 -383.00533) (xy 318.39273 -382.972798) (xy 318.403846 -382.908689)
			(xy 318.414146 -382.877822) (xy 318.417194 -382.869186) (xy 318.41694 -382.851406) (xy 318.387476 -382.77292)
			(xy 318.376046 -382.759712) (xy 318.367918 -382.75514) (xy 318.33566 -382.735328) (xy 318.329258 -382.731289)
			(xy 318.314779 -382.726895) (xy 318.307212 -382.726692) (xy 318.02578 -382.726692) (xy 318.018226 -382.726977)
			(xy 318.003768 -382.731363) (xy 317.997332 -382.735328) (xy 317.965074 -382.75514) (xy 317.956946 -382.759712)
			(xy 317.945516 -382.77292) (xy 317.916052 -382.851406) (xy 317.915798 -382.869186) (xy 317.918846 -382.877822)
			(xy 317.929132 -382.908692) (xy 317.940241 -382.972799) (xy 317.940944 -383.00533) (xy 317.940458 -383.032581)
			(xy 317.932702 -383.086529) (xy 317.917347 -383.138824) (xy 317.894705 -383.188401) (xy 317.865239 -383.234251)
			(xy 317.829548 -383.275442) (xy 317.788357 -383.311133) (xy 317.742507 -383.340599) (xy 317.69293 -383.363241)
			(xy 317.640635 -383.378596) (xy 317.586687 -383.386352) (xy 317.532185 -383.386352) (xy 317.478237 -383.378596)
			(xy 317.425942 -383.363241) (xy 317.376365 -383.340599) (xy 317.330515 -383.311133) (xy 317.289324 -383.275442)
			(xy 317.253633 -383.234251) (xy 317.224167 -383.188401) (xy 317.201525 -383.138824) (xy 317.18617 -383.086529)
			(xy 317.178414 -383.032581) (xy 317.177928 -383.00533) (xy 317.178278 -382.981258) (xy 317.18432 -382.933495)
			(xy 317.196314 -382.88687) (xy 317.204852 -382.86436) (xy 317.209932 -382.851914) (xy 317.20663 -382.826006)
			(xy 317.139828 -382.735328) (xy 317.116206 -382.724406) (xy 317.102998 -382.725422) (xy 317.074296 -382.726438)
			(xy 317.047047 -382.725892) (xy 316.993104 -382.718135) (xy 316.940814 -382.702781) (xy 316.891241 -382.680141)
			(xy 316.845395 -382.650677) (xy 316.804209 -382.614989) (xy 316.76852 -382.573802) (xy 316.739057 -382.527955)
			(xy 316.716418 -382.478382) (xy 316.701064 -382.426092) (xy 316.693308 -382.372149) (xy 312.832575 -382.372149)
			(xy 312.832575 -382.372155) (xy 312.824817 -382.426111) (xy 312.80946 -382.478413) (xy 312.786815 -382.527997)
			(xy 312.757345 -382.573854) (xy 312.721648 -382.615051) (xy 312.680451 -382.650747) (xy 312.634594 -382.680217)
			(xy 312.585009 -382.702861) (xy 312.532707 -382.718218) (xy 312.478751 -382.725975) (xy 312.451496 -382.726438)
			(xy 312.422794 -382.725422) (xy 312.409586 -382.724406) (xy 312.385964 -382.735328) (xy 312.319162 -382.826006)
			(xy 312.31586 -382.851914) (xy 312.32094 -382.86436) (xy 312.329492 -382.886865) (xy 312.34149 -382.933491)
			(xy 312.347516 -382.981257) (xy 312.347864 -383.00533) (xy 312.347378 -383.032581) (xy 312.339622 -383.086529)
			(xy 312.324267 -383.138824) (xy 312.301625 -383.188401) (xy 312.272159 -383.234251) (xy 312.236468 -383.275442)
			(xy 312.195277 -383.311133) (xy 312.149427 -383.340599) (xy 312.09985 -383.363241) (xy 312.047555 -383.378596)
			(xy 311.993607 -383.386352) (xy 311.939105 -383.386352) (xy 311.885157 -383.378596) (xy 311.832862 -383.363241)
			(xy 311.783285 -383.340599) (xy 311.737435 -383.311133) (xy 311.696244 -383.275442) (xy 311.660553 -383.234251)
			(xy 311.631087 -383.188401) (xy 311.608445 -383.138824) (xy 311.59309 -383.086529) (xy 311.585334 -383.032581)
			(xy 311.584848 -383.00533) (xy 311.58553 -382.972798) (xy 311.596646 -382.908689) (xy 311.606946 -382.877822)
			(xy 311.609994 -382.869186) (xy 311.60974 -382.851406) (xy 311.580276 -382.77292) (xy 311.568846 -382.759712)
			(xy 311.560718 -382.75514) (xy 311.52846 -382.735328) (xy 311.522058 -382.731289) (xy 311.507579 -382.726895)
			(xy 311.500012 -382.726692) (xy 311.21858 -382.726692) (xy 311.211026 -382.726977) (xy 311.196568 -382.731363)
			(xy 311.190132 -382.735328) (xy 311.157874 -382.75514) (xy 311.149746 -382.759712) (xy 311.138316 -382.77292)
			(xy 311.108852 -382.851406) (xy 311.108598 -382.869186) (xy 311.111646 -382.877822) (xy 311.121932 -382.908692)
			(xy 311.133041 -382.972799) (xy 311.133744 -383.00533) (xy 311.133258 -383.032581) (xy 311.125502 -383.086529)
			(xy 311.110147 -383.138824) (xy 311.087505 -383.188401) (xy 311.058039 -383.234251) (xy 311.022348 -383.275442)
			(xy 310.981157 -383.311133) (xy 310.935307 -383.340599) (xy 310.88573 -383.363241) (xy 310.833435 -383.378596)
			(xy 310.779487 -383.386352) (xy 310.724985 -383.386352) (xy 310.671037 -383.378596) (xy 310.618742 -383.363241)
			(xy 310.569165 -383.340599) (xy 310.523315 -383.311133) (xy 310.482124 -383.275442) (xy 310.446433 -383.234251)
			(xy 310.416967 -383.188401) (xy 310.394325 -383.138824) (xy 310.37897 -383.086529) (xy 310.371214 -383.032581)
			(xy 310.370728 -383.00533) (xy 310.371078 -382.981258) (xy 310.37712 -382.933495) (xy 310.389114 -382.88687)
			(xy 310.397652 -382.86436) (xy 310.402732 -382.851914) (xy 310.39943 -382.826006) (xy 310.332628 -382.735328)
			(xy 310.309006 -382.724406) (xy 310.295798 -382.725422) (xy 310.267096 -382.726438) (xy 310.239847 -382.725892)
			(xy 310.185904 -382.718135) (xy 310.133614 -382.702781) (xy 310.084041 -382.680141) (xy 310.038195 -382.650677)
			(xy 309.997009 -382.614989) (xy 309.96132 -382.573802) (xy 309.931857 -382.527955) (xy 309.909218 -382.478382)
			(xy 309.893864 -382.426092) (xy 309.886108 -382.372149) (xy 306.025375 -382.372149) (xy 306.025375 -382.372155)
			(xy 306.017617 -382.426111) (xy 306.00226 -382.478413) (xy 305.979615 -382.527997) (xy 305.950145 -382.573854)
			(xy 305.914448 -382.615051) (xy 305.873251 -382.650747) (xy 305.827394 -382.680217) (xy 305.777809 -382.702861)
			(xy 305.725507 -382.718218) (xy 305.671551 -382.725975) (xy 305.644296 -382.726438) (xy 305.615594 -382.725422)
			(xy 305.602386 -382.724406) (xy 305.578764 -382.735328) (xy 305.511962 -382.826006) (xy 305.50866 -382.851914)
			(xy 305.51374 -382.86436) (xy 305.522292 -382.886865) (xy 305.53429 -382.933491) (xy 305.540316 -382.981257)
			(xy 305.540664 -383.00533) (xy 305.540178 -383.032581) (xy 305.532422 -383.086529) (xy 305.517067 -383.138824)
			(xy 305.494425 -383.188401) (xy 305.464959 -383.234251) (xy 305.429268 -383.275442) (xy 305.388077 -383.311133)
			(xy 305.342227 -383.340599) (xy 305.29265 -383.363241) (xy 305.240355 -383.378596) (xy 305.186407 -383.386352)
			(xy 305.131905 -383.386352) (xy 305.077957 -383.378596) (xy 305.025662 -383.363241) (xy 304.976085 -383.340599)
			(xy 304.930235 -383.311133) (xy 304.889044 -383.275442) (xy 304.853353 -383.234251) (xy 304.823887 -383.188401)
			(xy 304.801245 -383.138824) (xy 304.78589 -383.086529) (xy 304.778134 -383.032581) (xy 304.777648 -383.00533)
			(xy 304.77833 -382.972798) (xy 304.789446 -382.908689) (xy 304.799746 -382.877822) (xy 304.802794 -382.869186)
			(xy 304.80254 -382.851406) (xy 304.773076 -382.77292) (xy 304.761646 -382.759712) (xy 304.753518 -382.75514)
			(xy 304.72126 -382.735328) (xy 304.714858 -382.731289) (xy 304.700379 -382.726895) (xy 304.692812 -382.726692)
			(xy 304.41138 -382.726692) (xy 304.403826 -382.726977) (xy 304.389368 -382.731363) (xy 304.382932 -382.735328)
			(xy 304.350674 -382.75514) (xy 304.342546 -382.759712) (xy 304.331116 -382.77292) (xy 304.301652 -382.851406)
			(xy 304.301398 -382.869186) (xy 304.304446 -382.877822) (xy 304.314732 -382.908692) (xy 304.325841 -382.972799)
			(xy 304.326544 -383.00533) (xy 304.326058 -383.032581) (xy 304.318302 -383.086529) (xy 304.302947 -383.138824)
			(xy 304.280305 -383.188401) (xy 304.250839 -383.234251) (xy 304.215148 -383.275442) (xy 304.173957 -383.311133)
			(xy 304.128107 -383.340599) (xy 304.07853 -383.363241) (xy 304.026235 -383.378596) (xy 303.972287 -383.386352)
			(xy 303.917785 -383.386352) (xy 303.863837 -383.378596) (xy 303.811542 -383.363241) (xy 303.761965 -383.340599)
			(xy 303.716115 -383.311133) (xy 303.674924 -383.275442) (xy 303.639233 -383.234251) (xy 303.609767 -383.188401)
			(xy 303.587125 -383.138824) (xy 303.57177 -383.086529) (xy 303.564014 -383.032581) (xy 303.563528 -383.00533)
			(xy 303.563878 -382.981258) (xy 303.56992 -382.933495) (xy 303.581914 -382.88687) (xy 303.590452 -382.86436)
			(xy 303.595532 -382.851914) (xy 303.59223 -382.826006) (xy 303.525428 -382.735328) (xy 303.501806 -382.724406)
			(xy 303.488598 -382.725422) (xy 303.459896 -382.726438) (xy 303.432647 -382.725892) (xy 303.378704 -382.718135)
			(xy 303.326414 -382.702781) (xy 303.276841 -382.680141) (xy 303.230995 -382.650677) (xy 303.189809 -382.614989)
			(xy 303.15412 -382.573802) (xy 303.124657 -382.527955) (xy 303.102018 -382.478382) (xy 303.086664 -382.426092)
			(xy 303.078908 -382.372149) (xy 295.716411 -382.372149) (xy 295.627806 -382.460754) (xy 295.620967 -382.468155)
			(xy 295.613252 -382.486753) (xy 295.61282 -382.496822) (xy 295.61282 -384.202255) (xy 296.388955 -384.202255)
			(xy 296.388955 -384.147745) (xy 296.396714 -384.09379) (xy 296.412072 -384.041489) (xy 296.434718 -383.991906)
			(xy 296.46419 -383.946051) (xy 296.499888 -383.904857) (xy 296.541086 -383.869163) (xy 296.586945 -383.839696)
			(xy 296.63653 -383.817056) (xy 296.688833 -383.801704) (xy 296.742789 -383.793952) (xy 296.770044 -383.793492)
			(xy 296.794116 -383.793845) (xy 296.841879 -383.799886) (xy 296.888504 -383.811878) (xy 296.911014 -383.820416)
			(xy 296.92346 -383.825496) (xy 296.949368 -383.822194) (xy 297.040046 -383.755392) (xy 297.050968 -383.73177)
			(xy 297.049952 -383.718562) (xy 297.048936 -383.68986) (xy 297.049422 -383.662609) (xy 297.057178 -383.608661)
			(xy 297.072533 -383.556366) (xy 297.095175 -383.506789) (xy 297.124641 -383.460939) (xy 297.160332 -383.419748)
			(xy 297.201523 -383.384057) (xy 297.247373 -383.354591) (xy 297.29695 -383.331949) (xy 297.349245 -383.316594)
			(xy 297.403193 -383.308838) (xy 297.457695 -383.308838) (xy 297.511643 -383.316594) (xy 297.563938 -383.331949)
			(xy 297.613515 -383.354591) (xy 297.659365 -383.384057) (xy 297.700556 -383.419748) (xy 297.736247 -383.460939)
			(xy 297.765713 -383.506789) (xy 297.788355 -383.556366) (xy 297.80371 -383.608661) (xy 297.811466 -383.662609)
			(xy 297.811952 -383.68986) (xy 297.810936 -383.718562) (xy 297.80992 -383.73177) (xy 297.820842 -383.755392)
			(xy 297.91152 -383.822194) (xy 297.937428 -383.825496) (xy 297.949874 -383.820416) (xy 297.972379 -383.811863)
			(xy 298.019005 -383.799864) (xy 298.066771 -383.793839) (xy 298.090844 -383.793492) (xy 298.118093 -383.793981)
			(xy 298.172036 -383.801742) (xy 298.224326 -383.817101) (xy 298.273897 -383.839745) (xy 298.319742 -383.869212)
			(xy 298.360927 -383.904904) (xy 298.396614 -383.946093) (xy 298.426076 -383.991941) (xy 298.448714 -384.041516)
			(xy 298.464067 -384.093807) (xy 298.471822 -384.147751) (xy 298.471822 -384.202249) (xy 298.464067 -384.256193)
			(xy 298.448714 -384.308484) (xy 298.440144 -384.327252) (xy 326.236046 -384.327252) (xy 326.236046 -384.272748)
			(xy 326.243802 -384.218797) (xy 326.259158 -384.1665) (xy 326.281799 -384.11692) (xy 326.311265 -384.071067)
			(xy 326.346957 -384.029874) (xy 326.388148 -383.99418) (xy 326.433999 -383.96471) (xy 326.483578 -383.942066)
			(xy 326.535874 -383.926707) (xy 326.589824 -383.918947) (xy 326.617076 -383.91846) (xy 326.641148 -383.918806)
			(xy 326.688911 -383.92485) (xy 326.735537 -383.936845) (xy 326.758046 -383.945384) (xy 326.770492 -383.950464)
			(xy 326.7964 -383.947162) (xy 326.887078 -383.88036) (xy 326.898 -383.856738) (xy 326.896984 -383.84353)
			(xy 326.895968 -383.814828) (xy 326.896454 -383.787577) (xy 326.90421 -383.733629) (xy 326.919565 -383.681334)
			(xy 326.942207 -383.631757) (xy 326.971673 -383.585907) (xy 327.007364 -383.544716) (xy 327.048555 -383.509025)
			(xy 327.094405 -383.479559) (xy 327.143982 -383.456917) (xy 327.196277 -383.441562) (xy 327.250225 -383.433806)
			(xy 327.304727 -383.433806) (xy 327.358675 -383.441562) (xy 327.41097 -383.456917) (xy 327.460547 -383.479559)
			(xy 327.506397 -383.509025) (xy 327.547588 -383.544716) (xy 327.583279 -383.585907) (xy 327.612745 -383.631757)
			(xy 327.635387 -383.681334) (xy 327.650742 -383.733629) (xy 327.658498 -383.787577) (xy 327.658984 -383.814828)
			(xy 327.657968 -383.84353) (xy 327.656952 -383.856738) (xy 327.667874 -383.88036) (xy 327.758552 -383.947162)
			(xy 327.78446 -383.950464) (xy 327.796906 -383.945384) (xy 327.819417 -383.936849) (xy 327.86604 -383.924844)
			(xy 327.913804 -383.918811) (xy 327.937876 -383.91846) (xy 327.965128 -383.918986) (xy 328.019077 -383.926739)
			(xy 328.071373 -383.942092) (xy 328.120952 -383.964731) (xy 328.166804 -383.994196) (xy 328.207996 -384.029887)
			(xy 328.24369 -384.071076) (xy 328.273157 -384.116927) (xy 328.2958 -384.166504) (xy 328.306297 -384.202251)
			(xy 328.916778 -384.202251) (xy 328.916778 -384.147749) (xy 328.924534 -384.093802) (xy 328.939889 -384.041508)
			(xy 328.962529 -383.991931) (xy 328.991995 -383.946081) (xy 329.027686 -383.904891) (xy 329.068875 -383.8692)
			(xy 329.114724 -383.839733) (xy 329.1643 -383.817092) (xy 329.216594 -383.801736) (xy 329.270541 -383.793978)
			(xy 329.297792 -383.793492) (xy 329.321863 -383.793861) (xy 329.369626 -383.799895) (xy 329.416252 -383.811881)
			(xy 329.438762 -383.820416) (xy 329.451208 -383.825496) (xy 329.477116 -383.822194) (xy 329.567794 -383.755392)
			(xy 329.578716 -383.73177) (xy 329.5777 -383.718562) (xy 329.576684 -383.68986) (xy 329.57717 -383.662609)
			(xy 329.584926 -383.608661) (xy 329.600281 -383.556366) (xy 329.622923 -383.506789) (xy 329.652389 -383.460939)
			(xy 329.68808 -383.419748) (xy 329.729271 -383.384057) (xy 329.775121 -383.354591) (xy 329.824698 -383.331949)
			(xy 329.876993 -383.316594) (xy 329.930941 -383.308838) (xy 329.985443 -383.308838) (xy 330.039391 -383.316594)
			(xy 330.091686 -383.331949) (xy 330.141263 -383.354591) (xy 330.187113 -383.384057) (xy 330.228304 -383.419748)
			(xy 330.263995 -383.460939) (xy 330.293461 -383.506789) (xy 330.316103 -383.556366) (xy 330.331458 -383.608661)
			(xy 330.339214 -383.662609) (xy 330.3397 -383.68986) (xy 330.338684 -383.718562) (xy 330.337668 -383.73177)
			(xy 330.34859 -383.755392) (xy 330.439268 -383.822194) (xy 330.465176 -383.825496) (xy 330.477622 -383.820416)
			(xy 330.500132 -383.811878) (xy 330.546755 -383.799874) (xy 330.59452 -383.793842) (xy 330.618592 -383.793492)
			(xy 330.645845 -383.793955) (xy 330.699797 -383.801711) (xy 330.752096 -383.817066) (xy 330.801677 -383.839708)
			(xy 330.847531 -383.869176) (xy 330.888725 -383.90487) (xy 330.924419 -383.946063) (xy 330.953888 -383.991916)
			(xy 330.976531 -384.041497) (xy 330.991887 -384.093795) (xy 330.999645 -384.147747) (xy 330.999645 -384.202253)
			(xy 330.991887 -384.256205) (xy 330.976531 -384.308503) (xy 330.967967 -384.327256) (xy 358.763723 -384.327256)
			(xy 358.763723 -384.272744) (xy 358.771481 -384.218786) (xy 358.78684 -384.166482) (xy 358.809486 -384.116896)
			(xy 358.838959 -384.071038) (xy 358.874658 -384.029841) (xy 358.915857 -383.994144) (xy 358.961717 -383.964674)
			(xy 359.011304 -383.942031) (xy 359.06361 -383.926676) (xy 359.117568 -383.918921) (xy 359.144824 -383.91846)
			(xy 359.168895 -383.918822) (xy 359.216658 -383.924859) (xy 359.263284 -383.936848) (xy 359.285794 -383.945384)
			(xy 359.29824 -383.950464) (xy 359.324148 -383.947162) (xy 359.414826 -383.88036) (xy 359.425748 -383.856738)
			(xy 359.424732 -383.84353) (xy 359.423716 -383.814828) (xy 359.424202 -383.787577) (xy 359.431958 -383.733629)
			(xy 359.447313 -383.681334) (xy 359.469955 -383.631757) (xy 359.499421 -383.585907) (xy 359.535112 -383.544716)
			(xy 359.576303 -383.509025) (xy 359.622153 -383.479559) (xy 359.67173 -383.456917) (xy 359.724025 -383.441562)
			(xy 359.777973 -383.433806) (xy 359.832475 -383.433806) (xy 359.886423 -383.441562) (xy 359.938718 -383.456917)
			(xy 359.988295 -383.479559) (xy 360.034145 -383.509025) (xy 360.075336 -383.544716) (xy 360.111027 -383.585907)
			(xy 360.140493 -383.631757) (xy 360.163135 -383.681334) (xy 360.17849 -383.733629) (xy 360.186246 -383.787577)
			(xy 360.186732 -383.814828) (xy 360.185716 -383.84353) (xy 360.1847 -383.856738) (xy 360.195622 -383.88036)
			(xy 360.2863 -383.947162) (xy 360.312208 -383.950464) (xy 360.324654 -383.945384) (xy 360.34716 -383.936835)
			(xy 360.393785 -383.924836) (xy 360.441551 -383.918808) (xy 360.465624 -383.91846) (xy 360.492872 -383.919012)
			(xy 360.546812 -383.92677) (xy 360.5991 -383.942126) (xy 360.64867 -383.964767) (xy 360.694513 -383.994231)
			(xy 360.735697 -384.02992) (xy 360.771383 -384.071106) (xy 360.800845 -384.116951) (xy 360.823482 -384.166523)
			(xy 360.833974 -384.202255) (xy 363.489155 -384.202255) (xy 363.489155 -384.147745) (xy 363.496913 -384.093791)
			(xy 363.512272 -384.04149) (xy 363.534917 -383.991907) (xy 363.564389 -383.946052) (xy 363.600087 -383.904858)
			(xy 363.641284 -383.869165) (xy 363.687142 -383.839698) (xy 363.736727 -383.817058) (xy 363.78903 -383.801705)
			(xy 363.842985 -383.793953) (xy 363.87024 -383.793492) (xy 363.894312 -383.793847) (xy 363.942075 -383.799887)
			(xy 363.9887 -383.811878) (xy 364.01121 -383.820416) (xy 364.023656 -383.825496) (xy 364.049564 -383.822194)
			(xy 364.140242 -383.755392) (xy 364.151164 -383.73177) (xy 364.150148 -383.718562) (xy 364.149132 -383.68986)
			(xy 364.149618 -383.662609) (xy 364.157374 -383.608661) (xy 364.172729 -383.556366) (xy 364.195371 -383.506789)
			(xy 364.224837 -383.460939) (xy 364.260528 -383.419748) (xy 364.301719 -383.384057) (xy 364.347569 -383.354591)
			(xy 364.397146 -383.331949) (xy 364.449441 -383.316594) (xy 364.503389 -383.308838) (xy 364.557891 -383.308838)
			(xy 364.611839 -383.316594) (xy 364.664134 -383.331949) (xy 364.713711 -383.354591) (xy 364.759561 -383.384057)
			(xy 364.800752 -383.419748) (xy 364.836443 -383.460939) (xy 364.865909 -383.506789) (xy 364.888551 -383.556366)
			(xy 364.903906 -383.608661) (xy 364.911662 -383.662609) (xy 364.912148 -383.68986) (xy 364.911132 -383.718562)
			(xy 364.910116 -383.73177) (xy 364.921038 -383.755392) (xy 365.011716 -383.822194) (xy 365.037624 -383.825496)
			(xy 365.05007 -383.820416) (xy 365.072575 -383.811864) (xy 365.119201 -383.799865) (xy 365.166967 -383.793839)
			(xy 365.19104 -383.793492) (xy 365.218289 -383.793981) (xy 365.272233 -383.801742) (xy 365.324523 -383.8171)
			(xy 365.374095 -383.839744) (xy 365.41994 -383.869211) (xy 365.461126 -383.904903) (xy 365.496813 -383.946092)
			(xy 365.526276 -383.99194) (xy 365.548914 -384.041515) (xy 365.564267 -384.093806) (xy 365.572022 -384.147751)
			(xy 365.572022 -384.202249) (xy 365.564267 -384.256194) (xy 365.548914 -384.308485) (xy 365.526276 -384.35806)
			(xy 365.496813 -384.403908) (xy 365.461126 -384.445097) (xy 365.41994 -384.480789) (xy 365.374095 -384.510256)
			(xy 365.324523 -384.5329) (xy 365.272233 -384.548258) (xy 365.218289 -384.556019) (xy 365.19104 -384.556508)
			(xy 365.158508 -384.555826) (xy 365.094398 -384.54471) (xy 365.063532 -384.53441) (xy 365.054896 -384.531362)
			(xy 365.037116 -384.531616) (xy 364.95863 -384.56108) (xy 364.945422 -384.57251) (xy 364.94085 -384.580638)
			(xy 364.921038 -384.612896) (xy 364.916988 -384.619306) (xy 364.912465 -384.633769) (xy 364.912148 -384.641344)
			(xy 364.912148 -384.922776) (xy 364.912468 -384.930351) (xy 364.916987 -384.944815) (xy 364.921038 -384.951224)
			(xy 364.94085 -384.983482) (xy 364.945422 -384.99161) (xy 364.95863 -385.00304) (xy 365.037116 -385.032504)
			(xy 365.054896 -385.032758) (xy 365.063532 -385.02971) (xy 365.094401 -385.019423) (xy 365.158509 -385.008314)
			(xy 365.19104 -385.007612) (xy 365.218291 -385.008061) (xy 365.272237 -385.015822) (xy 365.32453 -385.031181)
			(xy 365.374105 -385.053826) (xy 365.419952 -385.083295) (xy 365.46114 -385.118988) (xy 365.496829 -385.16018)
			(xy 365.526293 -385.206031) (xy 365.548933 -385.255608) (xy 365.564286 -385.307902) (xy 365.572042 -385.361849)
			(xy 365.572042 -385.416351) (xy 365.564286 -385.470298) (xy 365.548932 -385.522592) (xy 365.526293 -385.572169)
			(xy 365.496829 -385.61802) (xy 365.46114 -385.659212) (xy 365.419952 -385.694905) (xy 365.374105 -385.724374)
			(xy 365.32453 -385.747019) (xy 365.272237 -385.762378) (xy 365.218291 -385.770139) (xy 365.19104 -385.770628)
			(xy 365.166968 -385.770278) (xy 365.119205 -385.764236) (xy 365.072579 -385.752243) (xy 365.05007 -385.743704)
			(xy 365.037624 -385.738624) (xy 365.011716 -385.741926) (xy 364.921038 -385.808728) (xy 364.910116 -385.83235)
			(xy 364.911132 -385.845558) (xy 364.912148 -385.87426) (xy 364.911662 -385.901511) (xy 364.903906 -385.955459)
			(xy 364.888551 -386.007754) (xy 364.865909 -386.057331) (xy 364.836443 -386.103181) (xy 364.800752 -386.144372)
			(xy 364.759561 -386.180063) (xy 364.713711 -386.209529) (xy 364.664134 -386.232171) (xy 364.611839 -386.247526)
			(xy 364.557891 -386.255282) (xy 364.503389 -386.255282) (xy 364.449441 -386.247526) (xy 364.397146 -386.232171)
			(xy 364.347569 -386.209529) (xy 364.301719 -386.180063) (xy 364.260528 -386.144372) (xy 364.224837 -386.103181)
			(xy 364.195371 -386.057331) (xy 364.172729 -386.007754) (xy 364.157374 -385.955459) (xy 364.149618 -385.901511)
			(xy 364.149132 -385.87426) (xy 364.150148 -385.845558) (xy 364.151164 -385.83235) (xy 364.140242 -385.808728)
			(xy 364.049564 -385.741926) (xy 364.023656 -385.738624) (xy 364.01121 -385.743704) (xy 363.988707 -385.752263)
			(xy 363.94208 -385.764259) (xy 363.894313 -385.770282) (xy 363.87024 -385.770628) (xy 363.842987 -385.770127)
			(xy 363.789034 -385.762376) (xy 363.736734 -385.747024) (xy 363.687152 -385.724385) (xy 363.641296 -385.694919)
			(xy 363.600101 -385.659228) (xy 363.564405 -385.618036) (xy 363.534934 -385.572183) (xy 363.51229 -385.522603)
			(xy 363.496933 -385.470305) (xy 363.489175 -385.416353) (xy 363.489175 -385.361847) (xy 363.496933 -385.307895)
			(xy 363.51229 -385.255597) (xy 363.534934 -385.206017) (xy 363.564405 -385.160164) (xy 363.600101 -385.118972)
			(xy 363.641296 -385.083281) (xy 363.687152 -385.053815) (xy 363.736734 -385.031176) (xy 363.789034 -385.015824)
			(xy 363.842987 -385.008073) (xy 363.87024 -385.007612) (xy 363.902772 -385.008298) (xy 363.966881 -385.019411)
			(xy 363.997748 -385.02971) (xy 364.006384 -385.032758) (xy 364.024164 -385.032504) (xy 364.10265 -385.00304)
			(xy 364.115858 -384.99161) (xy 364.12043 -384.983482) (xy 364.140242 -384.951224) (xy 364.144283 -384.944809)
			(xy 364.148812 -384.93035) (xy 364.149132 -384.922776) (xy 364.149132 -384.641344) (xy 364.148807 -384.633769)
			(xy 364.144292 -384.619305) (xy 364.140242 -384.612896) (xy 364.12043 -384.580638) (xy 364.115858 -384.57251)
			(xy 364.10265 -384.56108) (xy 364.024164 -384.531616) (xy 364.006384 -384.531362) (xy 363.997748 -384.53441)
			(xy 363.96688 -384.544702) (xy 363.902771 -384.555808) (xy 363.87024 -384.556508) (xy 363.842985 -384.556047)
			(xy 363.78903 -384.548295) (xy 363.736727 -384.532942) (xy 363.687142 -384.510302) (xy 363.641284 -384.480835)
			(xy 363.600087 -384.445142) (xy 363.564389 -384.403948) (xy 363.534917 -384.358093) (xy 363.512272 -384.30851)
			(xy 363.496913 -384.256209) (xy 363.489155 -384.202255) (xy 360.833974 -384.202255) (xy 360.838835 -384.218811)
			(xy 360.84659 -384.272752) (xy 360.84659 -384.327248) (xy 360.838835 -384.381189) (xy 360.823482 -384.433477)
			(xy 360.800845 -384.483049) (xy 360.771383 -384.528894) (xy 360.735697 -384.57008) (xy 360.694513 -384.605769)
			(xy 360.64867 -384.635233) (xy 360.5991 -384.657874) (xy 360.546812 -384.67323) (xy 360.492872 -384.680988)
			(xy 360.465624 -384.681476) (xy 360.433091 -384.6808) (xy 360.368982 -384.66968) (xy 360.338116 -384.659378)
			(xy 360.32948 -384.65633) (xy 360.3117 -384.656584) (xy 360.233214 -384.686048) (xy 360.220006 -384.697478)
			(xy 360.215434 -384.705606) (xy 360.195622 -384.737864) (xy 360.191582 -384.74428) (xy 360.187054 -384.758738)
			(xy 360.186732 -384.766312) (xy 360.186732 -385.047744) (xy 360.187067 -385.055318) (xy 360.191576 -385.069782)
			(xy 360.195622 -385.076192) (xy 360.215434 -385.10845) (xy 360.220006 -385.116578) (xy 360.233214 -385.128008)
			(xy 360.3117 -385.157472) (xy 360.32948 -385.157726) (xy 360.338116 -385.154678) (xy 360.368986 -385.144394)
			(xy 360.433094 -385.133283) (xy 360.465624 -385.13258) (xy 360.492873 -385.133092) (xy 360.546817 -385.140851)
			(xy 360.599107 -385.156208) (xy 360.648679 -385.178849) (xy 360.694525 -385.208315) (xy 360.735711 -385.244006)
			(xy 360.771399 -385.285194) (xy 360.800862 -385.331042) (xy 360.823501 -385.380616) (xy 360.838854 -385.432907)
			(xy 360.84661 -385.486851) (xy 360.84661 -385.541349) (xy 360.838854 -385.595293) (xy 360.823501 -385.647584)
			(xy 360.800862 -385.697158) (xy 360.771399 -385.743006) (xy 360.735711 -385.784194) (xy 360.694525 -385.819885)
			(xy 360.648679 -385.849351) (xy 360.599107 -385.871992) (xy 360.546817 -385.887349) (xy 360.492873 -385.895108)
			(xy 360.465624 -385.895596) (xy 360.441552 -385.895246) (xy 360.393789 -385.889203) (xy 360.347164 -385.87721)
			(xy 360.324654 -385.868672) (xy 360.312208 -385.863592) (xy 360.2863 -385.866894) (xy 360.195622 -385.933696)
			(xy 360.1847 -385.957318) (xy 360.185716 -385.970526) (xy 360.186732 -385.999228) (xy 360.186246 -386.026479)
			(xy 360.17849 -386.080427) (xy 360.163135 -386.132722) (xy 360.140493 -386.182299) (xy 360.111027 -386.228149)
			(xy 360.075336 -386.26934) (xy 360.034145 -386.305031) (xy 359.988295 -386.334497) (xy 359.938718 -386.357139)
			(xy 359.886423 -386.372494) (xy 359.832475 -386.38025) (xy 359.777973 -386.38025) (xy 359.724025 -386.372494)
			(xy 359.67173 -386.357139) (xy 359.622153 -386.334497) (xy 359.576303 -386.305031) (xy 359.535112 -386.26934)
			(xy 359.499421 -386.228149) (xy 359.469955 -386.182299) (xy 359.447313 -386.132722) (xy 359.431958 -386.080427)
			(xy 359.424202 -386.026479) (xy 359.423716 -385.999228) (xy 359.424732 -385.970526) (xy 359.425748 -385.957318)
			(xy 359.414826 -385.933696) (xy 359.324148 -385.866894) (xy 359.29824 -385.863592) (xy 359.285794 -385.868672)
			(xy 359.263284 -385.87721) (xy 359.21666 -385.889213) (xy 359.168896 -385.895245) (xy 359.144824 -385.895596)
			(xy 359.117569 -385.895159) (xy 359.063614 -385.887404) (xy 359.011311 -385.87205) (xy 358.961727 -385.849408)
			(xy 358.915869 -385.81994) (xy 358.874672 -385.784245) (xy 358.838975 -385.74305) (xy 358.809504 -385.697194)
			(xy 358.786859 -385.647611) (xy 358.771501 -385.59531) (xy 358.763743 -385.541355) (xy 358.763743 -385.486845)
			(xy 358.771501 -385.43289) (xy 358.786859 -385.380589) (xy 358.809504 -385.331006) (xy 358.838975 -385.28515)
			(xy 358.874672 -385.243955) (xy 358.915869 -385.20826) (xy 358.961727 -385.178792) (xy 359.011311 -385.15615)
			(xy 359.063614 -385.140796) (xy 359.117569 -385.133041) (xy 359.144824 -385.13258) (xy 359.177356 -385.133272)
			(xy 359.241465 -385.144381) (xy 359.272332 -385.154678) (xy 359.280968 -385.157726) (xy 359.298748 -385.157472)
			(xy 359.377234 -385.128008) (xy 359.390442 -385.116578) (xy 359.395014 -385.10845) (xy 359.414826 -385.076192)
			(xy 359.418878 -385.069783) (xy 359.4234 -385.05532) (xy 359.423716 -385.047744) (xy 359.423716 -384.766312)
			(xy 359.423407 -384.758736) (xy 359.418881 -384.744272) (xy 359.414826 -384.737864) (xy 359.395014 -384.705606)
			(xy 359.390442 -384.697478) (xy 359.377234 -384.686048) (xy 359.298748 -384.656584) (xy 359.280968 -384.65633)
			(xy 359.272332 -384.659378) (xy 359.241465 -384.669673) (xy 359.177355 -384.680777) (xy 359.144824 -384.681476)
			(xy 359.117568 -384.681079) (xy 359.06361 -384.673324) (xy 359.011304 -384.657969) (xy 358.961717 -384.635326)
			(xy 358.915857 -384.605856) (xy 358.874658 -384.570159) (xy 358.838959 -384.528962) (xy 358.809486 -384.483104)
			(xy 358.78684 -384.433518) (xy 358.771481 -384.381214) (xy 358.763723 -384.327256) (xy 330.967967 -384.327256)
			(xy 330.953888 -384.358084) (xy 330.924419 -384.403937) (xy 330.888725 -384.44513) (xy 330.847531 -384.480824)
			(xy 330.801677 -384.510292) (xy 330.752096 -384.532934) (xy 330.699797 -384.548289) (xy 330.645845 -384.556045)
			(xy 330.618592 -384.556508) (xy 330.58606 -384.555813) (xy 330.521951 -384.544706) (xy 330.491084 -384.53441)
			(xy 330.482448 -384.531362) (xy 330.464668 -384.531616) (xy 330.386182 -384.56108) (xy 330.372974 -384.57251)
			(xy 330.368402 -384.580638) (xy 330.34859 -384.612896) (xy 330.344535 -384.619303) (xy 330.340016 -384.633768)
			(xy 330.3397 -384.641344) (xy 330.3397 -384.922776) (xy 330.340027 -384.93035) (xy 330.344542 -384.944814)
			(xy 330.34859 -384.951224) (xy 330.368402 -384.983482) (xy 330.372974 -384.99161) (xy 330.386182 -385.00304)
			(xy 330.464668 -385.032504) (xy 330.482448 -385.032758) (xy 330.491084 -385.02971) (xy 330.521957 -385.019435)
			(xy 330.586062 -385.008318) (xy 330.618592 -385.007612) (xy 330.645847 -385.008034) (xy 330.699801 -385.015791)
			(xy 330.752103 -385.031147) (xy 330.801687 -385.05379) (xy 330.847543 -385.08326) (xy 330.888739 -385.118955)
			(xy 330.924436 -385.16015) (xy 330.953906 -385.206006) (xy 330.97655 -385.25559) (xy 330.991907 -385.307891)
			(xy 330.999665 -385.361845) (xy 330.999665 -385.416355) (xy 330.991907 -385.470309) (xy 330.97655 -385.52261)
			(xy 330.953906 -385.572194) (xy 330.924436 -385.61805) (xy 330.888739 -385.659245) (xy 330.847543 -385.69494)
			(xy 330.801687 -385.72441) (xy 330.752103 -385.747053) (xy 330.699801 -385.762409) (xy 330.645847 -385.770166)
			(xy 330.618592 -385.770628) (xy 330.594521 -385.770262) (xy 330.546758 -385.764227) (xy 330.500132 -385.752239)
			(xy 330.477622 -385.743704) (xy 330.465176 -385.738624) (xy 330.439268 -385.741926) (xy 330.34859 -385.808728)
			(xy 330.337668 -385.83235) (xy 330.338684 -385.845558) (xy 330.3397 -385.87426) (xy 330.339214 -385.901511)
			(xy 330.331458 -385.955459) (xy 330.316103 -386.007754) (xy 330.293461 -386.057331) (xy 330.263995 -386.103181)
			(xy 330.228304 -386.144372) (xy 330.187113 -386.180063) (xy 330.141263 -386.209529) (xy 330.091686 -386.232171)
			(xy 330.039391 -386.247526) (xy 329.985443 -386.255282) (xy 329.930941 -386.255282) (xy 329.876993 -386.247526)
			(xy 329.824698 -386.232171) (xy 329.775121 -386.209529) (xy 329.729271 -386.180063) (xy 329.68808 -386.144372)
			(xy 329.652389 -386.103181) (xy 329.622923 -386.057331) (xy 329.600281 -386.007754) (xy 329.584926 -385.955459)
			(xy 329.57717 -385.901511) (xy 329.576684 -385.87426) (xy 329.5777 -385.845558) (xy 329.578716 -385.83235)
			(xy 329.567794 -385.808728) (xy 329.477116 -385.741926) (xy 329.451208 -385.738624) (xy 329.438762 -385.743704)
			(xy 329.416254 -385.752248) (xy 329.36963 -385.764249) (xy 329.321864 -385.770279) (xy 329.297792 -385.770628)
			(xy 329.270543 -385.770101) (xy 329.216599 -385.762344) (xy 329.164308 -385.746989) (xy 329.114734 -385.724349)
			(xy 329.068887 -385.694884) (xy 329.0277 -385.659194) (xy 328.992011 -385.618006) (xy 328.962547 -385.572159)
			(xy 328.939908 -385.522585) (xy 328.924554 -385.470294) (xy 328.916798 -385.416349) (xy 328.916798 -385.361851)
			(xy 328.924554 -385.307906) (xy 328.939908 -385.255615) (xy 328.962547 -385.206041) (xy 328.992011 -385.160194)
			(xy 329.0277 -385.119006) (xy 329.068887 -385.083316) (xy 329.114734 -385.053851) (xy 329.164308 -385.031211)
			(xy 329.216599 -385.015856) (xy 329.270543 -385.008099) (xy 329.297792 -385.007612) (xy 329.330323 -385.00831)
			(xy 329.394433 -385.019415) (xy 329.4253 -385.02971) (xy 329.433936 -385.032758) (xy 329.451716 -385.032504)
			(xy 329.530202 -385.00304) (xy 329.54341 -384.99161) (xy 329.547982 -384.983482) (xy 329.567794 -384.951224)
			(xy 329.57184 -384.944812) (xy 329.576365 -384.930351) (xy 329.576684 -384.922776) (xy 329.576684 -384.641344)
			(xy 329.576351 -384.63377) (xy 329.571841 -384.619306) (xy 329.567794 -384.612896) (xy 329.547982 -384.580638)
			(xy 329.54341 -384.57251) (xy 329.530202 -384.56108) (xy 329.451716 -384.531616) (xy 329.433936 -384.531362)
			(xy 329.4253 -384.53441) (xy 329.394429 -384.54469) (xy 329.330322 -384.555803) (xy 329.297792 -384.556508)
			(xy 329.270541 -384.556022) (xy 329.216594 -384.548264) (xy 329.1643 -384.532908) (xy 329.114724 -384.510267)
			(xy 329.068875 -384.4808) (xy 329.027686 -384.445109) (xy 328.991995 -384.403919) (xy 328.962529 -384.358069)
			(xy 328.939889 -384.308492) (xy 328.924534 -384.256198) (xy 328.916778 -384.202251) (xy 328.306297 -384.202251)
			(xy 328.311156 -384.2188) (xy 328.318913 -384.272748) (xy 328.318913 -384.327252) (xy 328.311156 -384.3812)
			(xy 328.2958 -384.433496) (xy 328.273157 -384.483073) (xy 328.24369 -384.528924) (xy 328.207996 -384.570113)
			(xy 328.166804 -384.605804) (xy 328.120952 -384.635269) (xy 328.071373 -384.657908) (xy 328.019077 -384.673261)
			(xy 327.965128 -384.681014) (xy 327.937876 -384.681476) (xy 327.905344 -384.680787) (xy 327.841235 -384.669676)
			(xy 327.810368 -384.659378) (xy 327.801732 -384.65633) (xy 327.783952 -384.656584) (xy 327.705466 -384.686048)
			(xy 327.692258 -384.697478) (xy 327.687686 -384.705606) (xy 327.667874 -384.737864) (xy 327.663839 -384.744282)
			(xy 327.659306 -384.758739) (xy 327.658984 -384.766312) (xy 327.658984 -385.047744) (xy 327.659311 -385.055319)
			(xy 327.663825 -385.069783) (xy 327.667874 -385.076192) (xy 327.687686 -385.10845) (xy 327.692258 -385.116578)
			(xy 327.705466 -385.128008) (xy 327.783952 -385.157472) (xy 327.801732 -385.157726) (xy 327.810368 -385.154678)
			(xy 327.841234 -385.144382) (xy 327.905345 -385.133279) (xy 327.937876 -385.13258) (xy 327.965129 -385.133066)
			(xy 328.019081 -385.14082) (xy 328.07138 -385.156173) (xy 328.120962 -385.178814) (xy 328.166816 -385.20828)
			(xy 328.208011 -385.243972) (xy 328.243706 -385.285164) (xy 328.273175 -385.331017) (xy 328.295819 -385.380597)
			(xy 328.311175 -385.432896) (xy 328.318933 -385.486847) (xy 328.318933 -385.541353) (xy 328.311175 -385.595304)
			(xy 328.295819 -385.647603) (xy 328.273175 -385.697183) (xy 328.243706 -385.743036) (xy 328.208011 -385.784228)
			(xy 328.166816 -385.81992) (xy 328.120962 -385.849386) (xy 328.07138 -385.872027) (xy 328.019081 -385.88738)
			(xy 327.965129 -385.895134) (xy 327.937876 -385.895596) (xy 327.913805 -385.89523) (xy 327.866042 -385.889194)
			(xy 327.819416 -385.877207) (xy 327.796906 -385.868672) (xy 327.78446 -385.863592) (xy 327.758552 -385.866894)
			(xy 327.667874 -385.933696) (xy 327.656952 -385.957318) (xy 327.657968 -385.970526) (xy 327.658984 -385.999228)
			(xy 327.658498 -386.026479) (xy 327.650742 -386.080427) (xy 327.635387 -386.132722) (xy 327.612745 -386.182299)
			(xy 327.583279 -386.228149) (xy 327.547588 -386.26934) (xy 327.506397 -386.305031) (xy 327.460547 -386.334497)
			(xy 327.41097 -386.357139) (xy 327.358675 -386.372494) (xy 327.304727 -386.38025) (xy 327.250225 -386.38025)
			(xy 327.196277 -386.372494) (xy 327.143982 -386.357139) (xy 327.094405 -386.334497) (xy 327.048555 -386.305031)
			(xy 327.007364 -386.26934) (xy 326.971673 -386.228149) (xy 326.942207 -386.182299) (xy 326.919565 -386.132722)
			(xy 326.90421 -386.080427) (xy 326.896454 -386.026479) (xy 326.895968 -385.999228) (xy 326.896984 -385.970526)
			(xy 326.898 -385.957318) (xy 326.887078 -385.933696) (xy 326.7964 -385.866894) (xy 326.770492 -385.863592)
			(xy 326.758046 -385.868672) (xy 326.735541 -385.877224) (xy 326.688915 -385.889221) (xy 326.641149 -385.895248)
			(xy 326.617076 -385.895596) (xy 326.589825 -385.895133) (xy 326.535878 -385.887373) (xy 326.483585 -385.872015)
			(xy 326.434009 -385.849372) (xy 326.38816 -385.819904) (xy 326.346971 -385.784212) (xy 326.311281 -385.743021)
			(xy 326.281816 -385.69717) (xy 326.259176 -385.647593) (xy 326.243822 -385.595298) (xy 326.236066 -385.541351)
			(xy 326.236066 -385.486849) (xy 326.243822 -385.432902) (xy 326.259176 -385.380607) (xy 326.281816 -385.33103)
			(xy 326.311281 -385.285179) (xy 326.346971 -385.243988) (xy 326.38816 -385.208296) (xy 326.434009 -385.178828)
			(xy 326.483585 -385.156185) (xy 326.535878 -385.140827) (xy 326.589825 -385.133067) (xy 326.617076 -385.13258)
			(xy 326.649608 -385.133259) (xy 326.713718 -385.144377) (xy 326.744584 -385.154678) (xy 326.75322 -385.157726)
			(xy 326.771 -385.157472) (xy 326.849486 -385.128008) (xy 326.862694 -385.116578) (xy 326.867266 -385.10845)
			(xy 326.887078 -385.076192) (xy 326.891134 -385.069786) (xy 326.895653 -385.05532) (xy 326.895968 -385.047744)
			(xy 326.895968 -384.766312) (xy 326.895651 -384.758737) (xy 326.89113 -384.744273) (xy 326.887078 -384.737864)
			(xy 326.867266 -384.705606) (xy 326.862694 -384.697478) (xy 326.849486 -384.686048) (xy 326.771 -384.656584)
			(xy 326.75322 -384.65633) (xy 326.744584 -384.659378) (xy 326.713713 -384.669661) (xy 326.649606 -384.680773)
			(xy 326.617076 -384.681476) (xy 326.589824 -384.681053) (xy 326.535874 -384.673293) (xy 326.483578 -384.657934)
			(xy 326.433999 -384.63529) (xy 326.388148 -384.60582) (xy 326.346957 -384.570126) (xy 326.311265 -384.528933)
			(xy 326.281799 -384.48308) (xy 326.259158 -384.4335) (xy 326.243802 -384.381203) (xy 326.236046 -384.327252)
			(xy 298.440144 -384.327252) (xy 298.426076 -384.358059) (xy 298.396614 -384.403907) (xy 298.360927 -384.445096)
			(xy 298.319742 -384.480788) (xy 298.273897 -384.510255) (xy 298.224326 -384.532899) (xy 298.172036 -384.548258)
			(xy 298.118093 -384.556019) (xy 298.090844 -384.556508) (xy 298.058312 -384.555825) (xy 297.994203 -384.54471)
			(xy 297.963336 -384.53441) (xy 297.9547 -384.531362) (xy 297.93692 -384.531616) (xy 297.858434 -384.56108)
			(xy 297.845226 -384.57251) (xy 297.840654 -384.580638) (xy 297.820842 -384.612896) (xy 297.816792 -384.619306)
			(xy 297.812269 -384.633769) (xy 297.811952 -384.641344) (xy 297.811952 -384.922776) (xy 297.812271 -384.930351)
			(xy 297.816791 -384.944815) (xy 297.820842 -384.951224) (xy 297.840654 -384.983482) (xy 297.845226 -384.99161)
			(xy 297.858434 -385.00304) (xy 297.93692 -385.032504) (xy 297.9547 -385.032758) (xy 297.963336 -385.02971)
			(xy 297.994205 -385.019422) (xy 298.058313 -385.008314) (xy 298.090844 -385.007612) (xy 298.118095 -385.008061)
			(xy 298.17204 -385.015823) (xy 298.224333 -385.031183) (xy 298.273907 -385.053827) (xy 298.319754 -385.083296)
			(xy 298.360941 -385.11899) (xy 298.39663 -385.160181) (xy 298.426094 -385.206032) (xy 298.448733 -385.255609)
			(xy 298.464087 -385.307903) (xy 298.471842 -385.361849) (xy 298.471842 -385.416351) (xy 298.464087 -385.470297)
			(xy 298.448733 -385.522591) (xy 298.426094 -385.572168) (xy 298.39663 -385.618019) (xy 298.360941 -385.65921)
			(xy 298.319754 -385.694904) (xy 298.273907 -385.724373) (xy 298.224333 -385.747017) (xy 298.17204 -385.762377)
			(xy 298.118095 -385.770139) (xy 298.090844 -385.770628) (xy 298.066772 -385.770277) (xy 298.019009 -385.764235)
			(xy 297.972384 -385.752242) (xy 297.949874 -385.743704) (xy 297.937428 -385.738624) (xy 297.91152 -385.741926)
			(xy 297.820842 -385.808728) (xy 297.80992 -385.83235) (xy 297.810936 -385.845558) (xy 297.811952 -385.87426)
			(xy 297.811466 -385.901511) (xy 297.80371 -385.955459) (xy 297.788355 -386.007754) (xy 297.765713 -386.057331)
			(xy 297.736247 -386.103181) (xy 297.700556 -386.144372) (xy 297.659365 -386.180063) (xy 297.613515 -386.209529)
			(xy 297.563938 -386.232171) (xy 297.511643 -386.247526) (xy 297.457695 -386.255282) (xy 297.403193 -386.255282)
			(xy 297.349245 -386.247526) (xy 297.29695 -386.232171) (xy 297.247373 -386.209529) (xy 297.201523 -386.180063)
			(xy 297.160332 -386.144372) (xy 297.124641 -386.103181) (xy 297.095175 -386.057331) (xy 297.072533 -386.007754)
			(xy 297.057178 -385.955459) (xy 297.049422 -385.901511) (xy 297.048936 -385.87426) (xy 297.049952 -385.845558)
			(xy 297.050968 -385.83235) (xy 297.040046 -385.808728) (xy 296.949368 -385.741926) (xy 296.92346 -385.738624)
			(xy 296.911014 -385.743704) (xy 296.888511 -385.752262) (xy 296.841884 -385.764258) (xy 296.794117 -385.770282)
			(xy 296.770044 -385.770628) (xy 296.742791 -385.770128) (xy 296.688838 -385.762376) (xy 296.636537 -385.747025)
			(xy 296.586954 -385.724386) (xy 296.541098 -385.694921) (xy 296.499902 -385.659229) (xy 296.464206 -385.618037)
			(xy 296.434735 -385.572184) (xy 296.412091 -385.522604) (xy 296.396733 -385.470305) (xy 296.388975 -385.416353)
			(xy 296.388975 -385.361847) (xy 296.396733 -385.307895) (xy 296.412091 -385.255596) (xy 296.434735 -385.206016)
			(xy 296.464206 -385.160163) (xy 296.499902 -385.118971) (xy 296.541098 -385.083279) (xy 296.586954 -385.053814)
			(xy 296.636537 -385.031175) (xy 296.688838 -385.015824) (xy 296.742791 -385.008072) (xy 296.770044 -385.007612)
			(xy 296.802576 -385.008297) (xy 296.866685 -385.019411) (xy 296.897552 -385.02971) (xy 296.906188 -385.032758)
			(xy 296.923968 -385.032504) (xy 297.002454 -385.00304) (xy 297.015662 -384.99161) (xy 297.020234 -384.983482)
			(xy 297.040046 -384.951224) (xy 297.044088 -384.944809) (xy 297.048616 -384.93035) (xy 297.048936 -384.922776)
			(xy 297.048936 -384.641344) (xy 297.048611 -384.633769) (xy 297.044095 -384.619305) (xy 297.040046 -384.612896)
			(xy 297.020234 -384.580638) (xy 297.015662 -384.57251) (xy 297.002454 -384.56108) (xy 296.923968 -384.531616)
			(xy 296.906188 -384.531362) (xy 296.897552 -384.53441) (xy 296.866684 -384.544701) (xy 296.802575 -384.555807)
			(xy 296.770044 -384.556508) (xy 296.742789 -384.556048) (xy 296.688833 -384.548296) (xy 296.63653 -384.532944)
			(xy 296.586945 -384.510304) (xy 296.541086 -384.480837) (xy 296.499888 -384.445143) (xy 296.46419 -384.403949)
			(xy 296.434718 -384.358094) (xy 296.412072 -384.308511) (xy 296.396714 -384.25621) (xy 296.388955 -384.202255)
			(xy 295.61282 -384.202255) (xy 295.61282 -386.549138) (xy 295.612391 -386.559206) (xy 295.604669 -386.577802)
			(xy 295.597834 -386.585206) (xy 292.841426 -389.341614) (xy 292.834028 -389.348458) (xy 292.815428 -389.356179)
			(xy 292.805358 -389.3566) (xy 289.211766 -389.3566) (xy 289.201699 -389.357029) (xy 289.183103 -389.364753)
			(xy 289.175698 -389.371586) (xy 288.84753 -389.699754) (xy 288.840689 -389.707154) (xy 288.832969 -389.725753)
			(xy 288.832544 -389.735822) (xy 288.832544 -389.739455) (xy 296.388955 -389.739455) (xy 296.388955 -389.684945)
			(xy 296.396714 -389.63099) (xy 296.412072 -389.578689) (xy 296.434718 -389.529106) (xy 296.46419 -389.483251)
			(xy 296.499888 -389.442057) (xy 296.541086 -389.406363) (xy 296.586945 -389.376896) (xy 296.63653 -389.354256)
			(xy 296.688833 -389.338904) (xy 296.742789 -389.331152) (xy 296.770044 -389.330692) (xy 296.793981 -389.331055)
			(xy 296.841481 -389.337024) (xy 296.887858 -389.3489) (xy 296.910252 -389.357362) (xy 296.92219 -389.362188)
			(xy 296.947082 -389.35914) (xy 297.038014 -389.295894) (xy 297.04919 -389.273796) (xy 297.048936 -389.260588)
			(xy 297.048936 -389.25246) (xy 297.049422 -389.225209) (xy 297.057178 -389.171261) (xy 297.072533 -389.118966)
			(xy 297.095175 -389.069389) (xy 297.124641 -389.023539) (xy 297.160332 -388.982348) (xy 297.201523 -388.946657)
			(xy 297.247373 -388.917191) (xy 297.29695 -388.894549) (xy 297.349245 -388.879194) (xy 297.403193 -388.871438)
			(xy 297.457695 -388.871438) (xy 297.511643 -388.879194) (xy 297.563938 -388.894549) (xy 297.613515 -388.917191)
			(xy 297.659365 -388.946657) (xy 297.700556 -388.982348) (xy 297.736247 -389.023539) (xy 297.765713 -389.069389)
			(xy 297.788355 -389.118966) (xy 297.80371 -389.171261) (xy 297.811466 -389.225209) (xy 297.811952 -389.25246)
			(xy 297.811952 -389.260588) (xy 297.811698 -389.273796) (xy 297.822874 -389.295894) (xy 297.913806 -389.35914)
			(xy 297.938698 -389.362188) (xy 297.950636 -389.357362) (xy 297.973037 -389.348921) (xy 298.019413 -389.337052)
			(xy 298.066909 -389.331067) (xy 298.090844 -389.330692) (xy 298.118093 -389.331181) (xy 298.172036 -389.338942)
			(xy 298.224326 -389.354301) (xy 298.273897 -389.376945) (xy 298.319742 -389.406412) (xy 298.360927 -389.442104)
			(xy 298.396614 -389.483293) (xy 298.426076 -389.529141) (xy 298.448714 -389.578716) (xy 298.464067 -389.631007)
			(xy 298.471822 -389.684951) (xy 298.471822 -389.739449) (xy 298.464067 -389.793393) (xy 298.448714 -389.845684)
			(xy 298.426076 -389.895259) (xy 298.396614 -389.941107) (xy 298.360927 -389.982296) (xy 298.319742 -390.017988)
			(xy 298.273897 -390.047455) (xy 298.224326 -390.070099) (xy 298.172036 -390.085458) (xy 298.118093 -390.093219)
			(xy 298.090844 -390.093708) (xy 298.058312 -390.093025) (xy 297.994203 -390.08191) (xy 297.963336 -390.07161)
			(xy 297.9547 -390.068562) (xy 297.93692 -390.068816) (xy 297.858434 -390.09828) (xy 297.845226 -390.10971)
			(xy 297.840654 -390.117838) (xy 297.820842 -390.150096) (xy 297.816792 -390.156506) (xy 297.812269 -390.170969)
			(xy 297.811952 -390.178544) (xy 297.811952 -390.459976) (xy 297.812271 -390.467551) (xy 297.816791 -390.482015)
			(xy 297.820842 -390.488424) (xy 297.840654 -390.520682) (xy 297.845226 -390.52881) (xy 297.858434 -390.54024)
			(xy 297.93692 -390.569704) (xy 297.9547 -390.569958) (xy 297.963336 -390.56691) (xy 297.994205 -390.556622)
			(xy 298.058313 -390.545514) (xy 298.090844 -390.544812) (xy 298.118095 -390.545261) (xy 298.17204 -390.553023)
			(xy 298.224333 -390.568383) (xy 298.273907 -390.591027) (xy 298.319754 -390.620496) (xy 298.360941 -390.65619)
			(xy 298.39663 -390.697381) (xy 298.426094 -390.743232) (xy 298.448733 -390.792809) (xy 298.464087 -390.845103)
			(xy 298.471842 -390.899049) (xy 298.471842 -390.953551) (xy 298.464087 -391.007497) (xy 298.448733 -391.059791)
			(xy 298.426094 -391.109368) (xy 298.39663 -391.155219) (xy 298.360941 -391.19641) (xy 298.319754 -391.232104)
			(xy 298.273907 -391.261573) (xy 298.224333 -391.284217) (xy 298.17204 -391.299577) (xy 298.118095 -391.307339)
			(xy 298.090844 -391.307828) (xy 298.066772 -391.307477) (xy 298.019009 -391.301435) (xy 297.972384 -391.289442)
			(xy 297.949874 -391.280904) (xy 297.937428 -391.275824) (xy 297.91152 -391.279126) (xy 297.820842 -391.345928)
			(xy 297.80992 -391.36955) (xy 297.810936 -391.382758) (xy 297.811952 -391.41146) (xy 297.811466 -391.438711)
			(xy 297.80371 -391.492659) (xy 297.788355 -391.544954) (xy 297.765713 -391.594531) (xy 297.736247 -391.640381)
			(xy 297.700556 -391.681572) (xy 297.659365 -391.717263) (xy 297.613515 -391.746729) (xy 297.563938 -391.769371)
			(xy 297.511643 -391.784726) (xy 297.457695 -391.792482) (xy 297.403193 -391.792482) (xy 297.349245 -391.784726)
			(xy 297.29695 -391.769371) (xy 297.247373 -391.746729) (xy 297.201523 -391.717263) (xy 297.160332 -391.681572)
			(xy 297.124641 -391.640381) (xy 297.095175 -391.594531) (xy 297.072533 -391.544954) (xy 297.057178 -391.492659)
			(xy 297.049422 -391.438711) (xy 297.048936 -391.41146) (xy 297.049952 -391.382758) (xy 297.050968 -391.36955)
			(xy 297.040046 -391.345928) (xy 296.949368 -391.279126) (xy 296.92346 -391.275824) (xy 296.911014 -391.280904)
			(xy 296.888511 -391.289462) (xy 296.841884 -391.301458) (xy 296.794117 -391.307482) (xy 296.770044 -391.307828)
			(xy 296.742791 -391.307328) (xy 296.688838 -391.299576) (xy 296.636537 -391.284225) (xy 296.586954 -391.261586)
			(xy 296.541098 -391.232121) (xy 296.499902 -391.196429) (xy 296.464206 -391.155237) (xy 296.434735 -391.109384)
			(xy 296.412091 -391.059804) (xy 296.396733 -391.007505) (xy 296.388975 -390.953553) (xy 296.388975 -390.899047)
			(xy 296.396733 -390.845095) (xy 296.412091 -390.792796) (xy 296.434735 -390.743216) (xy 296.464206 -390.697363)
			(xy 296.499902 -390.656171) (xy 296.541098 -390.620479) (xy 296.586954 -390.591014) (xy 296.636537 -390.568375)
			(xy 296.688838 -390.553024) (xy 296.742791 -390.545272) (xy 296.770044 -390.544812) (xy 296.802576 -390.545497)
			(xy 296.866685 -390.556611) (xy 296.897552 -390.56691) (xy 296.906188 -390.569958) (xy 296.923968 -390.569704)
			(xy 297.002454 -390.54024) (xy 297.015662 -390.52881) (xy 297.020234 -390.520682) (xy 297.040046 -390.488424)
			(xy 297.044088 -390.482009) (xy 297.048616 -390.46755) (xy 297.048936 -390.459976) (xy 297.048936 -390.178544)
			(xy 297.048611 -390.170969) (xy 297.044095 -390.156505) (xy 297.040046 -390.150096) (xy 297.020234 -390.117838)
			(xy 297.015662 -390.10971) (xy 297.002454 -390.09828) (xy 296.923968 -390.068816) (xy 296.906188 -390.068562)
			(xy 296.897552 -390.07161) (xy 296.866684 -390.081901) (xy 296.802575 -390.093007) (xy 296.770044 -390.093708)
			(xy 296.742789 -390.093248) (xy 296.688833 -390.085496) (xy 296.63653 -390.070144) (xy 296.586945 -390.047504)
			(xy 296.541086 -390.018037) (xy 296.499888 -389.982343) (xy 296.46419 -389.941149) (xy 296.434718 -389.895294)
			(xy 296.412072 -389.845711) (xy 296.396714 -389.79341) (xy 296.388955 -389.739455) (xy 288.832544 -389.739455)
			(xy 288.832544 -393.99845) (xy 294.43426 -393.99845) (xy 294.434845 -393.962144) (xy 294.443841 -393.890092)
			(xy 294.461688 -393.819707) (xy 294.488111 -393.752073) (xy 294.522704 -393.688231) (xy 294.564935 -393.629163)
			(xy 294.614154 -393.575778) (xy 294.641524 -393.551918) (xy 294.648387 -393.545546) (xy 294.657367 -393.529127)
			(xy 294.65905 -393.519914) (xy 294.663114 -393.489434) (xy 294.663902 -393.480302) (xy 294.659749 -393.462466)
			(xy 294.654986 -393.454636) (xy 294.639971 -393.431077) (xy 294.616233 -393.380507) (xy 294.600119 -393.327016)
			(xy 294.591974 -393.271748) (xy 294.591486 -393.243816) (xy 294.59199 -393.215359) (xy 294.600429 -393.159074)
			(xy 294.617139 -393.104668) (xy 294.641747 -393.053349) (xy 294.673707 -393.006256) (xy 294.71231 -392.964435)
			(xy 294.756699 -392.928814) (xy 294.805887 -392.900185) (xy 294.858784 -392.879182) (xy 294.88638 -392.872214)
			(xy 294.89518 -392.869812) (xy 294.910405 -392.859784) (xy 294.916098 -392.852656) (xy 294.934132 -392.827764)
			(xy 294.939287 -392.82) (xy 294.944104 -392.802014) (xy 294.94353 -392.792712) (xy 294.94211 -392.777958)
			(xy 294.940588 -392.748352) (xy 294.940482 -392.73353) (xy 294.940961 -392.699075) (xy 294.949057 -392.630643)
			(xy 294.96514 -392.563637) (xy 294.988988 -392.498985) (xy 295.02027 -392.437585) (xy 295.058551 -392.380287)
			(xy 295.103302 -392.327886) (xy 295.153902 -392.281108) (xy 295.20965 -392.240602) (xy 295.269772 -392.206929)
			(xy 295.333435 -392.180556) (xy 295.399757 -392.161849) (xy 295.467818 -392.151067) (xy 295.536674 -392.14836)
			(xy 295.605371 -392.153765) (xy 295.672957 -392.167207) (xy 295.738495 -392.188499) (xy 295.801075 -392.217347)
			(xy 295.859831 -392.253351) (xy 295.913948 -392.296012) (xy 295.962675 -392.344737) (xy 296.005337 -392.398853)
			(xy 296.041343 -392.457607) (xy 296.070193 -392.520187) (xy 296.091488 -392.585723) (xy 296.104933 -392.653309)
			(xy 296.11034 -392.722006) (xy 296.107635 -392.790862) (xy 296.096855 -392.858924) (xy 296.07815 -392.925246)
			(xy 296.05178 -392.98891) (xy 296.018109 -393.049033) (xy 295.977605 -393.104782) (xy 295.930829 -393.155384)
			(xy 295.878429 -393.200137) (xy 295.821132 -393.23842) (xy 295.759733 -393.269704) (xy 295.695083 -393.293554)
			(xy 295.628077 -393.30964) (xy 295.559645 -393.317738) (xy 295.52519 -393.318238) (xy 295.498819 -393.317962)
			(xy 295.446287 -393.31326) (xy 295.420288 -393.30884) (xy 295.411091 -393.307603) (xy 295.392861 -393.310979)
			(xy 295.384728 -393.315444) (xy 295.358566 -393.331446) (xy 295.350929 -393.336465) (xy 295.339615 -393.350804)
			(xy 295.336468 -393.359386) (xy 295.331831 -393.373533) (xy 295.320642 -393.401123) (xy 295.314116 -393.414504)
			(xy 295.310439 -393.422897) (xy 295.308604 -393.441113) (xy 295.31056 -393.450064) (xy 295.31818 -393.479782)
			(xy 295.320977 -393.488744) (xy 295.331919 -393.503983) (xy 295.339516 -393.5095) (xy 295.369499 -393.529808)
			(xy 295.424707 -393.576675) (xy 295.473702 -393.630003) (xy 295.515733 -393.688976) (xy 295.550156 -393.752689)
			(xy 295.576444 -393.820168) (xy 295.594195 -393.890377) (xy 295.603136 -393.962241) (xy 295.603676 -393.99845)
			(xy 295.603181 -394.032477) (xy 295.595281 -394.10007) (xy 295.579587 -394.166288) (xy 295.556311 -394.230237)
			(xy 295.525769 -394.291052) (xy 295.488373 -394.347909) (xy 295.44463 -394.400041) (xy 295.39513 -394.446742)
			(xy 295.340543 -394.48738) (xy 295.281607 -394.521407) (xy 295.219119 -394.548361) (xy 295.153925 -394.567879)
			(xy 295.086906 -394.579697) (xy 295.018968 -394.583654) (xy 294.95103 -394.579697) (xy 294.884011 -394.567879)
			(xy 294.818817 -394.548361) (xy 294.756329 -394.521407) (xy 294.697393 -394.48738) (xy 294.642806 -394.446742)
			(xy 294.593306 -394.400041) (xy 294.549563 -394.347909) (xy 294.512167 -394.291052) (xy 294.481625 -394.230237)
			(xy 294.458349 -394.166288) (xy 294.442655 -394.10007) (xy 294.434755 -394.032477) (xy 294.43426 -393.99845)
			(xy 288.832544 -393.99845) (xy 288.832544 -394.88745) (xy 288.832978 -394.897515) (xy 288.84071 -394.916102)
			(xy 288.84753 -394.923518) (xy 289.268408 -395.344396) (xy 289.275807 -395.351241) (xy 289.294405 -395.358974)
			(xy 289.304476 -395.359382) (xy 291.96919 -395.359382) (xy 291.97955 -395.358844) (xy 291.99856 -395.350589)
			(xy 292.00602 -395.34338) (xy 292.064186 -395.282166) (xy 292.071298 -395.262862) (xy 292.070536 -395.252194)
			(xy 292.070028 -395.231366) (xy 292.070494 -395.204116) (xy 292.078255 -395.15017) (xy 292.093614 -395.097879)
			(xy 292.116259 -395.048305) (xy 292.145729 -395.002459) (xy 292.181423 -394.961273) (xy 292.222615 -394.925587)
			(xy 292.268467 -394.896125) (xy 292.318044 -394.87349) (xy 292.370339 -394.85814) (xy 292.424286 -394.850389)
			(xy 292.451536 -394.849858) (xy 292.483154 -394.850503) (xy 292.545519 -394.860968) (xy 292.605311 -394.881556)
			(xy 292.6334 -394.896086) (xy 292.641555 -394.900069) (xy 292.659522 -394.902533) (xy 292.668452 -394.900912)
			(xy 292.69817 -394.894308) (xy 292.707178 -394.892011) (xy 292.722811 -394.881983) (xy 292.72865 -394.87475)
			(xy 292.749297 -394.847198) (xy 292.796044 -394.796649) (xy 292.848406 -394.751941) (xy 292.905656 -394.713693)
			(xy 292.967004 -394.682436) (xy 293.031598 -394.658601) (xy 293.098546 -394.64252) (xy 293.166918 -394.634413)
			(xy 293.201344 -394.633958) (xy 293.238129 -394.634516) (xy 293.311117 -394.64375) (xy 293.38237 -394.662066)
			(xy 293.450763 -394.689176) (xy 293.515215 -394.724651) (xy 293.574708 -394.76793) (xy 293.601902 -394.792708)
			(xy 293.6106 -394.800048) (xy 293.632242 -394.806993) (xy 293.654769 -394.803965) (xy 293.66464 -394.798296)
			(xy 293.689513 -394.782546) (xy 293.742189 -394.756249) (xy 293.797549 -394.736212) (xy 293.854852 -394.722701)
			(xy 293.913333 -394.715899) (xy 293.94277 -394.715492) (xy 293.973503 -394.715936) (xy 294.034522 -394.723342)
			(xy 294.094203 -394.738048) (xy 294.151676 -394.759842) (xy 294.206103 -394.788405) (xy 294.256691 -394.82332)
			(xy 294.3027 -394.864078) (xy 294.343461 -394.910086) (xy 294.37838 -394.960671) (xy 294.406945 -395.015096)
			(xy 294.428743 -395.072568) (xy 294.443453 -395.132248) (xy 294.450862 -395.193267) (xy 294.451278 -395.224)
			(xy 294.450516 -395.252194) (xy 294.450008 -395.262862) (xy 294.456866 -395.282166) (xy 294.515032 -395.34338)
			(xy 294.522478 -395.35061) (xy 294.541495 -395.358871) (xy 294.551862 -395.359382) (xy 296.723308 -395.359382)
			(xy 296.733327 -395.358961) (xy 296.751838 -395.351289) (xy 296.766004 -395.337116) (xy 296.773666 -395.318601)
			(xy 296.774108 -395.308582) (xy 296.774108 -395.308074) (xy 296.774574 -395.277344) (xy 296.781985 -395.216334)
			(xy 296.796696 -395.156661) (xy 296.818492 -395.099196) (xy 296.847056 -395.044778) (xy 296.881971 -394.9942)
			(xy 296.922728 -394.948199) (xy 296.968733 -394.907445) (xy 297.019314 -394.872534) (xy 297.073735 -394.843975)
			(xy 297.131201 -394.822183) (xy 297.190875 -394.807477) (xy 297.251886 -394.800071) (xy 297.282616 -394.799566)
			(xy 297.303541 -394.799782) (xy 297.345249 -394.803217) (xy 297.365928 -394.806424) (xy 297.375072 -394.807948)
			(xy 297.392852 -394.804646) (xy 297.464988 -394.760958) (xy 297.476164 -394.746988) (xy 297.479212 -394.738352)
			(xy 297.487979 -394.713331) (xy 297.51146 -394.665796) (xy 297.541302 -394.621975) (xy 297.576927 -394.58271)
			(xy 297.617651 -394.548762) (xy 297.662685 -394.520784) (xy 297.711162 -394.499316) (xy 297.762146 -394.484773)
			(xy 297.814653 -394.477435) (xy 297.841162 -394.476986) (xy 297.868417 -394.477447) (xy 297.922372 -394.485199)
			(xy 297.974675 -394.500552) (xy 298.02426 -394.523192) (xy 298.070118 -394.552659) (xy 298.111316 -394.588353)
			(xy 298.147015 -394.629546) (xy 298.176487 -394.675401) (xy 298.199133 -394.724984) (xy 298.214491 -394.777285)
			(xy 298.22225 -394.831239) (xy 298.22267 -394.858494) (xy 298.222131 -394.887481) (xy 298.21336 -394.944786)
			(xy 298.196018 -395.000105) (xy 298.170506 -395.052163) (xy 298.137411 -395.099761) (xy 298.097495 -395.141804)
			(xy 298.051676 -395.177323) (xy 298.001011 -395.205499) (xy 297.946666 -395.225685) (xy 297.889892 -395.237416)
			(xy 297.860974 -395.239494) (xy 297.851459 -395.240414) (xy 297.834098 -395.248378) (xy 297.827192 -395.254988)
			(xy 297.79087 -395.292326) (xy 297.791124 -395.308074) (xy 297.791124 -395.308582) (xy 297.791541 -395.318604)
			(xy 297.799209 -395.337123) (xy 297.813382 -395.351295) (xy 297.831902 -395.35896) (xy 297.841924 -395.359382)
			(xy 299.072808 -395.359382) (xy 299.082877 -395.358957) (xy 299.101478 -395.351239) (xy 299.108876 -395.344396)
			(xy 299.152818 -395.300454) (xy 299.159666 -395.293057) (xy 299.167397 -395.274458) (xy 299.167804 -395.264386)
			(xy 299.167804 -395.104366) (xy 299.16726 -395.094381) (xy 299.159539 -395.075958) (xy 299.152818 -395.068552)
			(xy 298.781216 -394.69695) (xy 298.76444 -394.679524) (xy 298.736033 -394.640376) (xy 298.714112 -394.59726)
			(xy 298.699218 -394.551241) (xy 298.69172 -394.503457) (xy 298.6913 -394.479272) (xy 298.6913 -394.29436)
			(xy 298.692009 -394.263758) (xy 298.704045 -394.203749) (xy 298.715176 -394.175234) (xy 298.71924 -394.165836)
			(xy 298.71924 -394.10386) (xy 298.719788 -394.087172) (xy 298.728426 -394.054933) (xy 298.745105 -394.026022)
			(xy 298.76869 -394.002406) (xy 298.797579 -393.98569) (xy 298.829807 -393.97701) (xy 298.846494 -393.976352)
			(xy 299.117004 -393.976352) (xy 299.127021 -393.975931) (xy 299.145529 -393.968259) (xy 299.159688 -393.954085)
			(xy 299.167341 -393.93557) (xy 299.167804 -393.925552) (xy 299.167804 -393.475718) (xy 299.16727 -393.465729)
			(xy 299.159561 -393.447292) (xy 299.152818 -393.439904) (xy 298.781216 -393.068302) (xy 298.764437 -393.050877)
			(xy 298.736023 -393.011731) (xy 298.714095 -392.968615) (xy 298.699193 -392.922596) (xy 298.691687 -392.87481)
			(xy 298.6913 -392.850624) (xy 298.6913 -392.66876) (xy 298.692009 -392.638158) (xy 298.704045 -392.578149)
			(xy 298.715176 -392.549634) (xy 298.71924 -392.540236) (xy 298.71924 -392.47826) (xy 298.719788 -392.461572)
			(xy 298.728426 -392.429333) (xy 298.745105 -392.400422) (xy 298.76869 -392.376806) (xy 298.797579 -392.36009)
			(xy 298.829807 -392.35141) (xy 298.846494 -392.350752) (xy 299.117004 -392.350752) (xy 299.127021 -392.350331)
			(xy 299.145529 -392.342659) (xy 299.159688 -392.328485) (xy 299.167341 -392.30997) (xy 299.167804 -392.299952)
			(xy 299.167804 -392.250168) (xy 299.16731 -392.240164) (xy 299.159645 -392.221683) (xy 299.145494 -392.207539)
			(xy 299.127008 -392.199884) (xy 299.117004 -392.199368) (xy 298.846494 -392.199368) (xy 298.829785 -392.198869)
			(xy 298.797508 -392.190208) (xy 298.768577 -392.17348) (xy 298.74497 -392.149827) (xy 298.728297 -392.120864)
			(xy 298.719699 -392.08857) (xy 298.71924 -392.07186) (xy 298.71924 -392.009884) (xy 298.715176 -392.000486)
			(xy 298.704024 -391.971978) (xy 298.692003 -391.911964) (xy 298.6913 -391.88136) (xy 298.6913 -391.697972)
			(xy 298.69176 -391.673793) (xy 298.69929 -391.626024) (xy 298.714194 -391.58002) (xy 298.736104 -391.53691)
			(xy 298.764483 -391.497754) (xy 298.781216 -391.480294) (xy 299.152818 -391.108692) (xy 299.159636 -391.10135)
			(xy 299.167378 -391.082887) (xy 299.167804 -391.072878) (xy 299.167804 -390.914128) (xy 299.168241 -390.904064)
			(xy 299.175974 -390.885479) (xy 299.18279 -390.87806) (xy 299.85335 -390.2075) (xy 299.8597 -390.2075)
			(xy 299.8597 -389.927084) (xy 299.859223 -389.916746) (xy 299.85111 -389.897727) (xy 299.843952 -389.890254)
			(xy 299.782484 -389.832088) (xy 299.76318 -389.82523) (xy 299.752512 -389.825738) (xy 299.731938 -389.826246)
			(xy 299.704681 -389.825786) (xy 299.65072 -389.818032) (xy 299.598412 -389.802678) (xy 299.548823 -389.780035)
			(xy 299.50296 -389.750565) (xy 299.461759 -389.714868) (xy 299.426057 -389.67367) (xy 299.396583 -389.627811)
			(xy 299.373935 -389.578223) (xy 299.358576 -389.525917) (xy 299.350817 -389.471957) (xy 299.350817 -389.417443)
			(xy 299.358576 -389.363483) (xy 299.373935 -389.311177) (xy 299.396583 -389.261589) (xy 299.426057 -389.21573)
			(xy 299.461759 -389.174532) (xy 299.50296 -389.138835) (xy 299.548823 -389.109365) (xy 299.598412 -389.086722)
			(xy 299.65072 -389.071368) (xy 299.704681 -389.063614) (xy 299.731938 -389.06323) (xy 299.764873 -389.06394)
			(xy 299.829757 -389.075301) (xy 299.86097 -389.085836) (xy 299.869352 -389.088884) (xy 299.9867 -389.088884)
			(xy 299.99672 -389.088464) (xy 300.015234 -389.080794) (xy 300.029403 -389.066621) (xy 300.037068 -389.048104)
			(xy 300.0375 -389.038084) (xy 300.0375 -388.809738) (xy 300.037993 -388.793023) (xy 300.046646 -388.760734)
			(xy 300.063371 -388.731789) (xy 300.087025 -388.708167) (xy 300.115991 -388.691481) (xy 300.148293 -388.682871)
			(xy 300.165008 -388.682484) (xy 301.181008 -388.682484) (xy 301.187593 -388.682531) (xy 301.2007 -388.683802)
			(xy 301.20717 -388.685024) (xy 301.220124 -388.687818) (xy 301.244508 -388.680452) (xy 301.409354 -388.515606)
			(xy 301.416206 -388.50821) (xy 301.42395 -388.489612) (xy 301.42434 -388.479538) (xy 301.42434 -387.899402)
			(xy 301.424764 -387.889333) (xy 301.432482 -387.870731) (xy 301.439326 -387.863334) (xy 301.894494 -387.408166)
			(xy 301.901889 -387.401311) (xy 301.920488 -387.393564) (xy 301.930562 -387.39318) (xy 322.462398 -387.39318)
			(xy 322.472469 -387.393602) (xy 322.491076 -387.401314) (xy 322.498466 -387.408166) (xy 322.821152 -387.730852)
			(xy 326.236046 -387.730852) (xy 326.236046 -387.676348) (xy 326.243802 -387.622397) (xy 326.259158 -387.5701)
			(xy 326.281799 -387.52052) (xy 326.311265 -387.474667) (xy 326.346957 -387.433474) (xy 326.388148 -387.39778)
			(xy 326.433999 -387.36831) (xy 326.483578 -387.345666) (xy 326.535874 -387.330307) (xy 326.589824 -387.322547)
			(xy 326.617076 -387.32206) (xy 326.641148 -387.322406) (xy 326.688911 -387.32845) (xy 326.735537 -387.340445)
			(xy 326.758046 -387.348984) (xy 326.770492 -387.354064) (xy 326.7964 -387.350762) (xy 326.887078 -387.28396)
			(xy 326.898 -387.260338) (xy 326.896984 -387.24713) (xy 326.895968 -387.218428) (xy 326.896454 -387.191177)
			(xy 326.90421 -387.137229) (xy 326.919565 -387.084934) (xy 326.942207 -387.035357) (xy 326.971673 -386.989507)
			(xy 327.007364 -386.948316) (xy 327.048555 -386.912625) (xy 327.094405 -386.883159) (xy 327.143982 -386.860517)
			(xy 327.196277 -386.845162) (xy 327.250225 -386.837406) (xy 327.304727 -386.837406) (xy 327.358675 -386.845162)
			(xy 327.41097 -386.860517) (xy 327.460547 -386.883159) (xy 327.506397 -386.912625) (xy 327.547588 -386.948316)
			(xy 327.583279 -386.989507) (xy 327.612745 -387.035357) (xy 327.635387 -387.084934) (xy 327.650742 -387.137229)
			(xy 327.658498 -387.191177) (xy 327.658984 -387.218428) (xy 327.657968 -387.24713) (xy 327.656952 -387.260338)
			(xy 327.667874 -387.28396) (xy 327.758552 -387.350762) (xy 327.78446 -387.354064) (xy 327.796906 -387.348984)
			(xy 327.819417 -387.340449) (xy 327.86604 -387.328444) (xy 327.913804 -387.322411) (xy 327.937876 -387.32206)
			(xy 327.965128 -387.322586) (xy 328.019077 -387.330339) (xy 328.071373 -387.345692) (xy 328.120952 -387.368331)
			(xy 328.166804 -387.397796) (xy 328.207996 -387.433487) (xy 328.24369 -387.474676) (xy 328.273157 -387.520527)
			(xy 328.2958 -387.570104) (xy 328.311156 -387.6224) (xy 328.318913 -387.676348) (xy 328.318913 -387.730852)
			(xy 328.311156 -387.7848) (xy 328.2958 -387.837096) (xy 328.273157 -387.886673) (xy 328.24369 -387.932524)
			(xy 328.207996 -387.973713) (xy 328.166804 -388.009404) (xy 328.120952 -388.038869) (xy 328.071373 -388.061508)
			(xy 328.019077 -388.076861) (xy 327.965128 -388.084614) (xy 327.937876 -388.085076) (xy 327.905344 -388.084387)
			(xy 327.841235 -388.073276) (xy 327.810368 -388.062978) (xy 327.801732 -388.05993) (xy 327.783952 -388.060184)
			(xy 327.705466 -388.089648) (xy 327.692258 -388.101078) (xy 327.687686 -388.109206) (xy 327.667874 -388.141464)
			(xy 327.663839 -388.147882) (xy 327.659306 -388.162339) (xy 327.658984 -388.169912) (xy 327.658984 -388.451344)
			(xy 327.659311 -388.458919) (xy 327.663825 -388.473383) (xy 327.667874 -388.479792) (xy 327.687686 -388.51205)
			(xy 327.692258 -388.520178) (xy 327.705466 -388.531608) (xy 327.783952 -388.561072) (xy 327.801732 -388.561326)
			(xy 327.810368 -388.558278) (xy 327.841234 -388.547982) (xy 327.905345 -388.536879) (xy 327.937876 -388.53618)
			(xy 327.965129 -388.536666) (xy 328.019081 -388.54442) (xy 328.07138 -388.559773) (xy 328.120962 -388.582414)
			(xy 328.166816 -388.61188) (xy 328.208011 -388.647572) (xy 328.243706 -388.688764) (xy 328.273175 -388.734617)
			(xy 328.295819 -388.784197) (xy 328.311175 -388.836496) (xy 328.318933 -388.890447) (xy 328.318933 -388.944953)
			(xy 328.311175 -388.998904) (xy 328.295819 -389.051203) (xy 328.273175 -389.100783) (xy 328.243706 -389.146636)
			(xy 328.208011 -389.187828) (xy 328.166816 -389.22352) (xy 328.120962 -389.252986) (xy 328.07138 -389.275627)
			(xy 328.019081 -389.29098) (xy 327.965129 -389.298734) (xy 327.937876 -389.299196) (xy 327.913805 -389.29883)
			(xy 327.866042 -389.292794) (xy 327.819416 -389.280807) (xy 327.796906 -389.272272) (xy 327.78446 -389.267192)
			(xy 327.758552 -389.270494) (xy 327.667874 -389.337296) (xy 327.656952 -389.360918) (xy 327.657968 -389.374126)
			(xy 327.658984 -389.402828) (xy 327.658498 -389.430079) (xy 327.650742 -389.484027) (xy 327.635387 -389.536322)
			(xy 327.612745 -389.585899) (xy 327.583279 -389.631749) (xy 327.547588 -389.67294) (xy 327.506397 -389.708631)
			(xy 327.460547 -389.738097) (xy 327.41097 -389.760739) (xy 327.358675 -389.776094) (xy 327.304727 -389.78385)
			(xy 327.250225 -389.78385) (xy 327.196277 -389.776094) (xy 327.143982 -389.760739) (xy 327.094405 -389.738097)
			(xy 327.048555 -389.708631) (xy 327.007364 -389.67294) (xy 326.971673 -389.631749) (xy 326.942207 -389.585899)
			(xy 326.919565 -389.536322) (xy 326.90421 -389.484027) (xy 326.896454 -389.430079) (xy 326.895968 -389.402828)
			(xy 326.896984 -389.374126) (xy 326.898 -389.360918) (xy 326.887078 -389.337296) (xy 326.7964 -389.270494)
			(xy 326.770492 -389.267192) (xy 326.758046 -389.272272) (xy 326.735541 -389.280824) (xy 326.688915 -389.292821)
			(xy 326.641149 -389.298848) (xy 326.617076 -389.299196) (xy 326.589825 -389.298733) (xy 326.535878 -389.290973)
			(xy 326.483585 -389.275615) (xy 326.434009 -389.252972) (xy 326.38816 -389.223504) (xy 326.346971 -389.187812)
			(xy 326.311281 -389.146621) (xy 326.281816 -389.10077) (xy 326.259176 -389.051193) (xy 326.243822 -388.998898)
			(xy 326.236066 -388.944951) (xy 326.236066 -388.890449) (xy 326.243822 -388.836502) (xy 326.259176 -388.784207)
			(xy 326.281816 -388.73463) (xy 326.311281 -388.688779) (xy 326.346971 -388.647588) (xy 326.38816 -388.611896)
			(xy 326.434009 -388.582428) (xy 326.483585 -388.559785) (xy 326.535878 -388.544427) (xy 326.589825 -388.536667)
			(xy 326.617076 -388.53618) (xy 326.649608 -388.536859) (xy 326.713718 -388.547977) (xy 326.744584 -388.558278)
			(xy 326.75322 -388.561326) (xy 326.771 -388.561072) (xy 326.849486 -388.531608) (xy 326.862694 -388.520178)
			(xy 326.867266 -388.51205) (xy 326.887078 -388.479792) (xy 326.891134 -388.473386) (xy 326.895653 -388.45892)
			(xy 326.895968 -388.451344) (xy 326.895968 -388.169912) (xy 326.895651 -388.162337) (xy 326.89113 -388.147873)
			(xy 326.887078 -388.141464) (xy 326.867266 -388.109206) (xy 326.862694 -388.101078) (xy 326.849486 -388.089648)
			(xy 326.771 -388.060184) (xy 326.75322 -388.05993) (xy 326.744584 -388.062978) (xy 326.713713 -388.073261)
			(xy 326.649606 -388.084373) (xy 326.617076 -388.085076) (xy 326.589824 -388.084653) (xy 326.535874 -388.076893)
			(xy 326.483578 -388.061534) (xy 326.433999 -388.03889) (xy 326.388148 -388.00942) (xy 326.346957 -387.973726)
			(xy 326.311265 -387.932533) (xy 326.281799 -387.88668) (xy 326.259158 -387.8371) (xy 326.243802 -387.784803)
			(xy 326.236046 -387.730852) (xy 322.821152 -387.730852) (xy 322.877434 -387.787134) (xy 322.884282 -387.794531)
			(xy 322.892015 -387.81313) (xy 322.89242 -387.823202) (xy 322.89242 -389.990838) (xy 322.892851 -390.000905)
			(xy 322.900577 -390.019497) (xy 322.907406 -390.026906) (xy 323.073014 -390.192514) (xy 323.080409 -390.199368)
			(xy 323.099008 -390.20711) (xy 323.109082 -390.2075) (xy 325.843138 -390.2075) (xy 325.853205 -390.20793)
			(xy 325.871799 -390.215654) (xy 325.879206 -390.222486) (xy 326.54621 -390.88949) (xy 326.553068 -390.896884)
			(xy 326.56082 -390.915483) (xy 326.561196 -390.925558) (xy 326.561196 -390.9695) (xy 326.566784 -390.985502)
			(xy 326.572118 -390.99236) (xy 326.580575 -391.003725) (xy 326.592737 -391.029302) (xy 326.598927 -391.056938)
			(xy 326.599296 -391.0711) (xy 326.599296 -391.4521) (xy 326.598741 -391.469328) (xy 326.589607 -391.50255)
			(xy 326.581262 -391.517632) (xy 326.577706 -391.523728) (xy 326.573896 -391.536936) (xy 326.573896 -391.639806)
			(xy 326.573563 -391.658298) (xy 326.568205 -391.694891) (xy 326.563228 -391.712704) (xy 326.561196 -391.719816)
			(xy 326.561196 -392.049508) (xy 326.561831 -392.060924) (xy 326.571732 -392.081499) (xy 326.580246 -392.089132)
			(xy 326.605298 -392.109876) (xy 326.650447 -392.156697) (xy 326.689257 -392.208892) (xy 326.721094 -392.265611)
			(xy 326.745438 -392.325927) (xy 326.761893 -392.388854) (xy 326.770189 -392.453366) (xy 326.77019 -392.518409)
			(xy 326.761898 -392.582921) (xy 326.745446 -392.64585) (xy 326.721105 -392.706166) (xy 326.689271 -392.762887)
			(xy 326.650463 -392.815084) (xy 326.605317 -392.861907) (xy 326.580246 -392.882628) (xy 326.571738 -392.890262)
			(xy 326.561859 -392.910839) (xy 326.561196 -392.922252) (xy 326.561196 -393.040108) (xy 326.561831 -393.051524)
			(xy 326.571732 -393.072099) (xy 326.580246 -393.079732) (xy 326.605298 -393.100476) (xy 326.650447 -393.147297)
			(xy 326.689259 -393.199492) (xy 326.721101 -393.256209) (xy 326.745452 -393.316522) (xy 326.761915 -393.379447)
			(xy 326.770222 -393.443958) (xy 326.770746 -393.47648) (xy 326.770284 -393.507213) (xy 326.762877 -393.56823)
			(xy 326.74817 -393.62791) (xy 326.726377 -393.685382) (xy 326.697816 -393.739808) (xy 326.662902 -393.790395)
			(xy 326.622146 -393.836405) (xy 326.576141 -393.877166) (xy 326.525558 -393.912086) (xy 326.471135 -393.940653)
			(xy 326.413665 -393.962453) (xy 326.353987 -393.977167) (xy 326.292971 -393.98458) (xy 326.262238 -393.984988)
			(xy 326.230138 -393.984479) (xy 326.166451 -393.976371) (xy 326.104286 -393.96033) (xy 326.074278 -393.94892)
			(xy 326.069765 -393.947233) (xy 326.0603 -393.945437) (xy 326.055482 -393.945364) (xy 326.050148 -393.945364)
			(xy 325.976488 -394.019024) (xy 325.969636 -394.02642) (xy 325.961896 -394.045019) (xy 325.961502 -394.055092)
			(xy 325.961502 -394.223748) (xy 325.965058 -394.232892) (xy 325.976698 -394.263156) (xy 325.993082 -394.325896)
			(xy 326.001358 -394.390209) (xy 326.001888 -394.42263) (xy 326.001363 -394.455052) (xy 325.993088 -394.519366)
			(xy 325.976703 -394.582105) (xy 325.965058 -394.612368) (xy 325.961502 -394.621512) (xy 325.961502 -395.01572)
			(xy 325.966328 -395.0208) (xy 329.242674 -395.0208) (xy 329.252664 -395.020267) (xy 329.271102 -395.01256)
			(xy 329.278488 -395.005814) (xy 329.444858 -394.839444) (xy 329.452258 -394.832602) (xy 329.470856 -394.824882)
			(xy 329.480926 -394.824458) (xy 329.653138 -394.824458) (xy 329.66025 -394.822172) (xy 329.69688 -394.811627)
			(xy 329.772253 -394.800279) (xy 329.810364 -394.799566) (xy 329.822 -394.79961) (xy 329.84525 -394.800629)
			(xy 329.856846 -394.801598) (xy 329.866498 -394.802614) (xy 329.884786 -394.79728) (xy 329.95489 -394.743432)
			(xy 329.964542 -394.727176) (xy 329.96632 -394.717778) (xy 329.971629 -394.68993) (xy 329.989385 -394.636093)
			(xy 330.014908 -394.585474) (xy 330.047638 -394.539188) (xy 330.086853 -394.498251) (xy 330.131692 -394.463564)
			(xy 330.181169 -394.435891) (xy 330.234194 -394.415841) (xy 330.289601 -394.403853) (xy 330.317856 -394.401548)
			(xy 330.327762 -394.40104) (xy 330.34478 -394.392912) (xy 330.399136 -394.335) (xy 330.405423 -394.327711)
			(xy 330.412481 -394.30982) (xy 330.412852 -394.300202) (xy 330.412852 -391.741152) (xy 330.412407 -391.730975)
			(xy 330.404499 -391.71222) (xy 330.389911 -391.698026) (xy 330.380594 -391.693908) (xy 330.277978 -391.653522)
			(xy 330.247752 -391.66038) (xy 330.237084 -391.67181) (xy 330.218981 -391.690581) (xy 330.178535 -391.7235)
			(xy 330.13398 -391.750601) (xy 330.086148 -391.771377) (xy 330.035932 -391.785443) (xy 329.984267 -391.792534)
			(xy 329.958192 -391.792968) (xy 329.930941 -391.792504) (xy 329.876993 -391.784746) (xy 329.824698 -391.769389)
			(xy 329.775121 -391.746745) (xy 329.729272 -391.717276) (xy 329.688084 -391.681582) (xy 329.652395 -391.640389)
			(xy 329.622932 -391.594536) (xy 329.600294 -391.544957) (xy 329.584944 -391.49266) (xy 329.577192 -391.438712)
			(xy 329.576684 -391.41146) (xy 329.5777 -391.382758) (xy 329.578716 -391.36955) (xy 329.567794 -391.345928)
			(xy 329.477116 -391.279126) (xy 329.451208 -391.275824) (xy 329.438762 -391.280904) (xy 329.416252 -391.289439)
			(xy 329.369626 -391.301424) (xy 329.321863 -391.307457) (xy 329.297792 -391.307828) (xy 329.27054 -391.307342)
			(xy 329.21659 -391.299584) (xy 329.164293 -391.284227) (xy 329.114715 -391.261584) (xy 329.068863 -391.232116)
			(xy 329.027671 -391.196423) (xy 328.991979 -391.155231) (xy 328.962512 -391.109378) (xy 328.93987 -391.059799)
			(xy 328.924515 -391.007502) (xy 328.916758 -390.953552) (xy 328.916758 -390.899048) (xy 328.924515 -390.845098)
			(xy 328.93987 -390.792801) (xy 328.962512 -390.743222) (xy 328.991979 -390.697369) (xy 329.027671 -390.656177)
			(xy 329.068863 -390.620484) (xy 329.114715 -390.591016) (xy 329.164293 -390.568373) (xy 329.21659 -390.553016)
			(xy 329.27054 -390.545258) (xy 329.297792 -390.544812) (xy 329.330322 -390.545517) (xy 329.394428 -390.556631)
			(xy 329.4253 -390.56691) (xy 329.433936 -390.569958) (xy 329.451716 -390.569704) (xy 329.530202 -390.54024)
			(xy 329.54341 -390.52881) (xy 329.547982 -390.520682) (xy 329.567794 -390.488424) (xy 329.571843 -390.482014)
			(xy 329.57636 -390.467551) (xy 329.576684 -390.459976) (xy 329.576684 -390.178544) (xy 329.576368 -390.170968)
			(xy 329.571848 -390.156504) (xy 329.567794 -390.150096) (xy 329.547982 -390.117838) (xy 329.54341 -390.10971)
			(xy 329.530202 -390.09828) (xy 329.451716 -390.068816) (xy 329.433936 -390.068562) (xy 329.4253 -390.07161)
			(xy 329.394433 -390.081905) (xy 329.330323 -390.093009) (xy 329.297792 -390.093708) (xy 329.270541 -390.093222)
			(xy 329.216594 -390.085464) (xy 329.1643 -390.070108) (xy 329.114724 -390.047467) (xy 329.068875 -390.018)
			(xy 329.027686 -389.982309) (xy 328.991995 -389.941119) (xy 328.962529 -389.895269) (xy 328.939889 -389.845692)
			(xy 328.924534 -389.793398) (xy 328.916778 -389.739451) (xy 328.916778 -389.684949) (xy 328.924534 -389.631002)
			(xy 328.939889 -389.578708) (xy 328.962529 -389.529131) (xy 328.991995 -389.483281) (xy 329.027686 -389.442091)
			(xy 329.068875 -389.4064) (xy 329.114724 -389.376933) (xy 329.1643 -389.354292) (xy 329.216594 -389.338936)
			(xy 329.270541 -389.331178) (xy 329.297792 -389.330692) (xy 329.321727 -389.331069) (xy 329.369221 -389.337059)
			(xy 329.415595 -389.348932) (xy 329.438 -389.357362) (xy 329.449938 -389.362188) (xy 329.47483 -389.35914)
			(xy 329.565762 -389.295894) (xy 329.576938 -389.273796) (xy 329.576684 -389.260588) (xy 329.576684 -389.25246)
			(xy 329.577281 -389.222623) (xy 329.586591 -389.163678) (xy 329.595226 -389.135112) (xy 329.598528 -389.124698)
			(xy 329.595988 -389.1026) (xy 329.544172 -389.017764) (xy 329.52563 -389.005572) (xy 329.514708 -389.003794)
			(xy 329.482562 -388.998118) (xy 329.419968 -388.979595) (xy 329.360258 -388.953212) (xy 329.304417 -388.919404)
			(xy 329.253362 -388.878727) (xy 329.207933 -388.831851) (xy 329.168877 -388.779545) (xy 329.136837 -388.722671)
			(xy 329.112339 -388.662164) (xy 329.095788 -388.599019) (xy 329.087454 -388.534275) (xy 329.086972 -388.501636)
			(xy 329.087412 -388.47165) (xy 329.094474 -388.412096) (xy 329.108492 -388.353785) (xy 329.129271 -388.297528)
			(xy 329.156523 -388.244106) (xy 329.172824 -388.218934) (xy 329.178453 -388.209572) (xy 329.181992 -388.188037)
			(xy 329.17634 -388.166957) (xy 329.169776 -388.158228) (xy 329.147976 -388.130809) (xy 329.111318 -388.071119)
			(xy 329.083202 -388.006961) (xy 329.06416 -387.93955) (xy 329.054552 -387.870164) (xy 329.053952 -387.83514)
			(xy 329.054454 -387.803179) (xy 329.062465 -387.739761) (xy 329.078362 -387.677847) (xy 329.101894 -387.618414)
			(xy 329.132688 -387.562399) (xy 329.170261 -387.510684) (xy 329.214018 -387.464087) (xy 329.263271 -387.423342)
			(xy 329.317242 -387.389091) (xy 329.375081 -387.361874) (xy 329.435874 -387.342121) (xy 329.498664 -387.330143)
			(xy 329.56246 -387.32613) (xy 329.626256 -387.330143) (xy 329.689046 -387.342121) (xy 329.749839 -387.361874)
			(xy 329.807678 -387.389091) (xy 329.861649 -387.423342) (xy 329.910902 -387.464087) (xy 329.954659 -387.510684)
			(xy 329.956754 -387.513567) (xy 331.876387 -387.513567) (xy 331.876387 -387.445513) (xy 331.884287 -387.37792)
			(xy 331.899981 -387.311702) (xy 331.923257 -387.247753) (xy 331.953799 -387.186938) (xy 331.991195 -387.130081)
			(xy 332.034938 -387.077949) (xy 332.084438 -387.031248) (xy 332.139025 -386.99061) (xy 332.197961 -386.956583)
			(xy 332.260449 -386.929629) (xy 332.325643 -386.910111) (xy 332.392662 -386.898293) (xy 332.4606 -386.894337)
			(xy 332.528538 -386.898293) (xy 332.595557 -386.910111) (xy 332.660751 -386.929629) (xy 332.723239 -386.956583)
			(xy 332.782175 -386.99061) (xy 332.836762 -387.031248) (xy 332.886262 -387.077949) (xy 332.930005 -387.130081)
			(xy 332.967401 -387.186938) (xy 332.997943 -387.247753) (xy 333.021219 -387.311702) (xy 333.036913 -387.37792)
			(xy 333.044813 -387.445513) (xy 333.045308 -387.47954) (xy 333.044813 -387.513567) (xy 333.036913 -387.58116)
			(xy 333.021219 -387.647378) (xy 332.997943 -387.711327) (xy 332.967401 -387.772142) (xy 332.930005 -387.828999)
			(xy 332.886262 -387.881131) (xy 332.836762 -387.927832) (xy 332.782175 -387.96847) (xy 332.723239 -388.002497)
			(xy 332.660751 -388.029451) (xy 332.595557 -388.048969) (xy 332.528538 -388.060787) (xy 332.4606 -388.064744)
			(xy 332.392662 -388.060787) (xy 332.325643 -388.048969) (xy 332.260449 -388.029451) (xy 332.197961 -388.002497)
			(xy 332.139025 -387.96847) (xy 332.084438 -387.927832) (xy 332.034938 -387.881131) (xy 331.991195 -387.828999)
			(xy 331.953799 -387.772142) (xy 331.923257 -387.711327) (xy 331.899981 -387.647378) (xy 331.884287 -387.58116)
			(xy 331.876387 -387.513567) (xy 329.956754 -387.513567) (xy 329.992232 -387.562399) (xy 330.023026 -387.618414)
			(xy 330.046558 -387.677847) (xy 330.062455 -387.739761) (xy 330.070466 -387.803179) (xy 330.070968 -387.83514)
			(xy 330.070529 -387.865126) (xy 330.063469 -387.924681) (xy 330.049453 -387.982992) (xy 330.028674 -388.03925)
			(xy 330.001421 -388.092672) (xy 329.985116 -388.117842) (xy 329.9795 -388.127201) (xy 329.975987 -388.148723)
			(xy 329.981663 -388.169777) (xy 329.988164 -388.178548) (xy 330.009964 -388.205967) (xy 330.046622 -388.265658)
			(xy 330.074739 -388.329816) (xy 330.093783 -388.397226) (xy 330.103393 -388.466612) (xy 330.103988 -388.501636)
			(xy 330.103455 -388.534127) (xy 330.095148 -388.598576) (xy 330.078712 -388.661446) (xy 330.054413 -388.721714)
			(xy 330.038964 -388.750302) (xy 330.03363 -388.760208) (xy 330.031852 -388.782052) (xy 330.065888 -388.875524)
			(xy 330.081636 -388.891272) (xy 330.09205 -388.895082) (xy 330.110963 -388.90244) (xy 330.147238 -388.920638)
			(xy 330.16444 -388.931404) (xy 330.17325 -388.936522) (xy 330.193307 -388.940004) (xy 330.213144 -388.93543)
			(xy 330.229651 -388.923517) (xy 330.240242 -388.906131) (xy 330.243257 -388.885999) (xy 330.241148 -388.876032)
			(xy 330.232371 -388.839965) (xy 330.222948 -388.766335) (xy 330.222352 -388.72922) (xy 330.222847 -388.695193)
			(xy 330.230747 -388.6276) (xy 330.246441 -388.561382) (xy 330.269717 -388.497433) (xy 330.300259 -388.436618)
			(xy 330.337655 -388.379761) (xy 330.381398 -388.327629) (xy 330.430898 -388.280928) (xy 330.485485 -388.24029)
			(xy 330.544421 -388.206263) (xy 330.606909 -388.179309) (xy 330.672103 -388.159791) (xy 330.739122 -388.147973)
			(xy 330.80706 -388.144017) (xy 330.874998 -388.147973) (xy 330.942017 -388.159791) (xy 331.007211 -388.179309)
			(xy 331.069699 -388.206263) (xy 331.128635 -388.24029) (xy 331.183222 -388.280928) (xy 331.232722 -388.327629)
			(xy 331.276465 -388.379761) (xy 331.313861 -388.436618) (xy 331.344403 -388.497433) (xy 331.367679 -388.561382)
			(xy 331.383373 -388.6276) (xy 331.391273 -388.695193) (xy 331.391768 -388.72922) (xy 331.391257 -388.764165)
			(xy 331.382926 -388.833556) (xy 331.366384 -388.90146) (xy 331.341868 -388.966909) (xy 331.309726 -389.02897)
			(xy 331.270418 -389.086757) (xy 331.224503 -389.139449) (xy 331.172635 -389.186293) (xy 331.115555 -389.226622)
			(xy 331.054075 -389.25986) (xy 330.989072 -389.285536) (xy 330.955396 -389.294878) (xy 330.942442 -389.29818)
			(xy 330.923646 -389.316214) (xy 330.890626 -389.424672) (xy 330.896214 -389.450072) (xy 330.905104 -389.460232)
			(xy 330.922915 -389.481234) (xy 330.952941 -389.527392) (xy 330.976028 -389.577385) (xy 330.991695 -389.630175)
			(xy 330.999617 -389.684667) (xy 331.0001 -389.7122) (xy 330.999637 -389.739453) (xy 330.99188 -389.793403)
			(xy 330.976524 -389.845701) (xy 330.953881 -389.89528) (xy 330.924413 -389.941133) (xy 330.888719 -389.982325)
			(xy 330.847526 -390.018018) (xy 330.801673 -390.047485) (xy 330.752093 -390.070126) (xy 330.699795 -390.085481)
			(xy 330.645845 -390.093237) (xy 330.618592 -390.093708) (xy 330.586062 -390.093002) (xy 330.521957 -390.081886)
			(xy 330.491084 -390.07161) (xy 330.482448 -390.068562) (xy 330.464668 -390.068816) (xy 330.386182 -390.09828)
			(xy 330.372974 -390.10971) (xy 330.368402 -390.117838) (xy 330.34859 -390.150096) (xy 330.344545 -390.156507)
			(xy 330.340035 -390.17097) (xy 330.3397 -390.178544) (xy 330.3397 -390.459976) (xy 330.340019 -390.467551)
			(xy 330.344542 -390.482013) (xy 330.34859 -390.488424) (xy 330.368402 -390.520682) (xy 330.372974 -390.52881)
			(xy 330.386182 -390.54024) (xy 330.464668 -390.569704) (xy 330.482448 -390.569958) (xy 330.491084 -390.56691)
			(xy 330.521951 -390.556614) (xy 330.58606 -390.545506) (xy 330.618592 -390.544812) (xy 330.649489 -390.545409)
			(xy 330.710476 -390.555368) (xy 330.769061 -390.575026) (xy 330.823711 -390.603869) (xy 330.848716 -390.622028)
			(xy 330.863956 -390.633458) (xy 330.901802 -390.630918) (xy 331.363574 -390.169146) (xy 331.370974 -390.162306)
			(xy 331.389573 -390.154591) (xy 331.399642 -390.15416) (xy 332.35519 -390.15416) (xy 332.365185 -390.153664)
			(xy 332.38366 -390.146027) (xy 332.397842 -390.131937) (xy 332.40218 -390.122918) (xy 332.408276 -390.10844)
			(xy 332.40218 -390.078468) (xy 332.151228 -389.827516) (xy 332.1431 -389.823706) (xy 332.118895 -389.811793)
			(xy 332.073812 -389.782163) (xy 332.033353 -389.746476) (xy 331.998326 -389.705446) (xy 331.96943 -389.659889)
			(xy 331.94724 -389.610715) (xy 331.932201 -389.558906) (xy 331.924611 -389.505494) (xy 331.924152 -389.47852)
			(xy 331.924636 -389.451267) (xy 331.93239 -389.397315) (xy 331.947743 -389.345015) (xy 331.970383 -389.295433)
			(xy 331.999848 -389.249577) (xy 332.035539 -389.208381) (xy 332.076729 -389.172684) (xy 332.12258 -389.143212)
			(xy 332.172159 -389.120564) (xy 332.224456 -389.105203) (xy 332.278407 -389.097441) (xy 332.30566 -389.097012)
			(xy 332.335424 -389.097581) (xy 332.39423 -389.106823) (xy 332.450886 -389.12509) (xy 332.504016 -389.151938)
			(xy 332.55233 -389.186714) (xy 332.573884 -389.207248) (xy 332.579551 -389.212495) (xy 332.593256 -389.2196)
			(xy 332.600808 -389.221218) (xy 332.62951 -389.226298) (xy 332.636359 -389.227338) (xy 332.650148 -389.226044)
			(xy 332.656688 -389.223758) (xy 332.667706 -389.219829) (xy 332.690713 -389.215617) (xy 332.702408 -389.215376)
			(xy 333.718408 -389.215376) (xy 333.735102 -389.21592) (xy 333.767355 -389.224551) (xy 333.796281 -389.241226)
			(xy 333.819914 -389.264811) (xy 333.836648 -389.293702) (xy 333.845346 -389.325937) (xy 333.845916 -389.34263)
			(xy 333.845916 -390.10336) (xy 333.846329 -390.113385) (xy 333.853992 -390.131913) (xy 333.868166 -390.146094)
			(xy 333.886691 -390.153767) (xy 333.896716 -390.15416) (xy 334.05826 -390.15416) (xy 334.068284 -390.153747)
			(xy 334.086807 -390.146082) (xy 334.100982 -390.131907) (xy 334.108647 -390.113384) (xy 334.10906 -390.10336)
			(xy 334.10906 -387.896862) (xy 334.109492 -387.886796) (xy 334.117222 -387.868207) (xy 334.124046 -387.860794)
			(xy 334.457294 -387.527546) (xy 334.46469 -387.520694) (xy 334.483288 -387.51295) (xy 334.493362 -387.51256)
			(xy 354.976938 -387.51256) (xy 354.987004 -387.512992) (xy 355.005593 -387.520722) (xy 355.013006 -387.527546)
			(xy 355.216316 -387.730856) (xy 358.763723 -387.730856) (xy 358.763723 -387.676344) (xy 358.771481 -387.622386)
			(xy 358.78684 -387.570082) (xy 358.809486 -387.520496) (xy 358.838959 -387.474638) (xy 358.874658 -387.433441)
			(xy 358.915857 -387.397744) (xy 358.961717 -387.368274) (xy 359.011304 -387.345631) (xy 359.06361 -387.330276)
			(xy 359.117568 -387.322521) (xy 359.144824 -387.32206) (xy 359.168895 -387.322422) (xy 359.216658 -387.328459)
			(xy 359.263284 -387.340448) (xy 359.285794 -387.348984) (xy 359.29824 -387.354064) (xy 359.324148 -387.350762)
			(xy 359.414826 -387.28396) (xy 359.425748 -387.260338) (xy 359.424732 -387.24713) (xy 359.423716 -387.218428)
			(xy 359.424202 -387.191177) (xy 359.431958 -387.137229) (xy 359.447313 -387.084934) (xy 359.469955 -387.035357)
			(xy 359.499421 -386.989507) (xy 359.535112 -386.948316) (xy 359.576303 -386.912625) (xy 359.622153 -386.883159)
			(xy 359.67173 -386.860517) (xy 359.724025 -386.845162) (xy 359.777973 -386.837406) (xy 359.832475 -386.837406)
			(xy 359.886423 -386.845162) (xy 359.938718 -386.860517) (xy 359.988295 -386.883159) (xy 360.034145 -386.912625)
			(xy 360.075336 -386.948316) (xy 360.111027 -386.989507) (xy 360.140493 -387.035357) (xy 360.163135 -387.084934)
			(xy 360.17849 -387.137229) (xy 360.186246 -387.191177) (xy 360.186732 -387.218428) (xy 360.186013 -387.238748)
			(xy 391.56132 -387.238748) (xy 391.561799 -387.206423) (xy 391.570011 -387.142297) (xy 391.586283 -387.079729)
			(xy 391.610352 -387.019727) (xy 391.641831 -386.963259) (xy 391.680212 -386.911235) (xy 391.724876 -386.864495)
			(xy 391.775103 -386.823791) (xy 391.830083 -386.78978) (xy 391.88893 -386.76301) (xy 391.950695 -386.743914)
			(xy 391.982452 -386.73786) (xy 391.991676 -386.735799) (xy 392.007829 -386.726015) (xy 392.013948 -386.71881)
			(xy 392.032998 -386.694426) (xy 392.038492 -386.686718) (xy 392.043842 -386.668576) (xy 392.043412 -386.65912)
			(xy 392.041634 -386.617718) (xy 392.042121 -386.586341) (xy 392.04983 -386.524063) (xy 392.065144 -386.463207)
			(xy 392.087831 -386.404698) (xy 392.117547 -386.349426) (xy 392.153838 -386.298232) (xy 392.196155 -386.251892)
			(xy 392.243852 -386.211113) (xy 392.296205 -386.176514) (xy 392.352419 -386.148621) (xy 392.411638 -386.127858)
			(xy 392.472962 -386.11454) (xy 392.504168 -386.111242) (xy 392.512922 -386.110144) (xy 392.528924 -386.102744)
			(xy 392.53541 -386.096764) (xy 392.556492 -386.075936) (xy 392.562519 -386.06951) (xy 392.570185 -386.053663)
			(xy 392.571478 -386.044948) (xy 392.575205 -386.014084) (xy 392.589147 -385.953498) (xy 392.610371 -385.895064)
			(xy 392.638563 -385.839654) (xy 392.6733 -385.788095) (xy 392.714065 -385.741157) (xy 392.760249 -385.699539)
			(xy 392.811163 -385.663863) (xy 392.866047 -385.634661) (xy 392.924082 -385.61237) (xy 392.984402 -385.597321)
			(xy 393.046107 -385.58974) (xy 393.077192 -385.589272) (xy 393.110276 -385.58978) (xy 393.175891 -385.59831)
			(xy 393.208002 -385.60629) (xy 393.219432 -385.609338) (xy 393.242292 -385.60502) (xy 393.325096 -385.542028)
			(xy 393.335764 -385.521454) (xy 393.335764 -385.509516) (xy 393.336603 -385.482481) (xy 393.344884 -385.429034)
			(xy 393.360631 -385.377291) (xy 393.383527 -385.328291) (xy 393.413113 -385.283015) (xy 393.448797 -385.242372)
			(xy 393.489864 -385.207176) (xy 393.535489 -385.178132) (xy 393.58476 -385.155823) (xy 393.636686 -385.140695)
			(xy 393.690229 -385.133053) (xy 393.717272 -385.13258) (xy 393.749804 -385.13326) (xy 393.813914 -385.144377)
			(xy 393.84478 -385.154678) (xy 393.853416 -385.157726) (xy 393.871196 -385.157472) (xy 393.949682 -385.128008)
			(xy 393.96289 -385.116578) (xy 393.967462 -385.10845) (xy 393.987274 -385.076192) (xy 393.99133 -385.069786)
			(xy 393.995849 -385.05532) (xy 393.996164 -385.047744) (xy 393.996164 -384.766312) (xy 393.995848 -384.758737)
			(xy 393.991326 -384.744273) (xy 393.987274 -384.737864) (xy 393.967462 -384.705606) (xy 393.96289 -384.697478)
			(xy 393.949682 -384.686048) (xy 393.871196 -384.656584) (xy 393.853416 -384.65633) (xy 393.84478 -384.659378)
			(xy 393.81391 -384.669661) (xy 393.749802 -384.680773) (xy 393.717272 -384.681476) (xy 393.69002 -384.681052)
			(xy 393.636071 -384.673292) (xy 393.583775 -384.657933) (xy 393.534197 -384.635288) (xy 393.488346 -384.605819)
			(xy 393.447156 -384.570124) (xy 393.411464 -384.528931) (xy 393.381998 -384.483078) (xy 393.359357 -384.433499)
			(xy 393.344002 -384.381202) (xy 393.336246 -384.327252) (xy 393.336246 -384.272748) (xy 393.344002 -384.218798)
			(xy 393.359357 -384.166501) (xy 393.381998 -384.116922) (xy 393.411464 -384.071069) (xy 393.447156 -384.029876)
			(xy 393.488346 -383.994181) (xy 393.534197 -383.964712) (xy 393.583775 -383.942067) (xy 393.636071 -383.926708)
			(xy 393.69002 -383.918948) (xy 393.717272 -383.91846) (xy 393.741344 -383.918807) (xy 393.789107 -383.92485)
			(xy 393.835733 -383.936845) (xy 393.858242 -383.945384) (xy 393.870688 -383.950464) (xy 393.896596 -383.947162)
			(xy 393.987274 -383.88036) (xy 393.998196 -383.856738) (xy 393.99718 -383.84353) (xy 393.996164 -383.814828)
			(xy 393.99665 -383.787577) (xy 394.004406 -383.733629) (xy 394.019761 -383.681334) (xy 394.042403 -383.631757)
			(xy 394.071869 -383.585907) (xy 394.10756 -383.544716) (xy 394.148751 -383.509025) (xy 394.194601 -383.479559)
			(xy 394.244178 -383.456917) (xy 394.296473 -383.441562) (xy 394.350421 -383.433806) (xy 394.404923 -383.433806)
			(xy 394.458871 -383.441562) (xy 394.511166 -383.456917) (xy 394.560743 -383.479559) (xy 394.606593 -383.509025)
			(xy 394.647784 -383.544716) (xy 394.683475 -383.585907) (xy 394.712941 -383.631757) (xy 394.735583 -383.681334)
			(xy 394.750938 -383.733629) (xy 394.758694 -383.787577) (xy 394.75918 -383.814828) (xy 394.758164 -383.84353)
			(xy 394.757148 -383.856738) (xy 394.76807 -383.88036) (xy 394.858748 -383.947162) (xy 394.884656 -383.950464)
			(xy 394.897102 -383.945384) (xy 394.919614 -383.93685) (xy 394.966236 -383.924845) (xy 395.014 -383.918812)
			(xy 395.038072 -383.91846) (xy 395.065324 -383.918985) (xy 395.119273 -383.926738) (xy 395.17157 -383.942091)
			(xy 395.22115 -383.96473) (xy 395.267002 -383.994195) (xy 395.308195 -384.029885) (xy 395.343889 -384.071075)
			(xy 395.373357 -384.116926) (xy 395.395999 -384.166504) (xy 395.406496 -384.202251) (xy 396.016978 -384.202251)
			(xy 396.016978 -384.147749) (xy 396.024734 -384.093803) (xy 396.040088 -384.041509) (xy 396.062729 -383.991932)
			(xy 396.092194 -383.946083) (xy 396.127884 -383.904893) (xy 396.169073 -383.869201) (xy 396.214922 -383.839735)
			(xy 396.264498 -383.817093) (xy 396.316791 -383.801737) (xy 396.370737 -383.793979) (xy 396.397988 -383.793492)
			(xy 396.422059 -383.793863) (xy 396.469822 -383.799896) (xy 396.516448 -383.811881) (xy 396.538958 -383.820416)
			(xy 396.551404 -383.825496) (xy 396.577312 -383.822194) (xy 396.66799 -383.755392) (xy 396.678912 -383.73177)
			(xy 396.677896 -383.718562) (xy 396.67688 -383.68986) (xy 396.677366 -383.662609) (xy 396.685122 -383.608661)
			(xy 396.700477 -383.556366) (xy 396.723119 -383.506789) (xy 396.752585 -383.460939) (xy 396.788276 -383.419748)
			(xy 396.829467 -383.384057) (xy 396.875317 -383.354591) (xy 396.924894 -383.331949) (xy 396.977189 -383.316594)
			(xy 397.031137 -383.308838) (xy 397.085639 -383.308838) (xy 397.139587 -383.316594) (xy 397.191882 -383.331949)
			(xy 397.241459 -383.354591) (xy 397.287309 -383.384057) (xy 397.3285 -383.419748) (xy 397.364191 -383.460939)
			(xy 397.393657 -383.506789) (xy 397.416299 -383.556366) (xy 397.431654 -383.608661) (xy 397.43941 -383.662609)
			(xy 397.439896 -383.68986) (xy 397.43888 -383.718562) (xy 397.437864 -383.73177) (xy 397.448786 -383.755392)
			(xy 397.539464 -383.822194) (xy 397.565372 -383.825496) (xy 397.577818 -383.820416) (xy 397.600328 -383.811879)
			(xy 397.646952 -383.799875) (xy 397.694716 -383.793843) (xy 397.718788 -383.793492) (xy 397.746041 -383.793955)
			(xy 397.799994 -383.80171) (xy 397.852293 -383.817065) (xy 397.901875 -383.839707) (xy 397.947729 -383.869175)
			(xy 397.988923 -383.904868) (xy 398.024618 -383.946061) (xy 398.054087 -383.991915) (xy 398.076731 -384.041496)
			(xy 398.092087 -384.093795) (xy 398.099845 -384.147747) (xy 398.099845 -384.202253) (xy 398.092087 -384.256205)
			(xy 398.076731 -384.308504) (xy 398.068167 -384.327256) (xy 425.863923 -384.327256) (xy 425.863923 -384.272744)
			(xy 425.871681 -384.218787) (xy 425.887039 -384.166483) (xy 425.909685 -384.116897) (xy 425.939158 -384.071039)
			(xy 425.974857 -384.029842) (xy 426.016055 -383.994146) (xy 426.061915 -383.964676) (xy 426.111502 -383.942032)
			(xy 426.163806 -383.926677) (xy 426.217764 -383.918922) (xy 426.24502 -383.91846) (xy 426.265175 -383.918692)
			(xy 426.305264 -383.922896) (xy 426.32503 -383.926842) (xy 426.336206 -383.929382) (xy 426.35805 -383.924302)
			(xy 426.437298 -383.86258) (xy 426.447458 -383.842514) (xy 426.447966 -383.831084) (xy 426.44937 -383.804466)
			(xy 426.458601 -383.751972) (xy 426.47505 -383.701274) (xy 426.498398 -383.653359) (xy 426.52819 -383.609162)
			(xy 426.563844 -383.569543) (xy 426.604667 -383.535274) (xy 426.649864 -383.507023) (xy 426.698554 -383.485339)
			(xy 426.749789 -383.470644) (xy 426.80257 -383.463227) (xy 426.82922 -383.462784) (xy 426.855942 -383.463226)
			(xy 426.908861 -383.470699) (xy 426.96022 -383.485482) (xy 427.009014 -383.507287) (xy 427.054288 -383.535686)
			(xy 427.095158 -383.570124) (xy 427.130823 -383.609927) (xy 427.160586 -383.654317) (xy 427.172628 -383.678176)
			(xy 427.176692 -383.686558) (xy 427.190154 -383.699512) (xy 427.269656 -383.732532) (xy 427.288198 -383.73304)
			(xy 427.297088 -383.729992) (xy 427.327174 -383.720394) (xy 427.389467 -383.710053) (xy 427.42104 -383.709418)
			(xy 427.448293 -383.709841) (xy 427.502245 -383.717603) (xy 427.554542 -383.732965) (xy 427.604121 -383.755613)
			(xy 427.649973 -383.785085) (xy 427.691163 -383.820783) (xy 427.726854 -383.86198) (xy 427.756319 -383.907837)
			(xy 427.778958 -383.95742) (xy 427.794311 -384.00972) (xy 427.802064 -384.063673) (xy 427.802548 -384.090926)
			(xy 427.802046 -384.11988) (xy 427.793306 -384.177123) (xy 427.776013 -384.232388) (xy 427.750567 -384.284405)
			(xy 427.717552 -384.331978) (xy 427.677726 -384.374015) (xy 427.632004 -384.409549) (xy 427.581436 -384.437766)
			(xy 427.527185 -384.458015) (xy 427.470497 -384.469833) (xy 427.441614 -384.471926) (xy 427.432914 -384.472754)
			(xy 427.416809 -384.479511) (xy 427.410118 -384.485134) (xy 427.387766 -384.505708) (xy 427.38146 -384.511958)
			(xy 427.373256 -384.52769) (xy 427.371764 -384.536442) (xy 427.367874 -384.563321) (xy 427.354696 -384.616012)
			(xy 427.335534 -384.666833) (xy 427.310642 -384.715107) (xy 427.295818 -384.737864) (xy 427.291778 -384.744279)
			(xy 427.28725 -384.758738) (xy 427.286928 -384.766312) (xy 427.286928 -385.047744) (xy 427.287264 -385.055318)
			(xy 427.291773 -385.069782) (xy 427.295818 -385.076192) (xy 427.31563 -385.10845) (xy 427.320202 -385.116578)
			(xy 427.33341 -385.128008) (xy 427.411896 -385.157472) (xy 427.429676 -385.157726) (xy 427.438312 -385.154678)
			(xy 427.469183 -385.144395) (xy 427.53329 -385.133284) (xy 427.56582 -385.13258) (xy 427.593069 -385.133092)
			(xy 427.647013 -385.14085) (xy 427.699304 -385.156207) (xy 427.748877 -385.178848) (xy 427.794723 -385.208314)
			(xy 427.83591 -385.244004) (xy 427.871598 -385.285193) (xy 427.901062 -385.331041) (xy 427.9237 -385.380615)
			(xy 427.939054 -385.432906) (xy 427.94681 -385.486851) (xy 427.94681 -385.541349) (xy 427.939054 -385.595294)
			(xy 427.9237 -385.647585) (xy 427.901062 -385.697159) (xy 427.871598 -385.743007) (xy 427.83591 -385.784196)
			(xy 427.794723 -385.819886) (xy 427.748877 -385.849352) (xy 427.699304 -385.871993) (xy 427.647013 -385.88735)
			(xy 427.593069 -385.895108) (xy 427.56582 -385.895596) (xy 427.541748 -385.895248) (xy 427.493985 -385.889204)
			(xy 427.44736 -385.87721) (xy 427.42485 -385.868672) (xy 427.412404 -385.863592) (xy 427.386496 -385.866894)
			(xy 427.295818 -385.933696) (xy 427.284896 -385.957318) (xy 427.285912 -385.970526) (xy 427.286928 -385.999228)
			(xy 427.286442 -386.026479) (xy 427.278686 -386.080427) (xy 427.263331 -386.132722) (xy 427.240689 -386.182299)
			(xy 427.211223 -386.228149) (xy 427.175532 -386.26934) (xy 427.134341 -386.305031) (xy 427.088491 -386.334497)
			(xy 427.038914 -386.357139) (xy 426.986619 -386.372494) (xy 426.932671 -386.38025) (xy 426.878169 -386.38025)
			(xy 426.824221 -386.372494) (xy 426.771926 -386.357139) (xy 426.722349 -386.334497) (xy 426.676499 -386.305031)
			(xy 426.635308 -386.26934) (xy 426.599617 -386.228149) (xy 426.570151 -386.182299) (xy 426.547509 -386.132722)
			(xy 426.532154 -386.080427) (xy 426.524398 -386.026479) (xy 426.523912 -385.999228) (xy 426.524928 -385.970526)
			(xy 426.525944 -385.957318) (xy 426.515022 -385.933696) (xy 426.424344 -385.866894) (xy 426.398436 -385.863592)
			(xy 426.38599 -385.868672) (xy 426.36348 -385.877211) (xy 426.316857 -385.889213) (xy 426.269092 -385.895245)
			(xy 426.24502 -385.895596) (xy 426.217765 -385.895158) (xy 426.16381 -385.887404) (xy 426.111509 -385.872049)
			(xy 426.061924 -385.849407) (xy 426.016067 -385.819938) (xy 425.974871 -385.784243) (xy 425.939174 -385.743049)
			(xy 425.909703 -385.697193) (xy 425.887058 -385.64761) (xy 425.871701 -385.595309) (xy 425.863943 -385.541355)
			(xy 425.863943 -385.486845) (xy 425.871701 -385.432891) (xy 425.887058 -385.38059) (xy 425.909703 -385.331007)
			(xy 425.939174 -385.285151) (xy 425.974871 -385.243957) (xy 426.016067 -385.208262) (xy 426.061924 -385.178793)
			(xy 426.111509 -385.156151) (xy 426.16381 -385.140796) (xy 426.217765 -385.133042) (xy 426.24502 -385.13258)
			(xy 426.277552 -385.133273) (xy 426.341661 -385.144382) (xy 426.372528 -385.154678) (xy 426.381164 -385.157726)
			(xy 426.398944 -385.157472) (xy 426.47743 -385.128008) (xy 426.490638 -385.116578) (xy 426.49521 -385.10845)
			(xy 426.515022 -385.076192) (xy 426.519074 -385.069783) (xy 426.523596 -385.05532) (xy 426.523912 -385.047744)
			(xy 426.523912 -384.766312) (xy 426.523604 -384.758736) (xy 426.519077 -384.744272) (xy 426.515022 -384.737864)
			(xy 426.49521 -384.705606) (xy 426.490638 -384.697478) (xy 426.47743 -384.686048) (xy 426.398944 -384.656584)
			(xy 426.381164 -384.65633) (xy 426.372528 -384.659378) (xy 426.341661 -384.669674) (xy 426.277551 -384.680777)
			(xy 426.24502 -384.681476) (xy 426.217764 -384.681078) (xy 426.163806 -384.673323) (xy 426.111502 -384.657968)
			(xy 426.061915 -384.635324) (xy 426.016055 -384.605854) (xy 425.974857 -384.570158) (xy 425.939158 -384.528961)
			(xy 425.909685 -384.483103) (xy 425.887039 -384.433517) (xy 425.871681 -384.381213) (xy 425.863923 -384.327256)
			(xy 398.068167 -384.327256) (xy 398.054087 -384.358085) (xy 398.024618 -384.403939) (xy 397.988923 -384.445132)
			(xy 397.947729 -384.480825) (xy 397.901875 -384.510293) (xy 397.852293 -384.532935) (xy 397.799994 -384.54829)
			(xy 397.746041 -384.556045) (xy 397.718788 -384.556508) (xy 397.686256 -384.555814) (xy 397.622147 -384.544706)
			(xy 397.59128 -384.53441) (xy 397.582644 -384.531362) (xy 397.564864 -384.531616) (xy 397.486378 -384.56108)
			(xy 397.47317 -384.57251) (xy 397.468598 -384.580638) (xy 397.448786 -384.612896) (xy 397.444731 -384.619303)
			(xy 397.440212 -384.633768) (xy 397.439896 -384.641344) (xy 397.439896 -384.922776) (xy 397.440208 -384.930352)
			(xy 397.444732 -384.944816) (xy 397.448786 -384.951224) (xy 397.468598 -384.983482) (xy 397.47317 -384.99161)
			(xy 397.486378 -385.00304) (xy 397.564864 -385.032504) (xy 397.582644 -385.032758) (xy 397.59128 -385.02971)
			(xy 397.622153 -385.019436) (xy 397.686258 -385.008318) (xy 397.718788 -385.007612) (xy 397.746043 -385.008034)
			(xy 397.799998 -385.01579) (xy 397.8523 -385.031146) (xy 397.901884 -385.053789) (xy 397.947741 -385.083258)
			(xy 397.988938 -385.118954) (xy 398.024635 -385.160149) (xy 398.054105 -385.206005) (xy 398.07675 -385.255589)
			(xy 398.092107 -385.30789) (xy 398.099865 -385.361845) (xy 398.099865 -385.416355) (xy 398.092107 -385.47031)
			(xy 398.07675 -385.522611) (xy 398.054105 -385.572195) (xy 398.024635 -385.618051) (xy 397.988938 -385.659246)
			(xy 397.947741 -385.694942) (xy 397.901884 -385.724411) (xy 397.8523 -385.747054) (xy 397.799998 -385.76241)
			(xy 397.746043 -385.770166) (xy 397.718788 -385.770628) (xy 397.694717 -385.770263) (xy 397.646954 -385.764227)
			(xy 397.600328 -385.75224) (xy 397.577818 -385.743704) (xy 397.565372 -385.738624) (xy 397.539464 -385.741926)
			(xy 397.448786 -385.808728) (xy 397.437864 -385.83235) (xy 397.43888 -385.845558) (xy 397.439896 -385.87426)
			(xy 397.43941 -385.901511) (xy 397.431654 -385.955459) (xy 397.416299 -386.007754) (xy 397.393657 -386.057331)
			(xy 397.364191 -386.103181) (xy 397.3285 -386.144372) (xy 397.287309 -386.180063) (xy 397.241459 -386.209529)
			(xy 397.191882 -386.232171) (xy 397.139587 -386.247526) (xy 397.085639 -386.255282) (xy 397.031137 -386.255282)
			(xy 396.977189 -386.247526) (xy 396.924894 -386.232171) (xy 396.875317 -386.209529) (xy 396.829467 -386.180063)
			(xy 396.788276 -386.144372) (xy 396.752585 -386.103181) (xy 396.723119 -386.057331) (xy 396.700477 -386.007754)
			(xy 396.685122 -385.955459) (xy 396.677366 -385.901511) (xy 396.67688 -385.87426) (xy 396.677896 -385.845558)
			(xy 396.678912 -385.83235) (xy 396.66799 -385.808728) (xy 396.577312 -385.741926) (xy 396.551404 -385.738624)
			(xy 396.538958 -385.743704) (xy 396.51645 -385.752249) (xy 396.469826 -385.76425) (xy 396.42206 -385.770279)
			(xy 396.397988 -385.770628) (xy 396.370739 -385.770101) (xy 396.316795 -385.762343) (xy 396.264505 -385.746988)
			(xy 396.214932 -385.724348) (xy 396.169085 -385.694882) (xy 396.127899 -385.659193) (xy 396.09221 -385.618005)
			(xy 396.062747 -385.572158) (xy 396.040108 -385.522584) (xy 396.024754 -385.470293) (xy 396.016998 -385.416349)
			(xy 396.016998 -385.361851) (xy 396.024754 -385.307907) (xy 396.040108 -385.255616) (xy 396.062747 -385.206042)
			(xy 396.09221 -385.160195) (xy 396.127899 -385.119007) (xy 396.169085 -385.083318) (xy 396.214932 -385.053852)
			(xy 396.264505 -385.031212) (xy 396.316795 -385.015857) (xy 396.370739 -385.008099) (xy 396.397988 -385.007612)
			(xy 396.430519 -385.008311) (xy 396.494629 -385.019416) (xy 396.525496 -385.02971) (xy 396.534132 -385.032758)
			(xy 396.551912 -385.032504) (xy 396.630398 -385.00304) (xy 396.643606 -384.99161) (xy 396.648178 -384.983482)
			(xy 396.66799 -384.951224) (xy 396.672036 -384.944812) (xy 396.676561 -384.930351) (xy 396.67688 -384.922776)
			(xy 396.67688 -384.641344) (xy 396.676548 -384.63377) (xy 396.672037 -384.619306) (xy 396.66799 -384.612896)
			(xy 396.648178 -384.580638) (xy 396.643606 -384.57251) (xy 396.630398 -384.56108) (xy 396.551912 -384.531616)
			(xy 396.534132 -384.531362) (xy 396.525496 -384.53441) (xy 396.494625 -384.544691) (xy 396.430518 -384.555804)
			(xy 396.397988 -384.556508) (xy 396.370737 -384.556021) (xy 396.316791 -384.548263) (xy 396.264498 -384.532907)
			(xy 396.214922 -384.510265) (xy 396.169073 -384.480799) (xy 396.127884 -384.445107) (xy 396.092194 -384.403917)
			(xy 396.062729 -384.358068) (xy 396.040088 -384.308491) (xy 396.024734 -384.256197) (xy 396.016978 -384.202251)
			(xy 395.406496 -384.202251) (xy 395.411356 -384.218799) (xy 395.419113 -384.272748) (xy 395.419113 -384.327252)
			(xy 395.411356 -384.381201) (xy 395.395999 -384.433496) (xy 395.373357 -384.483074) (xy 395.343889 -384.528925)
			(xy 395.308195 -384.570115) (xy 395.267002 -384.605805) (xy 395.22115 -384.63527) (xy 395.17157 -384.657909)
			(xy 395.119273 -384.673262) (xy 395.065324 -384.681015) (xy 395.038072 -384.681476) (xy 395.00554 -384.680788)
			(xy 394.941431 -384.669676) (xy 394.910564 -384.659378) (xy 394.901928 -384.65633) (xy 394.884148 -384.656584)
			(xy 394.805662 -384.686048) (xy 394.792454 -384.697478) (xy 394.787882 -384.705606) (xy 394.76807 -384.737864)
			(xy 394.764034 -384.744282) (xy 394.759502 -384.758739) (xy 394.75918 -384.766312) (xy 394.75918 -385.047744)
			(xy 394.759508 -385.055319) (xy 394.764021 -385.069783) (xy 394.76807 -385.076192) (xy 394.787882 -385.10845)
			(xy 394.792454 -385.116578) (xy 394.805662 -385.128008) (xy 394.884148 -385.157472) (xy 394.901928 -385.157726)
			(xy 394.910564 -385.154678) (xy 394.941431 -385.144383) (xy 395.005541 -385.133279) (xy 395.038072 -385.13258)
			(xy 395.065325 -385.133065) (xy 395.119278 -385.140819) (xy 395.171577 -385.156172) (xy 395.221159 -385.178812)
			(xy 395.267014 -385.208279) (xy 395.308209 -385.243971) (xy 395.343905 -385.285163) (xy 395.373374 -385.331016)
			(xy 395.396018 -385.380597) (xy 395.411375 -385.432895) (xy 395.419133 -385.486847) (xy 395.419133 -385.541353)
			(xy 395.411375 -385.595305) (xy 395.396018 -385.647603) (xy 395.373374 -385.697184) (xy 395.343905 -385.743037)
			(xy 395.308209 -385.784229) (xy 395.267014 -385.819921) (xy 395.221159 -385.849388) (xy 395.171577 -385.872028)
			(xy 395.119278 -385.887381) (xy 395.065325 -385.895135) (xy 395.038072 -385.895596) (xy 395.014001 -385.895232)
			(xy 394.966238 -385.889195) (xy 394.919612 -385.877207) (xy 394.897102 -385.868672) (xy 394.884656 -385.863592)
			(xy 394.858748 -385.866894) (xy 394.76807 -385.933696) (xy 394.757148 -385.957318) (xy 394.758164 -385.970526)
			(xy 394.75918 -385.999228) (xy 394.758694 -386.026479) (xy 394.750938 -386.080427) (xy 394.735583 -386.132722)
			(xy 394.712941 -386.182299) (xy 394.683475 -386.228149) (xy 394.647784 -386.26934) (xy 394.606593 -386.305031)
			(xy 394.560743 -386.334497) (xy 394.511166 -386.357139) (xy 394.458871 -386.372494) (xy 394.404923 -386.38025)
			(xy 394.350421 -386.38025) (xy 394.296473 -386.372494) (xy 394.244178 -386.357139) (xy 394.194601 -386.334497)
			(xy 394.148751 -386.305031) (xy 394.10756 -386.26934) (xy 394.071869 -386.228149) (xy 394.042403 -386.182299)
			(xy 394.019761 -386.132722) (xy 394.004406 -386.080427) (xy 393.99665 -386.026479) (xy 393.996164 -385.999228)
			(xy 393.99718 -385.970526) (xy 393.998196 -385.957318) (xy 393.987274 -385.933696) (xy 393.896596 -385.866894)
			(xy 393.870688 -385.863592) (xy 393.858242 -385.868672) (xy 393.835737 -385.877225) (xy 393.789111 -385.889222)
			(xy 393.741345 -385.895248) (xy 393.717272 -385.895596) (xy 393.686792 -385.894326) (xy 393.674854 -385.89331)
			(xy 393.653264 -385.901946) (xy 393.58316 -385.978654) (xy 393.576556 -386.001006) (xy 393.578588 -386.01269)
			(xy 393.581924 -386.033804) (xy 393.585484 -386.076405) (xy 393.5857 -386.09778) (xy 393.58518 -386.129156)
			(xy 393.577472 -386.191431) (xy 393.56216 -386.252285) (xy 393.539474 -386.310792) (xy 393.509762 -386.366062)
			(xy 393.473473 -386.417256) (xy 393.43116 -386.463595) (xy 393.383466 -386.504374) (xy 393.331117 -386.538975)
			(xy 393.274907 -386.56687) (xy 393.215692 -386.587635) (xy 393.154371 -386.600956) (xy 393.123166 -386.604256)
			(xy 393.114406 -386.605325) (xy 393.098406 -386.612746) (xy 393.091924 -386.618734) (xy 393.070842 -386.639562)
			(xy 393.06482 -386.645993) (xy 393.05715 -386.661836) (xy 393.055856 -386.67055) (xy 393.051886 -386.703223)
			(xy 393.036657 -386.767253) (xy 393.013293 -386.828783) (xy 392.982186 -386.886783) (xy 392.943854 -386.940286)
			(xy 392.89894 -386.988395) (xy 392.848193 -387.030307) (xy 392.792463 -387.06532) (xy 392.732681 -387.09285)
			(xy 392.669847 -387.112437) (xy 392.637518 -387.118606) (xy 392.628306 -387.120707) (xy 392.612147 -387.130463)
			(xy 392.606022 -387.137656) (xy 392.586972 -387.16204) (xy 392.581491 -387.169756) (xy 392.576133 -387.187892)
			(xy 392.576558 -387.197346) (xy 392.578336 -387.238748) (xy 392.577834 -387.270709) (xy 392.569823 -387.334127)
			(xy 392.553926 -387.396041) (xy 392.530394 -387.455474) (xy 392.4996 -387.511489) (xy 392.462027 -387.563204)
			(xy 392.41827 -387.609801) (xy 392.369017 -387.650546) (xy 392.315046 -387.684797) (xy 392.257207 -387.712014)
			(xy 392.19923 -387.730852) (xy 393.336246 -387.730852) (xy 393.336246 -387.676348) (xy 393.344002 -387.622398)
			(xy 393.359357 -387.570101) (xy 393.381998 -387.520522) (xy 393.411464 -387.474669) (xy 393.447156 -387.433476)
			(xy 393.488346 -387.397781) (xy 393.534197 -387.368312) (xy 393.583775 -387.345667) (xy 393.636071 -387.330308)
			(xy 393.69002 -387.322548) (xy 393.717272 -387.32206) (xy 393.741344 -387.322407) (xy 393.789107 -387.32845)
			(xy 393.835733 -387.340445) (xy 393.858242 -387.348984) (xy 393.870688 -387.354064) (xy 393.896596 -387.350762)
			(xy 393.987274 -387.28396) (xy 393.998196 -387.260338) (xy 393.99718 -387.24713) (xy 393.996164 -387.218428)
			(xy 393.99665 -387.191177) (xy 394.004406 -387.137229) (xy 394.019761 -387.084934) (xy 394.042403 -387.035357)
			(xy 394.071869 -386.989507) (xy 394.10756 -386.948316) (xy 394.148751 -386.912625) (xy 394.194601 -386.883159)
			(xy 394.244178 -386.860517) (xy 394.296473 -386.845162) (xy 394.350421 -386.837406) (xy 394.404923 -386.837406)
			(xy 394.458871 -386.845162) (xy 394.511166 -386.860517) (xy 394.560743 -386.883159) (xy 394.606593 -386.912625)
			(xy 394.647784 -386.948316) (xy 394.683475 -386.989507) (xy 394.712941 -387.035357) (xy 394.735583 -387.084934)
			(xy 394.750938 -387.137229) (xy 394.758694 -387.191177) (xy 394.75918 -387.218428) (xy 394.758164 -387.24713)
			(xy 394.757148 -387.260338) (xy 394.76807 -387.28396) (xy 394.858748 -387.350762) (xy 394.884656 -387.354064)
			(xy 394.897102 -387.348984) (xy 394.919614 -387.34045) (xy 394.966236 -387.328445) (xy 395.014 -387.322412)
			(xy 395.038072 -387.32206) (xy 395.065324 -387.322585) (xy 395.119273 -387.330338) (xy 395.17157 -387.345691)
			(xy 395.22115 -387.36833) (xy 395.267002 -387.397795) (xy 395.308195 -387.433485) (xy 395.343889 -387.474675)
			(xy 395.373357 -387.520526) (xy 395.395999 -387.570104) (xy 395.411356 -387.622399) (xy 395.419113 -387.676348)
			(xy 395.419113 -387.730852) (xy 395.411356 -387.784801) (xy 395.395999 -387.837096) (xy 395.373357 -387.886674)
			(xy 395.343889 -387.932525) (xy 395.308195 -387.973715) (xy 395.267002 -388.009405) (xy 395.22115 -388.03887)
			(xy 395.17157 -388.061509) (xy 395.119273 -388.076862) (xy 395.065324 -388.084615) (xy 395.038072 -388.085076)
			(xy 395.00554 -388.084388) (xy 394.941431 -388.073276) (xy 394.910564 -388.062978) (xy 394.901928 -388.05993)
			(xy 394.884148 -388.060184) (xy 394.805662 -388.089648) (xy 394.792454 -388.101078) (xy 394.787882 -388.109206)
			(xy 394.76807 -388.141464) (xy 394.764034 -388.147882) (xy 394.759502 -388.162339) (xy 394.75918 -388.169912)
			(xy 394.75918 -388.451344) (xy 394.759508 -388.458919) (xy 394.764021 -388.473383) (xy 394.76807 -388.479792)
			(xy 394.787882 -388.51205) (xy 394.792454 -388.520178) (xy 394.805662 -388.531608) (xy 394.884148 -388.561072)
			(xy 394.901928 -388.561326) (xy 394.910564 -388.558278) (xy 394.941431 -388.547983) (xy 395.005541 -388.536879)
			(xy 395.038072 -388.53618) (xy 395.065325 -388.536665) (xy 395.119278 -388.544419) (xy 395.171577 -388.559772)
			(xy 395.221159 -388.582412) (xy 395.267014 -388.611879) (xy 395.308209 -388.647571) (xy 395.343905 -388.688763)
			(xy 395.373374 -388.734616) (xy 395.396018 -388.784197) (xy 395.411375 -388.836495) (xy 395.419133 -388.890447)
			(xy 395.419133 -388.944953) (xy 395.411375 -388.998905) (xy 395.396018 -389.051203) (xy 395.373374 -389.100784)
			(xy 395.343905 -389.146637) (xy 395.308209 -389.187829) (xy 395.267014 -389.223521) (xy 395.221159 -389.252988)
			(xy 395.171577 -389.275628) (xy 395.119278 -389.290981) (xy 395.065325 -389.298735) (xy 395.038072 -389.299196)
			(xy 395.014001 -389.298832) (xy 394.966238 -389.292795) (xy 394.919612 -389.280807) (xy 394.897102 -389.272272)
			(xy 394.884656 -389.267192) (xy 394.858748 -389.270494) (xy 394.76807 -389.337296) (xy 394.757148 -389.360918)
			(xy 394.758164 -389.374126) (xy 394.75918 -389.402828) (xy 394.758694 -389.430079) (xy 394.750938 -389.484027)
			(xy 394.735583 -389.536322) (xy 394.712941 -389.585899) (xy 394.683475 -389.631749) (xy 394.647784 -389.67294)
			(xy 394.606593 -389.708631) (xy 394.560743 -389.738097) (xy 394.511166 -389.760739) (xy 394.458871 -389.776094)
			(xy 394.404923 -389.78385) (xy 394.350421 -389.78385) (xy 394.296473 -389.776094) (xy 394.244178 -389.760739)
			(xy 394.194601 -389.738097) (xy 394.148751 -389.708631) (xy 394.10756 -389.67294) (xy 394.071869 -389.631749)
			(xy 394.042403 -389.585899) (xy 394.019761 -389.536322) (xy 394.004406 -389.484027) (xy 393.99665 -389.430079)
			(xy 393.996164 -389.402828) (xy 393.99718 -389.374126) (xy 393.998196 -389.360918) (xy 393.987274 -389.337296)
			(xy 393.896596 -389.270494) (xy 393.870688 -389.267192) (xy 393.858242 -389.272272) (xy 393.835737 -389.280825)
			(xy 393.789111 -389.292822) (xy 393.741345 -389.298848) (xy 393.717272 -389.299196) (xy 393.690021 -389.298732)
			(xy 393.636075 -389.290972) (xy 393.583782 -389.275614) (xy 393.534207 -389.252971) (xy 393.488358 -389.223503)
			(xy 393.44717 -389.18781) (xy 393.41148 -389.146619) (xy 393.382016 -389.100769) (xy 393.359376 -389.051192)
			(xy 393.344022 -388.998898) (xy 393.336266 -388.944951) (xy 393.336266 -388.890449) (xy 393.344022 -388.836502)
			(xy 393.359376 -388.784208) (xy 393.382016 -388.734631) (xy 393.41148 -388.688781) (xy 393.44717 -388.64759)
			(xy 393.488358 -388.611897) (xy 393.534207 -388.582429) (xy 393.583782 -388.559786) (xy 393.636075 -388.544428)
			(xy 393.690021 -388.536668) (xy 393.717272 -388.53618) (xy 393.749804 -388.53686) (xy 393.813914 -388.547977)
			(xy 393.84478 -388.558278) (xy 393.853416 -388.561326) (xy 393.871196 -388.561072) (xy 393.949682 -388.531608)
			(xy 393.96289 -388.520178) (xy 393.967462 -388.51205) (xy 393.987274 -388.479792) (xy 393.99133 -388.473386)
			(xy 393.995849 -388.45892) (xy 393.996164 -388.451344) (xy 393.996164 -388.169912) (xy 393.995848 -388.162337)
			(xy 393.991326 -388.147873) (xy 393.987274 -388.141464) (xy 393.967462 -388.109206) (xy 393.96289 -388.101078)
			(xy 393.949682 -388.089648) (xy 393.871196 -388.060184) (xy 393.853416 -388.05993) (xy 393.84478 -388.062978)
			(xy 393.81391 -388.073261) (xy 393.749802 -388.084373) (xy 393.717272 -388.085076) (xy 393.69002 -388.084652)
			(xy 393.636071 -388.076892) (xy 393.583775 -388.061533) (xy 393.534197 -388.038888) (xy 393.488346 -388.009419)
			(xy 393.447156 -387.973724) (xy 393.411464 -387.932531) (xy 393.381998 -387.886678) (xy 393.359357 -387.837099)
			(xy 393.344002 -387.784802) (xy 393.336246 -387.730852) (xy 392.19923 -387.730852) (xy 392.196414 -387.731767)
			(xy 392.133624 -387.743745) (xy 392.069828 -387.747759) (xy 392.006032 -387.743745) (xy 391.943242 -387.731767)
			(xy 391.882449 -387.712014) (xy 391.82461 -387.684797) (xy 391.770639 -387.650546) (xy 391.721386 -387.609801)
			(xy 391.677629 -387.563204) (xy 391.640056 -387.511489) (xy 391.609262 -387.455474) (xy 391.58573 -387.396041)
			(xy 391.569833 -387.334127) (xy 391.561822 -387.270709) (xy 391.56132 -387.238748) (xy 360.186013 -387.238748)
			(xy 360.185716 -387.24713) (xy 360.1847 -387.260338) (xy 360.195622 -387.28396) (xy 360.2863 -387.350762)
			(xy 360.312208 -387.354064) (xy 360.324654 -387.348984) (xy 360.34716 -387.340435) (xy 360.393785 -387.328436)
			(xy 360.441551 -387.322408) (xy 360.465624 -387.32206) (xy 360.492872 -387.322612) (xy 360.546812 -387.33037)
			(xy 360.5991 -387.345726) (xy 360.64867 -387.368367) (xy 360.694513 -387.397831) (xy 360.735697 -387.43352)
			(xy 360.771383 -387.474706) (xy 360.800845 -387.520551) (xy 360.823482 -387.570123) (xy 360.838835 -387.622411)
			(xy 360.84659 -387.676352) (xy 360.84659 -387.730848) (xy 360.838835 -387.784789) (xy 360.823482 -387.837077)
			(xy 360.800845 -387.886649) (xy 360.771383 -387.932494) (xy 360.735697 -387.97368) (xy 360.694513 -388.009369)
			(xy 360.64867 -388.038833) (xy 360.5991 -388.061474) (xy 360.546812 -388.07683) (xy 360.492872 -388.084588)
			(xy 360.465624 -388.085076) (xy 360.433091 -388.0844) (xy 360.368982 -388.07328) (xy 360.338116 -388.062978)
			(xy 360.32948 -388.05993) (xy 360.3117 -388.060184) (xy 360.233214 -388.089648) (xy 360.220006 -388.101078)
			(xy 360.215434 -388.109206) (xy 360.195622 -388.141464) (xy 360.191582 -388.14788) (xy 360.187054 -388.162338)
			(xy 360.186732 -388.169912) (xy 360.186732 -388.451344) (xy 360.187067 -388.458918) (xy 360.191576 -388.473382)
			(xy 360.195622 -388.479792) (xy 360.215434 -388.51205) (xy 360.220006 -388.520178) (xy 360.233214 -388.531608)
			(xy 360.3117 -388.561072) (xy 360.32948 -388.561326) (xy 360.338116 -388.558278) (xy 360.368986 -388.547994)
			(xy 360.433094 -388.536883) (xy 360.465624 -388.53618) (xy 360.492873 -388.536692) (xy 360.546817 -388.544451)
			(xy 360.599107 -388.559808) (xy 360.648679 -388.582449) (xy 360.694525 -388.611915) (xy 360.735711 -388.647606)
			(xy 360.771399 -388.688794) (xy 360.800862 -388.734642) (xy 360.823501 -388.784216) (xy 360.838854 -388.836507)
			(xy 360.84661 -388.890451) (xy 360.84661 -388.944949) (xy 360.838854 -388.998893) (xy 360.823501 -389.051184)
			(xy 360.800862 -389.100758) (xy 360.771399 -389.146606) (xy 360.735711 -389.187794) (xy 360.694525 -389.223485)
			(xy 360.648679 -389.252951) (xy 360.599107 -389.275592) (xy 360.546817 -389.290949) (xy 360.492873 -389.298708)
			(xy 360.465624 -389.299196) (xy 360.441552 -389.298846) (xy 360.393789 -389.292803) (xy 360.347164 -389.28081)
			(xy 360.324654 -389.272272) (xy 360.312208 -389.267192) (xy 360.2863 -389.270494) (xy 360.195622 -389.337296)
			(xy 360.1847 -389.360918) (xy 360.185716 -389.374126) (xy 360.186732 -389.402828) (xy 360.186246 -389.430079)
			(xy 360.17849 -389.484027) (xy 360.163135 -389.536322) (xy 360.140493 -389.585899) (xy 360.111027 -389.631749)
			(xy 360.075336 -389.67294) (xy 360.034145 -389.708631) (xy 359.988295 -389.738097) (xy 359.938718 -389.760739)
			(xy 359.886423 -389.776094) (xy 359.832475 -389.78385) (xy 359.777973 -389.78385) (xy 359.724025 -389.776094)
			(xy 359.67173 -389.760739) (xy 359.622153 -389.738097) (xy 359.576303 -389.708631) (xy 359.535112 -389.67294)
			(xy 359.499421 -389.631749) (xy 359.469955 -389.585899) (xy 359.447313 -389.536322) (xy 359.431958 -389.484027)
			(xy 359.424202 -389.430079) (xy 359.423716 -389.402828) (xy 359.424732 -389.374126) (xy 359.425748 -389.360918)
			(xy 359.414826 -389.337296) (xy 359.324148 -389.270494) (xy 359.29824 -389.267192) (xy 359.285794 -389.272272)
			(xy 359.263284 -389.28081) (xy 359.21666 -389.292813) (xy 359.168896 -389.298845) (xy 359.144824 -389.299196)
			(xy 359.117569 -389.298759) (xy 359.063614 -389.291004) (xy 359.011311 -389.27565) (xy 358.961727 -389.253008)
			(xy 358.915869 -389.22354) (xy 358.874672 -389.187845) (xy 358.838975 -389.14665) (xy 358.809504 -389.100794)
			(xy 358.786859 -389.051211) (xy 358.771501 -388.99891) (xy 358.763743 -388.944955) (xy 358.763743 -388.890445)
			(xy 358.771501 -388.83649) (xy 358.786859 -388.784189) (xy 358.809504 -388.734606) (xy 358.838975 -388.68875)
			(xy 358.874672 -388.647555) (xy 358.915869 -388.61186) (xy 358.961727 -388.582392) (xy 359.011311 -388.55975)
			(xy 359.063614 -388.544396) (xy 359.117569 -388.536641) (xy 359.144824 -388.53618) (xy 359.177356 -388.536872)
			(xy 359.241465 -388.547981) (xy 359.272332 -388.558278) (xy 359.280968 -388.561326) (xy 359.298748 -388.561072)
			(xy 359.377234 -388.531608) (xy 359.390442 -388.520178) (xy 359.395014 -388.51205) (xy 359.414826 -388.479792)
			(xy 359.418878 -388.473383) (xy 359.4234 -388.45892) (xy 359.423716 -388.451344) (xy 359.423716 -388.169912)
			(xy 359.423407 -388.162336) (xy 359.418881 -388.147872) (xy 359.414826 -388.141464) (xy 359.395014 -388.109206)
			(xy 359.390442 -388.101078) (xy 359.377234 -388.089648) (xy 359.298748 -388.060184) (xy 359.280968 -388.05993)
			(xy 359.272332 -388.062978) (xy 359.241465 -388.073273) (xy 359.177355 -388.084377) (xy 359.144824 -388.085076)
			(xy 359.117568 -388.084679) (xy 359.06361 -388.076924) (xy 359.011304 -388.061569) (xy 358.961717 -388.038926)
			(xy 358.915857 -388.009456) (xy 358.874658 -387.973759) (xy 358.838959 -387.932562) (xy 358.809486 -387.886704)
			(xy 358.78684 -387.837118) (xy 358.771481 -387.784814) (xy 358.763723 -387.730856) (xy 355.216316 -387.730856)
			(xy 355.346254 -387.860794) (xy 355.353106 -387.86819) (xy 355.36085 -387.886788) (xy 355.36124 -387.896862)
			(xy 355.36124 -389.856218) (xy 355.361668 -389.866286) (xy 355.369391 -389.884882) (xy 355.376226 -389.892286)
			(xy 355.623114 -390.139174) (xy 355.630512 -390.146021) (xy 355.64911 -390.153754) (xy 355.659182 -390.15416)
			(xy 358.385618 -390.15416) (xy 358.395685 -390.154588) (xy 358.414279 -390.162314) (xy 358.421686 -390.169146)
			(xy 358.57815 -390.32561) (xy 361.246672 -390.32561) (xy 361.250743 -390.269988) (xy 361.262869 -390.215551)
			(xy 361.282792 -390.16346) (xy 361.310088 -390.114825) (xy 361.344174 -390.070682) (xy 361.384323 -390.031973)
			(xy 361.429681 -389.999522) (xy 361.479281 -389.974021) (xy 361.532065 -389.956014) (xy 361.586908 -389.945884)
			(xy 361.642642 -389.943847) (xy 361.698079 -389.949947) (xy 361.752036 -389.964053) (xy 361.803365 -389.985865)
			(xy 361.850971 -390.014919) (xy 361.893839 -390.050594) (xy 361.931056 -390.092131) (xy 361.961829 -390.138644)
			(xy 361.985501 -390.189141) (xy 362.001569 -390.242548) (xy 362.009689 -390.297724) (xy 362.010198 -390.32561)
			(xy 362.009689 -390.353496) (xy 362.001569 -390.408672) (xy 361.985501 -390.462079) (xy 361.961829 -390.512576)
			(xy 361.931056 -390.559089) (xy 361.893839 -390.600626) (xy 361.850971 -390.636301) (xy 361.803365 -390.665355)
			(xy 361.752036 -390.687167) (xy 361.698079 -390.701273) (xy 361.642642 -390.707373) (xy 361.586908 -390.705336)
			(xy 361.532065 -390.695206) (xy 361.479281 -390.677199) (xy 361.429681 -390.651698) (xy 361.384323 -390.619247)
			(xy 361.344174 -390.580538) (xy 361.310088 -390.536395) (xy 361.282792 -390.48776) (xy 361.262869 -390.435669)
			(xy 361.250743 -390.381232) (xy 361.246672 -390.32561) (xy 358.57815 -390.32561) (xy 359.073958 -390.821418)
			(xy 359.080806 -390.828815) (xy 359.088541 -390.847414) (xy 359.088944 -390.857486) (xy 359.088944 -390.9695)
			(xy 359.094532 -390.985502) (xy 359.099866 -390.99236) (xy 359.108326 -391.003724) (xy 359.120493 -391.0293)
			(xy 359.126686 -391.056937) (xy 359.127044 -391.0711) (xy 359.127044 -391.4521) (xy 359.126489 -391.469327)
			(xy 359.117351 -391.502548) (xy 359.10901 -391.517632) (xy 359.105454 -391.523728) (xy 359.101644 -391.536936)
			(xy 359.101644 -391.639806) (xy 359.101311 -391.658298) (xy 359.095952 -391.694891) (xy 359.090976 -391.712704)
			(xy 359.088944 -391.719816) (xy 359.088944 -392.049508) (xy 359.08958 -392.060923) (xy 359.099487 -392.081491)
			(xy 359.107994 -392.089132) (xy 359.133049 -392.109874) (xy 359.178202 -392.156693) (xy 359.217015 -392.208888)
			(xy 359.248856 -392.265607) (xy 359.273203 -392.325923) (xy 359.289659 -392.388852) (xy 359.297956 -392.453365)
			(xy 359.297957 -392.51841) (xy 359.289664 -392.582924) (xy 359.273211 -392.645853) (xy 359.248867 -392.706171)
			(xy 359.217029 -392.762891) (xy 359.178218 -392.815088) (xy 359.133067 -392.861909) (xy 359.107994 -392.882628)
			(xy 359.099493 -392.890265) (xy 359.089624 -392.910842) (xy 359.088944 -392.922252) (xy 359.088944 -393.040108)
			(xy 359.08958 -393.051523) (xy 359.099487 -393.072091) (xy 359.107994 -393.079732) (xy 359.133044 -393.100478)
			(xy 359.178189 -393.1473) (xy 359.216998 -393.199496) (xy 359.248836 -393.256213) (xy 359.273185 -393.316525)
			(xy 359.289646 -393.37945) (xy 359.297953 -393.443959) (xy 359.298494 -393.47648) (xy 359.29805 -393.507213)
			(xy 359.290643 -393.56823) (xy 359.275935 -393.627909) (xy 359.254141 -393.685381) (xy 359.225577 -393.739806)
			(xy 359.190662 -393.790391) (xy 359.149903 -393.836399) (xy 359.103896 -393.877158) (xy 359.053311 -393.912074)
			(xy 358.998886 -393.940638) (xy 358.941415 -393.962433) (xy 358.881736 -393.977142) (xy 358.820719 -393.984549)
			(xy 358.789986 -393.984988) (xy 358.757887 -393.984476) (xy 358.694202 -393.976362) (xy 358.63204 -393.960314)
			(xy 358.602026 -393.94892) (xy 358.597512 -393.947237) (xy 358.588047 -393.945452) (xy 358.58323 -393.945364)
			(xy 358.577896 -393.945364) (xy 358.504236 -394.019024) (xy 358.497389 -394.026422) (xy 358.489658 -394.045021)
			(xy 358.48925 -394.055092) (xy 358.48925 -394.223748) (xy 358.492806 -394.232892) (xy 358.504445 -394.263157)
			(xy 358.520827 -394.325896) (xy 358.529102 -394.390209) (xy 358.529636 -394.42263) (xy 358.529111 -394.455052)
			(xy 358.520837 -394.519366) (xy 358.504453 -394.582106) (xy 358.492806 -394.612368) (xy 358.48925 -394.621512)
			(xy 358.48925 -395.01572) (xy 358.494076 -395.0208) (xy 362.103162 -395.0208) (xy 362.111957 -395.020438)
			(xy 362.128512 -395.014497) (xy 362.142079 -395.003303) (xy 362.14685 -394.995908) (xy 362.198412 -394.90904)
			(xy 362.19892 -394.882624) (xy 362.192316 -394.870432) (xy 362.177624 -394.842389) (xy 362.15453 -394.783441)
			(xy 362.138932 -394.722083) (xy 362.131072 -394.659263) (xy 362.130594 -394.627608) (xy 362.131039 -394.596876)
			(xy 362.138447 -394.535859) (xy 362.153156 -394.47618) (xy 362.174951 -394.418709) (xy 362.203514 -394.364285)
			(xy 362.23843 -394.3137) (xy 362.279188 -394.267693) (xy 362.325195 -394.226934) (xy 362.375779 -394.192018)
			(xy 362.430204 -394.163453) (xy 362.487674 -394.141658) (xy 362.547353 -394.126948) (xy 362.60837 -394.11954)
			(xy 362.639102 -394.1191) (xy 362.669797 -394.119579) (xy 362.730738 -394.126999) (xy 362.790344 -394.141696)
			(xy 362.847749 -394.163455) (xy 362.902121 -394.191961) (xy 362.927646 -394.209016) (xy 362.936398 -394.214487)
			(xy 362.956602 -394.218615) (xy 362.976806 -394.214487) (xy 362.985558 -394.209016) (xy 363.011085 -394.191959)
			(xy 363.065446 -394.163426) (xy 363.12285 -394.141651) (xy 363.182459 -394.126952) (xy 363.243405 -394.119543)
			(xy 363.274102 -394.1191) (xy 363.304834 -394.119546) (xy 363.365849 -394.126955) (xy 363.425527 -394.141664)
			(xy 363.482996 -394.16346) (xy 363.53742 -394.192024) (xy 363.588003 -394.22694) (xy 363.634009 -394.267698)
			(xy 363.674766 -394.313705) (xy 363.709681 -394.364289) (xy 363.738244 -394.418713) (xy 363.760039 -394.476183)
			(xy 363.774747 -394.53586) (xy 363.782155 -394.596876) (xy 363.78261 -394.627608) (xy 363.782127 -394.659263)
			(xy 363.774267 -394.722082) (xy 363.75867 -394.78344) (xy 363.735576 -394.842387) (xy 363.720888 -394.870432)
			(xy 363.714284 -394.882624) (xy 363.714792 -394.90904) (xy 363.766354 -394.995908) (xy 363.771152 -395.003287)
			(xy 363.784704 -395.014497) (xy 363.801249 -395.020464) (xy 363.810042 -395.0208) (xy 363.833664 -395.0208)
			(xy 363.843626 -395.021286) (xy 363.862051 -395.028873) (xy 363.869478 -395.035532) (xy 363.876082 -395.042136)
			(xy 363.88346 -395.048949) (xy 363.90199 -395.056651) (xy 363.922056 -395.056651) (xy 363.940586 -395.048949)
			(xy 363.947964 -395.042136) (xy 363.951774 -395.038072) (xy 363.954822 -395.0335) (xy 363.972409 -395.006994)
			(xy 364.013163 -394.958153) (xy 364.059691 -394.914776) (xy 364.111264 -394.87754) (xy 364.167079 -394.847026)
			(xy 364.226263 -394.823711) (xy 364.287893 -394.807958) (xy 364.351006 -394.800015) (xy 364.382812 -394.799566)
			(xy 364.410601 -394.799969) (xy 364.465842 -394.806083) (xy 364.493048 -394.811758) (xy 364.506002 -394.814552)
			(xy 364.530894 -394.807186) (xy 364.598966 -394.739114) (xy 364.606078 -394.725652) (xy 364.607348 -394.717778)
			(xy 364.613058 -394.689483) (xy 364.631868 -394.634911) (xy 364.658681 -394.583795) (xy 364.692885 -394.537299)
			(xy 364.733701 -394.496483) (xy 364.780197 -394.462279) (xy 364.831314 -394.435467) (xy 364.885885 -394.416657)
			(xy 364.91418 -394.410946) (xy 364.922054 -394.409676) (xy 364.935516 -394.402564) (xy 364.975394 -394.362686)
			(xy 364.982239 -394.355287) (xy 364.989969 -394.336689) (xy 364.99038 -394.326618) (xy 364.99038 -391.735564)
			(xy 364.989867 -391.725372) (xy 364.981852 -391.706622) (xy 364.967206 -391.692436) (xy 364.957868 -391.68832)
			(xy 364.854744 -391.648442) (xy 364.82401 -391.655808) (xy 364.813596 -391.667492) (xy 364.795418 -391.686874)
			(xy 364.754625 -391.720924) (xy 364.709504 -391.748988) (xy 364.660927 -391.770522) (xy 364.609832 -391.785111)
			(xy 364.557208 -391.792473) (xy 364.53064 -391.792968) (xy 364.503386 -391.792507) (xy 364.449433 -391.784755)
			(xy 364.397133 -391.769402) (xy 364.34755 -391.746761) (xy 364.301695 -391.717294) (xy 364.260501 -391.681599)
			(xy 364.224806 -391.640405) (xy 364.195339 -391.59455) (xy 364.172698 -391.544967) (xy 364.157345 -391.492667)
			(xy 364.149593 -391.438714) (xy 364.149132 -391.41146) (xy 364.150148 -391.382758) (xy 364.151164 -391.36955)
			(xy 364.140242 -391.345928) (xy 364.049564 -391.279126) (xy 364.023656 -391.275824) (xy 364.01121 -391.280904)
			(xy 363.9887 -391.289441) (xy 363.942074 -391.301432) (xy 363.894312 -391.307472) (xy 363.87024 -391.307828)
			(xy 363.842984 -391.307368) (xy 363.789026 -391.299615) (xy 363.73672 -391.284262) (xy 363.687132 -391.26162)
			(xy 363.641272 -391.232152) (xy 363.600072 -391.196456) (xy 363.564372 -391.15526) (xy 363.534899 -391.109403)
			(xy 363.512252 -391.059817) (xy 363.496893 -391.007513) (xy 363.489135 -390.953556) (xy 363.489135 -390.899044)
			(xy 363.496893 -390.845087) (xy 363.512252 -390.792783) (xy 363.534899 -390.743197) (xy 363.564372 -390.69734)
			(xy 363.600072 -390.656144) (xy 363.641272 -390.620448) (xy 363.687132 -390.59098) (xy 363.73672 -390.568338)
			(xy 363.789026 -390.552985) (xy 363.842984 -390.545232) (xy 363.87024 -390.544812) (xy 363.902771 -390.545512)
			(xy 363.96688 -390.556618) (xy 363.997748 -390.56691) (xy 364.006384 -390.569958) (xy 364.024164 -390.569704)
			(xy 364.10265 -390.54024) (xy 364.115858 -390.52881) (xy 364.12043 -390.520682) (xy 364.140242 -390.488424)
			(xy 364.144294 -390.482016) (xy 364.148815 -390.467551) (xy 364.149132 -390.459976) (xy 364.149132 -390.178544)
			(xy 364.148815 -390.170969) (xy 364.144291 -390.156507) (xy 364.140242 -390.150096) (xy 364.12043 -390.117838)
			(xy 364.115858 -390.10971) (xy 364.10265 -390.09828) (xy 364.024164 -390.068816) (xy 364.006384 -390.068562)
			(xy 363.997748 -390.07161) (xy 363.966881 -390.081908) (xy 363.902772 -390.093021) (xy 363.87024 -390.093708)
			(xy 363.842985 -390.093247) (xy 363.78903 -390.085495) (xy 363.736727 -390.070142) (xy 363.687142 -390.047502)
			(xy 363.641284 -390.018035) (xy 363.600087 -389.982342) (xy 363.564389 -389.941148) (xy 363.534917 -389.895293)
			(xy 363.512272 -389.84571) (xy 363.496913 -389.793409) (xy 363.489155 -389.739455) (xy 363.489155 -389.684945)
			(xy 363.496913 -389.630991) (xy 363.512272 -389.57869) (xy 363.534917 -389.529107) (xy 363.564389 -389.483252)
			(xy 363.600087 -389.442058) (xy 363.641284 -389.406365) (xy 363.687142 -389.376898) (xy 363.736727 -389.354258)
			(xy 363.78903 -389.338905) (xy 363.842985 -389.331153) (xy 363.87024 -389.330692) (xy 363.894176 -389.331066)
			(xy 363.941672 -389.337049) (xy 363.988049 -389.348917) (xy 364.010448 -389.357362) (xy 364.022386 -389.362188)
			(xy 364.047278 -389.35914) (xy 364.13821 -389.295894) (xy 364.149386 -389.273796) (xy 364.149132 -389.260588)
			(xy 364.149132 -389.25246) (xy 364.149618 -389.225209) (xy 364.157374 -389.171261) (xy 364.172729 -389.118966)
			(xy 364.195371 -389.069389) (xy 364.224837 -389.023539) (xy 364.260528 -388.982348) (xy 364.301719 -388.946657)
			(xy 364.347569 -388.917191) (xy 364.397146 -388.894549) (xy 364.449441 -388.879194) (xy 364.503389 -388.871438)
			(xy 364.557891 -388.871438) (xy 364.611839 -388.879194) (xy 364.664134 -388.894549) (xy 364.713711 -388.917191)
			(xy 364.759561 -388.946657) (xy 364.800752 -388.982348) (xy 364.836443 -389.023539) (xy 364.865909 -389.069389)
			(xy 364.888551 -389.118966) (xy 364.903906 -389.171261) (xy 364.911662 -389.225209) (xy 364.912148 -389.25246)
			(xy 364.912148 -389.260588) (xy 364.911894 -389.273796) (xy 364.92307 -389.295894) (xy 365.014002 -389.35914)
			(xy 365.038894 -389.362188) (xy 365.050832 -389.357362) (xy 365.073226 -389.348899) (xy 365.119603 -389.337021)
			(xy 365.167103 -389.33105) (xy 365.19104 -389.330692) (xy 365.218289 -389.331181) (xy 365.272233 -389.338942)
			(xy 365.324523 -389.3543) (xy 365.374095 -389.376944) (xy 365.41994 -389.406411) (xy 365.461126 -389.442103)
			(xy 365.496813 -389.483292) (xy 365.526276 -389.52914) (xy 365.548914 -389.578715) (xy 365.564267 -389.631006)
			(xy 365.572022 -389.684951) (xy 365.572022 -389.739449) (xy 365.564267 -389.793394) (xy 365.548914 -389.845685)
			(xy 365.526276 -389.89526) (xy 365.496813 -389.941108) (xy 365.461126 -389.982297) (xy 365.41994 -390.017989)
			(xy 365.374095 -390.047456) (xy 365.324523 -390.0701) (xy 365.272233 -390.085458) (xy 365.218289 -390.093219)
			(xy 365.19104 -390.093708) (xy 365.158509 -390.093006) (xy 365.094401 -390.081897) (xy 365.063532 -390.07161)
			(xy 365.054896 -390.068562) (xy 365.037116 -390.068816) (xy 364.95863 -390.09828) (xy 364.945422 -390.10971)
			(xy 364.94085 -390.117838) (xy 364.921038 -390.150096) (xy 364.91699 -390.156506) (xy 364.912476 -390.17097)
			(xy 364.912148 -390.178544) (xy 364.912148 -390.459976) (xy 364.912468 -390.46755) (xy 364.916995 -390.48201)
			(xy 364.921038 -390.488424) (xy 364.94085 -390.520682) (xy 364.945422 -390.52881) (xy 364.95863 -390.54024)
			(xy 365.037116 -390.569704) (xy 365.054896 -390.569958) (xy 365.063532 -390.56691) (xy 365.09161 -390.557519)
			(xy 365.149786 -390.546542) (xy 365.179356 -390.545066) (xy 365.189262 -390.544812) (xy 365.207042 -390.536938)
			(xy 366.503204 -389.240776) (xy 366.506252 -389.236204) (xy 366.521391 -389.213593) (xy 366.557061 -389.172503)
			(xy 366.598212 -389.136903) (xy 366.644007 -389.107517) (xy 366.693516 -389.084941) (xy 366.745732 -389.069636)
			(xy 366.799593 -389.061913) (xy 366.8268 -389.061452) (xy 366.85632 -389.062005) (xy 366.914653 -389.071107)
			(xy 366.970887 -389.089092) (xy 367.023675 -389.11553) (xy 367.071757 -389.149791) (xy 367.113983 -389.191053)
			(xy 367.132108 -389.21436) (xy 367.139713 -389.22346) (xy 367.160904 -389.23404) (xy 367.172748 -389.23468)
			(xy 368.367818 -389.23468) (xy 368.377886 -389.234253) (xy 368.396484 -389.226532) (xy 368.403886 -389.219694)
			(xy 368.668554 -388.955026) (xy 368.675394 -388.947626) (xy 368.683109 -388.929027) (xy 368.68354 -388.918958)
			(xy 368.68354 -387.871462) (xy 368.683971 -387.861396) (xy 368.6917 -387.842805) (xy 368.698526 -387.835394)
			(xy 369.041934 -387.491986) (xy 369.04933 -387.485135) (xy 369.067929 -387.4774) (xy 369.078002 -387.477)
			(xy 389.531098 -387.477) (xy 389.541168 -387.477423) (xy 389.559773 -387.485137) (xy 389.567166 -387.491986)
			(xy 389.958834 -387.883654) (xy 389.965679 -387.891052) (xy 389.973404 -387.909651) (xy 389.97382 -387.919722)
			(xy 389.97382 -389.934958) (xy 389.974254 -389.945023) (xy 389.981986 -389.96361) (xy 389.988806 -389.971026)
			(xy 390.139174 -390.121394) (xy 390.146576 -390.128229) (xy 390.165175 -390.135938) (xy 390.175242 -390.13638)
			(xy 393.125198 -390.13638) (xy 393.135269 -390.136802) (xy 393.153876 -390.144514) (xy 393.161266 -390.151366)
			(xy 393.646406 -390.636506) (xy 393.653251 -390.643905) (xy 393.660982 -390.662503) (xy 393.661392 -390.672574)
			(xy 393.661392 -390.9695) (xy 393.66698 -390.985502) (xy 393.672314 -390.99236) (xy 393.680771 -391.003725)
			(xy 393.692933 -391.029302) (xy 393.699124 -391.056938) (xy 393.699492 -391.0711) (xy 393.699492 -391.4521)
			(xy 393.698937 -391.469328) (xy 393.689802 -391.50255) (xy 393.681458 -391.517632) (xy 393.677902 -391.523728)
			(xy 393.674092 -391.536936) (xy 393.674092 -391.639806) (xy 393.673759 -391.658298) (xy 393.668401 -391.694891)
			(xy 393.663424 -391.712704) (xy 393.661392 -391.719816) (xy 393.661392 -392.049508) (xy 393.662027 -392.060924)
			(xy 393.671927 -392.0815) (xy 393.680442 -392.089132) (xy 393.705495 -392.109876) (xy 393.750644 -392.156696)
			(xy 393.789454 -392.208892) (xy 393.821291 -392.265611) (xy 393.845636 -392.325926) (xy 393.86209 -392.388854)
			(xy 393.870386 -392.453366) (xy 393.870388 -392.518409) (xy 393.862095 -392.582922) (xy 393.845643 -392.64585)
			(xy 393.821302 -392.706167) (xy 393.789467 -392.762887) (xy 393.75066 -392.815085) (xy 393.705513 -392.861908)
			(xy 393.680442 -392.882628) (xy 393.671935 -392.890262) (xy 393.662056 -392.91084) (xy 393.661392 -392.922252)
			(xy 393.661392 -393.040108) (xy 393.662027 -393.051524) (xy 393.671927 -393.0721) (xy 393.680442 -393.079732)
			(xy 393.705494 -393.100476) (xy 393.750644 -393.147297) (xy 393.789456 -393.199492) (xy 393.821298 -393.256208)
			(xy 393.845649 -393.316522) (xy 393.862113 -393.379447) (xy 393.87042 -393.443958) (xy 393.870942 -393.47648)
			(xy 393.87048 -393.507213) (xy 393.863073 -393.56823) (xy 393.848366 -393.627909) (xy 393.826573 -393.685381)
			(xy 393.798012 -393.739807) (xy 393.763098 -393.790394) (xy 393.722341 -393.836403) (xy 393.676336 -393.877165)
			(xy 393.625754 -393.912084) (xy 393.571331 -393.940651) (xy 393.513861 -393.96245) (xy 393.454183 -393.977164)
			(xy 393.393167 -393.984576) (xy 393.362434 -393.984988) (xy 393.330334 -393.984479) (xy 393.266647 -393.97637)
			(xy 393.204483 -393.960328) (xy 393.174474 -393.94892) (xy 393.169961 -393.947233) (xy 393.160496 -393.945438)
			(xy 393.155678 -393.945364) (xy 393.150344 -393.945364) (xy 393.076684 -394.019024) (xy 393.069832 -394.02642)
			(xy 393.062093 -394.045019) (xy 393.061698 -394.055092) (xy 393.061698 -394.223748) (xy 393.065254 -394.232892)
			(xy 393.076894 -394.263156) (xy 393.093278 -394.325896) (xy 393.101554 -394.390209) (xy 393.102084 -394.42263)
			(xy 393.101559 -394.455052) (xy 393.093286 -394.519366) (xy 393.076904 -394.582107) (xy 393.065254 -394.612368)
			(xy 393.061698 -394.621512) (xy 393.061698 -395.01572) (xy 393.066524 -395.0208) (xy 396.34287 -395.0208)
			(xy 396.35286 -395.020268) (xy 396.3713 -395.012562) (xy 396.378684 -395.005814) (xy 396.545054 -394.839444)
			(xy 396.552453 -394.832601) (xy 396.571052 -394.82488) (xy 396.581122 -394.824458) (xy 396.753334 -394.824458)
			(xy 396.760446 -394.822172) (xy 396.797076 -394.811626) (xy 396.872449 -394.800278) (xy 396.91056 -394.799566)
			(xy 396.931485 -394.799779) (xy 396.973194 -394.80321) (xy 396.993872 -394.806424) (xy 397.003016 -394.807948)
			(xy 397.020796 -394.804646) (xy 397.092932 -394.760958) (xy 397.104108 -394.746988) (xy 397.107156 -394.738352)
			(xy 397.116512 -394.711784) (xy 397.141933 -394.661521) (xy 397.174468 -394.615543) (xy 397.21341 -394.574848)
			(xy 397.257912 -394.540321) (xy 397.307008 -394.512713) (xy 397.359629 -394.492624) (xy 397.414632 -394.480491)
			(xy 397.44269 -394.478002) (xy 397.451909 -394.476957) (xy 397.468714 -394.469136) (xy 397.475456 -394.462762)
			(xy 397.496792 -394.441172) (xy 397.503374 -394.43379) (xy 397.510828 -394.415492) (xy 397.51127 -394.405612)
			(xy 397.51127 -394.392404) (xy 397.513048 -394.390626) (xy 397.513048 -391.741152) (xy 397.512603 -391.730975)
			(xy 397.504695 -391.712221) (xy 397.490107 -391.698028) (xy 397.48079 -391.693908) (xy 397.378174 -391.653522)
			(xy 397.347948 -391.66038) (xy 397.33728 -391.67181) (xy 397.319177 -391.690581) (xy 397.278731 -391.723499)
			(xy 397.234176 -391.7506) (xy 397.186344 -391.771376) (xy 397.136128 -391.785441) (xy 397.084463 -391.792531)
			(xy 397.058388 -391.792968) (xy 397.031137 -391.792504) (xy 396.977189 -391.784745) (xy 396.924895 -391.769388)
			(xy 396.875319 -391.746744) (xy 396.82947 -391.717275) (xy 396.788282 -391.681581) (xy 396.752594 -391.640388)
			(xy 396.723131 -391.594535) (xy 396.700494 -391.544956) (xy 396.685144 -391.49266) (xy 396.677392 -391.438711)
			(xy 396.67688 -391.41146) (xy 396.677896 -391.382758) (xy 396.678912 -391.36955) (xy 396.66799 -391.345928)
			(xy 396.577312 -391.279126) (xy 396.551404 -391.275824) (xy 396.538958 -391.280904) (xy 396.516448 -391.289438)
			(xy 396.469821 -391.301423) (xy 396.422059 -391.307456) (xy 396.397988 -391.307828) (xy 396.370736 -391.307341)
			(xy 396.316787 -391.299583) (xy 396.264491 -391.284226) (xy 396.214912 -391.261583) (xy 396.169061 -391.232115)
			(xy 396.12787 -391.196422) (xy 396.092178 -391.155229) (xy 396.062711 -391.109377) (xy 396.04007 -391.059798)
			(xy 396.024714 -391.007502) (xy 396.016958 -390.953552) (xy 396.016958 -390.899048) (xy 396.024714 -390.845098)
			(xy 396.04007 -390.792802) (xy 396.062711 -390.743223) (xy 396.092178 -390.697371) (xy 396.12787 -390.656178)
			(xy 396.169061 -390.620485) (xy 396.214912 -390.591017) (xy 396.264491 -390.568374) (xy 396.316787 -390.553017)
			(xy 396.370736 -390.545259) (xy 396.397988 -390.544812) (xy 396.430518 -390.545516) (xy 396.494625 -390.55663)
			(xy 396.525496 -390.56691) (xy 396.534132 -390.569958) (xy 396.551912 -390.569704) (xy 396.630398 -390.54024)
			(xy 396.643606 -390.52881) (xy 396.648178 -390.520682) (xy 396.66799 -390.488424) (xy 396.672039 -390.482015)
			(xy 396.676556 -390.467551) (xy 396.67688 -390.459976) (xy 396.67688 -390.178544) (xy 396.676564 -390.170968)
			(xy 396.672043 -390.156504) (xy 396.66799 -390.150096) (xy 396.648178 -390.117838) (xy 396.643606 -390.10971)
			(xy 396.630398 -390.09828) (xy 396.551912 -390.068816) (xy 396.534132 -390.068562) (xy 396.525496 -390.07161)
			(xy 396.494629 -390.081904) (xy 396.430519 -390.093008) (xy 396.397988 -390.093708) (xy 396.370737 -390.093221)
			(xy 396.316791 -390.085463) (xy 396.264498 -390.070107) (xy 396.214922 -390.047465) (xy 396.169073 -390.017999)
			(xy 396.127884 -389.982307) (xy 396.092194 -389.941117) (xy 396.062729 -389.895268) (xy 396.040088 -389.845691)
			(xy 396.024734 -389.793397) (xy 396.016978 -389.739451) (xy 396.016978 -389.684949) (xy 396.024734 -389.631003)
			(xy 396.040088 -389.578709) (xy 396.062729 -389.529132) (xy 396.092194 -389.483283) (xy 396.127884 -389.442093)
			(xy 396.169073 -389.406401) (xy 396.214922 -389.376935) (xy 396.264498 -389.354293) (xy 396.316791 -389.338937)
			(xy 396.370737 -389.331179) (xy 396.397988 -389.330692) (xy 396.421923 -389.331069) (xy 396.469417 -389.337058)
			(xy 396.515792 -389.348931) (xy 396.538196 -389.357362) (xy 396.550134 -389.362188) (xy 396.575026 -389.35914)
			(xy 396.665958 -389.295894) (xy 396.677134 -389.273796) (xy 396.67688 -389.260588) (xy 396.67688 -389.25246)
			(xy 396.677366 -389.225209) (xy 396.685122 -389.171261) (xy 396.700477 -389.118966) (xy 396.723119 -389.069389)
			(xy 396.752585 -389.023539) (xy 396.788276 -388.982348) (xy 396.829467 -388.946657) (xy 396.875317 -388.917191)
			(xy 396.924894 -388.894549) (xy 396.977189 -388.879194) (xy 397.031137 -388.871438) (xy 397.085639 -388.871438)
			(xy 397.139587 -388.879194) (xy 397.191882 -388.894549) (xy 397.241459 -388.917191) (xy 397.287309 -388.946657)
			(xy 397.3285 -388.982348) (xy 397.364191 -389.023539) (xy 397.393657 -389.069389) (xy 397.416299 -389.118966)
			(xy 397.431654 -389.171261) (xy 397.43941 -389.225209) (xy 397.439896 -389.25246) (xy 397.439896 -389.260588)
			(xy 397.439642 -389.273796) (xy 397.450818 -389.295894) (xy 397.54175 -389.35914) (xy 397.566642 -389.362188)
			(xy 397.57858 -389.357362) (xy 397.600973 -389.348896) (xy 397.64735 -389.337012) (xy 397.69485 -389.331035)
			(xy 397.718788 -389.330692) (xy 397.746041 -389.331155) (xy 397.799994 -389.33891) (xy 397.852293 -389.354265)
			(xy 397.901875 -389.376907) (xy 397.947729 -389.406375) (xy 397.988923 -389.442068) (xy 398.024618 -389.483261)
			(xy 398.054087 -389.529115) (xy 398.076731 -389.578696) (xy 398.092087 -389.630995) (xy 398.099845 -389.684947)
			(xy 398.099845 -389.739453) (xy 398.092087 -389.793405) (xy 398.076731 -389.845704) (xy 398.054087 -389.895285)
			(xy 398.024618 -389.941139) (xy 397.988923 -389.982332) (xy 397.947729 -390.018025) (xy 397.901875 -390.047493)
			(xy 397.852293 -390.070135) (xy 397.799994 -390.08549) (xy 397.746041 -390.093245) (xy 397.718788 -390.093708)
			(xy 397.686258 -390.093002) (xy 397.622153 -390.081885) (xy 397.59128 -390.07161) (xy 397.582644 -390.068562)
			(xy 397.564864 -390.068816) (xy 397.486378 -390.09828) (xy 397.47317 -390.10971) (xy 397.468598 -390.117838)
			(xy 397.448786 -390.150096) (xy 397.444734 -390.156504) (xy 397.440216 -390.170969) (xy 397.439896 -390.178544)
			(xy 397.439896 -390.459976) (xy 397.440215 -390.467551) (xy 397.444738 -390.482013) (xy 397.448786 -390.488424)
			(xy 397.468598 -390.520682) (xy 397.47317 -390.52881) (xy 397.486378 -390.54024) (xy 397.564864 -390.569704)
			(xy 397.582644 -390.569958) (xy 397.59128 -390.56691) (xy 397.622147 -390.556613) (xy 397.686256 -390.545505)
			(xy 397.718788 -390.544812) (xy 397.746753 -390.545308) (xy 397.802083 -390.553483) (xy 397.855628 -390.569645)
			(xy 397.90624 -390.593449) (xy 397.952837 -390.624384) (xy 397.994421 -390.661788) (xy 398.012666 -390.682988)
			(xy 398.019524 -390.69137) (xy 398.038574 -390.701022) (xy 398.124426 -390.704832) (xy 398.135058 -390.704827)
			(xy 398.154883 -390.697218) (xy 398.16278 -390.6901) (xy 398.645634 -390.207246) (xy 398.653032 -390.2004)
			(xy 398.671631 -390.192671) (xy 398.681702 -390.19226) (xy 398.6911 -390.19226) (xy 399.08226 -389.8011)
			(xy 399.089147 -389.79365) (xy 399.096889 -389.774916) (xy 399.097246 -389.764778) (xy 399.096484 -389.681974)
			(xy 399.08861 -389.663432) (xy 399.081244 -389.656066) (xy 399.063204 -389.63804) (xy 399.031582 -389.598029)
			(xy 399.005574 -389.554161) (xy 398.985644 -389.507218) (xy 398.972147 -389.458039) (xy 398.965325 -389.407499)
			(xy 398.964912 -389.382) (xy 398.965375 -389.354748) (xy 398.973132 -389.300798) (xy 398.988489 -389.248501)
			(xy 399.011131 -389.198922) (xy 399.0406 -389.153071) (xy 399.076294 -389.11188) (xy 399.117487 -389.076188)
			(xy 399.16334 -389.046722) (xy 399.21292 -389.024082) (xy 399.265217 -389.008728) (xy 399.319168 -389.000974)
			(xy 399.34642 -389.000492) (xy 399.373393 -389.000959) (xy 399.4268 -389.008559) (xy 399.478605 -389.023605)
			(xy 399.527774 -389.045796) (xy 399.573329 -389.074691) (xy 399.61436 -389.109713) (xy 399.650049 -389.150165)
			(xy 399.679687 -389.195239) (xy 399.691606 -389.21944) (xy 399.693546 -389.223342) (xy 399.698526 -389.230491)
			(xy 399.701512 -389.233664) (xy 399.705068 -389.23722) (xy 399.72361 -389.24484) (xy 401.123658 -389.24484)
			(xy 401.133722 -389.244405) (xy 401.152306 -389.236669) (xy 401.159726 -389.229854) (xy 401.305014 -389.084566)
			(xy 401.311865 -389.07717) (xy 401.3196 -389.058571) (xy 401.32 -389.048498) (xy 401.32 -387.825742)
			(xy 401.320434 -387.815677) (xy 401.328163 -387.797087) (xy 401.334986 -387.789674) (xy 401.609814 -387.514846)
			(xy 401.617211 -387.507997) (xy 401.63581 -387.50026) (xy 401.645882 -387.49986) (xy 422.032938 -387.49986)
			(xy 422.043004 -387.500292) (xy 422.061593 -387.508022) (xy 422.069006 -387.514846) (xy 422.285016 -387.730856)
			(xy 425.863923 -387.730856) (xy 425.863923 -387.676344) (xy 425.871681 -387.622387) (xy 425.887039 -387.570083)
			(xy 425.909685 -387.520497) (xy 425.939158 -387.474639) (xy 425.974857 -387.433442) (xy 426.016055 -387.397746)
			(xy 426.061915 -387.368276) (xy 426.111502 -387.345632) (xy 426.163806 -387.330277) (xy 426.217764 -387.322522)
			(xy 426.24502 -387.32206) (xy 426.269091 -387.322423) (xy 426.316854 -387.32846) (xy 426.36348 -387.340448)
			(xy 426.38599 -387.348984) (xy 426.398436 -387.354064) (xy 426.424344 -387.350762) (xy 426.515022 -387.28396)
			(xy 426.525944 -387.260338) (xy 426.524928 -387.24713) (xy 426.523912 -387.218428) (xy 426.524398 -387.191177)
			(xy 426.532154 -387.137229) (xy 426.547509 -387.084934) (xy 426.570151 -387.035357) (xy 426.599617 -386.989507)
			(xy 426.635308 -386.948316) (xy 426.676499 -386.912625) (xy 426.722349 -386.883159) (xy 426.771926 -386.860517)
			(xy 426.824221 -386.845162) (xy 426.878169 -386.837406) (xy 426.932671 -386.837406) (xy 426.986619 -386.845162)
			(xy 427.038914 -386.860517) (xy 427.088491 -386.883159) (xy 427.134341 -386.912625) (xy 427.175532 -386.948316)
			(xy 427.211223 -386.989507) (xy 427.240689 -387.035357) (xy 427.263331 -387.084934) (xy 427.278686 -387.137229)
			(xy 427.286442 -387.191177) (xy 427.286928 -387.218428) (xy 427.285912 -387.24713) (xy 427.284896 -387.260338)
			(xy 427.295818 -387.28396) (xy 427.386496 -387.350762) (xy 427.412404 -387.354064) (xy 427.42485 -387.348984)
			(xy 427.447357 -387.340436) (xy 427.493982 -387.328436) (xy 427.541747 -387.322409) (xy 427.56582 -387.32206)
			(xy 427.593068 -387.322612) (xy 427.647009 -387.33037) (xy 427.699297 -387.345725) (xy 427.748867 -387.368366)
			(xy 427.794711 -387.39783) (xy 427.835896 -387.433518) (xy 427.871582 -387.474705) (xy 427.901044 -387.52055)
			(xy 427.923682 -387.570122) (xy 427.939035 -387.622411) (xy 427.94679 -387.676352) (xy 427.94679 -387.730848)
			(xy 427.939035 -387.784789) (xy 427.923682 -387.837078) (xy 427.901044 -387.88665) (xy 427.871582 -387.932495)
			(xy 427.835896 -387.973682) (xy 427.794711 -388.00937) (xy 427.748867 -388.038834) (xy 427.699297 -388.061475)
			(xy 427.647009 -388.07683) (xy 427.593068 -388.084588) (xy 427.56582 -388.085076) (xy 427.533289 -388.084375)
			(xy 427.469179 -388.073272) (xy 427.438312 -388.062978) (xy 427.429676 -388.05993) (xy 427.411896 -388.060184)
			(xy 427.33341 -388.089648) (xy 427.320202 -388.101078) (xy 427.31563 -388.109206) (xy 427.295818 -388.141464)
			(xy 427.291778 -388.147879) (xy 427.28725 -388.162338) (xy 427.286928 -388.169912) (xy 427.286928 -388.451344)
			(xy 427.287264 -388.458918) (xy 427.291773 -388.473382) (xy 427.295818 -388.479792) (xy 427.31563 -388.51205)
			(xy 427.320202 -388.520178) (xy 427.33341 -388.531608) (xy 427.411896 -388.561072) (xy 427.429676 -388.561326)
			(xy 427.438312 -388.558278) (xy 427.469183 -388.547995) (xy 427.53329 -388.536884) (xy 427.56582 -388.53618)
			(xy 427.593069 -388.536692) (xy 427.647013 -388.54445) (xy 427.699304 -388.559807) (xy 427.748877 -388.582448)
			(xy 427.794723 -388.611914) (xy 427.83591 -388.647604) (xy 427.871598 -388.688793) (xy 427.901062 -388.734641)
			(xy 427.9237 -388.784215) (xy 427.939054 -388.836506) (xy 427.94681 -388.890451) (xy 427.94681 -388.944949)
			(xy 427.939054 -388.998894) (xy 427.9237 -389.051185) (xy 427.901062 -389.100759) (xy 427.871598 -389.146607)
			(xy 427.83591 -389.187796) (xy 427.794723 -389.223486) (xy 427.748877 -389.252952) (xy 427.699304 -389.275593)
			(xy 427.647013 -389.29095) (xy 427.593069 -389.298708) (xy 427.56582 -389.299196) (xy 427.541748 -389.298848)
			(xy 427.493985 -389.292804) (xy 427.44736 -389.28081) (xy 427.42485 -389.272272) (xy 427.412404 -389.267192)
			(xy 427.386496 -389.270494) (xy 427.295818 -389.337296) (xy 427.284896 -389.360918) (xy 427.285912 -389.374126)
			(xy 427.286928 -389.402828) (xy 427.286442 -389.430079) (xy 427.278686 -389.484027) (xy 427.263331 -389.536322)
			(xy 427.240689 -389.585899) (xy 427.211223 -389.631749) (xy 427.175532 -389.67294) (xy 427.134341 -389.708631)
			(xy 427.088491 -389.738097) (xy 427.038914 -389.760739) (xy 426.986619 -389.776094) (xy 426.932671 -389.78385)
			(xy 426.878169 -389.78385) (xy 426.824221 -389.776094) (xy 426.771926 -389.760739) (xy 426.722349 -389.738097)
			(xy 426.676499 -389.708631) (xy 426.635308 -389.67294) (xy 426.599617 -389.631749) (xy 426.570151 -389.585899)
			(xy 426.547509 -389.536322) (xy 426.532154 -389.484027) (xy 426.524398 -389.430079) (xy 426.523912 -389.402828)
			(xy 426.524928 -389.374126) (xy 426.525944 -389.360918) (xy 426.515022 -389.337296) (xy 426.424344 -389.270494)
			(xy 426.398436 -389.267192) (xy 426.38599 -389.272272) (xy 426.36348 -389.280811) (xy 426.316857 -389.292813)
			(xy 426.269092 -389.298845) (xy 426.24502 -389.299196) (xy 426.217765 -389.298758) (xy 426.16381 -389.291004)
			(xy 426.111509 -389.275649) (xy 426.061924 -389.253007) (xy 426.016067 -389.223538) (xy 425.974871 -389.187843)
			(xy 425.939174 -389.146649) (xy 425.909703 -389.100793) (xy 425.887058 -389.05121) (xy 425.871701 -388.998909)
			(xy 425.863943 -388.944955) (xy 425.863943 -388.890445) (xy 425.871701 -388.836491) (xy 425.887058 -388.78419)
			(xy 425.909703 -388.734607) (xy 425.939174 -388.688751) (xy 425.974871 -388.647557) (xy 426.016067 -388.611862)
			(xy 426.061924 -388.582393) (xy 426.111509 -388.559751) (xy 426.16381 -388.544396) (xy 426.217765 -388.536642)
			(xy 426.24502 -388.53618) (xy 426.277552 -388.536873) (xy 426.341661 -388.547982) (xy 426.372528 -388.558278)
			(xy 426.381164 -388.561326) (xy 426.398944 -388.561072) (xy 426.47743 -388.531608) (xy 426.490638 -388.520178)
			(xy 426.49521 -388.51205) (xy 426.515022 -388.479792) (xy 426.519074 -388.473383) (xy 426.523596 -388.45892)
			(xy 426.523912 -388.451344) (xy 426.523912 -388.169912) (xy 426.523604 -388.162336) (xy 426.519077 -388.147872)
			(xy 426.515022 -388.141464) (xy 426.49521 -388.109206) (xy 426.490638 -388.101078) (xy 426.47743 -388.089648)
			(xy 426.398944 -388.060184) (xy 426.381164 -388.05993) (xy 426.372528 -388.062978) (xy 426.341661 -388.073274)
			(xy 426.277551 -388.084377) (xy 426.24502 -388.085076) (xy 426.217764 -388.084678) (xy 426.163806 -388.076923)
			(xy 426.111502 -388.061568) (xy 426.061915 -388.038924) (xy 426.016055 -388.009454) (xy 425.974857 -387.973758)
			(xy 425.939158 -387.932561) (xy 425.909685 -387.886703) (xy 425.887039 -387.837117) (xy 425.871681 -387.784813)
			(xy 425.863923 -387.730856) (xy 422.285016 -387.730856) (xy 422.412414 -387.858254) (xy 422.419261 -387.865651)
			(xy 422.426989 -387.884251) (xy 422.4274 -387.894322) (xy 422.4274 -389.405368) (xy 424.720002 -389.405368)
			(xy 424.724073 -389.349746) (xy 424.736199 -389.295309) (xy 424.756122 -389.243218) (xy 424.783418 -389.194583)
			(xy 424.817504 -389.15044) (xy 424.857653 -389.111731) (xy 424.903011 -389.07928) (xy 424.952611 -389.053779)
			(xy 425.005395 -389.035772) (xy 425.060238 -389.025642) (xy 425.115972 -389.023605) (xy 425.171409 -389.029705)
			(xy 425.225366 -389.043811) (xy 425.276695 -389.065623) (xy 425.324301 -389.094677) (xy 425.367169 -389.130352)
			(xy 425.404386 -389.171889) (xy 425.435159 -389.218402) (xy 425.458831 -389.268899) (xy 425.474899 -389.322306)
			(xy 425.483019 -389.377482) (xy 425.483528 -389.405368) (xy 425.483019 -389.433254) (xy 425.474899 -389.48843)
			(xy 425.458831 -389.541837) (xy 425.435159 -389.592334) (xy 425.404386 -389.638847) (xy 425.367169 -389.680384)
			(xy 425.324301 -389.716059) (xy 425.276695 -389.745113) (xy 425.225366 -389.766925) (xy 425.171409 -389.781031)
			(xy 425.115972 -389.787131) (xy 425.060238 -389.785094) (xy 425.005395 -389.774964) (xy 424.952611 -389.756957)
			(xy 424.903011 -389.731456) (xy 424.857653 -389.699005) (xy 424.817504 -389.660296) (xy 424.783418 -389.616153)
			(xy 424.756122 -389.567518) (xy 424.736199 -389.515427) (xy 424.724073 -389.46099) (xy 424.720002 -389.405368)
			(xy 422.4274 -389.405368) (xy 422.4274 -390.049258) (xy 422.427834 -390.059323) (xy 422.435563 -390.077913)
			(xy 422.442386 -390.085326) (xy 422.534334 -390.177274) (xy 422.541733 -390.184118) (xy 422.560331 -390.191844)
			(xy 422.570402 -390.19226) (xy 425.465494 -390.19226) (xy 425.474444 -390.191862) (xy 425.491222 -390.185612)
			(xy 425.49826 -390.180068) (xy 425.524792 -390.158094) (xy 425.582096 -390.119852) (xy 425.643493 -390.088603)
			(xy 425.708136 -390.06478) (xy 425.775128 -390.048711) (xy 425.843544 -390.040621) (xy 425.87799 -390.040114)
			(xy 425.910752 -390.040571) (xy 425.975866 -390.047897) (xy 426.039752 -390.062458) (xy 426.101608 -390.084072)
			(xy 426.160661 -390.112467) (xy 426.216167 -390.147288) (xy 426.267432 -390.188097) (xy 426.313811 -390.234382)
			(xy 426.354724 -390.285564) (xy 426.389658 -390.341) (xy 426.418173 -390.399994) (xy 426.429424 -390.430766)
			(xy 426.433234 -390.441434) (xy 426.708058 -390.716258) (xy 427.32247 -390.716258) (xy 427.32247 -390.656322)
			(xy 427.330293 -390.5969) (xy 427.345806 -390.539007) (xy 427.368742 -390.483634) (xy 427.398709 -390.431728)
			(xy 427.435196 -390.384178) (xy 427.477576 -390.341798) (xy 427.525126 -390.305311) (xy 427.577032 -390.275344)
			(xy 427.632405 -390.252408) (xy 427.690298 -390.236895) (xy 427.74972 -390.229072) (xy 427.809656 -390.229072)
			(xy 427.869078 -390.236895) (xy 427.926971 -390.252408) (xy 427.982344 -390.275344) (xy 428.03425 -390.305311)
			(xy 428.0818 -390.341798) (xy 428.12418 -390.384178) (xy 428.160667 -390.431728) (xy 428.190634 -390.483634)
			(xy 428.21357 -390.539007) (xy 428.229083 -390.5969) (xy 428.236906 -390.656322) (xy 428.237396 -390.68629)
			(xy 428.236906 -390.716258) (xy 428.229083 -390.77568) (xy 428.21357 -390.833573) (xy 428.190634 -390.888946)
			(xy 428.160667 -390.940852) (xy 428.12418 -390.988402) (xy 428.0818 -391.030782) (xy 428.03425 -391.067269)
			(xy 427.982344 -391.097236) (xy 427.926971 -391.120172) (xy 427.869078 -391.135685) (xy 427.809656 -391.143508)
			(xy 427.74972 -391.143508) (xy 427.690298 -391.135685) (xy 427.632405 -391.120172) (xy 427.577032 -391.097236)
			(xy 427.525126 -391.067269) (xy 427.477576 -391.030782) (xy 427.435196 -390.988402) (xy 427.398709 -390.940852)
			(xy 427.368742 -390.888946) (xy 427.345806 -390.833573) (xy 427.330293 -390.77568) (xy 427.32247 -390.716258)
			(xy 426.708058 -390.716258) (xy 427.629574 -391.637774) (xy 427.636412 -391.645175) (xy 427.644123 -391.663774)
			(xy 427.64456 -391.673842) (xy 427.64456 -394.107162) (xy 427.644953 -394.116353) (xy 427.651472 -394.133539)
			(xy 427.65726 -394.14069) (xy 427.675028 -394.161681) (xy 427.704978 -394.207805) (xy 427.728 -394.257749)
			(xy 427.743617 -394.31048) (xy 427.751508 -394.364906) (xy 427.751507 -394.4199) (xy 427.743616 -394.474326)
			(xy 427.727998 -394.527056) (xy 427.724734 -394.534136) (xy 428.518318 -394.534136) (xy 428.522389 -394.478514)
			(xy 428.534515 -394.424077) (xy 428.554438 -394.371986) (xy 428.581734 -394.323351) (xy 428.61582 -394.279208)
			(xy 428.655969 -394.240499) (xy 428.701327 -394.208048) (xy 428.750927 -394.182547) (xy 428.803711 -394.16454)
			(xy 428.858554 -394.15441) (xy 428.914288 -394.152373) (xy 428.969725 -394.158473) (xy 429.023682 -394.172579)
			(xy 429.075011 -394.194391) (xy 429.122617 -394.223445) (xy 429.165485 -394.25912) (xy 429.202702 -394.300657)
			(xy 429.233475 -394.34717) (xy 429.257147 -394.397667) (xy 429.273215 -394.451074) (xy 429.281335 -394.50625)
			(xy 429.281844 -394.534136) (xy 429.281335 -394.562022) (xy 429.273215 -394.617198) (xy 429.257147 -394.670605)
			(xy 429.233475 -394.721102) (xy 429.202702 -394.767615) (xy 429.165485 -394.809152) (xy 429.122617 -394.844827)
			(xy 429.075011 -394.873881) (xy 429.023682 -394.895693) (xy 428.969725 -394.909799) (xy 428.914288 -394.915899)
			(xy 428.858554 -394.913862) (xy 428.803711 -394.903732) (xy 428.750927 -394.885725) (xy 428.701327 -394.860224)
			(xy 428.655969 -394.827773) (xy 428.61582 -394.789064) (xy 428.581734 -394.744921) (xy 428.554438 -394.696286)
			(xy 428.534515 -394.644195) (xy 428.522389 -394.589758) (xy 428.518318 -394.534136) (xy 427.724734 -394.534136)
			(xy 427.704975 -394.577) (xy 427.675025 -394.623124) (xy 427.65726 -394.644118) (xy 427.651494 -394.651278)
			(xy 427.645001 -394.668462) (xy 427.64456 -394.677646) (xy 427.64456 -395.042898) (xy 429.271174 -395.042898)
			(xy 429.275245 -394.987276) (xy 429.287371 -394.932839) (xy 429.307294 -394.880748) (xy 429.33459 -394.832113)
			(xy 429.368676 -394.78797) (xy 429.408825 -394.749261) (xy 429.454183 -394.71681) (xy 429.503783 -394.691309)
			(xy 429.556567 -394.673302) (xy 429.61141 -394.663172) (xy 429.667144 -394.661135) (xy 429.722581 -394.667235)
			(xy 429.776538 -394.681341) (xy 429.827867 -394.703153) (xy 429.875473 -394.732207) (xy 429.918341 -394.767882)
			(xy 429.955558 -394.809419) (xy 429.986331 -394.855932) (xy 430.010003 -394.906429) (xy 430.026071 -394.959836)
			(xy 430.034191 -395.015012) (xy 430.0347 -395.042898) (xy 430.034191 -395.070784) (xy 430.026071 -395.12596)
			(xy 430.010003 -395.179367) (xy 429.986331 -395.229864) (xy 429.955558 -395.276377) (xy 429.918341 -395.317914)
			(xy 429.875473 -395.353589) (xy 429.827867 -395.382643) (xy 429.776538 -395.404455) (xy 429.722581 -395.418561)
			(xy 429.667144 -395.424661) (xy 429.61141 -395.422624) (xy 429.556567 -395.412494) (xy 429.503783 -395.394487)
			(xy 429.454183 -395.368986) (xy 429.408825 -395.336535) (xy 429.368676 -395.297826) (xy 429.33459 -395.253683)
			(xy 429.307294 -395.205048) (xy 429.287371 -395.152957) (xy 429.275245 -395.09852) (xy 429.271174 -395.042898)
			(xy 427.64456 -395.042898) (xy 427.64456 -395.610842) (xy 427.645107 -395.620825) (xy 427.652837 -395.63924)
			(xy 427.659546 -395.646656) (xy 427.856904 -395.844014) (xy 427.873681 -395.86144) (xy 427.902091 -395.900587)
			(xy 427.924016 -395.943703) (xy 427.938914 -395.989722) (xy 427.946417 -396.037506) (xy 427.94682 -396.061692)
			(xy 427.94682 -396.119604) (xy 429.189386 -396.119604) (xy 429.193457 -396.063982) (xy 429.205583 -396.009545)
			(xy 429.225506 -395.957454) (xy 429.252802 -395.908819) (xy 429.286888 -395.864676) (xy 429.327037 -395.825967)
			(xy 429.372395 -395.793516) (xy 429.421995 -395.768015) (xy 429.474779 -395.750008) (xy 429.529622 -395.739878)
			(xy 429.585356 -395.737841) (xy 429.640793 -395.743941) (xy 429.69475 -395.758047) (xy 429.746079 -395.779859)
			(xy 429.793685 -395.808913) (xy 429.836553 -395.844588) (xy 429.87377 -395.886125) (xy 429.904543 -395.932638)
			(xy 429.928215 -395.983135) (xy 429.944283 -396.036542) (xy 429.952403 -396.091718) (xy 429.952912 -396.119604)
			(xy 429.952403 -396.14749) (xy 429.944283 -396.202666) (xy 429.928215 -396.256073) (xy 429.904543 -396.30657)
			(xy 429.87377 -396.353083) (xy 429.836553 -396.39462) (xy 429.793685 -396.430295) (xy 429.746079 -396.459349)
			(xy 429.69475 -396.481161) (xy 429.640793 -396.495267) (xy 429.585356 -396.501367) (xy 429.529622 -396.49933)
			(xy 429.474779 -396.4892) (xy 429.421995 -396.471193) (xy 429.372395 -396.445692) (xy 429.327037 -396.413241)
			(xy 429.286888 -396.374532) (xy 429.252802 -396.330389) (xy 429.225506 -396.281754) (xy 429.205583 -396.229663)
			(xy 429.193457 -396.175226) (xy 429.189386 -396.119604) (xy 427.94682 -396.119604) (xy 427.94682 -397.331692)
			(xy 427.947242 -397.341762) (xy 427.954957 -397.360367) (xy 427.961806 -397.36776) (xy 428.117254 -397.522954)
			(xy 428.1246 -397.529761) (xy 428.143063 -397.537481) (xy 428.153068 -397.53794)
		)
		(stroke
			(width 0)
			(type solid)
		)
		(fill yes)
		(layer "B.Cu")
		(net "P1V8_CPU0_RT_1D")
	)
	(gr_poly
		(pts
			(xy 181.364382 -389.19658) (xy 181.373216 -389.196203) (xy 181.389847 -389.190235) (xy 181.396894 -389.184896)
			(xy 181.420832 -389.165756) (xy 181.473587 -389.134568) (xy 181.530647 -389.112207) (xy 181.56047 -389.10514)
			(xy 181.567582 -389.103616) (xy 181.580536 -389.096504) (xy 181.670198 -389.006842) (xy 181.678072 -388.989062)
			(xy 181.678326 -388.979156) (xy 181.679719 -388.950356) (xy 181.690102 -388.893641) (xy 181.708904 -388.839135)
			(xy 181.735694 -388.78808) (xy 181.769863 -388.741638) (xy 181.810633 -388.700867) (xy 181.857074 -388.666697)
			(xy 181.90813 -388.639906) (xy 181.962635 -388.621104) (xy 182.01935 -388.610719) (xy 182.04815 -388.609332)
			(xy 182.058056 -388.609078) (xy 182.075836 -388.601204) (xy 182.293006 -388.384034) (xy 182.299806 -388.376685)
			(xy 182.307513 -388.358222) (xy 182.307992 -388.34822) (xy 182.307992 -388.138416) (xy 182.308456 -388.114238)
			(xy 182.315994 -388.066474) (xy 182.330904 -388.020475) (xy 182.352819 -387.977371) (xy 182.3812 -387.938221)
			(xy 182.397908 -387.920738) (xy 186.201304 -384.117342) (xy 186.208105 -384.109993) (xy 186.215816 -384.091531)
			(xy 186.21629 -384.081528) (xy 186.21629 -372.952772) (xy 186.215861 -372.942704) (xy 186.208139 -372.924108)
			(xy 186.201304 -372.916704) (xy 185.769758 -372.485158) (xy 185.762413 -372.478348) (xy 185.74395 -372.470621)
			(xy 185.733944 -372.470172) (xy 180.112162 -372.470172) (xy 180.087982 -372.469712) (xy 180.040213 -372.462181)
			(xy 179.994208 -372.447279) (xy 179.951096 -372.425372) (xy 179.911936 -372.396997) (xy 179.894484 -372.380256)
			(xy 179.0446 -371.530118) (xy 179.037202 -371.52327) (xy 179.018604 -371.515533) (xy 179.008532 -371.515132)
			(xy 174.941484 -371.515132) (xy 174.917304 -371.514673) (xy 174.869534 -371.507145) (xy 174.823528 -371.492244)
			(xy 174.780415 -371.470336) (xy 174.741256 -371.441961) (xy 174.723806 -371.425216) (xy 170.337226 -367.038382)
			(xy 170.329827 -367.031538) (xy 170.311228 -367.023818) (xy 170.301158 -367.023396) (xy 44.291504 -367.023396)
			(xy 44.281433 -367.023818) (xy 44.262828 -367.031531) (xy 44.255436 -367.038382) (xy 42.231271 -369.062547)
			(xy 43.675608 -369.062547) (xy 43.675608 -369.008053) (xy 43.683363 -368.954114) (xy 43.698714 -368.901827)
			(xy 43.72135 -368.852257) (xy 43.75081 -368.806412) (xy 43.786494 -368.765226) (xy 43.827675 -368.729538)
			(xy 43.873516 -368.700072) (xy 43.923084 -368.67743) (xy 43.975369 -368.662073) (xy 44.029307 -368.654311)
			(xy 44.056554 -368.653822) (xy 44.085256 -368.654838) (xy 44.098464 -368.655854) (xy 44.122086 -368.644932)
			(xy 44.188888 -368.554254) (xy 44.19219 -368.528346) (xy 44.18711 -368.5159) (xy 44.178578 -368.493388)
			(xy 44.166572 -368.446766) (xy 44.160538 -368.399002) (xy 44.160186 -368.37493) (xy 44.160672 -368.347679)
			(xy 44.168428 -368.293731) (xy 44.183783 -368.241436) (xy 44.206425 -368.191859) (xy 44.235891 -368.146009)
			(xy 44.271582 -368.104818) (xy 44.312773 -368.069127) (xy 44.358623 -368.039661) (xy 44.4082 -368.017019)
			(xy 44.460495 -368.001664) (xy 44.514443 -367.993908) (xy 44.568945 -367.993908) (xy 44.622893 -368.001664)
			(xy 44.675188 -368.017019) (xy 44.724765 -368.039661) (xy 44.770615 -368.069127) (xy 44.811806 -368.104818)
			(xy 44.847497 -368.146009) (xy 44.876963 -368.191859) (xy 44.899605 -368.241436) (xy 44.91496 -368.293731)
			(xy 44.922716 -368.347679) (xy 44.923202 -368.37493) (xy 44.922513 -368.407462) (xy 44.911402 -368.471571)
			(xy 44.901104 -368.502438) (xy 44.898056 -368.511074) (xy 44.89831 -368.528854) (xy 44.927774 -368.60734)
			(xy 44.939204 -368.620548) (xy 44.947332 -368.62512) (xy 44.97959 -368.644932) (xy 44.986 -368.648957)
			(xy 45.000473 -368.653359) (xy 45.008038 -368.653568) (xy 45.28947 -368.653568) (xy 45.297025 -368.653294)
			(xy 45.311483 -368.648899) (xy 45.317918 -368.644932) (xy 45.350176 -368.62512) (xy 45.358304 -368.620548)
			(xy 45.369734 -368.60734) (xy 45.399198 -368.528854) (xy 45.399452 -368.511074) (xy 45.396404 -368.502438)
			(xy 45.38611 -368.471571) (xy 45.375006 -368.407461) (xy 45.374306 -368.37493) (xy 45.374792 -368.347679)
			(xy 45.382548 -368.293731) (xy 45.397903 -368.241436) (xy 45.420545 -368.191859) (xy 45.450011 -368.146009)
			(xy 45.485702 -368.104818) (xy 45.526893 -368.069127) (xy 45.572743 -368.039661) (xy 45.62232 -368.017019)
			(xy 45.674615 -368.001664) (xy 45.728563 -367.993908) (xy 45.783065 -367.993908) (xy 45.837013 -368.001664)
			(xy 45.889308 -368.017019) (xy 45.938885 -368.039661) (xy 45.984735 -368.069127) (xy 46.025926 -368.104818)
			(xy 46.061617 -368.146009) (xy 46.091083 -368.191859) (xy 46.113725 -368.241436) (xy 46.12908 -368.293731)
			(xy 46.136836 -368.347679) (xy 46.137322 -368.37493) (xy 46.136963 -368.399002) (xy 46.130925 -368.446764)
			(xy 46.118935 -368.49339) (xy 46.110398 -368.5159) (xy 46.105318 -368.528346) (xy 46.10862 -368.554254)
			(xy 46.175422 -368.644932) (xy 46.199044 -368.655854) (xy 46.212252 -368.654838) (xy 46.240954 -368.653822)
			(xy 46.268211 -368.654222) (xy 46.322171 -368.661974) (xy 46.374479 -368.677327) (xy 46.424069 -368.699969)
			(xy 46.469931 -368.729438) (xy 46.511133 -368.765135) (xy 46.546834 -368.806332) (xy 46.576309 -368.852191)
			(xy 46.598957 -368.901778) (xy 46.614316 -368.954084) (xy 46.622075 -369.008043) (xy 46.622075 -369.062547)
			(xy 50.482808 -369.062547) (xy 50.482808 -369.008053) (xy 50.490563 -368.954114) (xy 50.505914 -368.901827)
			(xy 50.52855 -368.852257) (xy 50.55801 -368.806412) (xy 50.593694 -368.765226) (xy 50.634875 -368.729538)
			(xy 50.680716 -368.700072) (xy 50.730284 -368.67743) (xy 50.782569 -368.662073) (xy 50.836507 -368.654311)
			(xy 50.863754 -368.653822) (xy 50.892456 -368.654838) (xy 50.905664 -368.655854) (xy 50.929286 -368.644932)
			(xy 50.996088 -368.554254) (xy 50.99939 -368.528346) (xy 50.99431 -368.5159) (xy 50.985778 -368.493388)
			(xy 50.973772 -368.446766) (xy 50.967738 -368.399002) (xy 50.967386 -368.37493) (xy 50.967872 -368.347679)
			(xy 50.975628 -368.293731) (xy 50.990983 -368.241436) (xy 51.013625 -368.191859) (xy 51.043091 -368.146009)
			(xy 51.078782 -368.104818) (xy 51.119973 -368.069127) (xy 51.165823 -368.039661) (xy 51.2154 -368.017019)
			(xy 51.267695 -368.001664) (xy 51.321643 -367.993908) (xy 51.376145 -367.993908) (xy 51.430093 -368.001664)
			(xy 51.482388 -368.017019) (xy 51.531965 -368.039661) (xy 51.577815 -368.069127) (xy 51.619006 -368.104818)
			(xy 51.654697 -368.146009) (xy 51.684163 -368.191859) (xy 51.706805 -368.241436) (xy 51.72216 -368.293731)
			(xy 51.729916 -368.347679) (xy 51.730402 -368.37493) (xy 51.729713 -368.407462) (xy 51.718602 -368.471571)
			(xy 51.708304 -368.502438) (xy 51.705256 -368.511074) (xy 51.70551 -368.528854) (xy 51.734974 -368.60734)
			(xy 51.746404 -368.620548) (xy 51.754532 -368.62512) (xy 51.78679 -368.644932) (xy 51.7932 -368.648957)
			(xy 51.807673 -368.653359) (xy 51.815238 -368.653568) (xy 52.09667 -368.653568) (xy 52.104225 -368.653294)
			(xy 52.118683 -368.648899) (xy 52.125118 -368.644932) (xy 52.157376 -368.62512) (xy 52.165504 -368.620548)
			(xy 52.176934 -368.60734) (xy 52.206398 -368.528854) (xy 52.206652 -368.511074) (xy 52.203604 -368.502438)
			(xy 52.19331 -368.471571) (xy 52.182206 -368.407461) (xy 52.181506 -368.37493) (xy 52.181992 -368.347679)
			(xy 52.189748 -368.293731) (xy 52.205103 -368.241436) (xy 52.227745 -368.191859) (xy 52.257211 -368.146009)
			(xy 52.292902 -368.104818) (xy 52.334093 -368.069127) (xy 52.379943 -368.039661) (xy 52.42952 -368.017019)
			(xy 52.481815 -368.001664) (xy 52.535763 -367.993908) (xy 52.590265 -367.993908) (xy 52.644213 -368.001664)
			(xy 52.696508 -368.017019) (xy 52.746085 -368.039661) (xy 52.791935 -368.069127) (xy 52.833126 -368.104818)
			(xy 52.868817 -368.146009) (xy 52.898283 -368.191859) (xy 52.920925 -368.241436) (xy 52.93628 -368.293731)
			(xy 52.944036 -368.347679) (xy 52.944522 -368.37493) (xy 52.944163 -368.399002) (xy 52.938125 -368.446764)
			(xy 52.926135 -368.49339) (xy 52.917598 -368.5159) (xy 52.912518 -368.528346) (xy 52.91582 -368.554254)
			(xy 52.982622 -368.644932) (xy 53.006244 -368.655854) (xy 53.019452 -368.654838) (xy 53.048154 -368.653822)
			(xy 53.075411 -368.654222) (xy 53.129371 -368.661974) (xy 53.181679 -368.677327) (xy 53.231269 -368.699969)
			(xy 53.277131 -368.729438) (xy 53.318333 -368.765135) (xy 53.354034 -368.806332) (xy 53.383509 -368.852191)
			(xy 53.406157 -368.901778) (xy 53.421516 -368.954084) (xy 53.429275 -369.008043) (xy 53.429275 -369.062547)
			(xy 57.290008 -369.062547) (xy 57.290008 -369.008053) (xy 57.297763 -368.954114) (xy 57.313114 -368.901827)
			(xy 57.33575 -368.852257) (xy 57.36521 -368.806412) (xy 57.400894 -368.765226) (xy 57.442075 -368.729538)
			(xy 57.487916 -368.700072) (xy 57.537484 -368.67743) (xy 57.589769 -368.662073) (xy 57.643707 -368.654311)
			(xy 57.670954 -368.653822) (xy 57.699656 -368.654838) (xy 57.712864 -368.655854) (xy 57.736486 -368.644932)
			(xy 57.803288 -368.554254) (xy 57.80659 -368.528346) (xy 57.80151 -368.5159) (xy 57.792978 -368.493388)
			(xy 57.780972 -368.446766) (xy 57.774938 -368.399002) (xy 57.774586 -368.37493) (xy 57.775072 -368.347679)
			(xy 57.782828 -368.293731) (xy 57.798183 -368.241436) (xy 57.820825 -368.191859) (xy 57.850291 -368.146009)
			(xy 57.885982 -368.104818) (xy 57.927173 -368.069127) (xy 57.973023 -368.039661) (xy 58.0226 -368.017019)
			(xy 58.074895 -368.001664) (xy 58.128843 -367.993908) (xy 58.183345 -367.993908) (xy 58.237293 -368.001664)
			(xy 58.289588 -368.017019) (xy 58.339165 -368.039661) (xy 58.385015 -368.069127) (xy 58.426206 -368.104818)
			(xy 58.461897 -368.146009) (xy 58.491363 -368.191859) (xy 58.514005 -368.241436) (xy 58.52936 -368.293731)
			(xy 58.537116 -368.347679) (xy 58.537602 -368.37493) (xy 58.536913 -368.407462) (xy 58.525802 -368.471571)
			(xy 58.515504 -368.502438) (xy 58.512456 -368.511074) (xy 58.51271 -368.528854) (xy 58.542174 -368.60734)
			(xy 58.553604 -368.620548) (xy 58.561732 -368.62512) (xy 58.59399 -368.644932) (xy 58.6004 -368.648957)
			(xy 58.614873 -368.653359) (xy 58.622438 -368.653568) (xy 58.90387 -368.653568) (xy 58.911425 -368.653294)
			(xy 58.925883 -368.648899) (xy 58.932318 -368.644932) (xy 58.964576 -368.62512) (xy 58.972704 -368.620548)
			(xy 58.984134 -368.60734) (xy 59.013598 -368.528854) (xy 59.013852 -368.511074) (xy 59.010804 -368.502438)
			(xy 59.00051 -368.471571) (xy 58.989406 -368.407461) (xy 58.988706 -368.37493) (xy 58.989192 -368.347679)
			(xy 58.996948 -368.293731) (xy 59.012303 -368.241436) (xy 59.034945 -368.191859) (xy 59.064411 -368.146009)
			(xy 59.100102 -368.104818) (xy 59.141293 -368.069127) (xy 59.187143 -368.039661) (xy 59.23672 -368.017019)
			(xy 59.289015 -368.001664) (xy 59.342963 -367.993908) (xy 59.397465 -367.993908) (xy 59.451413 -368.001664)
			(xy 59.503708 -368.017019) (xy 59.553285 -368.039661) (xy 59.599135 -368.069127) (xy 59.640326 -368.104818)
			(xy 59.676017 -368.146009) (xy 59.705483 -368.191859) (xy 59.728125 -368.241436) (xy 59.74348 -368.293731)
			(xy 59.751236 -368.347679) (xy 59.751722 -368.37493) (xy 59.751363 -368.399002) (xy 59.745325 -368.446764)
			(xy 59.733335 -368.49339) (xy 59.724798 -368.5159) (xy 59.719718 -368.528346) (xy 59.72302 -368.554254)
			(xy 59.789822 -368.644932) (xy 59.813444 -368.655854) (xy 59.826652 -368.654838) (xy 59.855354 -368.653822)
			(xy 59.882611 -368.654222) (xy 59.936571 -368.661974) (xy 59.988879 -368.677327) (xy 60.038469 -368.699969)
			(xy 60.084331 -368.729438) (xy 60.125533 -368.765135) (xy 60.161234 -368.806332) (xy 60.190709 -368.852191)
			(xy 60.213357 -368.901778) (xy 60.228716 -368.954084) (xy 60.236475 -369.008043) (xy 60.236475 -369.062547)
			(xy 64.097208 -369.062547) (xy 64.097208 -369.008053) (xy 64.104963 -368.954114) (xy 64.120314 -368.901827)
			(xy 64.14295 -368.852257) (xy 64.17241 -368.806412) (xy 64.208094 -368.765226) (xy 64.249275 -368.729538)
			(xy 64.295116 -368.700072) (xy 64.344684 -368.67743) (xy 64.396969 -368.662073) (xy 64.450907 -368.654311)
			(xy 64.478154 -368.653822) (xy 64.506856 -368.654838) (xy 64.520064 -368.655854) (xy 64.543686 -368.644932)
			(xy 64.610488 -368.554254) (xy 64.61379 -368.528346) (xy 64.60871 -368.5159) (xy 64.600178 -368.493388)
			(xy 64.588172 -368.446766) (xy 64.582138 -368.399002) (xy 64.581786 -368.37493) (xy 64.582272 -368.347679)
			(xy 64.590028 -368.293731) (xy 64.605383 -368.241436) (xy 64.628025 -368.191859) (xy 64.657491 -368.146009)
			(xy 64.693182 -368.104818) (xy 64.734373 -368.069127) (xy 64.780223 -368.039661) (xy 64.8298 -368.017019)
			(xy 64.882095 -368.001664) (xy 64.936043 -367.993908) (xy 64.990545 -367.993908) (xy 65.044493 -368.001664)
			(xy 65.096788 -368.017019) (xy 65.146365 -368.039661) (xy 65.192215 -368.069127) (xy 65.233406 -368.104818)
			(xy 65.269097 -368.146009) (xy 65.298563 -368.191859) (xy 65.321205 -368.241436) (xy 65.33656 -368.293731)
			(xy 65.344316 -368.347679) (xy 65.344802 -368.37493) (xy 65.344113 -368.407462) (xy 65.333002 -368.471571)
			(xy 65.322704 -368.502438) (xy 65.319656 -368.511074) (xy 65.31991 -368.528854) (xy 65.349374 -368.60734)
			(xy 65.360804 -368.620548) (xy 65.368932 -368.62512) (xy 65.40119 -368.644932) (xy 65.4076 -368.648957)
			(xy 65.422073 -368.653359) (xy 65.429638 -368.653568) (xy 65.71107 -368.653568) (xy 65.718625 -368.653294)
			(xy 65.733083 -368.648899) (xy 65.739518 -368.644932) (xy 65.771776 -368.62512) (xy 65.779904 -368.620548)
			(xy 65.791334 -368.60734) (xy 65.820798 -368.528854) (xy 65.821052 -368.511074) (xy 65.818004 -368.502438)
			(xy 65.80771 -368.471571) (xy 65.796606 -368.407461) (xy 65.795906 -368.37493) (xy 65.796392 -368.347679)
			(xy 65.804148 -368.293731) (xy 65.819503 -368.241436) (xy 65.842145 -368.191859) (xy 65.871611 -368.146009)
			(xy 65.907302 -368.104818) (xy 65.948493 -368.069127) (xy 65.994343 -368.039661) (xy 66.04392 -368.017019)
			(xy 66.096215 -368.001664) (xy 66.150163 -367.993908) (xy 66.204665 -367.993908) (xy 66.258613 -368.001664)
			(xy 66.310908 -368.017019) (xy 66.360485 -368.039661) (xy 66.406335 -368.069127) (xy 66.447526 -368.104818)
			(xy 66.483217 -368.146009) (xy 66.512683 -368.191859) (xy 66.535325 -368.241436) (xy 66.55068 -368.293731)
			(xy 66.558436 -368.347679) (xy 66.558922 -368.37493) (xy 66.558563 -368.399002) (xy 66.552525 -368.446764)
			(xy 66.540535 -368.49339) (xy 66.531998 -368.5159) (xy 66.526918 -368.528346) (xy 66.53022 -368.554254)
			(xy 66.597022 -368.644932) (xy 66.620644 -368.655854) (xy 66.633852 -368.654838) (xy 66.662554 -368.653822)
			(xy 66.689811 -368.654222) (xy 66.743771 -368.661974) (xy 66.796079 -368.677327) (xy 66.845669 -368.699969)
			(xy 66.891531 -368.729438) (xy 66.932733 -368.765135) (xy 66.968434 -368.806332) (xy 66.997909 -368.852191)
			(xy 67.020557 -368.901778) (xy 67.035916 -368.954084) (xy 67.043675 -369.008043) (xy 67.043675 -369.062547)
			(xy 67.500808 -369.062547) (xy 67.500808 -369.008053) (xy 67.508563 -368.954114) (xy 67.523914 -368.901827)
			(xy 67.54655 -368.852257) (xy 67.57601 -368.806412) (xy 67.611694 -368.765226) (xy 67.652875 -368.729538)
			(xy 67.698716 -368.700072) (xy 67.748284 -368.67743) (xy 67.800569 -368.662073) (xy 67.854507 -368.654311)
			(xy 67.881754 -368.653822) (xy 67.910456 -368.654838) (xy 67.923664 -368.655854) (xy 67.947286 -368.644932)
			(xy 68.014088 -368.554254) (xy 68.01739 -368.528346) (xy 68.01231 -368.5159) (xy 68.003778 -368.493388)
			(xy 67.991772 -368.446766) (xy 67.985738 -368.399002) (xy 67.985386 -368.37493) (xy 67.985872 -368.347679)
			(xy 67.993628 -368.293731) (xy 68.008983 -368.241436) (xy 68.031625 -368.191859) (xy 68.061091 -368.146009)
			(xy 68.096782 -368.104818) (xy 68.137973 -368.069127) (xy 68.183823 -368.039661) (xy 68.2334 -368.017019)
			(xy 68.285695 -368.001664) (xy 68.339643 -367.993908) (xy 68.394145 -367.993908) (xy 68.448093 -368.001664)
			(xy 68.500388 -368.017019) (xy 68.549965 -368.039661) (xy 68.595815 -368.069127) (xy 68.637006 -368.104818)
			(xy 68.672697 -368.146009) (xy 68.702163 -368.191859) (xy 68.724805 -368.241436) (xy 68.74016 -368.293731)
			(xy 68.747916 -368.347679) (xy 68.748402 -368.37493) (xy 68.747713 -368.407462) (xy 68.736602 -368.471571)
			(xy 68.726304 -368.502438) (xy 68.723256 -368.511074) (xy 68.72351 -368.528854) (xy 68.752974 -368.60734)
			(xy 68.764404 -368.620548) (xy 68.772532 -368.62512) (xy 68.80479 -368.644932) (xy 68.8112 -368.648957)
			(xy 68.825673 -368.653359) (xy 68.833238 -368.653568) (xy 69.11467 -368.653568) (xy 69.122225 -368.653294)
			(xy 69.136683 -368.648899) (xy 69.143118 -368.644932) (xy 69.175376 -368.62512) (xy 69.183504 -368.620548)
			(xy 69.194934 -368.60734) (xy 69.224398 -368.528854) (xy 69.224652 -368.511074) (xy 69.221604 -368.502438)
			(xy 69.21131 -368.471571) (xy 69.200206 -368.407461) (xy 69.199506 -368.37493) (xy 69.199992 -368.347679)
			(xy 69.207748 -368.293731) (xy 69.223103 -368.241436) (xy 69.245745 -368.191859) (xy 69.275211 -368.146009)
			(xy 69.310902 -368.104818) (xy 69.352093 -368.069127) (xy 69.397943 -368.039661) (xy 69.44752 -368.017019)
			(xy 69.499815 -368.001664) (xy 69.553763 -367.993908) (xy 69.608265 -367.993908) (xy 69.662213 -368.001664)
			(xy 69.714508 -368.017019) (xy 69.764085 -368.039661) (xy 69.809935 -368.069127) (xy 69.851126 -368.104818)
			(xy 69.886817 -368.146009) (xy 69.916283 -368.191859) (xy 69.938925 -368.241436) (xy 69.95428 -368.293731)
			(xy 69.962036 -368.347679) (xy 69.962522 -368.37493) (xy 69.962163 -368.399002) (xy 69.956125 -368.446764)
			(xy 69.944135 -368.49339) (xy 69.935598 -368.5159) (xy 69.930518 -368.528346) (xy 69.93382 -368.554254)
			(xy 70.000622 -368.644932) (xy 70.024244 -368.655854) (xy 70.037452 -368.654838) (xy 70.066154 -368.653822)
			(xy 70.093411 -368.654222) (xy 70.147371 -368.661974) (xy 70.199679 -368.677327) (xy 70.249269 -368.699969)
			(xy 70.295131 -368.729438) (xy 70.336333 -368.765135) (xy 70.372034 -368.806332) (xy 70.401509 -368.852191)
			(xy 70.424157 -368.901778) (xy 70.439516 -368.954084) (xy 70.447275 -369.008043) (xy 70.447275 -369.062551)
			(xy 76.203285 -369.062551) (xy 76.203285 -369.008049) (xy 76.211042 -368.954102) (xy 76.226397 -368.901808)
			(xy 76.249037 -368.852232) (xy 76.278503 -368.806382) (xy 76.314194 -368.765193) (xy 76.355384 -368.729502)
			(xy 76.401234 -368.700037) (xy 76.45081 -368.677396) (xy 76.503104 -368.662041) (xy 76.557051 -368.654285)
			(xy 76.584302 -368.653822) (xy 76.613004 -368.654838) (xy 76.626212 -368.655854) (xy 76.649834 -368.644932)
			(xy 76.716636 -368.554254) (xy 76.719938 -368.528346) (xy 76.714858 -368.5159) (xy 76.706324 -368.493389)
			(xy 76.694319 -368.446766) (xy 76.688286 -368.399002) (xy 76.687934 -368.37493) (xy 76.68842 -368.347679)
			(xy 76.696176 -368.293731) (xy 76.711531 -368.241436) (xy 76.734173 -368.191859) (xy 76.763639 -368.146009)
			(xy 76.79933 -368.104818) (xy 76.840521 -368.069127) (xy 76.886371 -368.039661) (xy 76.935948 -368.017019)
			(xy 76.988243 -368.001664) (xy 77.042191 -367.993908) (xy 77.096693 -367.993908) (xy 77.150641 -368.001664)
			(xy 77.202936 -368.017019) (xy 77.252513 -368.039661) (xy 77.298363 -368.069127) (xy 77.339554 -368.104818)
			(xy 77.375245 -368.146009) (xy 77.404711 -368.191859) (xy 77.427353 -368.241436) (xy 77.442708 -368.293731)
			(xy 77.450464 -368.347679) (xy 77.45095 -368.37493) (xy 77.450258 -368.407462) (xy 77.439149 -368.471571)
			(xy 77.428852 -368.502438) (xy 77.425804 -368.511074) (xy 77.426058 -368.528854) (xy 77.455522 -368.60734)
			(xy 77.466952 -368.620548) (xy 77.47508 -368.62512) (xy 77.507338 -368.644932) (xy 77.513738 -368.648975)
			(xy 77.528218 -368.653365) (xy 77.535786 -368.653568) (xy 77.817218 -368.653568) (xy 77.824771 -368.653272)
			(xy 77.839229 -368.648892) (xy 77.845666 -368.644932) (xy 77.877924 -368.62512) (xy 77.886052 -368.620548)
			(xy 77.897482 -368.60734) (xy 77.926946 -368.528854) (xy 77.9272 -368.511074) (xy 77.924152 -368.502438)
			(xy 77.913856 -368.471571) (xy 77.902753 -368.407461) (xy 77.902054 -368.37493) (xy 77.90254 -368.347679)
			(xy 77.910296 -368.293731) (xy 77.925651 -368.241436) (xy 77.948293 -368.191859) (xy 77.977759 -368.146009)
			(xy 78.01345 -368.104818) (xy 78.054641 -368.069127) (xy 78.100491 -368.039661) (xy 78.150068 -368.017019)
			(xy 78.202363 -368.001664) (xy 78.256311 -367.993908) (xy 78.310813 -367.993908) (xy 78.364761 -368.001664)
			(xy 78.417056 -368.017019) (xy 78.466633 -368.039661) (xy 78.512483 -368.069127) (xy 78.553674 -368.104818)
			(xy 78.589365 -368.146009) (xy 78.618831 -368.191859) (xy 78.641473 -368.241436) (xy 78.656828 -368.293731)
			(xy 78.664584 -368.347679) (xy 78.66507 -368.37493) (xy 78.664708 -368.399001) (xy 78.65867 -368.446764)
			(xy 78.646682 -368.49339) (xy 78.638146 -368.5159) (xy 78.633066 -368.528346) (xy 78.636368 -368.554254)
			(xy 78.70317 -368.644932) (xy 78.726792 -368.655854) (xy 78.74 -368.654838) (xy 78.768702 -368.653822)
			(xy 78.795955 -368.654248) (xy 78.849907 -368.662005) (xy 78.902206 -368.677362) (xy 78.951787 -368.700005)
			(xy 78.99764 -368.729474) (xy 79.038834 -368.765168) (xy 79.074528 -368.806361) (xy 79.103996 -368.852215)
			(xy 79.126639 -368.901796) (xy 79.141995 -368.954095) (xy 79.149752 -369.008047) (xy 79.149752 -369.062551)
			(xy 83.010485 -369.062551) (xy 83.010485 -369.008049) (xy 83.018242 -368.954102) (xy 83.033597 -368.901808)
			(xy 83.056237 -368.852232) (xy 83.085703 -368.806382) (xy 83.121394 -368.765193) (xy 83.162584 -368.729502)
			(xy 83.208434 -368.700037) (xy 83.25801 -368.677396) (xy 83.310304 -368.662041) (xy 83.364251 -368.654285)
			(xy 83.391502 -368.653822) (xy 83.420204 -368.654838) (xy 83.433412 -368.655854) (xy 83.457034 -368.644932)
			(xy 83.523836 -368.554254) (xy 83.527138 -368.528346) (xy 83.522058 -368.5159) (xy 83.513524 -368.493389)
			(xy 83.501519 -368.446766) (xy 83.495486 -368.399002) (xy 83.495134 -368.37493) (xy 83.49562 -368.347679)
			(xy 83.503376 -368.293731) (xy 83.518731 -368.241436) (xy 83.541373 -368.191859) (xy 83.570839 -368.146009)
			(xy 83.60653 -368.104818) (xy 83.647721 -368.069127) (xy 83.693571 -368.039661) (xy 83.743148 -368.017019)
			(xy 83.795443 -368.001664) (xy 83.849391 -367.993908) (xy 83.903893 -367.993908) (xy 83.957841 -368.001664)
			(xy 84.010136 -368.017019) (xy 84.059713 -368.039661) (xy 84.105563 -368.069127) (xy 84.146754 -368.104818)
			(xy 84.182445 -368.146009) (xy 84.211911 -368.191859) (xy 84.234553 -368.241436) (xy 84.249908 -368.293731)
			(xy 84.257664 -368.347679) (xy 84.25815 -368.37493) (xy 84.257458 -368.407462) (xy 84.246349 -368.471571)
			(xy 84.236052 -368.502438) (xy 84.233004 -368.511074) (xy 84.233258 -368.528854) (xy 84.262722 -368.60734)
			(xy 84.274152 -368.620548) (xy 84.28228 -368.62512) (xy 84.314538 -368.644932) (xy 84.320938 -368.648975)
			(xy 84.335418 -368.653365) (xy 84.342986 -368.653568) (xy 84.624418 -368.653568) (xy 84.631971 -368.653272)
			(xy 84.646429 -368.648892) (xy 84.652866 -368.644932) (xy 84.685124 -368.62512) (xy 84.693252 -368.620548)
			(xy 84.704682 -368.60734) (xy 84.734146 -368.528854) (xy 84.7344 -368.511074) (xy 84.731352 -368.502438)
			(xy 84.721056 -368.471571) (xy 84.709953 -368.407461) (xy 84.709254 -368.37493) (xy 84.70974 -368.347679)
			(xy 84.717496 -368.293731) (xy 84.732851 -368.241436) (xy 84.755493 -368.191859) (xy 84.784959 -368.146009)
			(xy 84.82065 -368.104818) (xy 84.861841 -368.069127) (xy 84.907691 -368.039661) (xy 84.957268 -368.017019)
			(xy 85.009563 -368.001664) (xy 85.063511 -367.993908) (xy 85.118013 -367.993908) (xy 85.171961 -368.001664)
			(xy 85.224256 -368.017019) (xy 85.273833 -368.039661) (xy 85.319683 -368.069127) (xy 85.360874 -368.104818)
			(xy 85.396565 -368.146009) (xy 85.426031 -368.191859) (xy 85.448673 -368.241436) (xy 85.464028 -368.293731)
			(xy 85.471784 -368.347679) (xy 85.47227 -368.37493) (xy 85.471908 -368.399001) (xy 85.46587 -368.446764)
			(xy 85.453882 -368.49339) (xy 85.445346 -368.5159) (xy 85.440266 -368.528346) (xy 85.443568 -368.554254)
			(xy 85.51037 -368.644932) (xy 85.533992 -368.655854) (xy 85.5472 -368.654838) (xy 85.575902 -368.653822)
			(xy 85.603155 -368.654248) (xy 85.657107 -368.662005) (xy 85.709406 -368.677362) (xy 85.758987 -368.700005)
			(xy 85.80484 -368.729474) (xy 85.846034 -368.765168) (xy 85.881728 -368.806361) (xy 85.911196 -368.852215)
			(xy 85.933839 -368.901796) (xy 85.949195 -368.954095) (xy 85.956952 -369.008047) (xy 85.956952 -369.062551)
			(xy 89.817685 -369.062551) (xy 89.817685 -369.008049) (xy 89.825442 -368.954102) (xy 89.840797 -368.901808)
			(xy 89.863437 -368.852232) (xy 89.892903 -368.806382) (xy 89.928594 -368.765193) (xy 89.969784 -368.729502)
			(xy 90.015634 -368.700037) (xy 90.06521 -368.677396) (xy 90.117504 -368.662041) (xy 90.171451 -368.654285)
			(xy 90.198702 -368.653822) (xy 90.227404 -368.654838) (xy 90.240612 -368.655854) (xy 90.264234 -368.644932)
			(xy 90.331036 -368.554254) (xy 90.334338 -368.528346) (xy 90.329258 -368.5159) (xy 90.320724 -368.493389)
			(xy 90.308719 -368.446766) (xy 90.302686 -368.399002) (xy 90.302334 -368.37493) (xy 90.30282 -368.347679)
			(xy 90.310576 -368.293731) (xy 90.325931 -368.241436) (xy 90.348573 -368.191859) (xy 90.378039 -368.146009)
			(xy 90.41373 -368.104818) (xy 90.454921 -368.069127) (xy 90.500771 -368.039661) (xy 90.550348 -368.017019)
			(xy 90.602643 -368.001664) (xy 90.656591 -367.993908) (xy 90.711093 -367.993908) (xy 90.765041 -368.001664)
			(xy 90.817336 -368.017019) (xy 90.866913 -368.039661) (xy 90.912763 -368.069127) (xy 90.953954 -368.104818)
			(xy 90.989645 -368.146009) (xy 91.019111 -368.191859) (xy 91.041753 -368.241436) (xy 91.057108 -368.293731)
			(xy 91.064864 -368.347679) (xy 91.06535 -368.37493) (xy 91.064658 -368.407462) (xy 91.053549 -368.471571)
			(xy 91.043252 -368.502438) (xy 91.040204 -368.511074) (xy 91.040458 -368.528854) (xy 91.069922 -368.60734)
			(xy 91.081352 -368.620548) (xy 91.08948 -368.62512) (xy 91.121738 -368.644932) (xy 91.128138 -368.648975)
			(xy 91.142618 -368.653365) (xy 91.150186 -368.653568) (xy 91.431618 -368.653568) (xy 91.439171 -368.653272)
			(xy 91.453629 -368.648892) (xy 91.460066 -368.644932) (xy 91.492324 -368.62512) (xy 91.500452 -368.620548)
			(xy 91.511882 -368.60734) (xy 91.541346 -368.528854) (xy 91.5416 -368.511074) (xy 91.538552 -368.502438)
			(xy 91.528256 -368.471571) (xy 91.517153 -368.407461) (xy 91.516454 -368.37493) (xy 91.51694 -368.347679)
			(xy 91.524696 -368.293731) (xy 91.540051 -368.241436) (xy 91.562693 -368.191859) (xy 91.592159 -368.146009)
			(xy 91.62785 -368.104818) (xy 91.669041 -368.069127) (xy 91.714891 -368.039661) (xy 91.764468 -368.017019)
			(xy 91.816763 -368.001664) (xy 91.870711 -367.993908) (xy 91.925213 -367.993908) (xy 91.979161 -368.001664)
			(xy 92.031456 -368.017019) (xy 92.081033 -368.039661) (xy 92.126883 -368.069127) (xy 92.168074 -368.104818)
			(xy 92.203765 -368.146009) (xy 92.233231 -368.191859) (xy 92.255873 -368.241436) (xy 92.271228 -368.293731)
			(xy 92.278984 -368.347679) (xy 92.27947 -368.37493) (xy 92.279108 -368.399001) (xy 92.27307 -368.446764)
			(xy 92.261082 -368.49339) (xy 92.252546 -368.5159) (xy 92.247466 -368.528346) (xy 92.250768 -368.554254)
			(xy 92.31757 -368.644932) (xy 92.341192 -368.655854) (xy 92.3544 -368.654838) (xy 92.383102 -368.653822)
			(xy 92.410355 -368.654248) (xy 92.464307 -368.662005) (xy 92.516606 -368.677362) (xy 92.566187 -368.700005)
			(xy 92.61204 -368.729474) (xy 92.653234 -368.765168) (xy 92.688928 -368.806361) (xy 92.718396 -368.852215)
			(xy 92.741039 -368.901796) (xy 92.756395 -368.954095) (xy 92.764152 -369.008047) (xy 92.764152 -369.062551)
			(xy 96.624885 -369.062551) (xy 96.624885 -369.008049) (xy 96.632642 -368.954102) (xy 96.647997 -368.901808)
			(xy 96.670637 -368.852232) (xy 96.700103 -368.806382) (xy 96.735794 -368.765193) (xy 96.776984 -368.729502)
			(xy 96.822834 -368.700037) (xy 96.87241 -368.677396) (xy 96.924704 -368.662041) (xy 96.978651 -368.654285)
			(xy 97.005902 -368.653822) (xy 97.034604 -368.654838) (xy 97.047812 -368.655854) (xy 97.071434 -368.644932)
			(xy 97.138236 -368.554254) (xy 97.141538 -368.528346) (xy 97.136458 -368.5159) (xy 97.127924 -368.493389)
			(xy 97.115919 -368.446766) (xy 97.109886 -368.399002) (xy 97.109534 -368.37493) (xy 97.11002 -368.347679)
			(xy 97.117776 -368.293731) (xy 97.133131 -368.241436) (xy 97.155773 -368.191859) (xy 97.185239 -368.146009)
			(xy 97.22093 -368.104818) (xy 97.262121 -368.069127) (xy 97.307971 -368.039661) (xy 97.357548 -368.017019)
			(xy 97.409843 -368.001664) (xy 97.463791 -367.993908) (xy 97.518293 -367.993908) (xy 97.572241 -368.001664)
			(xy 97.624536 -368.017019) (xy 97.674113 -368.039661) (xy 97.719963 -368.069127) (xy 97.761154 -368.104818)
			(xy 97.796845 -368.146009) (xy 97.826311 -368.191859) (xy 97.848953 -368.241436) (xy 97.864308 -368.293731)
			(xy 97.872064 -368.347679) (xy 97.87255 -368.37493) (xy 97.871858 -368.407462) (xy 97.860749 -368.471571)
			(xy 97.850452 -368.502438) (xy 97.847404 -368.511074) (xy 97.847658 -368.528854) (xy 97.877122 -368.60734)
			(xy 97.888552 -368.620548) (xy 97.89668 -368.62512) (xy 97.928938 -368.644932) (xy 97.935338 -368.648975)
			(xy 97.949818 -368.653365) (xy 97.957386 -368.653568) (xy 98.238818 -368.653568) (xy 98.246371 -368.653272)
			(xy 98.260829 -368.648892) (xy 98.267266 -368.644932) (xy 98.299524 -368.62512) (xy 98.307652 -368.620548)
			(xy 98.319082 -368.60734) (xy 98.348546 -368.528854) (xy 98.3488 -368.511074) (xy 98.345752 -368.502438)
			(xy 98.335456 -368.471571) (xy 98.324353 -368.407461) (xy 98.323654 -368.37493) (xy 98.32414 -368.347679)
			(xy 98.331896 -368.293731) (xy 98.347251 -368.241436) (xy 98.369893 -368.191859) (xy 98.399359 -368.146009)
			(xy 98.43505 -368.104818) (xy 98.476241 -368.069127) (xy 98.522091 -368.039661) (xy 98.571668 -368.017019)
			(xy 98.623963 -368.001664) (xy 98.677911 -367.993908) (xy 98.732413 -367.993908) (xy 98.786361 -368.001664)
			(xy 98.838656 -368.017019) (xy 98.888233 -368.039661) (xy 98.934083 -368.069127) (xy 98.975274 -368.104818)
			(xy 99.010965 -368.146009) (xy 99.040431 -368.191859) (xy 99.063073 -368.241436) (xy 99.078428 -368.293731)
			(xy 99.086184 -368.347679) (xy 99.08667 -368.37493) (xy 99.086308 -368.399001) (xy 99.08027 -368.446764)
			(xy 99.068282 -368.49339) (xy 99.059746 -368.5159) (xy 99.054666 -368.528346) (xy 99.057968 -368.554254)
			(xy 99.12477 -368.644932) (xy 99.148392 -368.655854) (xy 99.1616 -368.654838) (xy 99.190302 -368.653822)
			(xy 99.217555 -368.654248) (xy 99.271507 -368.662005) (xy 99.323806 -368.677362) (xy 99.373387 -368.700005)
			(xy 99.41924 -368.729474) (xy 99.460434 -368.765168) (xy 99.496128 -368.806361) (xy 99.525596 -368.852215)
			(xy 99.548239 -368.901796) (xy 99.563595 -368.954095) (xy 99.571352 -369.008047) (xy 99.571352 -369.062551)
			(xy 100.028485 -369.062551) (xy 100.028485 -369.008049) (xy 100.036242 -368.954102) (xy 100.051597 -368.901808)
			(xy 100.074237 -368.852232) (xy 100.103703 -368.806382) (xy 100.139394 -368.765193) (xy 100.180584 -368.729502)
			(xy 100.226434 -368.700037) (xy 100.27601 -368.677396) (xy 100.328304 -368.662041) (xy 100.382251 -368.654285)
			(xy 100.409502 -368.653822) (xy 100.438204 -368.654838) (xy 100.451412 -368.655854) (xy 100.475034 -368.644932)
			(xy 100.541836 -368.554254) (xy 100.545138 -368.528346) (xy 100.540058 -368.5159) (xy 100.531524 -368.493389)
			(xy 100.519519 -368.446766) (xy 100.513486 -368.399002) (xy 100.513134 -368.37493) (xy 100.51362 -368.347679)
			(xy 100.521376 -368.293731) (xy 100.536731 -368.241436) (xy 100.559373 -368.191859) (xy 100.588839 -368.146009)
			(xy 100.62453 -368.104818) (xy 100.665721 -368.069127) (xy 100.711571 -368.039661) (xy 100.761148 -368.017019)
			(xy 100.813443 -368.001664) (xy 100.867391 -367.993908) (xy 100.921893 -367.993908) (xy 100.975841 -368.001664)
			(xy 101.028136 -368.017019) (xy 101.077713 -368.039661) (xy 101.123563 -368.069127) (xy 101.164754 -368.104818)
			(xy 101.200445 -368.146009) (xy 101.229911 -368.191859) (xy 101.252553 -368.241436) (xy 101.267908 -368.293731)
			(xy 101.275664 -368.347679) (xy 101.27615 -368.37493) (xy 101.275458 -368.407462) (xy 101.264349 -368.471571)
			(xy 101.254052 -368.502438) (xy 101.251004 -368.511074) (xy 101.251258 -368.528854) (xy 101.280722 -368.60734)
			(xy 101.292152 -368.620548) (xy 101.30028 -368.62512) (xy 101.332538 -368.644932) (xy 101.338938 -368.648975)
			(xy 101.353418 -368.653365) (xy 101.360986 -368.653568) (xy 101.642418 -368.653568) (xy 101.649971 -368.653272)
			(xy 101.664429 -368.648892) (xy 101.670866 -368.644932) (xy 101.703124 -368.62512) (xy 101.711252 -368.620548)
			(xy 101.722682 -368.60734) (xy 101.752146 -368.528854) (xy 101.7524 -368.511074) (xy 101.749352 -368.502438)
			(xy 101.739056 -368.471571) (xy 101.727953 -368.407461) (xy 101.727254 -368.37493) (xy 101.72774 -368.347679)
			(xy 101.735496 -368.293731) (xy 101.750851 -368.241436) (xy 101.773493 -368.191859) (xy 101.802959 -368.146009)
			(xy 101.83865 -368.104818) (xy 101.879841 -368.069127) (xy 101.925691 -368.039661) (xy 101.975268 -368.017019)
			(xy 102.027563 -368.001664) (xy 102.081511 -367.993908) (xy 102.136013 -367.993908) (xy 102.189961 -368.001664)
			(xy 102.242256 -368.017019) (xy 102.291833 -368.039661) (xy 102.337683 -368.069127) (xy 102.378874 -368.104818)
			(xy 102.414565 -368.146009) (xy 102.444031 -368.191859) (xy 102.466673 -368.241436) (xy 102.482028 -368.293731)
			(xy 102.489784 -368.347679) (xy 102.49027 -368.37493) (xy 102.489908 -368.399001) (xy 102.48387 -368.446764)
			(xy 102.471882 -368.49339) (xy 102.463346 -368.5159) (xy 102.458266 -368.528346) (xy 102.461568 -368.554254)
			(xy 102.52837 -368.644932) (xy 102.551992 -368.655854) (xy 102.5652 -368.654838) (xy 102.593902 -368.653822)
			(xy 102.621155 -368.654248) (xy 102.675107 -368.662005) (xy 102.727406 -368.677362) (xy 102.776987 -368.700005)
			(xy 102.82284 -368.729474) (xy 102.864034 -368.765168) (xy 102.899728 -368.806361) (xy 102.929196 -368.852215)
			(xy 102.951839 -368.901796) (xy 102.967195 -368.954095) (xy 102.974952 -369.008047) (xy 102.974952 -369.062549)
			(xy 110.775508 -369.062549) (xy 110.775508 -369.008051) (xy 110.783264 -368.954108) (xy 110.798618 -368.901818)
			(xy 110.821257 -368.852245) (xy 110.85072 -368.806398) (xy 110.886409 -368.765211) (xy 110.927595 -368.729523)
			(xy 110.973441 -368.700059) (xy 111.023014 -368.677419) (xy 111.075304 -368.662065) (xy 111.129247 -368.654308)
			(xy 111.156496 -368.653822) (xy 111.185198 -368.654838) (xy 111.198406 -368.655854) (xy 111.222028 -368.644932)
			(xy 111.28883 -368.554254) (xy 111.292132 -368.528346) (xy 111.287052 -368.5159) (xy 111.278517 -368.493389)
			(xy 111.266513 -368.446766) (xy 111.26048 -368.399002) (xy 111.260128 -368.37493) (xy 111.260614 -368.347679)
			(xy 111.26837 -368.293731) (xy 111.283725 -368.241436) (xy 111.306367 -368.191859) (xy 111.335833 -368.146009)
			(xy 111.371524 -368.104818) (xy 111.412715 -368.069127) (xy 111.458565 -368.039661) (xy 111.508142 -368.017019)
			(xy 111.560437 -368.001664) (xy 111.614385 -367.993908) (xy 111.668887 -367.993908) (xy 111.722835 -368.001664)
			(xy 111.77513 -368.017019) (xy 111.824707 -368.039661) (xy 111.870557 -368.069127) (xy 111.911748 -368.104818)
			(xy 111.947439 -368.146009) (xy 111.976905 -368.191859) (xy 111.999547 -368.241436) (xy 112.014902 -368.293731)
			(xy 112.022658 -368.347679) (xy 112.023144 -368.37493) (xy 112.022453 -368.407462) (xy 112.011343 -368.471571)
			(xy 112.001046 -368.502438) (xy 111.997998 -368.511074) (xy 111.998252 -368.528854) (xy 112.027716 -368.60734)
			(xy 112.039146 -368.620548) (xy 112.047274 -368.62512) (xy 112.079532 -368.644932) (xy 112.085933 -368.648973)
			(xy 112.100413 -368.653365) (xy 112.10798 -368.653568) (xy 112.389412 -368.653568) (xy 112.396965 -368.65327)
			(xy 112.411423 -368.648892) (xy 112.41786 -368.644932) (xy 112.450118 -368.62512) (xy 112.458246 -368.620548)
			(xy 112.469676 -368.60734) (xy 112.49914 -368.528854) (xy 112.499394 -368.511074) (xy 112.496346 -368.502438)
			(xy 112.486053 -368.47157) (xy 112.474948 -368.407461) (xy 112.474248 -368.37493) (xy 112.474734 -368.347679)
			(xy 112.48249 -368.293731) (xy 112.497845 -368.241436) (xy 112.520487 -368.191859) (xy 112.549953 -368.146009)
			(xy 112.585644 -368.104818) (xy 112.626835 -368.069127) (xy 112.672685 -368.039661) (xy 112.722262 -368.017019)
			(xy 112.774557 -368.001664) (xy 112.828505 -367.993908) (xy 112.883007 -367.993908) (xy 112.936955 -368.001664)
			(xy 112.98925 -368.017019) (xy 113.038827 -368.039661) (xy 113.084677 -368.069127) (xy 113.125868 -368.104818)
			(xy 113.161559 -368.146009) (xy 113.191025 -368.191859) (xy 113.213667 -368.241436) (xy 113.229022 -368.293731)
			(xy 113.236778 -368.347679) (xy 113.237264 -368.37493) (xy 113.236902 -368.399001) (xy 113.230865 -368.446764)
			(xy 113.218876 -368.49339) (xy 113.21034 -368.5159) (xy 113.20526 -368.528346) (xy 113.208562 -368.554254)
			(xy 113.275364 -368.644932) (xy 113.298986 -368.655854) (xy 113.312194 -368.654838) (xy 113.340896 -368.653822)
			(xy 113.368151 -368.654225) (xy 113.422107 -368.661982) (xy 113.474409 -368.677339) (xy 113.523994 -368.699983)
			(xy 113.569851 -368.729453) (xy 113.611048 -368.765149) (xy 113.646745 -368.806346) (xy 113.676215 -368.852203)
			(xy 113.69886 -368.901787) (xy 113.714217 -368.954089) (xy 113.721975 -369.008045) (xy 113.721975 -369.062549)
			(xy 117.582708 -369.062549) (xy 117.582708 -369.008051) (xy 117.590464 -368.954108) (xy 117.605818 -368.901818)
			(xy 117.628457 -368.852245) (xy 117.65792 -368.806398) (xy 117.693609 -368.765211) (xy 117.734795 -368.729523)
			(xy 117.780641 -368.700059) (xy 117.830214 -368.677419) (xy 117.882504 -368.662065) (xy 117.936447 -368.654308)
			(xy 117.963696 -368.653822) (xy 117.992398 -368.654838) (xy 118.005606 -368.655854) (xy 118.029228 -368.644932)
			(xy 118.09603 -368.554254) (xy 118.099332 -368.528346) (xy 118.094252 -368.5159) (xy 118.085717 -368.493389)
			(xy 118.073713 -368.446766) (xy 118.06768 -368.399002) (xy 118.067328 -368.37493) (xy 118.067814 -368.347679)
			(xy 118.07557 -368.293731) (xy 118.090925 -368.241436) (xy 118.113567 -368.191859) (xy 118.143033 -368.146009)
			(xy 118.178724 -368.104818) (xy 118.219915 -368.069127) (xy 118.265765 -368.039661) (xy 118.315342 -368.017019)
			(xy 118.367637 -368.001664) (xy 118.421585 -367.993908) (xy 118.476087 -367.993908) (xy 118.530035 -368.001664)
			(xy 118.58233 -368.017019) (xy 118.631907 -368.039661) (xy 118.677757 -368.069127) (xy 118.718948 -368.104818)
			(xy 118.754639 -368.146009) (xy 118.784105 -368.191859) (xy 118.806747 -368.241436) (xy 118.822102 -368.293731)
			(xy 118.829858 -368.347679) (xy 118.830344 -368.37493) (xy 118.829653 -368.407462) (xy 118.818543 -368.471571)
			(xy 118.808246 -368.502438) (xy 118.805198 -368.511074) (xy 118.805452 -368.528854) (xy 118.834916 -368.60734)
			(xy 118.846346 -368.620548) (xy 118.854474 -368.62512) (xy 118.886732 -368.644932) (xy 118.893133 -368.648973)
			(xy 118.907613 -368.653365) (xy 118.91518 -368.653568) (xy 119.196612 -368.653568) (xy 119.204165 -368.65327)
			(xy 119.218623 -368.648892) (xy 119.22506 -368.644932) (xy 119.257318 -368.62512) (xy 119.265446 -368.620548)
			(xy 119.276876 -368.60734) (xy 119.30634 -368.528854) (xy 119.306594 -368.511074) (xy 119.303546 -368.502438)
			(xy 119.293253 -368.47157) (xy 119.282148 -368.407461) (xy 119.281448 -368.37493) (xy 119.281934 -368.347679)
			(xy 119.28969 -368.293731) (xy 119.305045 -368.241436) (xy 119.327687 -368.191859) (xy 119.357153 -368.146009)
			(xy 119.392844 -368.104818) (xy 119.434035 -368.069127) (xy 119.479885 -368.039661) (xy 119.529462 -368.017019)
			(xy 119.581757 -368.001664) (xy 119.635705 -367.993908) (xy 119.690207 -367.993908) (xy 119.744155 -368.001664)
			(xy 119.79645 -368.017019) (xy 119.846027 -368.039661) (xy 119.891877 -368.069127) (xy 119.933068 -368.104818)
			(xy 119.968759 -368.146009) (xy 119.998225 -368.191859) (xy 120.020867 -368.241436) (xy 120.036222 -368.293731)
			(xy 120.043978 -368.347679) (xy 120.044464 -368.37493) (xy 120.044102 -368.399001) (xy 120.038065 -368.446764)
			(xy 120.026076 -368.49339) (xy 120.01754 -368.5159) (xy 120.01246 -368.528346) (xy 120.015762 -368.554254)
			(xy 120.082564 -368.644932) (xy 120.106186 -368.655854) (xy 120.119394 -368.654838) (xy 120.148096 -368.653822)
			(xy 120.175351 -368.654225) (xy 120.229307 -368.661982) (xy 120.281609 -368.677339) (xy 120.331194 -368.699983)
			(xy 120.377051 -368.729453) (xy 120.418248 -368.765149) (xy 120.453945 -368.806346) (xy 120.483415 -368.852203)
			(xy 120.50606 -368.901787) (xy 120.521417 -368.954089) (xy 120.529175 -369.008045) (xy 120.529175 -369.062549)
			(xy 124.389908 -369.062549) (xy 124.389908 -369.008051) (xy 124.397664 -368.954108) (xy 124.413018 -368.901818)
			(xy 124.435657 -368.852245) (xy 124.46512 -368.806398) (xy 124.500809 -368.765211) (xy 124.541995 -368.729523)
			(xy 124.587841 -368.700059) (xy 124.637414 -368.677419) (xy 124.689704 -368.662065) (xy 124.743647 -368.654308)
			(xy 124.770896 -368.653822) (xy 124.799598 -368.654838) (xy 124.812806 -368.655854) (xy 124.836428 -368.644932)
			(xy 124.90323 -368.554254) (xy 124.906532 -368.528346) (xy 124.901452 -368.5159) (xy 124.892917 -368.493389)
			(xy 124.880913 -368.446766) (xy 124.87488 -368.399002) (xy 124.874528 -368.37493) (xy 124.875014 -368.347679)
			(xy 124.88277 -368.293731) (xy 124.898125 -368.241436) (xy 124.920767 -368.191859) (xy 124.950233 -368.146009)
			(xy 124.985924 -368.104818) (xy 125.027115 -368.069127) (xy 125.072965 -368.039661) (xy 125.122542 -368.017019)
			(xy 125.174837 -368.001664) (xy 125.228785 -367.993908) (xy 125.283287 -367.993908) (xy 125.337235 -368.001664)
			(xy 125.38953 -368.017019) (xy 125.439107 -368.039661) (xy 125.484957 -368.069127) (xy 125.526148 -368.104818)
			(xy 125.561839 -368.146009) (xy 125.591305 -368.191859) (xy 125.613947 -368.241436) (xy 125.629302 -368.293731)
			(xy 125.637058 -368.347679) (xy 125.637544 -368.37493) (xy 125.636853 -368.407462) (xy 125.625743 -368.471571)
			(xy 125.615446 -368.502438) (xy 125.612398 -368.511074) (xy 125.612652 -368.528854) (xy 125.642116 -368.60734)
			(xy 125.653546 -368.620548) (xy 125.661674 -368.62512) (xy 125.693932 -368.644932) (xy 125.700333 -368.648973)
			(xy 125.714813 -368.653365) (xy 125.72238 -368.653568) (xy 126.003812 -368.653568) (xy 126.011365 -368.65327)
			(xy 126.025823 -368.648892) (xy 126.03226 -368.644932) (xy 126.064518 -368.62512) (xy 126.072646 -368.620548)
			(xy 126.084076 -368.60734) (xy 126.11354 -368.528854) (xy 126.113794 -368.511074) (xy 126.110746 -368.502438)
			(xy 126.100453 -368.47157) (xy 126.089348 -368.407461) (xy 126.088648 -368.37493) (xy 126.089134 -368.347679)
			(xy 126.09689 -368.293731) (xy 126.112245 -368.241436) (xy 126.134887 -368.191859) (xy 126.164353 -368.146009)
			(xy 126.200044 -368.104818) (xy 126.241235 -368.069127) (xy 126.287085 -368.039661) (xy 126.336662 -368.017019)
			(xy 126.388957 -368.001664) (xy 126.442905 -367.993908) (xy 126.497407 -367.993908) (xy 126.551355 -368.001664)
			(xy 126.60365 -368.017019) (xy 126.653227 -368.039661) (xy 126.699077 -368.069127) (xy 126.740268 -368.104818)
			(xy 126.775959 -368.146009) (xy 126.805425 -368.191859) (xy 126.828067 -368.241436) (xy 126.843422 -368.293731)
			(xy 126.851178 -368.347679) (xy 126.851664 -368.37493) (xy 126.851302 -368.399001) (xy 126.845265 -368.446764)
			(xy 126.833276 -368.49339) (xy 126.82474 -368.5159) (xy 126.81966 -368.528346) (xy 126.822962 -368.554254)
			(xy 126.889764 -368.644932) (xy 126.913386 -368.655854) (xy 126.926594 -368.654838) (xy 126.955296 -368.653822)
			(xy 126.982551 -368.654225) (xy 127.036507 -368.661982) (xy 127.088809 -368.677339) (xy 127.138394 -368.699983)
			(xy 127.184251 -368.729453) (xy 127.225448 -368.765149) (xy 127.261145 -368.806346) (xy 127.290615 -368.852203)
			(xy 127.31326 -368.901787) (xy 127.328617 -368.954089) (xy 127.336375 -369.008045) (xy 127.336375 -369.062549)
			(xy 131.197108 -369.062549) (xy 131.197108 -369.008051) (xy 131.204864 -368.954108) (xy 131.220218 -368.901818)
			(xy 131.242857 -368.852245) (xy 131.27232 -368.806398) (xy 131.308009 -368.765211) (xy 131.349195 -368.729523)
			(xy 131.395041 -368.700059) (xy 131.444614 -368.677419) (xy 131.496904 -368.662065) (xy 131.550847 -368.654308)
			(xy 131.578096 -368.653822) (xy 131.606798 -368.654838) (xy 131.620006 -368.655854) (xy 131.643628 -368.644932)
			(xy 131.71043 -368.554254) (xy 131.713732 -368.528346) (xy 131.708652 -368.5159) (xy 131.700117 -368.493389)
			(xy 131.688113 -368.446766) (xy 131.68208 -368.399002) (xy 131.681728 -368.37493) (xy 131.682214 -368.347679)
			(xy 131.68997 -368.293731) (xy 131.705325 -368.241436) (xy 131.727967 -368.191859) (xy 131.757433 -368.146009)
			(xy 131.793124 -368.104818) (xy 131.834315 -368.069127) (xy 131.880165 -368.039661) (xy 131.929742 -368.017019)
			(xy 131.982037 -368.001664) (xy 132.035985 -367.993908) (xy 132.090487 -367.993908) (xy 132.144435 -368.001664)
			(xy 132.19673 -368.017019) (xy 132.246307 -368.039661) (xy 132.292157 -368.069127) (xy 132.333348 -368.104818)
			(xy 132.369039 -368.146009) (xy 132.398505 -368.191859) (xy 132.421147 -368.241436) (xy 132.436502 -368.293731)
			(xy 132.444258 -368.347679) (xy 132.444744 -368.37493) (xy 132.444053 -368.407462) (xy 132.432943 -368.471571)
			(xy 132.422646 -368.502438) (xy 132.419598 -368.511074) (xy 132.419852 -368.528854) (xy 132.449316 -368.60734)
			(xy 132.460746 -368.620548) (xy 132.468874 -368.62512) (xy 132.501132 -368.644932) (xy 132.507533 -368.648973)
			(xy 132.522013 -368.653365) (xy 132.52958 -368.653568) (xy 132.811012 -368.653568) (xy 132.818565 -368.65327)
			(xy 132.833023 -368.648892) (xy 132.83946 -368.644932) (xy 132.871718 -368.62512) (xy 132.879846 -368.620548)
			(xy 132.891276 -368.60734) (xy 132.92074 -368.528854) (xy 132.920994 -368.511074) (xy 132.917946 -368.502438)
			(xy 132.907653 -368.47157) (xy 132.896548 -368.407461) (xy 132.895848 -368.37493) (xy 132.896334 -368.347679)
			(xy 132.90409 -368.293731) (xy 132.919445 -368.241436) (xy 132.942087 -368.191859) (xy 132.971553 -368.146009)
			(xy 133.007244 -368.104818) (xy 133.048435 -368.069127) (xy 133.094285 -368.039661) (xy 133.143862 -368.017019)
			(xy 133.196157 -368.001664) (xy 133.250105 -367.993908) (xy 133.304607 -367.993908) (xy 133.358555 -368.001664)
			(xy 133.41085 -368.017019) (xy 133.460427 -368.039661) (xy 133.506277 -368.069127) (xy 133.547468 -368.104818)
			(xy 133.583159 -368.146009) (xy 133.612625 -368.191859) (xy 133.635267 -368.241436) (xy 133.650622 -368.293731)
			(xy 133.658378 -368.347679) (xy 133.658864 -368.37493) (xy 133.658502 -368.399001) (xy 133.652465 -368.446764)
			(xy 133.640476 -368.49339) (xy 133.63194 -368.5159) (xy 133.62686 -368.528346) (xy 133.630162 -368.554254)
			(xy 133.696964 -368.644932) (xy 133.720586 -368.655854) (xy 133.733794 -368.654838) (xy 133.762496 -368.653822)
			(xy 133.789751 -368.654225) (xy 133.843707 -368.661982) (xy 133.896009 -368.677339) (xy 133.945594 -368.699983)
			(xy 133.991451 -368.729453) (xy 134.032648 -368.765149) (xy 134.068345 -368.806346) (xy 134.097815 -368.852203)
			(xy 134.12046 -368.901787) (xy 134.135817 -368.954089) (xy 134.143575 -369.008045) (xy 134.143575 -369.062549)
			(xy 134.600708 -369.062549) (xy 134.600708 -369.008051) (xy 134.608464 -368.954108) (xy 134.623818 -368.901818)
			(xy 134.646457 -368.852245) (xy 134.67592 -368.806398) (xy 134.711609 -368.765211) (xy 134.752795 -368.729523)
			(xy 134.798641 -368.700059) (xy 134.848214 -368.677419) (xy 134.900504 -368.662065) (xy 134.954447 -368.654308)
			(xy 134.981696 -368.653822) (xy 135.010398 -368.654838) (xy 135.023606 -368.655854) (xy 135.047228 -368.644932)
			(xy 135.11403 -368.554254) (xy 135.117332 -368.528346) (xy 135.112252 -368.5159) (xy 135.103717 -368.493389)
			(xy 135.091713 -368.446766) (xy 135.08568 -368.399002) (xy 135.085328 -368.37493) (xy 135.085814 -368.347679)
			(xy 135.09357 -368.293731) (xy 135.108925 -368.241436) (xy 135.131567 -368.191859) (xy 135.161033 -368.146009)
			(xy 135.196724 -368.104818) (xy 135.237915 -368.069127) (xy 135.283765 -368.039661) (xy 135.333342 -368.017019)
			(xy 135.385637 -368.001664) (xy 135.439585 -367.993908) (xy 135.494087 -367.993908) (xy 135.548035 -368.001664)
			(xy 135.60033 -368.017019) (xy 135.649907 -368.039661) (xy 135.695757 -368.069127) (xy 135.736948 -368.104818)
			(xy 135.772639 -368.146009) (xy 135.802105 -368.191859) (xy 135.824747 -368.241436) (xy 135.840102 -368.293731)
			(xy 135.847858 -368.347679) (xy 135.848344 -368.37493) (xy 135.847653 -368.407462) (xy 135.836543 -368.471571)
			(xy 135.826246 -368.502438) (xy 135.823198 -368.511074) (xy 135.823452 -368.528854) (xy 135.852916 -368.60734)
			(xy 135.864346 -368.620548) (xy 135.872474 -368.62512) (xy 135.904732 -368.644932) (xy 135.911133 -368.648973)
			(xy 135.925613 -368.653365) (xy 135.93318 -368.653568) (xy 136.214612 -368.653568) (xy 136.222165 -368.65327)
			(xy 136.236623 -368.648892) (xy 136.24306 -368.644932) (xy 136.275318 -368.62512) (xy 136.283446 -368.620548)
			(xy 136.294876 -368.60734) (xy 136.32434 -368.528854) (xy 136.324594 -368.511074) (xy 136.321546 -368.502438)
			(xy 136.311253 -368.47157) (xy 136.300148 -368.407461) (xy 136.299448 -368.37493) (xy 136.299934 -368.347679)
			(xy 136.30769 -368.293731) (xy 136.323045 -368.241436) (xy 136.345687 -368.191859) (xy 136.375153 -368.146009)
			(xy 136.410844 -368.104818) (xy 136.452035 -368.069127) (xy 136.497885 -368.039661) (xy 136.547462 -368.017019)
			(xy 136.599757 -368.001664) (xy 136.653705 -367.993908) (xy 136.708207 -367.993908) (xy 136.762155 -368.001664)
			(xy 136.81445 -368.017019) (xy 136.864027 -368.039661) (xy 136.909877 -368.069127) (xy 136.951068 -368.104818)
			(xy 136.986759 -368.146009) (xy 137.016225 -368.191859) (xy 137.038867 -368.241436) (xy 137.054222 -368.293731)
			(xy 137.061978 -368.347679) (xy 137.062464 -368.37493) (xy 137.062102 -368.399001) (xy 137.056065 -368.446764)
			(xy 137.044076 -368.49339) (xy 137.03554 -368.5159) (xy 137.03046 -368.528346) (xy 137.033762 -368.554254)
			(xy 137.100564 -368.644932) (xy 137.124186 -368.655854) (xy 137.137394 -368.654838) (xy 137.166096 -368.653822)
			(xy 137.193351 -368.654225) (xy 137.247307 -368.661982) (xy 137.299609 -368.677339) (xy 137.349194 -368.699983)
			(xy 137.395051 -368.729453) (xy 137.436248 -368.765149) (xy 137.471945 -368.806346) (xy 137.501415 -368.852203)
			(xy 137.52406 -368.901787) (xy 137.539417 -368.954089) (xy 137.547175 -369.008045) (xy 137.547175 -369.062555)
			(xy 137.539417 -369.116511) (xy 137.52406 -369.168813) (xy 137.501415 -369.218397) (xy 137.471945 -369.264254)
			(xy 137.436248 -369.305451) (xy 137.395051 -369.341147) (xy 137.349194 -369.370617) (xy 137.299609 -369.393261)
			(xy 137.247307 -369.408618) (xy 137.193351 -369.416375) (xy 137.166096 -369.416838) (xy 137.137394 -369.415822)
			(xy 137.124186 -369.414806) (xy 137.100564 -369.425728) (xy 137.033762 -369.516406) (xy 137.03046 -369.542314)
			(xy 137.03554 -369.55476) (xy 137.044092 -369.577265) (xy 137.05609 -369.623891) (xy 137.062116 -369.671657)
			(xy 137.062464 -369.69573) (xy 137.061978 -369.722981) (xy 137.054222 -369.776929) (xy 137.038867 -369.829224)
			(xy 137.016225 -369.878801) (xy 136.986759 -369.924651) (xy 136.951068 -369.965842) (xy 136.909877 -370.001533)
			(xy 136.864027 -370.030999) (xy 136.81445 -370.053641) (xy 136.762155 -370.068996) (xy 136.708207 -370.076752)
			(xy 136.653705 -370.076752) (xy 136.599757 -370.068996) (xy 136.547462 -370.053641) (xy 136.497885 -370.030999)
			(xy 136.452035 -370.001533) (xy 136.410844 -369.965842) (xy 136.375153 -369.924651) (xy 136.345687 -369.878801)
			(xy 136.323045 -369.829224) (xy 136.30769 -369.776929) (xy 136.299934 -369.722981) (xy 136.299448 -369.69573)
			(xy 136.30013 -369.663198) (xy 136.311246 -369.599089) (xy 136.321546 -369.568222) (xy 136.324594 -369.559586)
			(xy 136.32434 -369.541806) (xy 136.294876 -369.46332) (xy 136.283446 -369.450112) (xy 136.275318 -369.44554)
			(xy 136.24306 -369.425728) (xy 136.236658 -369.421689) (xy 136.222179 -369.417295) (xy 136.214612 -369.417092)
			(xy 135.93318 -369.417092) (xy 135.925626 -369.417377) (xy 135.911168 -369.421763) (xy 135.904732 -369.425728)
			(xy 135.872474 -369.44554) (xy 135.864346 -369.450112) (xy 135.852916 -369.46332) (xy 135.823452 -369.541806)
			(xy 135.823198 -369.559586) (xy 135.826246 -369.568222) (xy 135.836532 -369.599092) (xy 135.847641 -369.663199)
			(xy 135.848344 -369.69573) (xy 135.847858 -369.722981) (xy 135.840102 -369.776929) (xy 135.824747 -369.829224)
			(xy 135.802105 -369.878801) (xy 135.772639 -369.924651) (xy 135.736948 -369.965842) (xy 135.695757 -370.001533)
			(xy 135.649907 -370.030999) (xy 135.60033 -370.053641) (xy 135.548035 -370.068996) (xy 135.494087 -370.076752)
			(xy 135.439585 -370.076752) (xy 135.385637 -370.068996) (xy 135.333342 -370.053641) (xy 135.283765 -370.030999)
			(xy 135.237915 -370.001533) (xy 135.196724 -369.965842) (xy 135.161033 -369.924651) (xy 135.131567 -369.878801)
			(xy 135.108925 -369.829224) (xy 135.09357 -369.776929) (xy 135.085814 -369.722981) (xy 135.085328 -369.69573)
			(xy 135.085678 -369.671658) (xy 135.09172 -369.623895) (xy 135.103714 -369.57727) (xy 135.112252 -369.55476)
			(xy 135.117332 -369.542314) (xy 135.11403 -369.516406) (xy 135.047228 -369.425728) (xy 135.023606 -369.414806)
			(xy 135.010398 -369.415822) (xy 134.981696 -369.416838) (xy 134.954447 -369.416292) (xy 134.900504 -369.408535)
			(xy 134.848214 -369.393181) (xy 134.798641 -369.370541) (xy 134.752795 -369.341077) (xy 134.711609 -369.305389)
			(xy 134.67592 -369.264202) (xy 134.646457 -369.218355) (xy 134.623818 -369.168782) (xy 134.608464 -369.116492)
			(xy 134.600708 -369.062549) (xy 134.143575 -369.062549) (xy 134.143575 -369.062555) (xy 134.135817 -369.116511)
			(xy 134.12046 -369.168813) (xy 134.097815 -369.218397) (xy 134.068345 -369.264254) (xy 134.032648 -369.305451)
			(xy 133.991451 -369.341147) (xy 133.945594 -369.370617) (xy 133.896009 -369.393261) (xy 133.843707 -369.408618)
			(xy 133.789751 -369.416375) (xy 133.762496 -369.416838) (xy 133.733794 -369.415822) (xy 133.720586 -369.414806)
			(xy 133.696964 -369.425728) (xy 133.630162 -369.516406) (xy 133.62686 -369.542314) (xy 133.63194 -369.55476)
			(xy 133.640492 -369.577265) (xy 133.65249 -369.623891) (xy 133.658516 -369.671657) (xy 133.658864 -369.69573)
			(xy 133.658378 -369.722981) (xy 133.650622 -369.776929) (xy 133.635267 -369.829224) (xy 133.612625 -369.878801)
			(xy 133.583159 -369.924651) (xy 133.547468 -369.965842) (xy 133.506277 -370.001533) (xy 133.460427 -370.030999)
			(xy 133.41085 -370.053641) (xy 133.358555 -370.068996) (xy 133.304607 -370.076752) (xy 133.250105 -370.076752)
			(xy 133.196157 -370.068996) (xy 133.143862 -370.053641) (xy 133.094285 -370.030999) (xy 133.048435 -370.001533)
			(xy 133.007244 -369.965842) (xy 132.971553 -369.924651) (xy 132.942087 -369.878801) (xy 132.919445 -369.829224)
			(xy 132.90409 -369.776929) (xy 132.896334 -369.722981) (xy 132.895848 -369.69573) (xy 132.89653 -369.663198)
			(xy 132.907646 -369.599089) (xy 132.917946 -369.568222) (xy 132.920994 -369.559586) (xy 132.92074 -369.541806)
			(xy 132.891276 -369.46332) (xy 132.879846 -369.450112) (xy 132.871718 -369.44554) (xy 132.83946 -369.425728)
			(xy 132.833058 -369.421689) (xy 132.818579 -369.417295) (xy 132.811012 -369.417092) (xy 132.52958 -369.417092)
			(xy 132.522026 -369.417377) (xy 132.507568 -369.421763) (xy 132.501132 -369.425728) (xy 132.468874 -369.44554)
			(xy 132.460746 -369.450112) (xy 132.449316 -369.46332) (xy 132.419852 -369.541806) (xy 132.419598 -369.559586)
			(xy 132.422646 -369.568222) (xy 132.432932 -369.599092) (xy 132.444041 -369.663199) (xy 132.444744 -369.69573)
			(xy 132.444258 -369.722981) (xy 132.436502 -369.776929) (xy 132.421147 -369.829224) (xy 132.398505 -369.878801)
			(xy 132.369039 -369.924651) (xy 132.333348 -369.965842) (xy 132.292157 -370.001533) (xy 132.246307 -370.030999)
			(xy 132.19673 -370.053641) (xy 132.144435 -370.068996) (xy 132.090487 -370.076752) (xy 132.035985 -370.076752)
			(xy 131.982037 -370.068996) (xy 131.929742 -370.053641) (xy 131.880165 -370.030999) (xy 131.834315 -370.001533)
			(xy 131.793124 -369.965842) (xy 131.757433 -369.924651) (xy 131.727967 -369.878801) (xy 131.705325 -369.829224)
			(xy 131.68997 -369.776929) (xy 131.682214 -369.722981) (xy 131.681728 -369.69573) (xy 131.682078 -369.671658)
			(xy 131.68812 -369.623895) (xy 131.700114 -369.57727) (xy 131.708652 -369.55476) (xy 131.713732 -369.542314)
			(xy 131.71043 -369.516406) (xy 131.643628 -369.425728) (xy 131.620006 -369.414806) (xy 131.606798 -369.415822)
			(xy 131.578096 -369.416838) (xy 131.550847 -369.416292) (xy 131.496904 -369.408535) (xy 131.444614 -369.393181)
			(xy 131.395041 -369.370541) (xy 131.349195 -369.341077) (xy 131.308009 -369.305389) (xy 131.27232 -369.264202)
			(xy 131.242857 -369.218355) (xy 131.220218 -369.168782) (xy 131.204864 -369.116492) (xy 131.197108 -369.062549)
			(xy 127.336375 -369.062549) (xy 127.336375 -369.062555) (xy 127.328617 -369.116511) (xy 127.31326 -369.168813)
			(xy 127.290615 -369.218397) (xy 127.261145 -369.264254) (xy 127.225448 -369.305451) (xy 127.184251 -369.341147)
			(xy 127.138394 -369.370617) (xy 127.088809 -369.393261) (xy 127.036507 -369.408618) (xy 126.982551 -369.416375)
			(xy 126.955296 -369.416838) (xy 126.926594 -369.415822) (xy 126.913386 -369.414806) (xy 126.889764 -369.425728)
			(xy 126.822962 -369.516406) (xy 126.81966 -369.542314) (xy 126.82474 -369.55476) (xy 126.833292 -369.577265)
			(xy 126.84529 -369.623891) (xy 126.851316 -369.671657) (xy 126.851664 -369.69573) (xy 126.851178 -369.722981)
			(xy 126.843422 -369.776929) (xy 126.828067 -369.829224) (xy 126.805425 -369.878801) (xy 126.775959 -369.924651)
			(xy 126.740268 -369.965842) (xy 126.699077 -370.001533) (xy 126.653227 -370.030999) (xy 126.60365 -370.053641)
			(xy 126.551355 -370.068996) (xy 126.497407 -370.076752) (xy 126.442905 -370.076752) (xy 126.388957 -370.068996)
			(xy 126.336662 -370.053641) (xy 126.287085 -370.030999) (xy 126.241235 -370.001533) (xy 126.200044 -369.965842)
			(xy 126.164353 -369.924651) (xy 126.134887 -369.878801) (xy 126.112245 -369.829224) (xy 126.09689 -369.776929)
			(xy 126.089134 -369.722981) (xy 126.088648 -369.69573) (xy 126.08933 -369.663198) (xy 126.100446 -369.599089)
			(xy 126.110746 -369.568222) (xy 126.113794 -369.559586) (xy 126.11354 -369.541806) (xy 126.084076 -369.46332)
			(xy 126.072646 -369.450112) (xy 126.064518 -369.44554) (xy 126.03226 -369.425728) (xy 126.025858 -369.421689)
			(xy 126.011379 -369.417295) (xy 126.003812 -369.417092) (xy 125.72238 -369.417092) (xy 125.714826 -369.417377)
			(xy 125.700368 -369.421763) (xy 125.693932 -369.425728) (xy 125.661674 -369.44554) (xy 125.653546 -369.450112)
			(xy 125.642116 -369.46332) (xy 125.612652 -369.541806) (xy 125.612398 -369.559586) (xy 125.615446 -369.568222)
			(xy 125.625732 -369.599092) (xy 125.636841 -369.663199) (xy 125.637544 -369.69573) (xy 125.637058 -369.722981)
			(xy 125.629302 -369.776929) (xy 125.613947 -369.829224) (xy 125.591305 -369.878801) (xy 125.561839 -369.924651)
			(xy 125.526148 -369.965842) (xy 125.484957 -370.001533) (xy 125.439107 -370.030999) (xy 125.38953 -370.053641)
			(xy 125.337235 -370.068996) (xy 125.283287 -370.076752) (xy 125.228785 -370.076752) (xy 125.174837 -370.068996)
			(xy 125.122542 -370.053641) (xy 125.072965 -370.030999) (xy 125.027115 -370.001533) (xy 124.985924 -369.965842)
			(xy 124.950233 -369.924651) (xy 124.920767 -369.878801) (xy 124.898125 -369.829224) (xy 124.88277 -369.776929)
			(xy 124.875014 -369.722981) (xy 124.874528 -369.69573) (xy 124.874878 -369.671658) (xy 124.88092 -369.623895)
			(xy 124.892914 -369.57727) (xy 124.901452 -369.55476) (xy 124.906532 -369.542314) (xy 124.90323 -369.516406)
			(xy 124.836428 -369.425728) (xy 124.812806 -369.414806) (xy 124.799598 -369.415822) (xy 124.770896 -369.416838)
			(xy 124.743647 -369.416292) (xy 124.689704 -369.408535) (xy 124.637414 -369.393181) (xy 124.587841 -369.370541)
			(xy 124.541995 -369.341077) (xy 124.500809 -369.305389) (xy 124.46512 -369.264202) (xy 124.435657 -369.218355)
			(xy 124.413018 -369.168782) (xy 124.397664 -369.116492) (xy 124.389908 -369.062549) (xy 120.529175 -369.062549)
			(xy 120.529175 -369.062555) (xy 120.521417 -369.116511) (xy 120.50606 -369.168813) (xy 120.483415 -369.218397)
			(xy 120.453945 -369.264254) (xy 120.418248 -369.305451) (xy 120.377051 -369.341147) (xy 120.331194 -369.370617)
			(xy 120.281609 -369.393261) (xy 120.229307 -369.408618) (xy 120.175351 -369.416375) (xy 120.148096 -369.416838)
			(xy 120.119394 -369.415822) (xy 120.106186 -369.414806) (xy 120.082564 -369.425728) (xy 120.015762 -369.516406)
			(xy 120.01246 -369.542314) (xy 120.01754 -369.55476) (xy 120.026092 -369.577265) (xy 120.03809 -369.623891)
			(xy 120.044116 -369.671657) (xy 120.044464 -369.69573) (xy 120.043978 -369.722981) (xy 120.036222 -369.776929)
			(xy 120.020867 -369.829224) (xy 119.998225 -369.878801) (xy 119.968759 -369.924651) (xy 119.933068 -369.965842)
			(xy 119.891877 -370.001533) (xy 119.846027 -370.030999) (xy 119.79645 -370.053641) (xy 119.744155 -370.068996)
			(xy 119.690207 -370.076752) (xy 119.635705 -370.076752) (xy 119.581757 -370.068996) (xy 119.529462 -370.053641)
			(xy 119.479885 -370.030999) (xy 119.434035 -370.001533) (xy 119.392844 -369.965842) (xy 119.357153 -369.924651)
			(xy 119.327687 -369.878801) (xy 119.305045 -369.829224) (xy 119.28969 -369.776929) (xy 119.281934 -369.722981)
			(xy 119.281448 -369.69573) (xy 119.28213 -369.663198) (xy 119.293246 -369.599089) (xy 119.303546 -369.568222)
			(xy 119.306594 -369.559586) (xy 119.30634 -369.541806) (xy 119.276876 -369.46332) (xy 119.265446 -369.450112)
			(xy 119.257318 -369.44554) (xy 119.22506 -369.425728) (xy 119.218658 -369.421689) (xy 119.204179 -369.417295)
			(xy 119.196612 -369.417092) (xy 118.91518 -369.417092) (xy 118.907626 -369.417377) (xy 118.893168 -369.421763)
			(xy 118.886732 -369.425728) (xy 118.854474 -369.44554) (xy 118.846346 -369.450112) (xy 118.834916 -369.46332)
			(xy 118.805452 -369.541806) (xy 118.805198 -369.559586) (xy 118.808246 -369.568222) (xy 118.818532 -369.599092)
			(xy 118.829641 -369.663199) (xy 118.830344 -369.69573) (xy 118.829858 -369.722981) (xy 118.822102 -369.776929)
			(xy 118.806747 -369.829224) (xy 118.784105 -369.878801) (xy 118.754639 -369.924651) (xy 118.718948 -369.965842)
			(xy 118.677757 -370.001533) (xy 118.631907 -370.030999) (xy 118.58233 -370.053641) (xy 118.530035 -370.068996)
			(xy 118.476087 -370.076752) (xy 118.421585 -370.076752) (xy 118.367637 -370.068996) (xy 118.315342 -370.053641)
			(xy 118.265765 -370.030999) (xy 118.219915 -370.001533) (xy 118.178724 -369.965842) (xy 118.143033 -369.924651)
			(xy 118.113567 -369.878801) (xy 118.090925 -369.829224) (xy 118.07557 -369.776929) (xy 118.067814 -369.722981)
			(xy 118.067328 -369.69573) (xy 118.067678 -369.671658) (xy 118.07372 -369.623895) (xy 118.085714 -369.57727)
			(xy 118.094252 -369.55476) (xy 118.099332 -369.542314) (xy 118.09603 -369.516406) (xy 118.029228 -369.425728)
			(xy 118.005606 -369.414806) (xy 117.992398 -369.415822) (xy 117.963696 -369.416838) (xy 117.936447 -369.416292)
			(xy 117.882504 -369.408535) (xy 117.830214 -369.393181) (xy 117.780641 -369.370541) (xy 117.734795 -369.341077)
			(xy 117.693609 -369.305389) (xy 117.65792 -369.264202) (xy 117.628457 -369.218355) (xy 117.605818 -369.168782)
			(xy 117.590464 -369.116492) (xy 117.582708 -369.062549) (xy 113.721975 -369.062549) (xy 113.721975 -369.062555)
			(xy 113.714217 -369.116511) (xy 113.69886 -369.168813) (xy 113.676215 -369.218397) (xy 113.646745 -369.264254)
			(xy 113.611048 -369.305451) (xy 113.569851 -369.341147) (xy 113.523994 -369.370617) (xy 113.474409 -369.393261)
			(xy 113.422107 -369.408618) (xy 113.368151 -369.416375) (xy 113.340896 -369.416838) (xy 113.312194 -369.415822)
			(xy 113.298986 -369.414806) (xy 113.275364 -369.425728) (xy 113.208562 -369.516406) (xy 113.20526 -369.542314)
			(xy 113.21034 -369.55476) (xy 113.218892 -369.577265) (xy 113.23089 -369.623891) (xy 113.236916 -369.671657)
			(xy 113.237264 -369.69573) (xy 113.236778 -369.722981) (xy 113.229022 -369.776929) (xy 113.213667 -369.829224)
			(xy 113.191025 -369.878801) (xy 113.161559 -369.924651) (xy 113.125868 -369.965842) (xy 113.084677 -370.001533)
			(xy 113.038827 -370.030999) (xy 112.98925 -370.053641) (xy 112.936955 -370.068996) (xy 112.883007 -370.076752)
			(xy 112.828505 -370.076752) (xy 112.774557 -370.068996) (xy 112.722262 -370.053641) (xy 112.672685 -370.030999)
			(xy 112.626835 -370.001533) (xy 112.585644 -369.965842) (xy 112.549953 -369.924651) (xy 112.520487 -369.878801)
			(xy 112.497845 -369.829224) (xy 112.48249 -369.776929) (xy 112.474734 -369.722981) (xy 112.474248 -369.69573)
			(xy 112.47493 -369.663198) (xy 112.486046 -369.599089) (xy 112.496346 -369.568222) (xy 112.499394 -369.559586)
			(xy 112.49914 -369.541806) (xy 112.469676 -369.46332) (xy 112.458246 -369.450112) (xy 112.450118 -369.44554)
			(xy 112.41786 -369.425728) (xy 112.411458 -369.421689) (xy 112.396979 -369.417295) (xy 112.389412 -369.417092)
			(xy 112.10798 -369.417092) (xy 112.100426 -369.417377) (xy 112.085968 -369.421763) (xy 112.079532 -369.425728)
			(xy 112.047274 -369.44554) (xy 112.039146 -369.450112) (xy 112.027716 -369.46332) (xy 111.998252 -369.541806)
			(xy 111.997998 -369.559586) (xy 112.001046 -369.568222) (xy 112.011332 -369.599092) (xy 112.022441 -369.663199)
			(xy 112.023144 -369.69573) (xy 112.022658 -369.722981) (xy 112.014902 -369.776929) (xy 111.999547 -369.829224)
			(xy 111.976905 -369.878801) (xy 111.947439 -369.924651) (xy 111.911748 -369.965842) (xy 111.870557 -370.001533)
			(xy 111.824707 -370.030999) (xy 111.77513 -370.053641) (xy 111.722835 -370.068996) (xy 111.668887 -370.076752)
			(xy 111.614385 -370.076752) (xy 111.560437 -370.068996) (xy 111.508142 -370.053641) (xy 111.458565 -370.030999)
			(xy 111.412715 -370.001533) (xy 111.371524 -369.965842) (xy 111.335833 -369.924651) (xy 111.306367 -369.878801)
			(xy 111.283725 -369.829224) (xy 111.26837 -369.776929) (xy 111.260614 -369.722981) (xy 111.260128 -369.69573)
			(xy 111.260478 -369.671658) (xy 111.26652 -369.623895) (xy 111.278514 -369.57727) (xy 111.287052 -369.55476)
			(xy 111.292132 -369.542314) (xy 111.28883 -369.516406) (xy 111.222028 -369.425728) (xy 111.198406 -369.414806)
			(xy 111.185198 -369.415822) (xy 111.156496 -369.416838) (xy 111.129247 -369.416292) (xy 111.075304 -369.408535)
			(xy 111.023014 -369.393181) (xy 110.973441 -369.370541) (xy 110.927595 -369.341077) (xy 110.886409 -369.305389)
			(xy 110.85072 -369.264202) (xy 110.821257 -369.218355) (xy 110.798618 -369.168782) (xy 110.783264 -369.116492)
			(xy 110.775508 -369.062549) (xy 102.974952 -369.062549) (xy 102.974952 -369.062553) (xy 102.967195 -369.116505)
			(xy 102.951839 -369.168804) (xy 102.929196 -369.218385) (xy 102.899728 -369.264239) (xy 102.864034 -369.305432)
			(xy 102.82284 -369.341126) (xy 102.776987 -369.370595) (xy 102.727406 -369.393238) (xy 102.675107 -369.408595)
			(xy 102.621155 -369.416352) (xy 102.593902 -369.416838) (xy 102.5652 -369.415822) (xy 102.551992 -369.414806)
			(xy 102.52837 -369.425728) (xy 102.461568 -369.516406) (xy 102.458266 -369.542314) (xy 102.463346 -369.55476)
			(xy 102.471898 -369.577265) (xy 102.483896 -369.623891) (xy 102.489922 -369.671657) (xy 102.49027 -369.69573)
			(xy 102.489784 -369.722981) (xy 102.482028 -369.776929) (xy 102.466673 -369.829224) (xy 102.444031 -369.878801)
			(xy 102.414565 -369.924651) (xy 102.378874 -369.965842) (xy 102.337683 -370.001533) (xy 102.291833 -370.030999)
			(xy 102.242256 -370.053641) (xy 102.189961 -370.068996) (xy 102.136013 -370.076752) (xy 102.081511 -370.076752)
			(xy 102.027563 -370.068996) (xy 101.975268 -370.053641) (xy 101.925691 -370.030999) (xy 101.879841 -370.001533)
			(xy 101.83865 -369.965842) (xy 101.802959 -369.924651) (xy 101.773493 -369.878801) (xy 101.750851 -369.829224)
			(xy 101.735496 -369.776929) (xy 101.72774 -369.722981) (xy 101.727254 -369.69573) (xy 101.727936 -369.663198)
			(xy 101.739052 -369.599089) (xy 101.749352 -369.568222) (xy 101.7524 -369.559586) (xy 101.752146 -369.541806)
			(xy 101.722682 -369.46332) (xy 101.711252 -369.450112) (xy 101.703124 -369.44554) (xy 101.670866 -369.425728)
			(xy 101.664462 -369.421692) (xy 101.649985 -369.417296) (xy 101.642418 -369.417092) (xy 101.360986 -369.417092)
			(xy 101.353432 -369.41738) (xy 101.338974 -369.421764) (xy 101.332538 -369.425728) (xy 101.30028 -369.44554)
			(xy 101.292152 -369.450112) (xy 101.280722 -369.46332) (xy 101.251258 -369.541806) (xy 101.251004 -369.559586)
			(xy 101.254052 -369.568222) (xy 101.264338 -369.599091) (xy 101.275447 -369.663199) (xy 101.27615 -369.69573)
			(xy 101.275664 -369.722981) (xy 101.267908 -369.776929) (xy 101.252553 -369.829224) (xy 101.229911 -369.878801)
			(xy 101.200445 -369.924651) (xy 101.164754 -369.965842) (xy 101.123563 -370.001533) (xy 101.077713 -370.030999)
			(xy 101.028136 -370.053641) (xy 100.975841 -370.068996) (xy 100.921893 -370.076752) (xy 100.867391 -370.076752)
			(xy 100.813443 -370.068996) (xy 100.761148 -370.053641) (xy 100.711571 -370.030999) (xy 100.665721 -370.001533)
			(xy 100.62453 -369.965842) (xy 100.588839 -369.924651) (xy 100.559373 -369.878801) (xy 100.536731 -369.829224)
			(xy 100.521376 -369.776929) (xy 100.51362 -369.722981) (xy 100.513134 -369.69573) (xy 100.513483 -369.671658)
			(xy 100.519526 -369.623895) (xy 100.53152 -369.57727) (xy 100.540058 -369.55476) (xy 100.545138 -369.542314)
			(xy 100.541836 -369.516406) (xy 100.475034 -369.425728) (xy 100.451412 -369.414806) (xy 100.438204 -369.415822)
			(xy 100.409502 -369.416838) (xy 100.382251 -369.416315) (xy 100.328304 -369.408559) (xy 100.27601 -369.393204)
			(xy 100.226434 -369.370563) (xy 100.180584 -369.341098) (xy 100.139394 -369.305407) (xy 100.103703 -369.264218)
			(xy 100.074237 -369.218368) (xy 100.051597 -369.168792) (xy 100.036242 -369.116498) (xy 100.028485 -369.062551)
			(xy 99.571352 -369.062551) (xy 99.571352 -369.062553) (xy 99.563595 -369.116505) (xy 99.548239 -369.168804)
			(xy 99.525596 -369.218385) (xy 99.496128 -369.264239) (xy 99.460434 -369.305432) (xy 99.41924 -369.341126)
			(xy 99.373387 -369.370595) (xy 99.323806 -369.393238) (xy 99.271507 -369.408595) (xy 99.217555 -369.416352)
			(xy 99.190302 -369.416838) (xy 99.1616 -369.415822) (xy 99.148392 -369.414806) (xy 99.12477 -369.425728)
			(xy 99.057968 -369.516406) (xy 99.054666 -369.542314) (xy 99.059746 -369.55476) (xy 99.068298 -369.577265)
			(xy 99.080296 -369.623891) (xy 99.086322 -369.671657) (xy 99.08667 -369.69573) (xy 99.086184 -369.722981)
			(xy 99.078428 -369.776929) (xy 99.063073 -369.829224) (xy 99.040431 -369.878801) (xy 99.010965 -369.924651)
			(xy 98.975274 -369.965842) (xy 98.934083 -370.001533) (xy 98.888233 -370.030999) (xy 98.838656 -370.053641)
			(xy 98.786361 -370.068996) (xy 98.732413 -370.076752) (xy 98.677911 -370.076752) (xy 98.623963 -370.068996)
			(xy 98.571668 -370.053641) (xy 98.522091 -370.030999) (xy 98.476241 -370.001533) (xy 98.43505 -369.965842)
			(xy 98.399359 -369.924651) (xy 98.369893 -369.878801) (xy 98.347251 -369.829224) (xy 98.331896 -369.776929)
			(xy 98.32414 -369.722981) (xy 98.323654 -369.69573) (xy 98.324336 -369.663198) (xy 98.335452 -369.599089)
			(xy 98.345752 -369.568222) (xy 98.3488 -369.559586) (xy 98.348546 -369.541806) (xy 98.319082 -369.46332)
			(xy 98.307652 -369.450112) (xy 98.299524 -369.44554) (xy 98.267266 -369.425728) (xy 98.260862 -369.421692)
			(xy 98.246385 -369.417296) (xy 98.238818 -369.417092) (xy 97.957386 -369.417092) (xy 97.949832 -369.41738)
			(xy 97.935374 -369.421764) (xy 97.928938 -369.425728) (xy 97.89668 -369.44554) (xy 97.888552 -369.450112)
			(xy 97.877122 -369.46332) (xy 97.847658 -369.541806) (xy 97.847404 -369.559586) (xy 97.850452 -369.568222)
			(xy 97.860738 -369.599091) (xy 97.871847 -369.663199) (xy 97.87255 -369.69573) (xy 97.872064 -369.722981)
			(xy 97.864308 -369.776929) (xy 97.848953 -369.829224) (xy 97.826311 -369.878801) (xy 97.796845 -369.924651)
			(xy 97.761154 -369.965842) (xy 97.719963 -370.001533) (xy 97.674113 -370.030999) (xy 97.624536 -370.053641)
			(xy 97.572241 -370.068996) (xy 97.518293 -370.076752) (xy 97.463791 -370.076752) (xy 97.409843 -370.068996)
			(xy 97.357548 -370.053641) (xy 97.307971 -370.030999) (xy 97.262121 -370.001533) (xy 97.22093 -369.965842)
			(xy 97.185239 -369.924651) (xy 97.155773 -369.878801) (xy 97.133131 -369.829224) (xy 97.117776 -369.776929)
			(xy 97.11002 -369.722981) (xy 97.109534 -369.69573) (xy 97.109883 -369.671658) (xy 97.115926 -369.623895)
			(xy 97.12792 -369.57727) (xy 97.136458 -369.55476) (xy 97.141538 -369.542314) (xy 97.138236 -369.516406)
			(xy 97.071434 -369.425728) (xy 97.047812 -369.414806) (xy 97.034604 -369.415822) (xy 97.005902 -369.416838)
			(xy 96.978651 -369.416315) (xy 96.924704 -369.408559) (xy 96.87241 -369.393204) (xy 96.822834 -369.370563)
			(xy 96.776984 -369.341098) (xy 96.735794 -369.305407) (xy 96.700103 -369.264218) (xy 96.670637 -369.218368)
			(xy 96.647997 -369.168792) (xy 96.632642 -369.116498) (xy 96.624885 -369.062551) (xy 92.764152 -369.062551)
			(xy 92.764152 -369.062553) (xy 92.756395 -369.116505) (xy 92.741039 -369.168804) (xy 92.718396 -369.218385)
			(xy 92.688928 -369.264239) (xy 92.653234 -369.305432) (xy 92.61204 -369.341126) (xy 92.566187 -369.370595)
			(xy 92.516606 -369.393238) (xy 92.464307 -369.408595) (xy 92.410355 -369.416352) (xy 92.383102 -369.416838)
			(xy 92.3544 -369.415822) (xy 92.341192 -369.414806) (xy 92.31757 -369.425728) (xy 92.250768 -369.516406)
			(xy 92.247466 -369.542314) (xy 92.252546 -369.55476) (xy 92.261098 -369.577265) (xy 92.273096 -369.623891)
			(xy 92.279122 -369.671657) (xy 92.27947 -369.69573) (xy 92.278984 -369.722981) (xy 92.271228 -369.776929)
			(xy 92.255873 -369.829224) (xy 92.233231 -369.878801) (xy 92.203765 -369.924651) (xy 92.168074 -369.965842)
			(xy 92.126883 -370.001533) (xy 92.081033 -370.030999) (xy 92.031456 -370.053641) (xy 91.979161 -370.068996)
			(xy 91.925213 -370.076752) (xy 91.870711 -370.076752) (xy 91.816763 -370.068996) (xy 91.764468 -370.053641)
			(xy 91.714891 -370.030999) (xy 91.669041 -370.001533) (xy 91.62785 -369.965842) (xy 91.592159 -369.924651)
			(xy 91.562693 -369.878801) (xy 91.540051 -369.829224) (xy 91.524696 -369.776929) (xy 91.51694 -369.722981)
			(xy 91.516454 -369.69573) (xy 91.517136 -369.663198) (xy 91.528252 -369.599089) (xy 91.538552 -369.568222)
			(xy 91.5416 -369.559586) (xy 91.541346 -369.541806) (xy 91.511882 -369.46332) (xy 91.500452 -369.450112)
			(xy 91.492324 -369.44554) (xy 91.460066 -369.425728) (xy 91.453662 -369.421692) (xy 91.439185 -369.417296)
			(xy 91.431618 -369.417092) (xy 91.150186 -369.417092) (xy 91.142632 -369.41738) (xy 91.128174 -369.421764)
			(xy 91.121738 -369.425728) (xy 91.08948 -369.44554) (xy 91.081352 -369.450112) (xy 91.069922 -369.46332)
			(xy 91.040458 -369.541806) (xy 91.040204 -369.559586) (xy 91.043252 -369.568222) (xy 91.053538 -369.599091)
			(xy 91.064647 -369.663199) (xy 91.06535 -369.69573) (xy 91.064864 -369.722981) (xy 91.057108 -369.776929)
			(xy 91.041753 -369.829224) (xy 91.019111 -369.878801) (xy 90.989645 -369.924651) (xy 90.953954 -369.965842)
			(xy 90.912763 -370.001533) (xy 90.866913 -370.030999) (xy 90.817336 -370.053641) (xy 90.765041 -370.068996)
			(xy 90.711093 -370.076752) (xy 90.656591 -370.076752) (xy 90.602643 -370.068996) (xy 90.550348 -370.053641)
			(xy 90.500771 -370.030999) (xy 90.454921 -370.001533) (xy 90.41373 -369.965842) (xy 90.378039 -369.924651)
			(xy 90.348573 -369.878801) (xy 90.325931 -369.829224) (xy 90.310576 -369.776929) (xy 90.30282 -369.722981)
			(xy 90.302334 -369.69573) (xy 90.302683 -369.671658) (xy 90.308726 -369.623895) (xy 90.32072 -369.57727)
			(xy 90.329258 -369.55476) (xy 90.334338 -369.542314) (xy 90.331036 -369.516406) (xy 90.264234 -369.425728)
			(xy 90.240612 -369.414806) (xy 90.227404 -369.415822) (xy 90.198702 -369.416838) (xy 90.171451 -369.416315)
			(xy 90.117504 -369.408559) (xy 90.06521 -369.393204) (xy 90.015634 -369.370563) (xy 89.969784 -369.341098)
			(xy 89.928594 -369.305407) (xy 89.892903 -369.264218) (xy 89.863437 -369.218368) (xy 89.840797 -369.168792)
			(xy 89.825442 -369.116498) (xy 89.817685 -369.062551) (xy 85.956952 -369.062551) (xy 85.956952 -369.062553)
			(xy 85.949195 -369.116505) (xy 85.933839 -369.168804) (xy 85.911196 -369.218385) (xy 85.881728 -369.264239)
			(xy 85.846034 -369.305432) (xy 85.80484 -369.341126) (xy 85.758987 -369.370595) (xy 85.709406 -369.393238)
			(xy 85.657107 -369.408595) (xy 85.603155 -369.416352) (xy 85.575902 -369.416838) (xy 85.5472 -369.415822)
			(xy 85.533992 -369.414806) (xy 85.51037 -369.425728) (xy 85.443568 -369.516406) (xy 85.440266 -369.542314)
			(xy 85.445346 -369.55476) (xy 85.453898 -369.577265) (xy 85.465896 -369.623891) (xy 85.471922 -369.671657)
			(xy 85.47227 -369.69573) (xy 85.471784 -369.722981) (xy 85.464028 -369.776929) (xy 85.448673 -369.829224)
			(xy 85.426031 -369.878801) (xy 85.396565 -369.924651) (xy 85.360874 -369.965842) (xy 85.319683 -370.001533)
			(xy 85.273833 -370.030999) (xy 85.224256 -370.053641) (xy 85.171961 -370.068996) (xy 85.118013 -370.076752)
			(xy 85.063511 -370.076752) (xy 85.009563 -370.068996) (xy 84.957268 -370.053641) (xy 84.907691 -370.030999)
			(xy 84.861841 -370.001533) (xy 84.82065 -369.965842) (xy 84.784959 -369.924651) (xy 84.755493 -369.878801)
			(xy 84.732851 -369.829224) (xy 84.717496 -369.776929) (xy 84.70974 -369.722981) (xy 84.709254 -369.69573)
			(xy 84.709936 -369.663198) (xy 84.721052 -369.599089) (xy 84.731352 -369.568222) (xy 84.7344 -369.559586)
			(xy 84.734146 -369.541806) (xy 84.704682 -369.46332) (xy 84.693252 -369.450112) (xy 84.685124 -369.44554)
			(xy 84.652866 -369.425728) (xy 84.646462 -369.421692) (xy 84.631985 -369.417296) (xy 84.624418 -369.417092)
			(xy 84.342986 -369.417092) (xy 84.335432 -369.41738) (xy 84.320974 -369.421764) (xy 84.314538 -369.425728)
			(xy 84.28228 -369.44554) (xy 84.274152 -369.450112) (xy 84.262722 -369.46332) (xy 84.233258 -369.541806)
			(xy 84.233004 -369.559586) (xy 84.236052 -369.568222) (xy 84.246338 -369.599091) (xy 84.257447 -369.663199)
			(xy 84.25815 -369.69573) (xy 84.257664 -369.722981) (xy 84.249908 -369.776929) (xy 84.234553 -369.829224)
			(xy 84.211911 -369.878801) (xy 84.182445 -369.924651) (xy 84.146754 -369.965842) (xy 84.105563 -370.001533)
			(xy 84.059713 -370.030999) (xy 84.010136 -370.053641) (xy 83.957841 -370.068996) (xy 83.903893 -370.076752)
			(xy 83.849391 -370.076752) (xy 83.795443 -370.068996) (xy 83.743148 -370.053641) (xy 83.693571 -370.030999)
			(xy 83.647721 -370.001533) (xy 83.60653 -369.965842) (xy 83.570839 -369.924651) (xy 83.541373 -369.878801)
			(xy 83.518731 -369.829224) (xy 83.503376 -369.776929) (xy 83.49562 -369.722981) (xy 83.495134 -369.69573)
			(xy 83.495483 -369.671658) (xy 83.501526 -369.623895) (xy 83.51352 -369.57727) (xy 83.522058 -369.55476)
			(xy 83.527138 -369.542314) (xy 83.523836 -369.516406) (xy 83.457034 -369.425728) (xy 83.433412 -369.414806)
			(xy 83.420204 -369.415822) (xy 83.391502 -369.416838) (xy 83.364251 -369.416315) (xy 83.310304 -369.408559)
			(xy 83.25801 -369.393204) (xy 83.208434 -369.370563) (xy 83.162584 -369.341098) (xy 83.121394 -369.305407)
			(xy 83.085703 -369.264218) (xy 83.056237 -369.218368) (xy 83.033597 -369.168792) (xy 83.018242 -369.116498)
			(xy 83.010485 -369.062551) (xy 79.149752 -369.062551) (xy 79.149752 -369.062553) (xy 79.141995 -369.116505)
			(xy 79.126639 -369.168804) (xy 79.103996 -369.218385) (xy 79.074528 -369.264239) (xy 79.038834 -369.305432)
			(xy 78.99764 -369.341126) (xy 78.951787 -369.370595) (xy 78.902206 -369.393238) (xy 78.849907 -369.408595)
			(xy 78.795955 -369.416352) (xy 78.768702 -369.416838) (xy 78.74 -369.415822) (xy 78.726792 -369.414806)
			(xy 78.70317 -369.425728) (xy 78.636368 -369.516406) (xy 78.633066 -369.542314) (xy 78.638146 -369.55476)
			(xy 78.646698 -369.577265) (xy 78.658696 -369.623891) (xy 78.664722 -369.671657) (xy 78.66507 -369.69573)
			(xy 78.664584 -369.722981) (xy 78.656828 -369.776929) (xy 78.641473 -369.829224) (xy 78.618831 -369.878801)
			(xy 78.589365 -369.924651) (xy 78.553674 -369.965842) (xy 78.512483 -370.001533) (xy 78.466633 -370.030999)
			(xy 78.417056 -370.053641) (xy 78.364761 -370.068996) (xy 78.310813 -370.076752) (xy 78.256311 -370.076752)
			(xy 78.202363 -370.068996) (xy 78.150068 -370.053641) (xy 78.100491 -370.030999) (xy 78.054641 -370.001533)
			(xy 78.01345 -369.965842) (xy 77.977759 -369.924651) (xy 77.948293 -369.878801) (xy 77.925651 -369.829224)
			(xy 77.910296 -369.776929) (xy 77.90254 -369.722981) (xy 77.902054 -369.69573) (xy 77.902736 -369.663198)
			(xy 77.913852 -369.599089) (xy 77.924152 -369.568222) (xy 77.9272 -369.559586) (xy 77.926946 -369.541806)
			(xy 77.897482 -369.46332) (xy 77.886052 -369.450112) (xy 77.877924 -369.44554) (xy 77.845666 -369.425728)
			(xy 77.839262 -369.421692) (xy 77.824785 -369.417296) (xy 77.817218 -369.417092) (xy 77.535786 -369.417092)
			(xy 77.528232 -369.41738) (xy 77.513774 -369.421764) (xy 77.507338 -369.425728) (xy 77.47508 -369.44554)
			(xy 77.466952 -369.450112) (xy 77.455522 -369.46332) (xy 77.426058 -369.541806) (xy 77.425804 -369.559586)
			(xy 77.428852 -369.568222) (xy 77.439138 -369.599091) (xy 77.450247 -369.663199) (xy 77.45095 -369.69573)
			(xy 77.450464 -369.722981) (xy 77.442708 -369.776929) (xy 77.427353 -369.829224) (xy 77.404711 -369.878801)
			(xy 77.375245 -369.924651) (xy 77.339554 -369.965842) (xy 77.298363 -370.001533) (xy 77.252513 -370.030999)
			(xy 77.202936 -370.053641) (xy 77.150641 -370.068996) (xy 77.096693 -370.076752) (xy 77.042191 -370.076752)
			(xy 76.988243 -370.068996) (xy 76.935948 -370.053641) (xy 76.886371 -370.030999) (xy 76.840521 -370.001533)
			(xy 76.79933 -369.965842) (xy 76.763639 -369.924651) (xy 76.734173 -369.878801) (xy 76.711531 -369.829224)
			(xy 76.696176 -369.776929) (xy 76.68842 -369.722981) (xy 76.687934 -369.69573) (xy 76.688283 -369.671658)
			(xy 76.694326 -369.623895) (xy 76.70632 -369.57727) (xy 76.714858 -369.55476) (xy 76.719938 -369.542314)
			(xy 76.716636 -369.516406) (xy 76.649834 -369.425728) (xy 76.626212 -369.414806) (xy 76.613004 -369.415822)
			(xy 76.584302 -369.416838) (xy 76.557051 -369.416315) (xy 76.503104 -369.408559) (xy 76.45081 -369.393204)
			(xy 76.401234 -369.370563) (xy 76.355384 -369.341098) (xy 76.314194 -369.305407) (xy 76.278503 -369.264218)
			(xy 76.249037 -369.218368) (xy 76.226397 -369.168792) (xy 76.211042 -369.116498) (xy 76.203285 -369.062551)
			(xy 70.447275 -369.062551) (xy 70.447275 -369.062557) (xy 70.439516 -369.116516) (xy 70.424157 -369.168822)
			(xy 70.401509 -369.218409) (xy 70.372034 -369.264268) (xy 70.336333 -369.305465) (xy 70.295131 -369.341162)
			(xy 70.249269 -369.370631) (xy 70.199679 -369.393273) (xy 70.147371 -369.408626) (xy 70.093411 -369.416378)
			(xy 70.066154 -369.416838) (xy 70.037452 -369.415822) (xy 70.024244 -369.414806) (xy 70.000622 -369.425728)
			(xy 69.93382 -369.516406) (xy 69.930518 -369.542314) (xy 69.935598 -369.55476) (xy 69.944148 -369.577266)
			(xy 69.956147 -369.623891) (xy 69.962174 -369.671657) (xy 69.962522 -369.69573) (xy 69.962036 -369.722981)
			(xy 69.95428 -369.776929) (xy 69.938925 -369.829224) (xy 69.916283 -369.878801) (xy 69.886817 -369.924651)
			(xy 69.851126 -369.965842) (xy 69.809935 -370.001533) (xy 69.764085 -370.030999) (xy 69.714508 -370.053641)
			(xy 69.662213 -370.068996) (xy 69.608265 -370.076752) (xy 69.553763 -370.076752) (xy 69.499815 -370.068996)
			(xy 69.44752 -370.053641) (xy 69.397943 -370.030999) (xy 69.352093 -370.001533) (xy 69.310902 -369.965842)
			(xy 69.275211 -369.924651) (xy 69.245745 -369.878801) (xy 69.223103 -369.829224) (xy 69.207748 -369.776929)
			(xy 69.199992 -369.722981) (xy 69.199506 -369.69573) (xy 69.200185 -369.663198) (xy 69.211303 -369.599088)
			(xy 69.221604 -369.568222) (xy 69.224652 -369.559586) (xy 69.224398 -369.541806) (xy 69.194934 -369.46332)
			(xy 69.183504 -369.450112) (xy 69.175376 -369.44554) (xy 69.143118 -369.425728) (xy 69.136703 -369.421712)
			(xy 69.122234 -369.417304) (xy 69.11467 -369.417092) (xy 68.833238 -369.417092) (xy 68.825683 -369.41736)
			(xy 68.811224 -369.421758) (xy 68.80479 -369.425728) (xy 68.772532 -369.44554) (xy 68.764404 -369.450112)
			(xy 68.752974 -369.46332) (xy 68.72351 -369.541806) (xy 68.723256 -369.559586) (xy 68.726304 -369.568222)
			(xy 68.736589 -369.599092) (xy 68.747699 -369.663199) (xy 68.748402 -369.69573) (xy 68.747916 -369.722981)
			(xy 68.74016 -369.776929) (xy 68.724805 -369.829224) (xy 68.702163 -369.878801) (xy 68.672697 -369.924651)
			(xy 68.637006 -369.965842) (xy 68.595815 -370.001533) (xy 68.549965 -370.030999) (xy 68.500388 -370.053641)
			(xy 68.448093 -370.068996) (xy 68.394145 -370.076752) (xy 68.339643 -370.076752) (xy 68.285695 -370.068996)
			(xy 68.2334 -370.053641) (xy 68.183823 -370.030999) (xy 68.137973 -370.001533) (xy 68.096782 -369.965842)
			(xy 68.061091 -369.924651) (xy 68.031625 -369.878801) (xy 68.008983 -369.829224) (xy 67.993628 -369.776929)
			(xy 67.985872 -369.722981) (xy 67.985386 -369.69573) (xy 67.985732 -369.671658) (xy 67.991775 -369.623895)
			(xy 68.003771 -369.577269) (xy 68.01231 -369.55476) (xy 68.01739 -369.542314) (xy 68.014088 -369.516406)
			(xy 67.947286 -369.425728) (xy 67.923664 -369.414806) (xy 67.910456 -369.415822) (xy 67.881754 -369.416838)
			(xy 67.854507 -369.416289) (xy 67.800569 -369.408527) (xy 67.748284 -369.39317) (xy 67.698716 -369.370528)
			(xy 67.652875 -369.341062) (xy 67.611694 -369.305374) (xy 67.57601 -369.264188) (xy 67.54655 -369.218343)
			(xy 67.523914 -369.168773) (xy 67.508563 -369.116486) (xy 67.500808 -369.062547) (xy 67.043675 -369.062547)
			(xy 67.043675 -369.062557) (xy 67.035916 -369.116516) (xy 67.020557 -369.168822) (xy 66.997909 -369.218409)
			(xy 66.968434 -369.264268) (xy 66.932733 -369.305465) (xy 66.891531 -369.341162) (xy 66.845669 -369.370631)
			(xy 66.796079 -369.393273) (xy 66.743771 -369.408626) (xy 66.689811 -369.416378) (xy 66.662554 -369.416838)
			(xy 66.633852 -369.415822) (xy 66.620644 -369.414806) (xy 66.597022 -369.425728) (xy 66.53022 -369.516406)
			(xy 66.526918 -369.542314) (xy 66.531998 -369.55476) (xy 66.540548 -369.577266) (xy 66.552547 -369.623891)
			(xy 66.558574 -369.671657) (xy 66.558922 -369.69573) (xy 66.558436 -369.722981) (xy 66.55068 -369.776929)
			(xy 66.535325 -369.829224) (xy 66.512683 -369.878801) (xy 66.483217 -369.924651) (xy 66.447526 -369.965842)
			(xy 66.406335 -370.001533) (xy 66.360485 -370.030999) (xy 66.310908 -370.053641) (xy 66.258613 -370.068996)
			(xy 66.204665 -370.076752) (xy 66.150163 -370.076752) (xy 66.096215 -370.068996) (xy 66.04392 -370.053641)
			(xy 65.994343 -370.030999) (xy 65.948493 -370.001533) (xy 65.907302 -369.965842) (xy 65.871611 -369.924651)
			(xy 65.842145 -369.878801) (xy 65.819503 -369.829224) (xy 65.804148 -369.776929) (xy 65.796392 -369.722981)
			(xy 65.795906 -369.69573) (xy 65.796585 -369.663198) (xy 65.807703 -369.599088) (xy 65.818004 -369.568222)
			(xy 65.821052 -369.559586) (xy 65.820798 -369.541806) (xy 65.791334 -369.46332) (xy 65.779904 -369.450112)
			(xy 65.771776 -369.44554) (xy 65.739518 -369.425728) (xy 65.733103 -369.421712) (xy 65.718634 -369.417304)
			(xy 65.71107 -369.417092) (xy 65.429638 -369.417092) (xy 65.422083 -369.41736) (xy 65.407624 -369.421758)
			(xy 65.40119 -369.425728) (xy 65.368932 -369.44554) (xy 65.360804 -369.450112) (xy 65.349374 -369.46332)
			(xy 65.31991 -369.541806) (xy 65.319656 -369.559586) (xy 65.322704 -369.568222) (xy 65.332989 -369.599092)
			(xy 65.344099 -369.663199) (xy 65.344802 -369.69573) (xy 65.344316 -369.722981) (xy 65.33656 -369.776929)
			(xy 65.321205 -369.829224) (xy 65.298563 -369.878801) (xy 65.269097 -369.924651) (xy 65.233406 -369.965842)
			(xy 65.192215 -370.001533) (xy 65.146365 -370.030999) (xy 65.096788 -370.053641) (xy 65.044493 -370.068996)
			(xy 64.990545 -370.076752) (xy 64.936043 -370.076752) (xy 64.882095 -370.068996) (xy 64.8298 -370.053641)
			(xy 64.780223 -370.030999) (xy 64.734373 -370.001533) (xy 64.693182 -369.965842) (xy 64.657491 -369.924651)
			(xy 64.628025 -369.878801) (xy 64.605383 -369.829224) (xy 64.590028 -369.776929) (xy 64.582272 -369.722981)
			(xy 64.581786 -369.69573) (xy 64.582132 -369.671658) (xy 64.588175 -369.623895) (xy 64.600171 -369.577269)
			(xy 64.60871 -369.55476) (xy 64.61379 -369.542314) (xy 64.610488 -369.516406) (xy 64.543686 -369.425728)
			(xy 64.520064 -369.414806) (xy 64.506856 -369.415822) (xy 64.478154 -369.416838) (xy 64.450907 -369.416289)
			(xy 64.396969 -369.408527) (xy 64.344684 -369.39317) (xy 64.295116 -369.370528) (xy 64.249275 -369.341062)
			(xy 64.208094 -369.305374) (xy 64.17241 -369.264188) (xy 64.14295 -369.218343) (xy 64.120314 -369.168773)
			(xy 64.104963 -369.116486) (xy 64.097208 -369.062547) (xy 60.236475 -369.062547) (xy 60.236475 -369.062557)
			(xy 60.228716 -369.116516) (xy 60.213357 -369.168822) (xy 60.190709 -369.218409) (xy 60.161234 -369.264268)
			(xy 60.125533 -369.305465) (xy 60.084331 -369.341162) (xy 60.038469 -369.370631) (xy 59.988879 -369.393273)
			(xy 59.936571 -369.408626) (xy 59.882611 -369.416378) (xy 59.855354 -369.416838) (xy 59.826652 -369.415822)
			(xy 59.813444 -369.414806) (xy 59.789822 -369.425728) (xy 59.72302 -369.516406) (xy 59.719718 -369.542314)
			(xy 59.724798 -369.55476) (xy 59.733348 -369.577266) (xy 59.745347 -369.623891) (xy 59.751374 -369.671657)
			(xy 59.751722 -369.69573) (xy 59.751236 -369.722981) (xy 59.74348 -369.776929) (xy 59.728125 -369.829224)
			(xy 59.705483 -369.878801) (xy 59.676017 -369.924651) (xy 59.640326 -369.965842) (xy 59.599135 -370.001533)
			(xy 59.553285 -370.030999) (xy 59.503708 -370.053641) (xy 59.451413 -370.068996) (xy 59.397465 -370.076752)
			(xy 59.342963 -370.076752) (xy 59.289015 -370.068996) (xy 59.23672 -370.053641) (xy 59.187143 -370.030999)
			(xy 59.141293 -370.001533) (xy 59.100102 -369.965842) (xy 59.064411 -369.924651) (xy 59.034945 -369.878801)
			(xy 59.012303 -369.829224) (xy 58.996948 -369.776929) (xy 58.989192 -369.722981) (xy 58.988706 -369.69573)
			(xy 58.989385 -369.663198) (xy 59.000503 -369.599088) (xy 59.010804 -369.568222) (xy 59.013852 -369.559586)
			(xy 59.013598 -369.541806) (xy 58.984134 -369.46332) (xy 58.972704 -369.450112) (xy 58.964576 -369.44554)
			(xy 58.932318 -369.425728) (xy 58.925903 -369.421712) (xy 58.911434 -369.417304) (xy 58.90387 -369.417092)
			(xy 58.622438 -369.417092) (xy 58.614883 -369.41736) (xy 58.600424 -369.421758) (xy 58.59399 -369.425728)
			(xy 58.561732 -369.44554) (xy 58.553604 -369.450112) (xy 58.542174 -369.46332) (xy 58.51271 -369.541806)
			(xy 58.512456 -369.559586) (xy 58.515504 -369.568222) (xy 58.525789 -369.599092) (xy 58.536899 -369.663199)
			(xy 58.537602 -369.69573) (xy 58.537116 -369.722981) (xy 58.52936 -369.776929) (xy 58.514005 -369.829224)
			(xy 58.491363 -369.878801) (xy 58.461897 -369.924651) (xy 58.426206 -369.965842) (xy 58.385015 -370.001533)
			(xy 58.339165 -370.030999) (xy 58.289588 -370.053641) (xy 58.237293 -370.068996) (xy 58.183345 -370.076752)
			(xy 58.128843 -370.076752) (xy 58.074895 -370.068996) (xy 58.0226 -370.053641) (xy 57.973023 -370.030999)
			(xy 57.927173 -370.001533) (xy 57.885982 -369.965842) (xy 57.850291 -369.924651) (xy 57.820825 -369.878801)
			(xy 57.798183 -369.829224) (xy 57.782828 -369.776929) (xy 57.775072 -369.722981) (xy 57.774586 -369.69573)
			(xy 57.774932 -369.671658) (xy 57.780975 -369.623895) (xy 57.792971 -369.577269) (xy 57.80151 -369.55476)
			(xy 57.80659 -369.542314) (xy 57.803288 -369.516406) (xy 57.736486 -369.425728) (xy 57.712864 -369.414806)
			(xy 57.699656 -369.415822) (xy 57.670954 -369.416838) (xy 57.643707 -369.416289) (xy 57.589769 -369.408527)
			(xy 57.537484 -369.39317) (xy 57.487916 -369.370528) (xy 57.442075 -369.341062) (xy 57.400894 -369.305374)
			(xy 57.36521 -369.264188) (xy 57.33575 -369.218343) (xy 57.313114 -369.168773) (xy 57.297763 -369.116486)
			(xy 57.290008 -369.062547) (xy 53.429275 -369.062547) (xy 53.429275 -369.062557) (xy 53.421516 -369.116516)
			(xy 53.406157 -369.168822) (xy 53.383509 -369.218409) (xy 53.354034 -369.264268) (xy 53.318333 -369.305465)
			(xy 53.277131 -369.341162) (xy 53.231269 -369.370631) (xy 53.181679 -369.393273) (xy 53.129371 -369.408626)
			(xy 53.075411 -369.416378) (xy 53.048154 -369.416838) (xy 53.019452 -369.415822) (xy 53.006244 -369.414806)
			(xy 52.982622 -369.425728) (xy 52.91582 -369.516406) (xy 52.912518 -369.542314) (xy 52.917598 -369.55476)
			(xy 52.926148 -369.577266) (xy 52.938147 -369.623891) (xy 52.944174 -369.671657) (xy 52.944522 -369.69573)
			(xy 52.944036 -369.722981) (xy 52.93628 -369.776929) (xy 52.920925 -369.829224) (xy 52.898283 -369.878801)
			(xy 52.868817 -369.924651) (xy 52.833126 -369.965842) (xy 52.791935 -370.001533) (xy 52.746085 -370.030999)
			(xy 52.696508 -370.053641) (xy 52.644213 -370.068996) (xy 52.590265 -370.076752) (xy 52.535763 -370.076752)
			(xy 52.481815 -370.068996) (xy 52.42952 -370.053641) (xy 52.379943 -370.030999) (xy 52.334093 -370.001533)
			(xy 52.292902 -369.965842) (xy 52.257211 -369.924651) (xy 52.227745 -369.878801) (xy 52.205103 -369.829224)
			(xy 52.189748 -369.776929) (xy 52.181992 -369.722981) (xy 52.181506 -369.69573) (xy 52.182185 -369.663198)
			(xy 52.193303 -369.599088) (xy 52.203604 -369.568222) (xy 52.206652 -369.559586) (xy 52.206398 -369.541806)
			(xy 52.176934 -369.46332) (xy 52.165504 -369.450112) (xy 52.157376 -369.44554) (xy 52.125118 -369.425728)
			(xy 52.118703 -369.421712) (xy 52.104234 -369.417304) (xy 52.09667 -369.417092) (xy 51.815238 -369.417092)
			(xy 51.807683 -369.41736) (xy 51.793224 -369.421758) (xy 51.78679 -369.425728) (xy 51.754532 -369.44554)
			(xy 51.746404 -369.450112) (xy 51.734974 -369.46332) (xy 51.70551 -369.541806) (xy 51.705256 -369.559586)
			(xy 51.708304 -369.568222) (xy 51.718589 -369.599092) (xy 51.729699 -369.663199) (xy 51.730402 -369.69573)
			(xy 51.729916 -369.722981) (xy 51.72216 -369.776929) (xy 51.706805 -369.829224) (xy 51.684163 -369.878801)
			(xy 51.654697 -369.924651) (xy 51.619006 -369.965842) (xy 51.577815 -370.001533) (xy 51.531965 -370.030999)
			(xy 51.482388 -370.053641) (xy 51.430093 -370.068996) (xy 51.376145 -370.076752) (xy 51.321643 -370.076752)
			(xy 51.267695 -370.068996) (xy 51.2154 -370.053641) (xy 51.165823 -370.030999) (xy 51.119973 -370.001533)
			(xy 51.078782 -369.965842) (xy 51.043091 -369.924651) (xy 51.013625 -369.878801) (xy 50.990983 -369.829224)
			(xy 50.975628 -369.776929) (xy 50.967872 -369.722981) (xy 50.967386 -369.69573) (xy 50.967732 -369.671658)
			(xy 50.973775 -369.623895) (xy 50.985771 -369.577269) (xy 50.99431 -369.55476) (xy 50.99939 -369.542314)
			(xy 50.996088 -369.516406) (xy 50.929286 -369.425728) (xy 50.905664 -369.414806) (xy 50.892456 -369.415822)
			(xy 50.863754 -369.416838) (xy 50.836507 -369.416289) (xy 50.782569 -369.408527) (xy 50.730284 -369.39317)
			(xy 50.680716 -369.370528) (xy 50.634875 -369.341062) (xy 50.593694 -369.305374) (xy 50.55801 -369.264188)
			(xy 50.52855 -369.218343) (xy 50.505914 -369.168773) (xy 50.490563 -369.116486) (xy 50.482808 -369.062547)
			(xy 46.622075 -369.062547) (xy 46.622075 -369.062557) (xy 46.614316 -369.116516) (xy 46.598957 -369.168822)
			(xy 46.576309 -369.218409) (xy 46.546834 -369.264268) (xy 46.511133 -369.305465) (xy 46.469931 -369.341162)
			(xy 46.424069 -369.370631) (xy 46.374479 -369.393273) (xy 46.322171 -369.408626) (xy 46.268211 -369.416378)
			(xy 46.240954 -369.416838) (xy 46.212252 -369.415822) (xy 46.199044 -369.414806) (xy 46.175422 -369.425728)
			(xy 46.10862 -369.516406) (xy 46.105318 -369.542314) (xy 46.110398 -369.55476) (xy 46.118948 -369.577266)
			(xy 46.130947 -369.623891) (xy 46.136974 -369.671657) (xy 46.137322 -369.69573) (xy 46.136836 -369.722981)
			(xy 46.12908 -369.776929) (xy 46.113725 -369.829224) (xy 46.091083 -369.878801) (xy 46.061617 -369.924651)
			(xy 46.025926 -369.965842) (xy 45.984735 -370.001533) (xy 45.938885 -370.030999) (xy 45.889308 -370.053641)
			(xy 45.837013 -370.068996) (xy 45.783065 -370.076752) (xy 45.728563 -370.076752) (xy 45.674615 -370.068996)
			(xy 45.62232 -370.053641) (xy 45.572743 -370.030999) (xy 45.526893 -370.001533) (xy 45.485702 -369.965842)
			(xy 45.450011 -369.924651) (xy 45.420545 -369.878801) (xy 45.397903 -369.829224) (xy 45.382548 -369.776929)
			(xy 45.374792 -369.722981) (xy 45.374306 -369.69573) (xy 45.374985 -369.663198) (xy 45.386103 -369.599088)
			(xy 45.396404 -369.568222) (xy 45.399452 -369.559586) (xy 45.399198 -369.541806) (xy 45.369734 -369.46332)
			(xy 45.358304 -369.450112) (xy 45.350176 -369.44554) (xy 45.317918 -369.425728) (xy 45.311503 -369.421712)
			(xy 45.297034 -369.417304) (xy 45.28947 -369.417092) (xy 45.008038 -369.417092) (xy 45.000483 -369.41736)
			(xy 44.986024 -369.421758) (xy 44.97959 -369.425728) (xy 44.947332 -369.44554) (xy 44.939204 -369.450112)
			(xy 44.927774 -369.46332) (xy 44.89831 -369.541806) (xy 44.898056 -369.559586) (xy 44.901104 -369.568222)
			(xy 44.911389 -369.599092) (xy 44.922499 -369.663199) (xy 44.923202 -369.69573) (xy 44.922716 -369.722981)
			(xy 44.91496 -369.776929) (xy 44.899605 -369.829224) (xy 44.876963 -369.878801) (xy 44.847497 -369.924651)
			(xy 44.811806 -369.965842) (xy 44.770615 -370.001533) (xy 44.724765 -370.030999) (xy 44.675188 -370.053641)
			(xy 44.622893 -370.068996) (xy 44.568945 -370.076752) (xy 44.514443 -370.076752) (xy 44.460495 -370.068996)
			(xy 44.4082 -370.053641) (xy 44.358623 -370.030999) (xy 44.312773 -370.001533) (xy 44.271582 -369.965842)
			(xy 44.235891 -369.924651) (xy 44.206425 -369.878801) (xy 44.183783 -369.829224) (xy 44.168428 -369.776929)
			(xy 44.160672 -369.722981) (xy 44.160186 -369.69573) (xy 44.160532 -369.671658) (xy 44.166575 -369.623895)
			(xy 44.178571 -369.577269) (xy 44.18711 -369.55476) (xy 44.19219 -369.542314) (xy 44.188888 -369.516406)
			(xy 44.122086 -369.425728) (xy 44.098464 -369.414806) (xy 44.085256 -369.415822) (xy 44.056554 -369.416838)
			(xy 44.029307 -369.416289) (xy 43.975369 -369.408527) (xy 43.923084 -369.39317) (xy 43.873516 -369.370528)
			(xy 43.827675 -369.341062) (xy 43.786494 -369.305374) (xy 43.75081 -369.264188) (xy 43.72135 -369.218343)
			(xy 43.698714 -369.168773) (xy 43.683363 -369.116486) (xy 43.675608 -369.062547) (xy 42.231271 -369.062547)
			(xy 41.028112 -370.265706) (xy 41.021334 -370.27313) (xy 41.013741 -370.291727) (xy 41.01338 -370.301774)
			(xy 41.01338 -371.526347) (xy 41.973808 -371.526347) (xy 41.973808 -371.471853) (xy 41.981563 -371.417914)
			(xy 41.996914 -371.365627) (xy 42.01955 -371.316057) (xy 42.04901 -371.270212) (xy 42.084694 -371.229026)
			(xy 42.125875 -371.193338) (xy 42.171716 -371.163872) (xy 42.221284 -371.14123) (xy 42.273569 -371.125873)
			(xy 42.327507 -371.118111) (xy 42.354754 -371.117622) (xy 42.383456 -371.118638) (xy 42.396664 -371.119654)
			(xy 42.420286 -371.108732) (xy 42.487088 -371.018054) (xy 42.49039 -370.992146) (xy 42.48531 -370.9797)
			(xy 42.476778 -370.957188) (xy 42.464772 -370.910566) (xy 42.458738 -370.862802) (xy 42.458386 -370.83873)
			(xy 42.458872 -370.811479) (xy 42.466628 -370.757531) (xy 42.481983 -370.705236) (xy 42.504625 -370.655659)
			(xy 42.534091 -370.609809) (xy 42.569782 -370.568618) (xy 42.610973 -370.532927) (xy 42.656823 -370.503461)
			(xy 42.7064 -370.480819) (xy 42.758695 -370.465464) (xy 42.812643 -370.457708) (xy 42.867145 -370.457708)
			(xy 42.921093 -370.465464) (xy 42.973388 -370.480819) (xy 43.022965 -370.503461) (xy 43.068815 -370.532927)
			(xy 43.110006 -370.568618) (xy 43.145697 -370.609809) (xy 43.175163 -370.655659) (xy 43.197805 -370.705236)
			(xy 43.21316 -370.757531) (xy 43.220916 -370.811479) (xy 43.221402 -370.83873) (xy 43.220713 -370.871262)
			(xy 43.209602 -370.935371) (xy 43.199304 -370.966238) (xy 43.196256 -370.974874) (xy 43.19651 -370.992654)
			(xy 43.225974 -371.07114) (xy 43.237404 -371.084348) (xy 43.245532 -371.08892) (xy 43.27779 -371.108732)
			(xy 43.2842 -371.112757) (xy 43.298673 -371.117159) (xy 43.306238 -371.117368) (xy 43.58767 -371.117368)
			(xy 43.595225 -371.117094) (xy 43.609683 -371.112699) (xy 43.616118 -371.108732) (xy 43.648376 -371.08892)
			(xy 43.656504 -371.084348) (xy 43.667934 -371.07114) (xy 43.697398 -370.992654) (xy 43.697652 -370.974874)
			(xy 43.694604 -370.966238) (xy 43.68431 -370.935371) (xy 43.673206 -370.871261) (xy 43.672506 -370.83873)
			(xy 43.672992 -370.811479) (xy 43.680748 -370.757531) (xy 43.696103 -370.705236) (xy 43.718745 -370.655659)
			(xy 43.748211 -370.609809) (xy 43.783902 -370.568618) (xy 43.825093 -370.532927) (xy 43.870943 -370.503461)
			(xy 43.92052 -370.480819) (xy 43.972815 -370.465464) (xy 44.026763 -370.457708) (xy 44.081265 -370.457708)
			(xy 44.135213 -370.465464) (xy 44.187508 -370.480819) (xy 44.237085 -370.503461) (xy 44.282935 -370.532927)
			(xy 44.324126 -370.568618) (xy 44.359817 -370.609809) (xy 44.389283 -370.655659) (xy 44.411925 -370.705236)
			(xy 44.42728 -370.757531) (xy 44.435036 -370.811479) (xy 44.435522 -370.83873) (xy 44.435163 -370.862802)
			(xy 44.429125 -370.910564) (xy 44.417135 -370.95719) (xy 44.408598 -370.9797) (xy 44.403518 -370.992146)
			(xy 44.40682 -371.018054) (xy 44.473622 -371.108732) (xy 44.497244 -371.119654) (xy 44.510452 -371.118638)
			(xy 44.539154 -371.117622) (xy 44.566411 -371.118022) (xy 44.620371 -371.125774) (xy 44.672679 -371.141127)
			(xy 44.722269 -371.163769) (xy 44.768131 -371.193238) (xy 44.809333 -371.228935) (xy 44.845034 -371.270132)
			(xy 44.874509 -371.315991) (xy 44.897157 -371.365578) (xy 44.912516 -371.417884) (xy 44.920275 -371.471843)
			(xy 44.920275 -371.526347) (xy 48.781008 -371.526347) (xy 48.781008 -371.471853) (xy 48.788763 -371.417914)
			(xy 48.804114 -371.365627) (xy 48.82675 -371.316057) (xy 48.85621 -371.270212) (xy 48.891894 -371.229026)
			(xy 48.933075 -371.193338) (xy 48.978916 -371.163872) (xy 49.028484 -371.14123) (xy 49.080769 -371.125873)
			(xy 49.134707 -371.118111) (xy 49.161954 -371.117622) (xy 49.190656 -371.118638) (xy 49.203864 -371.119654)
			(xy 49.227486 -371.108732) (xy 49.294288 -371.018054) (xy 49.29759 -370.992146) (xy 49.29251 -370.9797)
			(xy 49.283978 -370.957188) (xy 49.271972 -370.910566) (xy 49.265938 -370.862802) (xy 49.265586 -370.83873)
			(xy 49.266072 -370.811479) (xy 49.273828 -370.757531) (xy 49.289183 -370.705236) (xy 49.311825 -370.655659)
			(xy 49.341291 -370.609809) (xy 49.376982 -370.568618) (xy 49.418173 -370.532927) (xy 49.464023 -370.503461)
			(xy 49.5136 -370.480819) (xy 49.565895 -370.465464) (xy 49.619843 -370.457708) (xy 49.674345 -370.457708)
			(xy 49.728293 -370.465464) (xy 49.780588 -370.480819) (xy 49.830165 -370.503461) (xy 49.876015 -370.532927)
			(xy 49.917206 -370.568618) (xy 49.952897 -370.609809) (xy 49.982363 -370.655659) (xy 50.005005 -370.705236)
			(xy 50.02036 -370.757531) (xy 50.028116 -370.811479) (xy 50.028602 -370.83873) (xy 50.027913 -370.871262)
			(xy 50.016802 -370.935371) (xy 50.006504 -370.966238) (xy 50.003456 -370.974874) (xy 50.00371 -370.992654)
			(xy 50.033174 -371.07114) (xy 50.044604 -371.084348) (xy 50.052732 -371.08892) (xy 50.08499 -371.108732)
			(xy 50.0914 -371.112757) (xy 50.105873 -371.117159) (xy 50.113438 -371.117368) (xy 50.39487 -371.117368)
			(xy 50.402425 -371.117094) (xy 50.416883 -371.112699) (xy 50.423318 -371.108732) (xy 50.455576 -371.08892)
			(xy 50.463704 -371.084348) (xy 50.475134 -371.07114) (xy 50.504598 -370.992654) (xy 50.504852 -370.974874)
			(xy 50.501804 -370.966238) (xy 50.49151 -370.935371) (xy 50.480406 -370.871261) (xy 50.479706 -370.83873)
			(xy 50.480192 -370.811479) (xy 50.487948 -370.757531) (xy 50.503303 -370.705236) (xy 50.525945 -370.655659)
			(xy 50.555411 -370.609809) (xy 50.591102 -370.568618) (xy 50.632293 -370.532927) (xy 50.678143 -370.503461)
			(xy 50.72772 -370.480819) (xy 50.780015 -370.465464) (xy 50.833963 -370.457708) (xy 50.888465 -370.457708)
			(xy 50.942413 -370.465464) (xy 50.994708 -370.480819) (xy 51.044285 -370.503461) (xy 51.090135 -370.532927)
			(xy 51.131326 -370.568618) (xy 51.167017 -370.609809) (xy 51.196483 -370.655659) (xy 51.219125 -370.705236)
			(xy 51.23448 -370.757531) (xy 51.242236 -370.811479) (xy 51.242722 -370.83873) (xy 51.242363 -370.862802)
			(xy 51.236325 -370.910564) (xy 51.224335 -370.95719) (xy 51.215798 -370.9797) (xy 51.210718 -370.992146)
			(xy 51.21402 -371.018054) (xy 51.280822 -371.108732) (xy 51.304444 -371.119654) (xy 51.317652 -371.118638)
			(xy 51.346354 -371.117622) (xy 51.373611 -371.118022) (xy 51.427571 -371.125774) (xy 51.479879 -371.141127)
			(xy 51.529469 -371.163769) (xy 51.575331 -371.193238) (xy 51.616533 -371.228935) (xy 51.652234 -371.270132)
			(xy 51.681709 -371.315991) (xy 51.704357 -371.365578) (xy 51.719716 -371.417884) (xy 51.727475 -371.471843)
			(xy 51.727475 -371.526347) (xy 55.588208 -371.526347) (xy 55.588208 -371.471853) (xy 55.595963 -371.417914)
			(xy 55.611314 -371.365627) (xy 55.63395 -371.316057) (xy 55.66341 -371.270212) (xy 55.699094 -371.229026)
			(xy 55.740275 -371.193338) (xy 55.786116 -371.163872) (xy 55.835684 -371.14123) (xy 55.887969 -371.125873)
			(xy 55.941907 -371.118111) (xy 55.969154 -371.117622) (xy 55.997856 -371.118638) (xy 56.011064 -371.119654)
			(xy 56.034686 -371.108732) (xy 56.101488 -371.018054) (xy 56.10479 -370.992146) (xy 56.09971 -370.9797)
			(xy 56.091178 -370.957188) (xy 56.079172 -370.910566) (xy 56.073138 -370.862802) (xy 56.072786 -370.83873)
			(xy 56.073272 -370.811479) (xy 56.081028 -370.757531) (xy 56.096383 -370.705236) (xy 56.119025 -370.655659)
			(xy 56.148491 -370.609809) (xy 56.184182 -370.568618) (xy 56.225373 -370.532927) (xy 56.271223 -370.503461)
			(xy 56.3208 -370.480819) (xy 56.373095 -370.465464) (xy 56.427043 -370.457708) (xy 56.481545 -370.457708)
			(xy 56.535493 -370.465464) (xy 56.587788 -370.480819) (xy 56.637365 -370.503461) (xy 56.683215 -370.532927)
			(xy 56.724406 -370.568618) (xy 56.760097 -370.609809) (xy 56.789563 -370.655659) (xy 56.812205 -370.705236)
			(xy 56.82756 -370.757531) (xy 56.835316 -370.811479) (xy 56.835802 -370.83873) (xy 56.835113 -370.871262)
			(xy 56.824002 -370.935371) (xy 56.813704 -370.966238) (xy 56.810656 -370.974874) (xy 56.81091 -370.992654)
			(xy 56.840374 -371.07114) (xy 56.851804 -371.084348) (xy 56.859932 -371.08892) (xy 56.89219 -371.108732)
			(xy 56.8986 -371.112757) (xy 56.913073 -371.117159) (xy 56.920638 -371.117368) (xy 57.20207 -371.117368)
			(xy 57.209625 -371.117094) (xy 57.224083 -371.112699) (xy 57.230518 -371.108732) (xy 57.262776 -371.08892)
			(xy 57.270904 -371.084348) (xy 57.282334 -371.07114) (xy 57.311798 -370.992654) (xy 57.312052 -370.974874)
			(xy 57.309004 -370.966238) (xy 57.29871 -370.935371) (xy 57.287606 -370.871261) (xy 57.286906 -370.83873)
			(xy 57.287392 -370.811479) (xy 57.295148 -370.757531) (xy 57.310503 -370.705236) (xy 57.333145 -370.655659)
			(xy 57.362611 -370.609809) (xy 57.398302 -370.568618) (xy 57.439493 -370.532927) (xy 57.485343 -370.503461)
			(xy 57.53492 -370.480819) (xy 57.587215 -370.465464) (xy 57.641163 -370.457708) (xy 57.695665 -370.457708)
			(xy 57.749613 -370.465464) (xy 57.801908 -370.480819) (xy 57.851485 -370.503461) (xy 57.897335 -370.532927)
			(xy 57.938526 -370.568618) (xy 57.974217 -370.609809) (xy 58.003683 -370.655659) (xy 58.026325 -370.705236)
			(xy 58.04168 -370.757531) (xy 58.049436 -370.811479) (xy 58.049922 -370.83873) (xy 58.049563 -370.862802)
			(xy 58.043525 -370.910564) (xy 58.031535 -370.95719) (xy 58.022998 -370.9797) (xy 58.017918 -370.992146)
			(xy 58.02122 -371.018054) (xy 58.088022 -371.108732) (xy 58.111644 -371.119654) (xy 58.124852 -371.118638)
			(xy 58.153554 -371.117622) (xy 58.180811 -371.118022) (xy 58.234771 -371.125774) (xy 58.287079 -371.141127)
			(xy 58.336669 -371.163769) (xy 58.382531 -371.193238) (xy 58.423733 -371.228935) (xy 58.459434 -371.270132)
			(xy 58.488909 -371.315991) (xy 58.511557 -371.365578) (xy 58.526916 -371.417884) (xy 58.534675 -371.471843)
			(xy 58.534675 -371.526347) (xy 62.395408 -371.526347) (xy 62.395408 -371.471853) (xy 62.403163 -371.417914)
			(xy 62.418514 -371.365627) (xy 62.44115 -371.316057) (xy 62.47061 -371.270212) (xy 62.506294 -371.229026)
			(xy 62.547475 -371.193338) (xy 62.593316 -371.163872) (xy 62.642884 -371.14123) (xy 62.695169 -371.125873)
			(xy 62.749107 -371.118111) (xy 62.776354 -371.117622) (xy 62.805056 -371.118638) (xy 62.818264 -371.119654)
			(xy 62.841886 -371.108732) (xy 62.908688 -371.018054) (xy 62.91199 -370.992146) (xy 62.90691 -370.9797)
			(xy 62.898378 -370.957188) (xy 62.886372 -370.910566) (xy 62.880338 -370.862802) (xy 62.879986 -370.83873)
			(xy 62.880472 -370.811479) (xy 62.888228 -370.757531) (xy 62.903583 -370.705236) (xy 62.926225 -370.655659)
			(xy 62.955691 -370.609809) (xy 62.991382 -370.568618) (xy 63.032573 -370.532927) (xy 63.078423 -370.503461)
			(xy 63.128 -370.480819) (xy 63.180295 -370.465464) (xy 63.234243 -370.457708) (xy 63.288745 -370.457708)
			(xy 63.342693 -370.465464) (xy 63.394988 -370.480819) (xy 63.444565 -370.503461) (xy 63.490415 -370.532927)
			(xy 63.531606 -370.568618) (xy 63.567297 -370.609809) (xy 63.596763 -370.655659) (xy 63.619405 -370.705236)
			(xy 63.63476 -370.757531) (xy 63.642516 -370.811479) (xy 63.643002 -370.83873) (xy 63.642313 -370.871262)
			(xy 63.631202 -370.935371) (xy 63.620904 -370.966238) (xy 63.617856 -370.974874) (xy 63.61811 -370.992654)
			(xy 63.647574 -371.07114) (xy 63.659004 -371.084348) (xy 63.667132 -371.08892) (xy 63.69939 -371.108732)
			(xy 63.7058 -371.112757) (xy 63.720273 -371.117159) (xy 63.727838 -371.117368) (xy 64.00927 -371.117368)
			(xy 64.016825 -371.117094) (xy 64.031283 -371.112699) (xy 64.037718 -371.108732) (xy 64.069976 -371.08892)
			(xy 64.078104 -371.084348) (xy 64.089534 -371.07114) (xy 64.118998 -370.992654) (xy 64.119252 -370.974874)
			(xy 64.116204 -370.966238) (xy 64.10591 -370.935371) (xy 64.094806 -370.871261) (xy 64.094106 -370.83873)
			(xy 64.094592 -370.811479) (xy 64.102348 -370.757531) (xy 64.117703 -370.705236) (xy 64.140345 -370.655659)
			(xy 64.169811 -370.609809) (xy 64.205502 -370.568618) (xy 64.246693 -370.532927) (xy 64.292543 -370.503461)
			(xy 64.34212 -370.480819) (xy 64.394415 -370.465464) (xy 64.448363 -370.457708) (xy 64.502865 -370.457708)
			(xy 64.556813 -370.465464) (xy 64.609108 -370.480819) (xy 64.658685 -370.503461) (xy 64.704535 -370.532927)
			(xy 64.745726 -370.568618) (xy 64.781417 -370.609809) (xy 64.810883 -370.655659) (xy 64.833525 -370.705236)
			(xy 64.84888 -370.757531) (xy 64.856636 -370.811479) (xy 64.857122 -370.83873) (xy 64.856763 -370.862802)
			(xy 64.850725 -370.910564) (xy 64.838735 -370.95719) (xy 64.830198 -370.9797) (xy 64.825118 -370.992146)
			(xy 64.82842 -371.018054) (xy 64.895222 -371.108732) (xy 64.918844 -371.119654) (xy 64.932052 -371.118638)
			(xy 64.960754 -371.117622) (xy 64.988011 -371.118022) (xy 65.041971 -371.125774) (xy 65.094279 -371.141127)
			(xy 65.143869 -371.163769) (xy 65.189731 -371.193238) (xy 65.230933 -371.228935) (xy 65.266634 -371.270132)
			(xy 65.296109 -371.315991) (xy 65.318757 -371.365578) (xy 65.334116 -371.417884) (xy 65.341875 -371.471843)
			(xy 65.341875 -371.526351) (xy 74.501485 -371.526351) (xy 74.501485 -371.471849) (xy 74.509242 -371.417902)
			(xy 74.524597 -371.365608) (xy 74.547237 -371.316032) (xy 74.576703 -371.270182) (xy 74.612394 -371.228993)
			(xy 74.653584 -371.193302) (xy 74.699434 -371.163837) (xy 74.74901 -371.141196) (xy 74.801304 -371.125841)
			(xy 74.855251 -371.118085) (xy 74.882502 -371.117622) (xy 74.911204 -371.118638) (xy 74.924412 -371.119654)
			(xy 74.948034 -371.108732) (xy 75.014836 -371.018054) (xy 75.018138 -370.992146) (xy 75.013058 -370.9797)
			(xy 75.004524 -370.957189) (xy 74.992519 -370.910566) (xy 74.986486 -370.862802) (xy 74.986134 -370.83873)
			(xy 74.98662 -370.811479) (xy 74.994376 -370.757531) (xy 75.009731 -370.705236) (xy 75.032373 -370.655659)
			(xy 75.061839 -370.609809) (xy 75.09753 -370.568618) (xy 75.138721 -370.532927) (xy 75.184571 -370.503461)
			(xy 75.234148 -370.480819) (xy 75.286443 -370.465464) (xy 75.340391 -370.457708) (xy 75.394893 -370.457708)
			(xy 75.448841 -370.465464) (xy 75.501136 -370.480819) (xy 75.550713 -370.503461) (xy 75.596563 -370.532927)
			(xy 75.637754 -370.568618) (xy 75.673445 -370.609809) (xy 75.702911 -370.655659) (xy 75.725553 -370.705236)
			(xy 75.740908 -370.757531) (xy 75.748664 -370.811479) (xy 75.74915 -370.83873) (xy 75.748458 -370.871262)
			(xy 75.737349 -370.935371) (xy 75.727052 -370.966238) (xy 75.724004 -370.974874) (xy 75.724258 -370.992654)
			(xy 75.753722 -371.07114) (xy 75.765152 -371.084348) (xy 75.77328 -371.08892) (xy 75.805538 -371.108732)
			(xy 75.811938 -371.112775) (xy 75.826418 -371.117165) (xy 75.833986 -371.117368) (xy 76.115418 -371.117368)
			(xy 76.122971 -371.117072) (xy 76.137429 -371.112692) (xy 76.143866 -371.108732) (xy 76.176124 -371.08892)
			(xy 76.184252 -371.084348) (xy 76.195682 -371.07114) (xy 76.225146 -370.992654) (xy 76.2254 -370.974874)
			(xy 76.222352 -370.966238) (xy 76.212056 -370.935371) (xy 76.200953 -370.871261) (xy 76.200254 -370.83873)
			(xy 76.20074 -370.811479) (xy 76.208496 -370.757531) (xy 76.223851 -370.705236) (xy 76.246493 -370.655659)
			(xy 76.275959 -370.609809) (xy 76.31165 -370.568618) (xy 76.352841 -370.532927) (xy 76.398691 -370.503461)
			(xy 76.448268 -370.480819) (xy 76.500563 -370.465464) (xy 76.554511 -370.457708) (xy 76.609013 -370.457708)
			(xy 76.662961 -370.465464) (xy 76.715256 -370.480819) (xy 76.764833 -370.503461) (xy 76.810683 -370.532927)
			(xy 76.851874 -370.568618) (xy 76.887565 -370.609809) (xy 76.917031 -370.655659) (xy 76.939673 -370.705236)
			(xy 76.955028 -370.757531) (xy 76.962784 -370.811479) (xy 76.96327 -370.83873) (xy 76.962908 -370.862801)
			(xy 76.95687 -370.910564) (xy 76.944882 -370.95719) (xy 76.936346 -370.9797) (xy 76.931266 -370.992146)
			(xy 76.934568 -371.018054) (xy 77.00137 -371.108732) (xy 77.024992 -371.119654) (xy 77.0382 -371.118638)
			(xy 77.066902 -371.117622) (xy 77.094155 -371.118048) (xy 77.148107 -371.125805) (xy 77.200406 -371.141162)
			(xy 77.249987 -371.163805) (xy 77.29584 -371.193274) (xy 77.337034 -371.228968) (xy 77.372728 -371.270161)
			(xy 77.402196 -371.316015) (xy 77.424839 -371.365596) (xy 77.440195 -371.417895) (xy 77.447952 -371.471847)
			(xy 77.447952 -371.526351) (xy 81.308685 -371.526351) (xy 81.308685 -371.471849) (xy 81.316442 -371.417902)
			(xy 81.331797 -371.365608) (xy 81.354437 -371.316032) (xy 81.383903 -371.270182) (xy 81.419594 -371.228993)
			(xy 81.460784 -371.193302) (xy 81.506634 -371.163837) (xy 81.55621 -371.141196) (xy 81.608504 -371.125841)
			(xy 81.662451 -371.118085) (xy 81.689702 -371.117622) (xy 81.718404 -371.118638) (xy 81.731612 -371.119654)
			(xy 81.755234 -371.108732) (xy 81.822036 -371.018054) (xy 81.825338 -370.992146) (xy 81.820258 -370.9797)
			(xy 81.811724 -370.957189) (xy 81.799719 -370.910566) (xy 81.793686 -370.862802) (xy 81.793334 -370.83873)
			(xy 81.79382 -370.811479) (xy 81.801576 -370.757531) (xy 81.816931 -370.705236) (xy 81.839573 -370.655659)
			(xy 81.869039 -370.609809) (xy 81.90473 -370.568618) (xy 81.945921 -370.532927) (xy 81.991771 -370.503461)
			(xy 82.041348 -370.480819) (xy 82.093643 -370.465464) (xy 82.147591 -370.457708) (xy 82.202093 -370.457708)
			(xy 82.256041 -370.465464) (xy 82.308336 -370.480819) (xy 82.357913 -370.503461) (xy 82.403763 -370.532927)
			(xy 82.444954 -370.568618) (xy 82.480645 -370.609809) (xy 82.510111 -370.655659) (xy 82.532753 -370.705236)
			(xy 82.548108 -370.757531) (xy 82.555864 -370.811479) (xy 82.55635 -370.83873) (xy 82.555658 -370.871262)
			(xy 82.544549 -370.935371) (xy 82.534252 -370.966238) (xy 82.531204 -370.974874) (xy 82.531458 -370.992654)
			(xy 82.560922 -371.07114) (xy 82.572352 -371.084348) (xy 82.58048 -371.08892) (xy 82.612738 -371.108732)
			(xy 82.619138 -371.112775) (xy 82.633618 -371.117165) (xy 82.641186 -371.117368) (xy 82.922618 -371.117368)
			(xy 82.930171 -371.117072) (xy 82.944629 -371.112692) (xy 82.951066 -371.108732) (xy 82.983324 -371.08892)
			(xy 82.991452 -371.084348) (xy 83.002882 -371.07114) (xy 83.032346 -370.992654) (xy 83.0326 -370.974874)
			(xy 83.029552 -370.966238) (xy 83.019256 -370.935371) (xy 83.008153 -370.871261) (xy 83.007454 -370.83873)
			(xy 83.00794 -370.811479) (xy 83.015696 -370.757531) (xy 83.031051 -370.705236) (xy 83.053693 -370.655659)
			(xy 83.083159 -370.609809) (xy 83.11885 -370.568618) (xy 83.160041 -370.532927) (xy 83.205891 -370.503461)
			(xy 83.255468 -370.480819) (xy 83.307763 -370.465464) (xy 83.361711 -370.457708) (xy 83.416213 -370.457708)
			(xy 83.470161 -370.465464) (xy 83.522456 -370.480819) (xy 83.572033 -370.503461) (xy 83.617883 -370.532927)
			(xy 83.659074 -370.568618) (xy 83.694765 -370.609809) (xy 83.724231 -370.655659) (xy 83.746873 -370.705236)
			(xy 83.762228 -370.757531) (xy 83.769984 -370.811479) (xy 83.77047 -370.83873) (xy 83.770108 -370.862801)
			(xy 83.76407 -370.910564) (xy 83.752082 -370.95719) (xy 83.743546 -370.9797) (xy 83.738466 -370.992146)
			(xy 83.741768 -371.018054) (xy 83.80857 -371.108732) (xy 83.832192 -371.119654) (xy 83.8454 -371.118638)
			(xy 83.874102 -371.117622) (xy 83.901355 -371.118048) (xy 83.955307 -371.125805) (xy 84.007606 -371.141162)
			(xy 84.057187 -371.163805) (xy 84.10304 -371.193274) (xy 84.144234 -371.228968) (xy 84.179928 -371.270161)
			(xy 84.209396 -371.316015) (xy 84.232039 -371.365596) (xy 84.247395 -371.417895) (xy 84.255152 -371.471847)
			(xy 84.255152 -371.526351) (xy 88.115885 -371.526351) (xy 88.115885 -371.471849) (xy 88.123642 -371.417902)
			(xy 88.138997 -371.365608) (xy 88.161637 -371.316032) (xy 88.191103 -371.270182) (xy 88.226794 -371.228993)
			(xy 88.267984 -371.193302) (xy 88.313834 -371.163837) (xy 88.36341 -371.141196) (xy 88.415704 -371.125841)
			(xy 88.469651 -371.118085) (xy 88.496902 -371.117622) (xy 88.525604 -371.118638) (xy 88.538812 -371.119654)
			(xy 88.562434 -371.108732) (xy 88.629236 -371.018054) (xy 88.632538 -370.992146) (xy 88.627458 -370.9797)
			(xy 88.618924 -370.957189) (xy 88.606919 -370.910566) (xy 88.600886 -370.862802) (xy 88.600534 -370.83873)
			(xy 88.60102 -370.811479) (xy 88.608776 -370.757531) (xy 88.624131 -370.705236) (xy 88.646773 -370.655659)
			(xy 88.676239 -370.609809) (xy 88.71193 -370.568618) (xy 88.753121 -370.532927) (xy 88.798971 -370.503461)
			(xy 88.848548 -370.480819) (xy 88.900843 -370.465464) (xy 88.954791 -370.457708) (xy 89.009293 -370.457708)
			(xy 89.063241 -370.465464) (xy 89.115536 -370.480819) (xy 89.165113 -370.503461) (xy 89.210963 -370.532927)
			(xy 89.252154 -370.568618) (xy 89.287845 -370.609809) (xy 89.317311 -370.655659) (xy 89.339953 -370.705236)
			(xy 89.355308 -370.757531) (xy 89.363064 -370.811479) (xy 89.36355 -370.83873) (xy 89.362858 -370.871262)
			(xy 89.351749 -370.935371) (xy 89.341452 -370.966238) (xy 89.338404 -370.974874) (xy 89.338658 -370.992654)
			(xy 89.368122 -371.07114) (xy 89.379552 -371.084348) (xy 89.38768 -371.08892) (xy 89.419938 -371.108732)
			(xy 89.426338 -371.112775) (xy 89.440818 -371.117165) (xy 89.448386 -371.117368) (xy 89.729818 -371.117368)
			(xy 89.737371 -371.117072) (xy 89.751829 -371.112692) (xy 89.758266 -371.108732) (xy 89.790524 -371.08892)
			(xy 89.798652 -371.084348) (xy 89.810082 -371.07114) (xy 89.839546 -370.992654) (xy 89.8398 -370.974874)
			(xy 89.836752 -370.966238) (xy 89.826456 -370.935371) (xy 89.815353 -370.871261) (xy 89.814654 -370.83873)
			(xy 89.81514 -370.811479) (xy 89.822896 -370.757531) (xy 89.838251 -370.705236) (xy 89.860893 -370.655659)
			(xy 89.890359 -370.609809) (xy 89.92605 -370.568618) (xy 89.967241 -370.532927) (xy 90.013091 -370.503461)
			(xy 90.062668 -370.480819) (xy 90.114963 -370.465464) (xy 90.168911 -370.457708) (xy 90.223413 -370.457708)
			(xy 90.277361 -370.465464) (xy 90.329656 -370.480819) (xy 90.379233 -370.503461) (xy 90.425083 -370.532927)
			(xy 90.466274 -370.568618) (xy 90.501965 -370.609809) (xy 90.531431 -370.655659) (xy 90.554073 -370.705236)
			(xy 90.569428 -370.757531) (xy 90.577184 -370.811479) (xy 90.57767 -370.83873) (xy 90.577308 -370.862801)
			(xy 90.57127 -370.910564) (xy 90.559282 -370.95719) (xy 90.550746 -370.9797) (xy 90.545666 -370.992146)
			(xy 90.548968 -371.018054) (xy 90.61577 -371.108732) (xy 90.639392 -371.119654) (xy 90.6526 -371.118638)
			(xy 90.681302 -371.117622) (xy 90.708555 -371.118048) (xy 90.762507 -371.125805) (xy 90.814806 -371.141162)
			(xy 90.864387 -371.163805) (xy 90.91024 -371.193274) (xy 90.951434 -371.228968) (xy 90.987128 -371.270161)
			(xy 91.016596 -371.316015) (xy 91.039239 -371.365596) (xy 91.054595 -371.417895) (xy 91.062352 -371.471847)
			(xy 91.062352 -371.526351) (xy 94.923085 -371.526351) (xy 94.923085 -371.471849) (xy 94.930842 -371.417902)
			(xy 94.946197 -371.365608) (xy 94.968837 -371.316032) (xy 94.998303 -371.270182) (xy 95.033994 -371.228993)
			(xy 95.075184 -371.193302) (xy 95.121034 -371.163837) (xy 95.17061 -371.141196) (xy 95.222904 -371.125841)
			(xy 95.276851 -371.118085) (xy 95.304102 -371.117622) (xy 95.332804 -371.118638) (xy 95.346012 -371.119654)
			(xy 95.369634 -371.108732) (xy 95.436436 -371.018054) (xy 95.439738 -370.992146) (xy 95.434658 -370.9797)
			(xy 95.426124 -370.957189) (xy 95.414119 -370.910566) (xy 95.408086 -370.862802) (xy 95.407734 -370.83873)
			(xy 95.40822 -370.811479) (xy 95.415976 -370.757531) (xy 95.431331 -370.705236) (xy 95.453973 -370.655659)
			(xy 95.483439 -370.609809) (xy 95.51913 -370.568618) (xy 95.560321 -370.532927) (xy 95.606171 -370.503461)
			(xy 95.655748 -370.480819) (xy 95.708043 -370.465464) (xy 95.761991 -370.457708) (xy 95.816493 -370.457708)
			(xy 95.870441 -370.465464) (xy 95.922736 -370.480819) (xy 95.972313 -370.503461) (xy 96.018163 -370.532927)
			(xy 96.059354 -370.568618) (xy 96.095045 -370.609809) (xy 96.124511 -370.655659) (xy 96.147153 -370.705236)
			(xy 96.162508 -370.757531) (xy 96.170264 -370.811479) (xy 96.17075 -370.83873) (xy 96.170058 -370.871262)
			(xy 96.158949 -370.935371) (xy 96.148652 -370.966238) (xy 96.145604 -370.974874) (xy 96.145858 -370.992654)
			(xy 96.175322 -371.07114) (xy 96.186752 -371.084348) (xy 96.19488 -371.08892) (xy 96.227138 -371.108732)
			(xy 96.233538 -371.112775) (xy 96.248018 -371.117165) (xy 96.255586 -371.117368) (xy 96.537018 -371.117368)
			(xy 96.544571 -371.117072) (xy 96.559029 -371.112692) (xy 96.565466 -371.108732) (xy 96.597724 -371.08892)
			(xy 96.605852 -371.084348) (xy 96.617282 -371.07114) (xy 96.646746 -370.992654) (xy 96.647 -370.974874)
			(xy 96.643952 -370.966238) (xy 96.633656 -370.935371) (xy 96.622553 -370.871261) (xy 96.621854 -370.83873)
			(xy 96.62234 -370.811479) (xy 96.630096 -370.757531) (xy 96.645451 -370.705236) (xy 96.668093 -370.655659)
			(xy 96.697559 -370.609809) (xy 96.73325 -370.568618) (xy 96.774441 -370.532927) (xy 96.820291 -370.503461)
			(xy 96.869868 -370.480819) (xy 96.922163 -370.465464) (xy 96.976111 -370.457708) (xy 97.030613 -370.457708)
			(xy 97.084561 -370.465464) (xy 97.136856 -370.480819) (xy 97.186433 -370.503461) (xy 97.232283 -370.532927)
			(xy 97.273474 -370.568618) (xy 97.309165 -370.609809) (xy 97.338631 -370.655659) (xy 97.361273 -370.705236)
			(xy 97.376628 -370.757531) (xy 97.384384 -370.811479) (xy 97.38487 -370.83873) (xy 97.384508 -370.862801)
			(xy 97.37847 -370.910564) (xy 97.366482 -370.95719) (xy 97.357946 -370.9797) (xy 97.352866 -370.992146)
			(xy 97.356168 -371.018054) (xy 97.42297 -371.108732) (xy 97.446592 -371.119654) (xy 97.4598 -371.118638)
			(xy 97.488502 -371.117622) (xy 97.515755 -371.118048) (xy 97.569707 -371.125805) (xy 97.622006 -371.141162)
			(xy 97.671587 -371.163805) (xy 97.71744 -371.193274) (xy 97.758634 -371.228968) (xy 97.794328 -371.270161)
			(xy 97.823796 -371.316015) (xy 97.846439 -371.365596) (xy 97.861795 -371.417895) (xy 97.869552 -371.471847)
			(xy 97.869552 -371.526349) (xy 109.073708 -371.526349) (xy 109.073708 -371.471851) (xy 109.081464 -371.417908)
			(xy 109.096818 -371.365618) (xy 109.119457 -371.316045) (xy 109.14892 -371.270198) (xy 109.184609 -371.229011)
			(xy 109.225795 -371.193323) (xy 109.271641 -371.163859) (xy 109.321214 -371.141219) (xy 109.373504 -371.125865)
			(xy 109.427447 -371.118108) (xy 109.454696 -371.117622) (xy 109.483398 -371.118638) (xy 109.496606 -371.119654)
			(xy 109.520228 -371.108732) (xy 109.58703 -371.018054) (xy 109.590332 -370.992146) (xy 109.585252 -370.9797)
			(xy 109.576717 -370.957189) (xy 109.564713 -370.910566) (xy 109.55868 -370.862802) (xy 109.558328 -370.83873)
			(xy 109.558814 -370.811479) (xy 109.56657 -370.757531) (xy 109.581925 -370.705236) (xy 109.604567 -370.655659)
			(xy 109.634033 -370.609809) (xy 109.669724 -370.568618) (xy 109.710915 -370.532927) (xy 109.756765 -370.503461)
			(xy 109.806342 -370.480819) (xy 109.858637 -370.465464) (xy 109.912585 -370.457708) (xy 109.967087 -370.457708)
			(xy 110.021035 -370.465464) (xy 110.07333 -370.480819) (xy 110.122907 -370.503461) (xy 110.168757 -370.532927)
			(xy 110.209948 -370.568618) (xy 110.245639 -370.609809) (xy 110.275105 -370.655659) (xy 110.297747 -370.705236)
			(xy 110.313102 -370.757531) (xy 110.320858 -370.811479) (xy 110.321344 -370.83873) (xy 110.320653 -370.871262)
			(xy 110.309543 -370.935371) (xy 110.299246 -370.966238) (xy 110.296198 -370.974874) (xy 110.296452 -370.992654)
			(xy 110.325916 -371.07114) (xy 110.337346 -371.084348) (xy 110.345474 -371.08892) (xy 110.377732 -371.108732)
			(xy 110.384133 -371.112773) (xy 110.398613 -371.117165) (xy 110.40618 -371.117368) (xy 110.687612 -371.117368)
			(xy 110.695165 -371.11707) (xy 110.709623 -371.112692) (xy 110.71606 -371.108732) (xy 110.748318 -371.08892)
			(xy 110.756446 -371.084348) (xy 110.767876 -371.07114) (xy 110.79734 -370.992654) (xy 110.797594 -370.974874)
			(xy 110.794546 -370.966238) (xy 110.784253 -370.93537) (xy 110.773148 -370.871261) (xy 110.772448 -370.83873)
			(xy 110.772934 -370.811479) (xy 110.78069 -370.757531) (xy 110.796045 -370.705236) (xy 110.818687 -370.655659)
			(xy 110.848153 -370.609809) (xy 110.883844 -370.568618) (xy 110.925035 -370.532927) (xy 110.970885 -370.503461)
			(xy 111.020462 -370.480819) (xy 111.072757 -370.465464) (xy 111.126705 -370.457708) (xy 111.181207 -370.457708)
			(xy 111.235155 -370.465464) (xy 111.28745 -370.480819) (xy 111.337027 -370.503461) (xy 111.382877 -370.532927)
			(xy 111.424068 -370.568618) (xy 111.459759 -370.609809) (xy 111.489225 -370.655659) (xy 111.511867 -370.705236)
			(xy 111.527222 -370.757531) (xy 111.534978 -370.811479) (xy 111.535464 -370.83873) (xy 111.535102 -370.862801)
			(xy 111.529065 -370.910564) (xy 111.517076 -370.95719) (xy 111.50854 -370.9797) (xy 111.50346 -370.992146)
			(xy 111.506762 -371.018054) (xy 111.573564 -371.108732) (xy 111.597186 -371.119654) (xy 111.610394 -371.118638)
			(xy 111.639096 -371.117622) (xy 111.666351 -371.118025) (xy 111.720307 -371.125782) (xy 111.772609 -371.141139)
			(xy 111.822194 -371.163783) (xy 111.868051 -371.193253) (xy 111.909248 -371.228949) (xy 111.944945 -371.270146)
			(xy 111.974415 -371.316003) (xy 111.99706 -371.365587) (xy 112.012417 -371.417889) (xy 112.020175 -371.471845)
			(xy 112.020175 -371.526349) (xy 115.880908 -371.526349) (xy 115.880908 -371.471851) (xy 115.888664 -371.417908)
			(xy 115.904018 -371.365618) (xy 115.926657 -371.316045) (xy 115.95612 -371.270198) (xy 115.991809 -371.229011)
			(xy 116.032995 -371.193323) (xy 116.078841 -371.163859) (xy 116.128414 -371.141219) (xy 116.180704 -371.125865)
			(xy 116.234647 -371.118108) (xy 116.261896 -371.117622) (xy 116.290598 -371.118638) (xy 116.303806 -371.119654)
			(xy 116.327428 -371.108732) (xy 116.39423 -371.018054) (xy 116.397532 -370.992146) (xy 116.392452 -370.9797)
			(xy 116.383917 -370.957189) (xy 116.371913 -370.910566) (xy 116.36588 -370.862802) (xy 116.365528 -370.83873)
			(xy 116.366014 -370.811479) (xy 116.37377 -370.757531) (xy 116.389125 -370.705236) (xy 116.411767 -370.655659)
			(xy 116.441233 -370.609809) (xy 116.476924 -370.568618) (xy 116.518115 -370.532927) (xy 116.563965 -370.503461)
			(xy 116.613542 -370.480819) (xy 116.665837 -370.465464) (xy 116.719785 -370.457708) (xy 116.774287 -370.457708)
			(xy 116.828235 -370.465464) (xy 116.88053 -370.480819) (xy 116.930107 -370.503461) (xy 116.975957 -370.532927)
			(xy 117.017148 -370.568618) (xy 117.052839 -370.609809) (xy 117.082305 -370.655659) (xy 117.104947 -370.705236)
			(xy 117.120302 -370.757531) (xy 117.128058 -370.811479) (xy 117.128544 -370.83873) (xy 117.127853 -370.871262)
			(xy 117.116743 -370.935371) (xy 117.106446 -370.966238) (xy 117.103398 -370.974874) (xy 117.103652 -370.992654)
			(xy 117.133116 -371.07114) (xy 117.144546 -371.084348) (xy 117.152674 -371.08892) (xy 117.184932 -371.108732)
			(xy 117.191333 -371.112773) (xy 117.205813 -371.117165) (xy 117.21338 -371.117368) (xy 117.494812 -371.117368)
			(xy 117.502365 -371.11707) (xy 117.516823 -371.112692) (xy 117.52326 -371.108732) (xy 117.555518 -371.08892)
			(xy 117.563646 -371.084348) (xy 117.575076 -371.07114) (xy 117.60454 -370.992654) (xy 117.604794 -370.974874)
			(xy 117.601746 -370.966238) (xy 117.591453 -370.93537) (xy 117.580348 -370.871261) (xy 117.579648 -370.83873)
			(xy 117.580134 -370.811479) (xy 117.58789 -370.757531) (xy 117.603245 -370.705236) (xy 117.625887 -370.655659)
			(xy 117.655353 -370.609809) (xy 117.691044 -370.568618) (xy 117.732235 -370.532927) (xy 117.778085 -370.503461)
			(xy 117.827662 -370.480819) (xy 117.879957 -370.465464) (xy 117.933905 -370.457708) (xy 117.988407 -370.457708)
			(xy 118.042355 -370.465464) (xy 118.09465 -370.480819) (xy 118.144227 -370.503461) (xy 118.190077 -370.532927)
			(xy 118.231268 -370.568618) (xy 118.266959 -370.609809) (xy 118.296425 -370.655659) (xy 118.319067 -370.705236)
			(xy 118.334422 -370.757531) (xy 118.342178 -370.811479) (xy 118.342664 -370.83873) (xy 118.342302 -370.862801)
			(xy 118.336265 -370.910564) (xy 118.324276 -370.95719) (xy 118.31574 -370.9797) (xy 118.31066 -370.992146)
			(xy 118.313962 -371.018054) (xy 118.380764 -371.108732) (xy 118.404386 -371.119654) (xy 118.417594 -371.118638)
			(xy 118.446296 -371.117622) (xy 118.473551 -371.118025) (xy 118.527507 -371.125782) (xy 118.579809 -371.141139)
			(xy 118.629394 -371.163783) (xy 118.675251 -371.193253) (xy 118.716448 -371.228949) (xy 118.752145 -371.270146)
			(xy 118.781615 -371.316003) (xy 118.80426 -371.365587) (xy 118.819617 -371.417889) (xy 118.827375 -371.471845)
			(xy 118.827375 -371.526349) (xy 122.688108 -371.526349) (xy 122.688108 -371.471851) (xy 122.695864 -371.417908)
			(xy 122.711218 -371.365618) (xy 122.733857 -371.316045) (xy 122.76332 -371.270198) (xy 122.799009 -371.229011)
			(xy 122.840195 -371.193323) (xy 122.886041 -371.163859) (xy 122.935614 -371.141219) (xy 122.987904 -371.125865)
			(xy 123.041847 -371.118108) (xy 123.069096 -371.117622) (xy 123.097798 -371.118638) (xy 123.111006 -371.119654)
			(xy 123.134628 -371.108732) (xy 123.20143 -371.018054) (xy 123.204732 -370.992146) (xy 123.199652 -370.9797)
			(xy 123.191117 -370.957189) (xy 123.179113 -370.910566) (xy 123.17308 -370.862802) (xy 123.172728 -370.83873)
			(xy 123.173214 -370.811479) (xy 123.18097 -370.757531) (xy 123.196325 -370.705236) (xy 123.218967 -370.655659)
			(xy 123.248433 -370.609809) (xy 123.284124 -370.568618) (xy 123.325315 -370.532927) (xy 123.371165 -370.503461)
			(xy 123.420742 -370.480819) (xy 123.473037 -370.465464) (xy 123.526985 -370.457708) (xy 123.581487 -370.457708)
			(xy 123.635435 -370.465464) (xy 123.68773 -370.480819) (xy 123.737307 -370.503461) (xy 123.783157 -370.532927)
			(xy 123.824348 -370.568618) (xy 123.860039 -370.609809) (xy 123.889505 -370.655659) (xy 123.912147 -370.705236)
			(xy 123.927502 -370.757531) (xy 123.935258 -370.811479) (xy 123.935744 -370.83873) (xy 123.935053 -370.871262)
			(xy 123.923943 -370.935371) (xy 123.913646 -370.966238) (xy 123.910598 -370.974874) (xy 123.910852 -370.992654)
			(xy 123.940316 -371.07114) (xy 123.951746 -371.084348) (xy 123.959874 -371.08892) (xy 123.992132 -371.108732)
			(xy 123.998533 -371.112773) (xy 124.013013 -371.117165) (xy 124.02058 -371.117368) (xy 124.302012 -371.117368)
			(xy 124.309565 -371.11707) (xy 124.324023 -371.112692) (xy 124.33046 -371.108732) (xy 124.362718 -371.08892)
			(xy 124.370846 -371.084348) (xy 124.382276 -371.07114) (xy 124.41174 -370.992654) (xy 124.411994 -370.974874)
			(xy 124.408946 -370.966238) (xy 124.398653 -370.93537) (xy 124.387548 -370.871261) (xy 124.386848 -370.83873)
			(xy 124.387334 -370.811479) (xy 124.39509 -370.757531) (xy 124.410445 -370.705236) (xy 124.433087 -370.655659)
			(xy 124.462553 -370.609809) (xy 124.498244 -370.568618) (xy 124.539435 -370.532927) (xy 124.585285 -370.503461)
			(xy 124.634862 -370.480819) (xy 124.687157 -370.465464) (xy 124.741105 -370.457708) (xy 124.795607 -370.457708)
			(xy 124.849555 -370.465464) (xy 124.90185 -370.480819) (xy 124.951427 -370.503461) (xy 124.997277 -370.532927)
			(xy 125.038468 -370.568618) (xy 125.074159 -370.609809) (xy 125.103625 -370.655659) (xy 125.126267 -370.705236)
			(xy 125.141622 -370.757531) (xy 125.149378 -370.811479) (xy 125.149864 -370.83873) (xy 125.149502 -370.862801)
			(xy 125.143465 -370.910564) (xy 125.131476 -370.95719) (xy 125.12294 -370.9797) (xy 125.11786 -370.992146)
			(xy 125.121162 -371.018054) (xy 125.187964 -371.108732) (xy 125.211586 -371.119654) (xy 125.224794 -371.118638)
			(xy 125.253496 -371.117622) (xy 125.280751 -371.118025) (xy 125.334707 -371.125782) (xy 125.387009 -371.141139)
			(xy 125.436594 -371.163783) (xy 125.482451 -371.193253) (xy 125.523648 -371.228949) (xy 125.559345 -371.270146)
			(xy 125.588815 -371.316003) (xy 125.61146 -371.365587) (xy 125.626817 -371.417889) (xy 125.634575 -371.471845)
			(xy 125.634575 -371.526349) (xy 129.495308 -371.526349) (xy 129.495308 -371.471851) (xy 129.503064 -371.417908)
			(xy 129.518418 -371.365618) (xy 129.541057 -371.316045) (xy 129.57052 -371.270198) (xy 129.606209 -371.229011)
			(xy 129.647395 -371.193323) (xy 129.693241 -371.163859) (xy 129.742814 -371.141219) (xy 129.795104 -371.125865)
			(xy 129.849047 -371.118108) (xy 129.876296 -371.117622) (xy 129.904998 -371.118638) (xy 129.918206 -371.119654)
			(xy 129.941828 -371.108732) (xy 130.00863 -371.018054) (xy 130.011932 -370.992146) (xy 130.006852 -370.9797)
			(xy 129.998317 -370.957189) (xy 129.986313 -370.910566) (xy 129.98028 -370.862802) (xy 129.979928 -370.83873)
			(xy 129.980414 -370.811479) (xy 129.98817 -370.757531) (xy 130.003525 -370.705236) (xy 130.026167 -370.655659)
			(xy 130.055633 -370.609809) (xy 130.091324 -370.568618) (xy 130.132515 -370.532927) (xy 130.178365 -370.503461)
			(xy 130.227942 -370.480819) (xy 130.280237 -370.465464) (xy 130.334185 -370.457708) (xy 130.388687 -370.457708)
			(xy 130.442635 -370.465464) (xy 130.49493 -370.480819) (xy 130.544507 -370.503461) (xy 130.590357 -370.532927)
			(xy 130.631548 -370.568618) (xy 130.667239 -370.609809) (xy 130.696705 -370.655659) (xy 130.719347 -370.705236)
			(xy 130.734702 -370.757531) (xy 130.742458 -370.811479) (xy 130.742944 -370.83873) (xy 130.742253 -370.871262)
			(xy 130.731143 -370.935371) (xy 130.720846 -370.966238) (xy 130.717798 -370.974874) (xy 130.718052 -370.992654)
			(xy 130.747516 -371.07114) (xy 130.758946 -371.084348) (xy 130.767074 -371.08892) (xy 130.799332 -371.108732)
			(xy 130.805733 -371.112773) (xy 130.820213 -371.117165) (xy 130.82778 -371.117368) (xy 131.109212 -371.117368)
			(xy 131.116765 -371.11707) (xy 131.131223 -371.112692) (xy 131.13766 -371.108732) (xy 131.169918 -371.08892)
			(xy 131.178046 -371.084348) (xy 131.189476 -371.07114) (xy 131.21894 -370.992654) (xy 131.219194 -370.974874)
			(xy 131.216146 -370.966238) (xy 131.205853 -370.93537) (xy 131.194748 -370.871261) (xy 131.194048 -370.83873)
			(xy 131.194534 -370.811479) (xy 131.20229 -370.757531) (xy 131.217645 -370.705236) (xy 131.240287 -370.655659)
			(xy 131.269753 -370.609809) (xy 131.305444 -370.568618) (xy 131.346635 -370.532927) (xy 131.392485 -370.503461)
			(xy 131.442062 -370.480819) (xy 131.494357 -370.465464) (xy 131.548305 -370.457708) (xy 131.602807 -370.457708)
			(xy 131.656755 -370.465464) (xy 131.70905 -370.480819) (xy 131.758627 -370.503461) (xy 131.804477 -370.532927)
			(xy 131.845668 -370.568618) (xy 131.881359 -370.609809) (xy 131.910825 -370.655659) (xy 131.933467 -370.705236)
			(xy 131.948822 -370.757531) (xy 131.956578 -370.811479) (xy 131.957064 -370.83873) (xy 138.001248 -370.83873)
			(xy 138.001781 -370.812084) (xy 138.009206 -370.75931) (xy 138.023903 -370.708084) (xy 138.045585 -370.659401)
			(xy 138.07383 -370.614209) (xy 138.108089 -370.573386) (xy 138.147695 -370.537728) (xy 138.191878 -370.507928)
			(xy 138.215624 -370.49583) (xy 138.224006 -370.491766) (xy 138.236706 -370.478304) (xy 138.269726 -370.398802)
			(xy 138.270234 -370.38026) (xy 138.267186 -370.371624) (xy 138.258489 -370.345021) (xy 138.246283 -370.290397)
			(xy 138.240139 -370.234764) (xy 138.239754 -370.206778) (xy 138.240333 -370.171823) (xy 138.249897 -370.10257)
			(xy 138.268855 -370.035279) (xy 138.296851 -369.971219) (xy 138.333355 -369.911596) (xy 138.35507 -369.884198)
			(xy 138.360349 -369.877205) (xy 138.366189 -369.860697) (xy 138.3665 -369.85194) (xy 138.3665 -369.698016)
			(xy 138.366128 -369.68927) (xy 138.360297 -369.672779) (xy 138.35507 -369.665758) (xy 138.333333 -369.638377)
			(xy 138.29684 -369.578746) (xy 138.268853 -369.514681) (xy 138.249898 -369.447388) (xy 138.240331 -369.378134)
			(xy 138.239754 -369.343178) (xy 138.240266 -369.311055) (xy 138.248371 -369.247321) (xy 138.264435 -369.185114)
			(xy 138.288204 -369.125426) (xy 138.319299 -369.069205) (xy 138.357226 -369.017346) (xy 138.378946 -368.993674)
			(xy 138.385255 -368.986461) (xy 138.392421 -368.968701) (xy 138.392916 -368.95913) (xy 138.39317 -368.928142)
			(xy 138.392855 -368.918761) (xy 138.386341 -368.901175) (xy 138.38047 -368.893852) (xy 138.362563 -368.872839)
			(xy 138.332371 -368.826618) (xy 138.309158 -368.776527) (xy 138.293409 -368.723612) (xy 138.285453 -368.66898)
			(xy 138.284966 -368.641376) (xy 138.285452 -368.614125) (xy 138.293208 -368.560177) (xy 138.308563 -368.507882)
			(xy 138.331205 -368.458305) (xy 138.360671 -368.412455) (xy 138.396362 -368.371264) (xy 138.437553 -368.335573)
			(xy 138.483403 -368.306107) (xy 138.53298 -368.283465) (xy 138.585275 -368.26811) (xy 138.639223 -368.260354)
			(xy 138.693725 -368.260354) (xy 138.747673 -368.26811) (xy 138.799968 -368.283465) (xy 138.849545 -368.306107)
			(xy 138.895395 -368.335573) (xy 138.936586 -368.371264) (xy 138.972277 -368.412455) (xy 139.001743 -368.458305)
			(xy 139.024385 -368.507882) (xy 139.03974 -368.560177) (xy 139.047496 -368.614125) (xy 139.047982 -368.641376)
			(xy 139.047341 -368.672654) (xy 139.037133 -368.734371) (xy 139.016987 -368.793595) (xy 139.00277 -368.821462)
			(xy 138.998735 -368.829874) (xy 138.996405 -368.848373) (xy 138.998198 -368.85753) (xy 139.005818 -368.887756)
			(xy 139.008442 -368.896904) (xy 139.019422 -368.912432) (xy 139.027154 -368.917982) (xy 139.053206 -368.935665)
			(xy 139.101193 -368.976431) (xy 139.143779 -369.022811) (xy 139.180313 -369.074094) (xy 139.210234 -369.129495)
			(xy 139.233086 -369.188167) (xy 139.248519 -369.249212) (xy 139.256297 -369.311695) (xy 139.25677 -369.343178)
			(xy 139.25616 -369.378132) (xy 139.246603 -369.447384) (xy 139.227652 -369.514674) (xy 139.199663 -369.578734)
			(xy 139.163165 -369.638358) (xy 139.141454 -369.665758) (xy 139.136196 -369.672765) (xy 139.130343 -369.689262)
			(xy 139.130024 -369.698016) (xy 139.130024 -369.85194) (xy 139.130365 -369.860689) (xy 139.136217 -369.87718)
			(xy 139.141454 -369.884198) (xy 139.163159 -369.911603) (xy 139.19966 -369.971227) (xy 139.227654 -370.035285)
			(xy 139.246617 -370.102573) (xy 139.25619 -370.171824) (xy 139.25677 -370.206778) (xy 139.256241 -370.238654)
			(xy 139.248262 -370.301906) (xy 139.23244 -370.363664) (xy 139.214351 -370.40947) (xy 141.445996 -370.40947)
			(xy 141.446561 -370.374514) (xy 141.456127 -370.30526) (xy 141.475088 -370.237969) (xy 141.503087 -370.173909)
			(xy 141.539595 -370.114288) (xy 141.561312 -370.08689) (xy 141.566612 -370.079893) (xy 141.572585 -370.0634)
			(xy 141.572996 -370.054632) (xy 141.572996 -369.900708) (xy 141.572632 -369.891931) (xy 141.566649 -369.875428)
			(xy 141.561312 -369.86845) (xy 141.539624 -369.841032) (xy 141.503122 -369.781412) (xy 141.475124 -369.717356)
			(xy 141.456158 -369.650071) (xy 141.44658 -369.580823) (xy 141.445996 -369.54587) (xy 141.44652 -369.511736)
			(xy 141.455646 -369.444082) (xy 141.473743 -369.378258) (xy 141.500484 -369.315447) (xy 141.535391 -369.256779)
			(xy 141.577834 -369.203309) (xy 141.62705 -369.156) (xy 141.654276 -369.135406) (xy 141.661476 -369.129619)
			(xy 141.671498 -369.114118) (xy 141.673834 -369.10518) (xy 141.680438 -369.074954) (xy 141.681885 -369.065982)
			(xy 141.67917 -369.048028) (xy 141.675104 -369.039902) (xy 141.660105 -369.011411) (xy 141.638825 -368.950649)
			(xy 141.628024 -368.88718) (xy 141.627352 -368.85499) (xy 141.627838 -368.827739) (xy 141.635594 -368.773791)
			(xy 141.650949 -368.721496) (xy 141.673591 -368.671919) (xy 141.703057 -368.626069) (xy 141.738748 -368.584878)
			(xy 141.779939 -368.549187) (xy 141.825789 -368.519721) (xy 141.875366 -368.497079) (xy 141.927661 -368.481724)
			(xy 141.981609 -368.473968) (xy 142.036111 -368.473968) (xy 142.090059 -368.481724) (xy 142.142354 -368.497079)
			(xy 142.191931 -368.519721) (xy 142.237781 -368.549187) (xy 142.278972 -368.584878) (xy 142.314663 -368.626069)
			(xy 142.344129 -368.671919) (xy 142.366771 -368.721496) (xy 142.382126 -368.773791) (xy 142.389882 -368.827739)
			(xy 142.390368 -368.85499) (xy 142.389957 -368.880281) (xy 142.383279 -368.930421) (xy 142.370026 -368.979237)
			(xy 142.350432 -369.02587) (xy 142.328915 -369.062553) (xy 143.303185 -369.062553) (xy 143.303185 -369.008047)
			(xy 143.310943 -368.954097) (xy 143.3263 -368.901799) (xy 143.348944 -368.85222) (xy 143.378414 -368.806369)
			(xy 143.414109 -368.765178) (xy 143.455304 -368.729487) (xy 143.501159 -368.700023) (xy 143.550741 -368.677385)
			(xy 143.60304 -368.662034) (xy 143.656991 -368.654282) (xy 143.684244 -368.653822) (xy 143.712946 -368.654838)
			(xy 143.726154 -368.655854) (xy 143.749776 -368.644932) (xy 143.816578 -368.554254) (xy 143.81988 -368.528346)
			(xy 143.8148 -368.5159) (xy 143.806267 -368.493388) (xy 143.794262 -368.446766) (xy 143.788228 -368.399002)
			(xy 143.787876 -368.37493) (xy 143.788362 -368.347679) (xy 143.796118 -368.293731) (xy 143.811473 -368.241436)
			(xy 143.834115 -368.191859) (xy 143.863581 -368.146009) (xy 143.899272 -368.104818) (xy 143.940463 -368.069127)
			(xy 143.986313 -368.039661) (xy 144.03589 -368.017019) (xy 144.088185 -368.001664) (xy 144.142133 -367.993908)
			(xy 144.196635 -367.993908) (xy 144.250583 -368.001664) (xy 144.302878 -368.017019) (xy 144.352455 -368.039661)
			(xy 144.398305 -368.069127) (xy 144.439496 -368.104818) (xy 144.475187 -368.146009) (xy 144.504653 -368.191859)
			(xy 144.527295 -368.241436) (xy 144.54265 -368.293731) (xy 144.550406 -368.347679) (xy 144.550892 -368.37493)
			(xy 144.550203 -368.407462) (xy 144.539092 -368.471571) (xy 144.528794 -368.502438) (xy 144.525746 -368.511074)
			(xy 144.526 -368.528854) (xy 144.555464 -368.60734) (xy 144.566894 -368.620548) (xy 144.575022 -368.62512)
			(xy 144.60728 -368.644932) (xy 144.613671 -368.648991) (xy 144.628158 -368.653372) (xy 144.635728 -368.653568)
			(xy 144.91716 -368.653568) (xy 144.924714 -368.65329) (xy 144.939172 -368.648898) (xy 144.945608 -368.644932)
			(xy 144.977866 -368.62512) (xy 144.985994 -368.620548) (xy 144.997424 -368.60734) (xy 145.026888 -368.528854)
			(xy 145.027142 -368.511074) (xy 145.024094 -368.502438) (xy 145.013799 -368.471571) (xy 145.002695 -368.407461)
			(xy 145.001996 -368.37493) (xy 145.002482 -368.347679) (xy 145.010238 -368.293731) (xy 145.025593 -368.241436)
			(xy 145.048235 -368.191859) (xy 145.077701 -368.146009) (xy 145.113392 -368.104818) (xy 145.154583 -368.069127)
			(xy 145.200433 -368.039661) (xy 145.25001 -368.017019) (xy 145.302305 -368.001664) (xy 145.356253 -367.993908)
			(xy 145.410755 -367.993908) (xy 145.464703 -368.001664) (xy 145.516998 -368.017019) (xy 145.566575 -368.039661)
			(xy 145.612425 -368.069127) (xy 145.653616 -368.104818) (xy 145.689307 -368.146009) (xy 145.718773 -368.191859)
			(xy 145.741415 -368.241436) (xy 145.75677 -368.293731) (xy 145.764526 -368.347679) (xy 145.765012 -368.37493)
			(xy 145.764654 -368.399002) (xy 145.758615 -368.446764) (xy 145.746625 -368.49339) (xy 145.738088 -368.5159)
			(xy 145.733008 -368.528346) (xy 145.73631 -368.554254) (xy 145.803112 -368.644932) (xy 145.826734 -368.655854)
			(xy 145.839942 -368.654838) (xy 145.868644 -368.653822) (xy 145.895895 -368.654251) (xy 145.949843 -368.662013)
			(xy 146.002136 -368.677373) (xy 146.051712 -368.700019) (xy 146.09756 -368.729488) (xy 146.138748 -368.765183)
			(xy 146.174438 -368.806375) (xy 146.203902 -368.852227) (xy 146.226542 -368.901805) (xy 146.241896 -368.954101)
			(xy 146.249652 -369.008049) (xy 146.249652 -369.062551) (xy 146.249652 -369.062553) (xy 150.110385 -369.062553)
			(xy 150.110385 -369.008047) (xy 150.118143 -368.954097) (xy 150.1335 -368.901799) (xy 150.156144 -368.85222)
			(xy 150.185614 -368.806369) (xy 150.221309 -368.765178) (xy 150.262504 -368.729487) (xy 150.308359 -368.700023)
			(xy 150.357941 -368.677385) (xy 150.41024 -368.662034) (xy 150.464191 -368.654282) (xy 150.491444 -368.653822)
			(xy 150.520146 -368.654838) (xy 150.533354 -368.655854) (xy 150.556976 -368.644932) (xy 150.623778 -368.554254)
			(xy 150.62708 -368.528346) (xy 150.622 -368.5159) (xy 150.613467 -368.493388) (xy 150.601462 -368.446766)
			(xy 150.595428 -368.399002) (xy 150.595076 -368.37493) (xy 150.595562 -368.347679) (xy 150.603318 -368.293731)
			(xy 150.618673 -368.241436) (xy 150.641315 -368.191859) (xy 150.670781 -368.146009) (xy 150.706472 -368.104818)
			(xy 150.747663 -368.069127) (xy 150.793513 -368.039661) (xy 150.84309 -368.017019) (xy 150.895385 -368.001664)
			(xy 150.949333 -367.993908) (xy 151.003835 -367.993908) (xy 151.057783 -368.001664) (xy 151.110078 -368.017019)
			(xy 151.159655 -368.039661) (xy 151.205505 -368.069127) (xy 151.246696 -368.104818) (xy 151.282387 -368.146009)
			(xy 151.311853 -368.191859) (xy 151.334495 -368.241436) (xy 151.34985 -368.293731) (xy 151.357606 -368.347679)
			(xy 151.358092 -368.37493) (xy 151.357403 -368.407462) (xy 151.346292 -368.471571) (xy 151.335994 -368.502438)
			(xy 151.332946 -368.511074) (xy 151.3332 -368.528854) (xy 151.362664 -368.60734) (xy 151.374094 -368.620548)
			(xy 151.382222 -368.62512) (xy 151.41448 -368.644932) (xy 151.420871 -368.648991) (xy 151.435358 -368.653372)
			(xy 151.442928 -368.653568) (xy 151.72436 -368.653568) (xy 151.731914 -368.65329) (xy 151.746372 -368.648898)
			(xy 151.752808 -368.644932) (xy 151.785066 -368.62512) (xy 151.793194 -368.620548) (xy 151.804624 -368.60734)
			(xy 151.834088 -368.528854) (xy 151.834342 -368.511074) (xy 151.831294 -368.502438) (xy 151.820999 -368.471571)
			(xy 151.809895 -368.407461) (xy 151.809196 -368.37493) (xy 151.809682 -368.347679) (xy 151.817438 -368.293731)
			(xy 151.832793 -368.241436) (xy 151.855435 -368.191859) (xy 151.884901 -368.146009) (xy 151.920592 -368.104818)
			(xy 151.961783 -368.069127) (xy 152.007633 -368.039661) (xy 152.05721 -368.017019) (xy 152.109505 -368.001664)
			(xy 152.163453 -367.993908) (xy 152.217955 -367.993908) (xy 152.271903 -368.001664) (xy 152.324198 -368.017019)
			(xy 152.373775 -368.039661) (xy 152.419625 -368.069127) (xy 152.460816 -368.104818) (xy 152.496507 -368.146009)
			(xy 152.525973 -368.191859) (xy 152.548615 -368.241436) (xy 152.56397 -368.293731) (xy 152.571726 -368.347679)
			(xy 152.572212 -368.37493) (xy 152.571854 -368.399002) (xy 152.565815 -368.446764) (xy 152.553825 -368.49339)
			(xy 152.545288 -368.5159) (xy 152.540208 -368.528346) (xy 152.54351 -368.554254) (xy 152.610312 -368.644932)
			(xy 152.633934 -368.655854) (xy 152.647142 -368.654838) (xy 152.675844 -368.653822) (xy 152.703095 -368.654251)
			(xy 152.757043 -368.662013) (xy 152.809336 -368.677373) (xy 152.858912 -368.700019) (xy 152.90476 -368.729488)
			(xy 152.945948 -368.765183) (xy 152.981638 -368.806375) (xy 153.011102 -368.852227) (xy 153.033742 -368.901805)
			(xy 153.049096 -368.954101) (xy 153.056852 -369.008049) (xy 153.056852 -369.062551) (xy 153.056852 -369.062553)
			(xy 156.917585 -369.062553) (xy 156.917585 -369.008047) (xy 156.925343 -368.954097) (xy 156.9407 -368.901799)
			(xy 156.963344 -368.85222) (xy 156.992814 -368.806369) (xy 157.028509 -368.765178) (xy 157.069704 -368.729487)
			(xy 157.115559 -368.700023) (xy 157.165141 -368.677385) (xy 157.21744 -368.662034) (xy 157.271391 -368.654282)
			(xy 157.298644 -368.653822) (xy 157.327346 -368.654838) (xy 157.340554 -368.655854) (xy 157.364176 -368.644932)
			(xy 157.430978 -368.554254) (xy 157.43428 -368.528346) (xy 157.4292 -368.5159) (xy 157.420667 -368.493388)
			(xy 157.408662 -368.446766) (xy 157.402628 -368.399002) (xy 157.402276 -368.37493) (xy 157.402762 -368.347679)
			(xy 157.410518 -368.293731) (xy 157.425873 -368.241436) (xy 157.448515 -368.191859) (xy 157.477981 -368.146009)
			(xy 157.513672 -368.104818) (xy 157.554863 -368.069127) (xy 157.600713 -368.039661) (xy 157.65029 -368.017019)
			(xy 157.702585 -368.001664) (xy 157.756533 -367.993908) (xy 157.811035 -367.993908) (xy 157.864983 -368.001664)
			(xy 157.917278 -368.017019) (xy 157.966855 -368.039661) (xy 158.012705 -368.069127) (xy 158.053896 -368.104818)
			(xy 158.089587 -368.146009) (xy 158.119053 -368.191859) (xy 158.141695 -368.241436) (xy 158.15705 -368.293731)
			(xy 158.164806 -368.347679) (xy 158.165292 -368.37493) (xy 158.164603 -368.407462) (xy 158.153492 -368.471571)
			(xy 158.143194 -368.502438) (xy 158.140146 -368.511074) (xy 158.1404 -368.528854) (xy 158.169864 -368.60734)
			(xy 158.181294 -368.620548) (xy 158.189422 -368.62512) (xy 158.22168 -368.644932) (xy 158.228071 -368.648991)
			(xy 158.242558 -368.653372) (xy 158.250128 -368.653568) (xy 158.53156 -368.653568) (xy 158.539114 -368.65329)
			(xy 158.553572 -368.648898) (xy 158.560008 -368.644932) (xy 158.592266 -368.62512) (xy 158.600394 -368.620548)
			(xy 158.611824 -368.60734) (xy 158.641288 -368.528854) (xy 158.641542 -368.511074) (xy 158.638494 -368.502438)
			(xy 158.628199 -368.471571) (xy 158.617095 -368.407461) (xy 158.616396 -368.37493) (xy 158.616882 -368.347679)
			(xy 158.624638 -368.293731) (xy 158.639993 -368.241436) (xy 158.662635 -368.191859) (xy 158.692101 -368.146009)
			(xy 158.727792 -368.104818) (xy 158.768983 -368.069127) (xy 158.814833 -368.039661) (xy 158.86441 -368.017019)
			(xy 158.916705 -368.001664) (xy 158.970653 -367.993908) (xy 159.025155 -367.993908) (xy 159.079103 -368.001664)
			(xy 159.131398 -368.017019) (xy 159.180975 -368.039661) (xy 159.226825 -368.069127) (xy 159.268016 -368.104818)
			(xy 159.303707 -368.146009) (xy 159.333173 -368.191859) (xy 159.355815 -368.241436) (xy 159.37117 -368.293731)
			(xy 159.378926 -368.347679) (xy 159.379412 -368.37493) (xy 159.379054 -368.399002) (xy 159.373015 -368.446764)
			(xy 159.361025 -368.49339) (xy 159.352488 -368.5159) (xy 159.347408 -368.528346) (xy 159.35071 -368.554254)
			(xy 159.417512 -368.644932) (xy 159.441134 -368.655854) (xy 159.454342 -368.654838) (xy 159.483044 -368.653822)
			(xy 159.510295 -368.654251) (xy 159.564243 -368.662013) (xy 159.616536 -368.677373) (xy 159.666112 -368.700019)
			(xy 159.71196 -368.729488) (xy 159.753148 -368.765183) (xy 159.788838 -368.806375) (xy 159.818302 -368.852227)
			(xy 159.840942 -368.901805) (xy 159.856296 -368.954101) (xy 159.864052 -369.008049) (xy 159.864052 -369.062551)
			(xy 159.864052 -369.062553) (xy 163.724785 -369.062553) (xy 163.724785 -369.008047) (xy 163.732543 -368.954097)
			(xy 163.7479 -368.901799) (xy 163.770544 -368.85222) (xy 163.800014 -368.806369) (xy 163.835709 -368.765178)
			(xy 163.876904 -368.729487) (xy 163.922759 -368.700023) (xy 163.972341 -368.677385) (xy 164.02464 -368.662034)
			(xy 164.078591 -368.654282) (xy 164.105844 -368.653822) (xy 164.134546 -368.654838) (xy 164.147754 -368.655854)
			(xy 164.171376 -368.644932) (xy 164.238178 -368.554254) (xy 164.24148 -368.528346) (xy 164.2364 -368.5159)
			(xy 164.227867 -368.493388) (xy 164.215862 -368.446766) (xy 164.209828 -368.399002) (xy 164.209476 -368.37493)
			(xy 164.209962 -368.347679) (xy 164.217718 -368.293731) (xy 164.233073 -368.241436) (xy 164.255715 -368.191859)
			(xy 164.285181 -368.146009) (xy 164.320872 -368.104818) (xy 164.362063 -368.069127) (xy 164.407913 -368.039661)
			(xy 164.45749 -368.017019) (xy 164.509785 -368.001664) (xy 164.563733 -367.993908) (xy 164.618235 -367.993908)
			(xy 164.672183 -368.001664) (xy 164.724478 -368.017019) (xy 164.774055 -368.039661) (xy 164.819905 -368.069127)
			(xy 164.861096 -368.104818) (xy 164.896787 -368.146009) (xy 164.926253 -368.191859) (xy 164.948895 -368.241436)
			(xy 164.96425 -368.293731) (xy 164.972006 -368.347679) (xy 164.972492 -368.37493) (xy 164.971803 -368.407462)
			(xy 164.960692 -368.471571) (xy 164.950394 -368.502438) (xy 164.947346 -368.511074) (xy 164.9476 -368.528854)
			(xy 164.977064 -368.60734) (xy 164.988494 -368.620548) (xy 164.996622 -368.62512) (xy 165.02888 -368.644932)
			(xy 165.035271 -368.648991) (xy 165.049758 -368.653372) (xy 165.057328 -368.653568) (xy 165.33876 -368.653568)
			(xy 165.346314 -368.65329) (xy 165.360772 -368.648898) (xy 165.367208 -368.644932) (xy 165.399466 -368.62512)
			(xy 165.407594 -368.620548) (xy 165.419024 -368.60734) (xy 165.448488 -368.528854) (xy 165.448742 -368.511074)
			(xy 165.445694 -368.502438) (xy 165.435399 -368.471571) (xy 165.424295 -368.407461) (xy 165.423596 -368.37493)
			(xy 165.424082 -368.347679) (xy 165.431838 -368.293731) (xy 165.447193 -368.241436) (xy 165.469835 -368.191859)
			(xy 165.499301 -368.146009) (xy 165.534992 -368.104818) (xy 165.576183 -368.069127) (xy 165.622033 -368.039661)
			(xy 165.67161 -368.017019) (xy 165.723905 -368.001664) (xy 165.777853 -367.993908) (xy 165.832355 -367.993908)
			(xy 165.886303 -368.001664) (xy 165.938598 -368.017019) (xy 165.988175 -368.039661) (xy 166.034025 -368.069127)
			(xy 166.075216 -368.104818) (xy 166.110907 -368.146009) (xy 166.140373 -368.191859) (xy 166.163015 -368.241436)
			(xy 166.17837 -368.293731) (xy 166.186126 -368.347679) (xy 166.186612 -368.37493) (xy 166.186254 -368.399002)
			(xy 166.180215 -368.446764) (xy 166.168225 -368.49339) (xy 166.159688 -368.5159) (xy 166.154608 -368.528346)
			(xy 166.15791 -368.554254) (xy 166.224712 -368.644932) (xy 166.248334 -368.655854) (xy 166.261542 -368.654838)
			(xy 166.290244 -368.653822) (xy 166.317495 -368.654251) (xy 166.371443 -368.662013) (xy 166.423736 -368.677373)
			(xy 166.473312 -368.700019) (xy 166.51916 -368.729488) (xy 166.560348 -368.765183) (xy 166.596038 -368.806375)
			(xy 166.625502 -368.852227) (xy 166.648142 -368.901805) (xy 166.663496 -368.954101) (xy 166.671252 -369.008049)
			(xy 166.671252 -369.062551) (xy 166.671252 -369.062553) (xy 167.128385 -369.062553) (xy 167.128385 -369.008047)
			(xy 167.136143 -368.954097) (xy 167.1515 -368.901799) (xy 167.174144 -368.85222) (xy 167.203614 -368.806369)
			(xy 167.239309 -368.765178) (xy 167.280504 -368.729487) (xy 167.326359 -368.700023) (xy 167.375941 -368.677385)
			(xy 167.42824 -368.662034) (xy 167.482191 -368.654282) (xy 167.509444 -368.653822) (xy 167.538146 -368.654838)
			(xy 167.551354 -368.655854) (xy 167.574976 -368.644932) (xy 167.641778 -368.554254) (xy 167.64508 -368.528346)
			(xy 167.64 -368.5159) (xy 167.631467 -368.493388) (xy 167.619462 -368.446766) (xy 167.613428 -368.399002)
			(xy 167.613076 -368.37493) (xy 167.613562 -368.347679) (xy 167.621318 -368.293731) (xy 167.636673 -368.241436)
			(xy 167.659315 -368.191859) (xy 167.688781 -368.146009) (xy 167.724472 -368.104818) (xy 167.765663 -368.069127)
			(xy 167.811513 -368.039661) (xy 167.86109 -368.017019) (xy 167.913385 -368.001664) (xy 167.967333 -367.993908)
			(xy 168.021835 -367.993908) (xy 168.075783 -368.001664) (xy 168.128078 -368.017019) (xy 168.177655 -368.039661)
			(xy 168.223505 -368.069127) (xy 168.264696 -368.104818) (xy 168.300387 -368.146009) (xy 168.329853 -368.191859)
			(xy 168.352495 -368.241436) (xy 168.36785 -368.293731) (xy 168.375606 -368.347679) (xy 168.376092 -368.37493)
			(xy 168.375403 -368.407462) (xy 168.364292 -368.471571) (xy 168.353994 -368.502438) (xy 168.350946 -368.511074)
			(xy 168.3512 -368.528854) (xy 168.380664 -368.60734) (xy 168.392094 -368.620548) (xy 168.400222 -368.62512)
			(xy 168.43248 -368.644932) (xy 168.438871 -368.648991) (xy 168.453358 -368.653372) (xy 168.460928 -368.653568)
			(xy 168.74236 -368.653568) (xy 168.749914 -368.65329) (xy 168.764372 -368.648898) (xy 168.770808 -368.644932)
			(xy 168.803066 -368.62512) (xy 168.811194 -368.620548) (xy 168.822624 -368.60734) (xy 168.852088 -368.528854)
			(xy 168.852342 -368.511074) (xy 168.849294 -368.502438) (xy 168.838999 -368.471571) (xy 168.827895 -368.407461)
			(xy 168.827196 -368.37493) (xy 168.827682 -368.347679) (xy 168.835438 -368.293731) (xy 168.850793 -368.241436)
			(xy 168.873435 -368.191859) (xy 168.902901 -368.146009) (xy 168.938592 -368.104818) (xy 168.979783 -368.069127)
			(xy 169.025633 -368.039661) (xy 169.07521 -368.017019) (xy 169.127505 -368.001664) (xy 169.181453 -367.993908)
			(xy 169.235955 -367.993908) (xy 169.289903 -368.001664) (xy 169.342198 -368.017019) (xy 169.391775 -368.039661)
			(xy 169.437625 -368.069127) (xy 169.478816 -368.104818) (xy 169.514507 -368.146009) (xy 169.543973 -368.191859)
			(xy 169.566615 -368.241436) (xy 169.58197 -368.293731) (xy 169.589726 -368.347679) (xy 169.590212 -368.37493)
			(xy 169.589854 -368.399002) (xy 169.583815 -368.446764) (xy 169.571825 -368.49339) (xy 169.563288 -368.5159)
			(xy 169.558208 -368.528346) (xy 169.56151 -368.554254) (xy 169.628312 -368.644932) (xy 169.651934 -368.655854)
			(xy 169.665142 -368.654838) (xy 169.693844 -368.653822) (xy 169.721095 -368.654251) (xy 169.775043 -368.662013)
			(xy 169.827336 -368.677373) (xy 169.876912 -368.700019) (xy 169.92276 -368.729488) (xy 169.963948 -368.765183)
			(xy 169.999638 -368.806375) (xy 170.029102 -368.852227) (xy 170.051742 -368.901805) (xy 170.067096 -368.954101)
			(xy 170.074852 -369.008049) (xy 170.074852 -369.062551) (xy 170.067096 -369.116499) (xy 170.051742 -369.168795)
			(xy 170.029102 -369.218373) (xy 169.999638 -369.264225) (xy 169.963948 -369.305417) (xy 169.92276 -369.341112)
			(xy 169.876912 -369.370581) (xy 169.827336 -369.393227) (xy 169.775043 -369.408587) (xy 169.721095 -369.416349)
			(xy 169.693844 -369.416838) (xy 169.665142 -369.415822) (xy 169.651934 -369.414806) (xy 169.628312 -369.425728)
			(xy 169.56151 -369.516406) (xy 169.558208 -369.542314) (xy 169.563288 -369.55476) (xy 169.571838 -369.577266)
			(xy 169.583837 -369.623891) (xy 169.589864 -369.671657) (xy 169.590212 -369.69573) (xy 169.589726 -369.722981)
			(xy 169.58197 -369.776929) (xy 169.566615 -369.829224) (xy 169.543973 -369.878801) (xy 169.514507 -369.924651)
			(xy 169.478816 -369.965842) (xy 169.437625 -370.001533) (xy 169.391775 -370.030999) (xy 169.342198 -370.053641)
			(xy 169.289903 -370.068996) (xy 169.235955 -370.076752) (xy 169.181453 -370.076752) (xy 169.127505 -370.068996)
			(xy 169.07521 -370.053641) (xy 169.025633 -370.030999) (xy 168.979783 -370.001533) (xy 168.938592 -369.965842)
			(xy 168.902901 -369.924651) (xy 168.873435 -369.878801) (xy 168.850793 -369.829224) (xy 168.835438 -369.776929)
			(xy 168.827682 -369.722981) (xy 168.827196 -369.69573) (xy 168.827875 -369.663198) (xy 168.838993 -369.599088)
			(xy 168.849294 -369.568222) (xy 168.852342 -369.559586) (xy 168.852088 -369.541806) (xy 168.822624 -369.46332)
			(xy 168.811194 -369.450112) (xy 168.803066 -369.44554) (xy 168.770808 -369.425728) (xy 168.764395 -369.421708)
			(xy 168.749925 -369.417302) (xy 168.74236 -369.417092) (xy 168.460928 -369.417092) (xy 168.453372 -369.417356)
			(xy 168.438914 -369.421757) (xy 168.43248 -369.425728) (xy 168.400222 -369.44554) (xy 168.392094 -369.450112)
			(xy 168.380664 -369.46332) (xy 168.3512 -369.541806) (xy 168.350946 -369.559586) (xy 168.353994 -369.568222)
			(xy 168.364278 -369.599092) (xy 168.375389 -369.663199) (xy 168.376092 -369.69573) (xy 168.375606 -369.722981)
			(xy 168.36785 -369.776929) (xy 168.352495 -369.829224) (xy 168.329853 -369.878801) (xy 168.300387 -369.924651)
			(xy 168.264696 -369.965842) (xy 168.223505 -370.001533) (xy 168.177655 -370.030999) (xy 168.128078 -370.053641)
			(xy 168.075783 -370.068996) (xy 168.021835 -370.076752) (xy 167.967333 -370.076752) (xy 167.913385 -370.068996)
			(xy 167.86109 -370.053641) (xy 167.811513 -370.030999) (xy 167.765663 -370.001533) (xy 167.724472 -369.965842)
			(xy 167.688781 -369.924651) (xy 167.659315 -369.878801) (xy 167.636673 -369.829224) (xy 167.621318 -369.776929)
			(xy 167.613562 -369.722981) (xy 167.613076 -369.69573) (xy 167.613423 -369.671658) (xy 167.619466 -369.623895)
			(xy 167.631461 -369.577269) (xy 167.64 -369.55476) (xy 167.64508 -369.542314) (xy 167.641778 -369.516406)
			(xy 167.574976 -369.425728) (xy 167.551354 -369.414806) (xy 167.538146 -369.415822) (xy 167.509444 -369.416838)
			(xy 167.482191 -369.416318) (xy 167.42824 -369.408566) (xy 167.375941 -369.393215) (xy 167.326359 -369.370577)
			(xy 167.280504 -369.341113) (xy 167.239309 -369.305422) (xy 167.203614 -369.264231) (xy 167.174144 -369.21838)
			(xy 167.1515 -369.168801) (xy 167.136143 -369.116503) (xy 167.128385 -369.062553) (xy 166.671252 -369.062553)
			(xy 166.663496 -369.116499) (xy 166.648142 -369.168795) (xy 166.625502 -369.218373) (xy 166.596038 -369.264225)
			(xy 166.560348 -369.305417) (xy 166.51916 -369.341112) (xy 166.473312 -369.370581) (xy 166.423736 -369.393227)
			(xy 166.371443 -369.408587) (xy 166.317495 -369.416349) (xy 166.290244 -369.416838) (xy 166.261542 -369.415822)
			(xy 166.248334 -369.414806) (xy 166.224712 -369.425728) (xy 166.15791 -369.516406) (xy 166.154608 -369.542314)
			(xy 166.159688 -369.55476) (xy 166.168238 -369.577266) (xy 166.180237 -369.623891) (xy 166.186264 -369.671657)
			(xy 166.186612 -369.69573) (xy 166.186126 -369.722981) (xy 166.17837 -369.776929) (xy 166.163015 -369.829224)
			(xy 166.140373 -369.878801) (xy 166.110907 -369.924651) (xy 166.075216 -369.965842) (xy 166.034025 -370.001533)
			(xy 165.988175 -370.030999) (xy 165.938598 -370.053641) (xy 165.886303 -370.068996) (xy 165.832355 -370.076752)
			(xy 165.777853 -370.076752) (xy 165.723905 -370.068996) (xy 165.67161 -370.053641) (xy 165.622033 -370.030999)
			(xy 165.576183 -370.001533) (xy 165.534992 -369.965842) (xy 165.499301 -369.924651) (xy 165.469835 -369.878801)
			(xy 165.447193 -369.829224) (xy 165.431838 -369.776929) (xy 165.424082 -369.722981) (xy 165.423596 -369.69573)
			(xy 165.424275 -369.663198) (xy 165.435393 -369.599088) (xy 165.445694 -369.568222) (xy 165.448742 -369.559586)
			(xy 165.448488 -369.541806) (xy 165.419024 -369.46332) (xy 165.407594 -369.450112) (xy 165.399466 -369.44554)
			(xy 165.367208 -369.425728) (xy 165.360795 -369.421708) (xy 165.346325 -369.417302) (xy 165.33876 -369.417092)
			(xy 165.057328 -369.417092) (xy 165.049772 -369.417356) (xy 165.035314 -369.421757) (xy 165.02888 -369.425728)
			(xy 164.996622 -369.44554) (xy 164.988494 -369.450112) (xy 164.977064 -369.46332) (xy 164.9476 -369.541806)
			(xy 164.947346 -369.559586) (xy 164.950394 -369.568222) (xy 164.960678 -369.599092) (xy 164.971789 -369.663199)
			(xy 164.972492 -369.69573) (xy 164.972006 -369.722981) (xy 164.96425 -369.776929) (xy 164.948895 -369.829224)
			(xy 164.926253 -369.878801) (xy 164.896787 -369.924651) (xy 164.861096 -369.965842) (xy 164.819905 -370.001533)
			(xy 164.774055 -370.030999) (xy 164.724478 -370.053641) (xy 164.672183 -370.068996) (xy 164.618235 -370.076752)
			(xy 164.563733 -370.076752) (xy 164.509785 -370.068996) (xy 164.45749 -370.053641) (xy 164.407913 -370.030999)
			(xy 164.362063 -370.001533) (xy 164.320872 -369.965842) (xy 164.285181 -369.924651) (xy 164.255715 -369.878801)
			(xy 164.233073 -369.829224) (xy 164.217718 -369.776929) (xy 164.209962 -369.722981) (xy 164.209476 -369.69573)
			(xy 164.209823 -369.671658) (xy 164.215866 -369.623895) (xy 164.227861 -369.577269) (xy 164.2364 -369.55476)
			(xy 164.24148 -369.542314) (xy 164.238178 -369.516406) (xy 164.171376 -369.425728) (xy 164.147754 -369.414806)
			(xy 164.134546 -369.415822) (xy 164.105844 -369.416838) (xy 164.078591 -369.416318) (xy 164.02464 -369.408566)
			(xy 163.972341 -369.393215) (xy 163.922759 -369.370577) (xy 163.876904 -369.341113) (xy 163.835709 -369.305422)
			(xy 163.800014 -369.264231) (xy 163.770544 -369.21838) (xy 163.7479 -369.168801) (xy 163.732543 -369.116503)
			(xy 163.724785 -369.062553) (xy 159.864052 -369.062553) (xy 159.856296 -369.116499) (xy 159.840942 -369.168795)
			(xy 159.818302 -369.218373) (xy 159.788838 -369.264225) (xy 159.753148 -369.305417) (xy 159.71196 -369.341112)
			(xy 159.666112 -369.370581) (xy 159.616536 -369.393227) (xy 159.564243 -369.408587) (xy 159.510295 -369.416349)
			(xy 159.483044 -369.416838) (xy 159.454342 -369.415822) (xy 159.441134 -369.414806) (xy 159.417512 -369.425728)
			(xy 159.35071 -369.516406) (xy 159.347408 -369.542314) (xy 159.352488 -369.55476) (xy 159.361038 -369.577266)
			(xy 159.373037 -369.623891) (xy 159.379064 -369.671657) (xy 159.379412 -369.69573) (xy 159.378926 -369.722981)
			(xy 159.37117 -369.776929) (xy 159.355815 -369.829224) (xy 159.333173 -369.878801) (xy 159.303707 -369.924651)
			(xy 159.268016 -369.965842) (xy 159.226825 -370.001533) (xy 159.180975 -370.030999) (xy 159.131398 -370.053641)
			(xy 159.079103 -370.068996) (xy 159.025155 -370.076752) (xy 158.970653 -370.076752) (xy 158.916705 -370.068996)
			(xy 158.86441 -370.053641) (xy 158.814833 -370.030999) (xy 158.768983 -370.001533) (xy 158.727792 -369.965842)
			(xy 158.692101 -369.924651) (xy 158.662635 -369.878801) (xy 158.639993 -369.829224) (xy 158.624638 -369.776929)
			(xy 158.616882 -369.722981) (xy 158.616396 -369.69573) (xy 158.617075 -369.663198) (xy 158.628193 -369.599088)
			(xy 158.638494 -369.568222) (xy 158.641542 -369.559586) (xy 158.641288 -369.541806) (xy 158.611824 -369.46332)
			(xy 158.600394 -369.450112) (xy 158.592266 -369.44554) (xy 158.560008 -369.425728) (xy 158.553595 -369.421708)
			(xy 158.539125 -369.417302) (xy 158.53156 -369.417092) (xy 158.250128 -369.417092) (xy 158.242572 -369.417356)
			(xy 158.228114 -369.421757) (xy 158.22168 -369.425728) (xy 158.189422 -369.44554) (xy 158.181294 -369.450112)
			(xy 158.169864 -369.46332) (xy 158.1404 -369.541806) (xy 158.140146 -369.559586) (xy 158.143194 -369.568222)
			(xy 158.153478 -369.599092) (xy 158.164589 -369.663199) (xy 158.165292 -369.69573) (xy 158.164806 -369.722981)
			(xy 158.15705 -369.776929) (xy 158.141695 -369.829224) (xy 158.119053 -369.878801) (xy 158.089587 -369.924651)
			(xy 158.053896 -369.965842) (xy 158.012705 -370.001533) (xy 157.966855 -370.030999) (xy 157.917278 -370.053641)
			(xy 157.864983 -370.068996) (xy 157.811035 -370.076752) (xy 157.756533 -370.076752) (xy 157.702585 -370.068996)
			(xy 157.65029 -370.053641) (xy 157.600713 -370.030999) (xy 157.554863 -370.001533) (xy 157.513672 -369.965842)
			(xy 157.477981 -369.924651) (xy 157.448515 -369.878801) (xy 157.425873 -369.829224) (xy 157.410518 -369.776929)
			(xy 157.402762 -369.722981) (xy 157.402276 -369.69573) (xy 157.402623 -369.671658) (xy 157.408666 -369.623895)
			(xy 157.420661 -369.577269) (xy 157.4292 -369.55476) (xy 157.43428 -369.542314) (xy 157.430978 -369.516406)
			(xy 157.364176 -369.425728) (xy 157.340554 -369.414806) (xy 157.327346 -369.415822) (xy 157.298644 -369.416838)
			(xy 157.271391 -369.416318) (xy 157.21744 -369.408566) (xy 157.165141 -369.393215) (xy 157.115559 -369.370577)
			(xy 157.069704 -369.341113) (xy 157.028509 -369.305422) (xy 156.992814 -369.264231) (xy 156.963344 -369.21838)
			(xy 156.9407 -369.168801) (xy 156.925343 -369.116503) (xy 156.917585 -369.062553) (xy 153.056852 -369.062553)
			(xy 153.049096 -369.116499) (xy 153.033742 -369.168795) (xy 153.011102 -369.218373) (xy 152.981638 -369.264225)
			(xy 152.945948 -369.305417) (xy 152.90476 -369.341112) (xy 152.858912 -369.370581) (xy 152.809336 -369.393227)
			(xy 152.757043 -369.408587) (xy 152.703095 -369.416349) (xy 152.675844 -369.416838) (xy 152.647142 -369.415822)
			(xy 152.633934 -369.414806) (xy 152.610312 -369.425728) (xy 152.54351 -369.516406) (xy 152.540208 -369.542314)
			(xy 152.545288 -369.55476) (xy 152.553838 -369.577266) (xy 152.565837 -369.623891) (xy 152.571864 -369.671657)
			(xy 152.572212 -369.69573) (xy 152.571726 -369.722981) (xy 152.56397 -369.776929) (xy 152.548615 -369.829224)
			(xy 152.525973 -369.878801) (xy 152.496507 -369.924651) (xy 152.460816 -369.965842) (xy 152.419625 -370.001533)
			(xy 152.373775 -370.030999) (xy 152.324198 -370.053641) (xy 152.271903 -370.068996) (xy 152.217955 -370.076752)
			(xy 152.163453 -370.076752) (xy 152.109505 -370.068996) (xy 152.05721 -370.053641) (xy 152.007633 -370.030999)
			(xy 151.961783 -370.001533) (xy 151.920592 -369.965842) (xy 151.884901 -369.924651) (xy 151.855435 -369.878801)
			(xy 151.832793 -369.829224) (xy 151.817438 -369.776929) (xy 151.809682 -369.722981) (xy 151.809196 -369.69573)
			(xy 151.809875 -369.663198) (xy 151.820993 -369.599088) (xy 151.831294 -369.568222) (xy 151.834342 -369.559586)
			(xy 151.834088 -369.541806) (xy 151.804624 -369.46332) (xy 151.793194 -369.450112) (xy 151.785066 -369.44554)
			(xy 151.752808 -369.425728) (xy 151.746395 -369.421708) (xy 151.731925 -369.417302) (xy 151.72436 -369.417092)
			(xy 151.442928 -369.417092) (xy 151.435372 -369.417356) (xy 151.420914 -369.421757) (xy 151.41448 -369.425728)
			(xy 151.382222 -369.44554) (xy 151.374094 -369.450112) (xy 151.362664 -369.46332) (xy 151.3332 -369.541806)
			(xy 151.332946 -369.559586) (xy 151.335994 -369.568222) (xy 151.346278 -369.599092) (xy 151.357389 -369.663199)
			(xy 151.358092 -369.69573) (xy 151.357606 -369.722981) (xy 151.34985 -369.776929) (xy 151.334495 -369.829224)
			(xy 151.311853 -369.878801) (xy 151.282387 -369.924651) (xy 151.246696 -369.965842) (xy 151.205505 -370.001533)
			(xy 151.159655 -370.030999) (xy 151.110078 -370.053641) (xy 151.057783 -370.068996) (xy 151.003835 -370.076752)
			(xy 150.949333 -370.076752) (xy 150.895385 -370.068996) (xy 150.84309 -370.053641) (xy 150.793513 -370.030999)
			(xy 150.747663 -370.001533) (xy 150.706472 -369.965842) (xy 150.670781 -369.924651) (xy 150.641315 -369.878801)
			(xy 150.618673 -369.829224) (xy 150.603318 -369.776929) (xy 150.595562 -369.722981) (xy 150.595076 -369.69573)
			(xy 150.595423 -369.671658) (xy 150.601466 -369.623895) (xy 150.613461 -369.577269) (xy 150.622 -369.55476)
			(xy 150.62708 -369.542314) (xy 150.623778 -369.516406) (xy 150.556976 -369.425728) (xy 150.533354 -369.414806)
			(xy 150.520146 -369.415822) (xy 150.491444 -369.416838) (xy 150.464191 -369.416318) (xy 150.41024 -369.408566)
			(xy 150.357941 -369.393215) (xy 150.308359 -369.370577) (xy 150.262504 -369.341113) (xy 150.221309 -369.305422)
			(xy 150.185614 -369.264231) (xy 150.156144 -369.21838) (xy 150.1335 -369.168801) (xy 150.118143 -369.116503)
			(xy 150.110385 -369.062553) (xy 146.249652 -369.062553) (xy 146.241896 -369.116499) (xy 146.226542 -369.168795)
			(xy 146.203902 -369.218373) (xy 146.174438 -369.264225) (xy 146.138748 -369.305417) (xy 146.09756 -369.341112)
			(xy 146.051712 -369.370581) (xy 146.002136 -369.393227) (xy 145.949843 -369.408587) (xy 145.895895 -369.416349)
			(xy 145.868644 -369.416838) (xy 145.839942 -369.415822) (xy 145.826734 -369.414806) (xy 145.803112 -369.425728)
			(xy 145.73631 -369.516406) (xy 145.733008 -369.542314) (xy 145.738088 -369.55476) (xy 145.746638 -369.577266)
			(xy 145.758637 -369.623891) (xy 145.764664 -369.671657) (xy 145.765012 -369.69573) (xy 145.764526 -369.722981)
			(xy 145.75677 -369.776929) (xy 145.741415 -369.829224) (xy 145.718773 -369.878801) (xy 145.689307 -369.924651)
			(xy 145.653616 -369.965842) (xy 145.612425 -370.001533) (xy 145.566575 -370.030999) (xy 145.516998 -370.053641)
			(xy 145.464703 -370.068996) (xy 145.410755 -370.076752) (xy 145.356253 -370.076752) (xy 145.302305 -370.068996)
			(xy 145.25001 -370.053641) (xy 145.200433 -370.030999) (xy 145.154583 -370.001533) (xy 145.113392 -369.965842)
			(xy 145.077701 -369.924651) (xy 145.048235 -369.878801) (xy 145.025593 -369.829224) (xy 145.010238 -369.776929)
			(xy 145.002482 -369.722981) (xy 145.001996 -369.69573) (xy 145.002675 -369.663198) (xy 145.013793 -369.599088)
			(xy 145.024094 -369.568222) (xy 145.027142 -369.559586) (xy 145.026888 -369.541806) (xy 144.997424 -369.46332)
			(xy 144.985994 -369.450112) (xy 144.977866 -369.44554) (xy 144.945608 -369.425728) (xy 144.939195 -369.421708)
			(xy 144.924725 -369.417302) (xy 144.91716 -369.417092) (xy 144.635728 -369.417092) (xy 144.628172 -369.417356)
			(xy 144.613714 -369.421757) (xy 144.60728 -369.425728) (xy 144.575022 -369.44554) (xy 144.566894 -369.450112)
			(xy 144.555464 -369.46332) (xy 144.526 -369.541806) (xy 144.525746 -369.559586) (xy 144.528794 -369.568222)
			(xy 144.539078 -369.599092) (xy 144.550189 -369.663199) (xy 144.550892 -369.69573) (xy 144.550406 -369.722981)
			(xy 144.54265 -369.776929) (xy 144.527295 -369.829224) (xy 144.504653 -369.878801) (xy 144.475187 -369.924651)
			(xy 144.439496 -369.965842) (xy 144.398305 -370.001533) (xy 144.352455 -370.030999) (xy 144.302878 -370.053641)
			(xy 144.250583 -370.068996) (xy 144.196635 -370.076752) (xy 144.142133 -370.076752) (xy 144.088185 -370.068996)
			(xy 144.03589 -370.053641) (xy 143.986313 -370.030999) (xy 143.940463 -370.001533) (xy 143.899272 -369.965842)
			(xy 143.863581 -369.924651) (xy 143.834115 -369.878801) (xy 143.811473 -369.829224) (xy 143.796118 -369.776929)
			(xy 143.788362 -369.722981) (xy 143.787876 -369.69573) (xy 143.788223 -369.671658) (xy 143.794266 -369.623895)
			(xy 143.806261 -369.577269) (xy 143.8148 -369.55476) (xy 143.81988 -369.542314) (xy 143.816578 -369.516406)
			(xy 143.749776 -369.425728) (xy 143.726154 -369.414806) (xy 143.712946 -369.415822) (xy 143.684244 -369.416838)
			(xy 143.656991 -369.416318) (xy 143.60304 -369.408566) (xy 143.550741 -369.393215) (xy 143.501159 -369.370577)
			(xy 143.455304 -369.341113) (xy 143.414109 -369.305422) (xy 143.378414 -369.264231) (xy 143.348944 -369.21838)
			(xy 143.3263 -369.168801) (xy 143.310943 -369.116503) (xy 143.303185 -369.062553) (xy 142.328915 -369.062553)
			(xy 142.32484 -369.069501) (xy 142.309596 -369.089686) (xy 142.304267 -369.097124) (xy 142.298803 -369.114573)
			(xy 142.298928 -369.123722) (xy 142.300706 -369.154456) (xy 142.301592 -369.163663) (xy 142.309008 -369.180591)
			(xy 142.315184 -369.187476) (xy 142.338176 -369.211374) (xy 142.378415 -369.264086) (xy 142.411458 -369.321583)
			(xy 142.436746 -369.382888) (xy 142.453848 -369.44696) (xy 142.462474 -369.512712) (xy 142.463012 -369.54587)
			(xy 142.462467 -369.580827) (xy 142.452896 -369.650081) (xy 142.433931 -369.717373) (xy 142.405927 -369.781432)
			(xy 142.369415 -369.841053) (xy 142.347696 -369.86845) (xy 142.342409 -369.875456) (xy 142.33643 -369.891942)
			(xy 142.336012 -369.900708) (xy 142.336012 -370.054632) (xy 142.336355 -370.063411) (xy 142.342353 -370.079914)
			(xy 142.347696 -370.08689) (xy 142.368259 -370.112834) (xy 142.40326 -370.169024) (xy 142.430673 -370.229282)
			(xy 142.450035 -370.292587) (xy 142.461018 -370.35787) (xy 142.462758 -370.390928) (xy 142.463502 -370.39973)
			(xy 142.470122 -370.416093) (xy 142.475712 -370.422932) (xy 142.495778 -370.445538) (xy 142.501858 -370.451795)
			(xy 142.51719 -370.4601) (xy 142.52575 -370.461794) (xy 142.552418 -370.466357) (xy 142.604187 -370.482076)
			(xy 142.653216 -370.504952) (xy 142.698521 -370.534525) (xy 142.739194 -370.570202) (xy 142.774418 -370.611268)
			(xy 142.803487 -370.656899) (xy 142.825817 -370.706179) (xy 142.840961 -370.758119) (xy 142.848615 -370.811679)
			(xy 142.849092 -370.83873) (xy 142.848403 -370.871262) (xy 142.837292 -370.935371) (xy 142.826994 -370.966238)
			(xy 142.823946 -370.974874) (xy 142.8242 -370.992654) (xy 142.853664 -371.07114) (xy 142.865094 -371.084348)
			(xy 142.873222 -371.08892) (xy 142.90548 -371.108732) (xy 142.911871 -371.112791) (xy 142.926358 -371.117172)
			(xy 142.933928 -371.117368) (xy 143.21536 -371.117368) (xy 143.222914 -371.11709) (xy 143.237372 -371.112698)
			(xy 143.243808 -371.108732) (xy 143.276066 -371.08892) (xy 143.284194 -371.084348) (xy 143.295624 -371.07114)
			(xy 143.325088 -370.992654) (xy 143.325342 -370.974874) (xy 143.322294 -370.966238) (xy 143.311999 -370.935371)
			(xy 143.300895 -370.871261) (xy 143.300196 -370.83873) (xy 143.300682 -370.811479) (xy 143.308438 -370.757531)
			(xy 143.323793 -370.705236) (xy 143.346435 -370.655659) (xy 143.375901 -370.609809) (xy 143.411592 -370.568618)
			(xy 143.452783 -370.532927) (xy 143.498633 -370.503461) (xy 143.54821 -370.480819) (xy 143.600505 -370.465464)
			(xy 143.654453 -370.457708) (xy 143.708955 -370.457708) (xy 143.762903 -370.465464) (xy 143.815198 -370.480819)
			(xy 143.864775 -370.503461) (xy 143.910625 -370.532927) (xy 143.951816 -370.568618) (xy 143.987507 -370.609809)
			(xy 144.016973 -370.655659) (xy 144.039615 -370.705236) (xy 144.05497 -370.757531) (xy 144.062726 -370.811479)
			(xy 144.063212 -370.83873) (xy 144.062854 -370.862802) (xy 144.056815 -370.910564) (xy 144.044825 -370.95719)
			(xy 144.036288 -370.9797) (xy 144.031208 -370.992146) (xy 144.03451 -371.018054) (xy 144.101312 -371.108732)
			(xy 144.124934 -371.119654) (xy 144.138142 -371.118638) (xy 144.166844 -371.117622) (xy 144.194095 -371.118051)
			(xy 144.248043 -371.125813) (xy 144.300336 -371.141173) (xy 144.349912 -371.163819) (xy 144.39576 -371.193288)
			(xy 144.436948 -371.228983) (xy 144.472638 -371.270175) (xy 144.502102 -371.316027) (xy 144.524742 -371.365605)
			(xy 144.540096 -371.417901) (xy 144.547852 -371.471849) (xy 144.547852 -371.526351) (xy 144.547852 -371.526353)
			(xy 148.408585 -371.526353) (xy 148.408585 -371.471847) (xy 148.416343 -371.417897) (xy 148.4317 -371.365599)
			(xy 148.454344 -371.31602) (xy 148.483814 -371.270169) (xy 148.519509 -371.228978) (xy 148.560704 -371.193287)
			(xy 148.606559 -371.163823) (xy 148.656141 -371.141185) (xy 148.70844 -371.125834) (xy 148.762391 -371.118082)
			(xy 148.789644 -371.117622) (xy 148.818346 -371.118638) (xy 148.831554 -371.119654) (xy 148.855176 -371.108732)
			(xy 148.921978 -371.018054) (xy 148.92528 -370.992146) (xy 148.9202 -370.9797) (xy 148.911667 -370.957188)
			(xy 148.899662 -370.910566) (xy 148.893628 -370.862802) (xy 148.893276 -370.83873) (xy 148.893762 -370.811479)
			(xy 148.901518 -370.757531) (xy 148.916873 -370.705236) (xy 148.939515 -370.655659) (xy 148.968981 -370.609809)
			(xy 149.004672 -370.568618) (xy 149.045863 -370.532927) (xy 149.091713 -370.503461) (xy 149.14129 -370.480819)
			(xy 149.193585 -370.465464) (xy 149.247533 -370.457708) (xy 149.302035 -370.457708) (xy 149.355983 -370.465464)
			(xy 149.408278 -370.480819) (xy 149.457855 -370.503461) (xy 149.503705 -370.532927) (xy 149.544896 -370.568618)
			(xy 149.580587 -370.609809) (xy 149.610053 -370.655659) (xy 149.632695 -370.705236) (xy 149.64805 -370.757531)
			(xy 149.655806 -370.811479) (xy 149.656292 -370.83873) (xy 149.655603 -370.871262) (xy 149.644492 -370.935371)
			(xy 149.634194 -370.966238) (xy 149.631146 -370.974874) (xy 149.6314 -370.992654) (xy 149.660864 -371.07114)
			(xy 149.672294 -371.084348) (xy 149.680422 -371.08892) (xy 149.71268 -371.108732) (xy 149.719071 -371.112791)
			(xy 149.733558 -371.117172) (xy 149.741128 -371.117368) (xy 150.02256 -371.117368) (xy 150.030114 -371.11709)
			(xy 150.044572 -371.112698) (xy 150.051008 -371.108732) (xy 150.083266 -371.08892) (xy 150.091394 -371.084348)
			(xy 150.102824 -371.07114) (xy 150.132288 -370.992654) (xy 150.132542 -370.974874) (xy 150.129494 -370.966238)
			(xy 150.119199 -370.935371) (xy 150.108095 -370.871261) (xy 150.107396 -370.83873) (xy 150.107882 -370.811479)
			(xy 150.115638 -370.757531) (xy 150.130993 -370.705236) (xy 150.153635 -370.655659) (xy 150.183101 -370.609809)
			(xy 150.218792 -370.568618) (xy 150.259983 -370.532927) (xy 150.305833 -370.503461) (xy 150.35541 -370.480819)
			(xy 150.407705 -370.465464) (xy 150.461653 -370.457708) (xy 150.516155 -370.457708) (xy 150.570103 -370.465464)
			(xy 150.622398 -370.480819) (xy 150.671975 -370.503461) (xy 150.717825 -370.532927) (xy 150.759016 -370.568618)
			(xy 150.794707 -370.609809) (xy 150.824173 -370.655659) (xy 150.846815 -370.705236) (xy 150.86217 -370.757531)
			(xy 150.869926 -370.811479) (xy 150.870412 -370.83873) (xy 150.870054 -370.862802) (xy 150.864015 -370.910564)
			(xy 150.852025 -370.95719) (xy 150.843488 -370.9797) (xy 150.838408 -370.992146) (xy 150.84171 -371.018054)
			(xy 150.908512 -371.108732) (xy 150.932134 -371.119654) (xy 150.945342 -371.118638) (xy 150.974044 -371.117622)
			(xy 151.001295 -371.118051) (xy 151.055243 -371.125813) (xy 151.107536 -371.141173) (xy 151.157112 -371.163819)
			(xy 151.20296 -371.193288) (xy 151.244148 -371.228983) (xy 151.279838 -371.270175) (xy 151.309302 -371.316027)
			(xy 151.331942 -371.365605) (xy 151.347296 -371.417901) (xy 151.355052 -371.471849) (xy 151.355052 -371.526351)
			(xy 151.355052 -371.526353) (xy 155.215785 -371.526353) (xy 155.215785 -371.471847) (xy 155.223543 -371.417897)
			(xy 155.2389 -371.365599) (xy 155.261544 -371.31602) (xy 155.291014 -371.270169) (xy 155.326709 -371.228978)
			(xy 155.367904 -371.193287) (xy 155.413759 -371.163823) (xy 155.463341 -371.141185) (xy 155.51564 -371.125834)
			(xy 155.569591 -371.118082) (xy 155.596844 -371.117622) (xy 155.625546 -371.118638) (xy 155.638754 -371.119654)
			(xy 155.662376 -371.108732) (xy 155.729178 -371.018054) (xy 155.73248 -370.992146) (xy 155.7274 -370.9797)
			(xy 155.718867 -370.957188) (xy 155.706862 -370.910566) (xy 155.700828 -370.862802) (xy 155.700476 -370.83873)
			(xy 155.700962 -370.811479) (xy 155.708718 -370.757531) (xy 155.724073 -370.705236) (xy 155.746715 -370.655659)
			(xy 155.776181 -370.609809) (xy 155.811872 -370.568618) (xy 155.853063 -370.532927) (xy 155.898913 -370.503461)
			(xy 155.94849 -370.480819) (xy 156.000785 -370.465464) (xy 156.054733 -370.457708) (xy 156.109235 -370.457708)
			(xy 156.163183 -370.465464) (xy 156.215478 -370.480819) (xy 156.265055 -370.503461) (xy 156.310905 -370.532927)
			(xy 156.352096 -370.568618) (xy 156.387787 -370.609809) (xy 156.417253 -370.655659) (xy 156.439895 -370.705236)
			(xy 156.45525 -370.757531) (xy 156.463006 -370.811479) (xy 156.463492 -370.83873) (xy 156.462803 -370.871262)
			(xy 156.451692 -370.935371) (xy 156.441394 -370.966238) (xy 156.438346 -370.974874) (xy 156.4386 -370.992654)
			(xy 156.468064 -371.07114) (xy 156.479494 -371.084348) (xy 156.487622 -371.08892) (xy 156.51988 -371.108732)
			(xy 156.526271 -371.112791) (xy 156.540758 -371.117172) (xy 156.548328 -371.117368) (xy 156.82976 -371.117368)
			(xy 156.837314 -371.11709) (xy 156.851772 -371.112698) (xy 156.858208 -371.108732) (xy 156.890466 -371.08892)
			(xy 156.898594 -371.084348) (xy 156.910024 -371.07114) (xy 156.939488 -370.992654) (xy 156.939742 -370.974874)
			(xy 156.936694 -370.966238) (xy 156.926399 -370.935371) (xy 156.915295 -370.871261) (xy 156.914596 -370.83873)
			(xy 156.915082 -370.811479) (xy 156.922838 -370.757531) (xy 156.938193 -370.705236) (xy 156.960835 -370.655659)
			(xy 156.990301 -370.609809) (xy 157.025992 -370.568618) (xy 157.067183 -370.532927) (xy 157.113033 -370.503461)
			(xy 157.16261 -370.480819) (xy 157.214905 -370.465464) (xy 157.268853 -370.457708) (xy 157.323355 -370.457708)
			(xy 157.377303 -370.465464) (xy 157.429598 -370.480819) (xy 157.479175 -370.503461) (xy 157.525025 -370.532927)
			(xy 157.566216 -370.568618) (xy 157.601907 -370.609809) (xy 157.631373 -370.655659) (xy 157.654015 -370.705236)
			(xy 157.66937 -370.757531) (xy 157.677126 -370.811479) (xy 157.677612 -370.83873) (xy 157.677254 -370.862802)
			(xy 157.671215 -370.910564) (xy 157.659225 -370.95719) (xy 157.650688 -370.9797) (xy 157.645608 -370.992146)
			(xy 157.64891 -371.018054) (xy 157.715712 -371.108732) (xy 157.739334 -371.119654) (xy 157.752542 -371.118638)
			(xy 157.781244 -371.117622) (xy 157.808495 -371.118051) (xy 157.862443 -371.125813) (xy 157.914736 -371.141173)
			(xy 157.964312 -371.163819) (xy 158.01016 -371.193288) (xy 158.051348 -371.228983) (xy 158.087038 -371.270175)
			(xy 158.116502 -371.316027) (xy 158.139142 -371.365605) (xy 158.154496 -371.417901) (xy 158.162252 -371.471849)
			(xy 158.162252 -371.526351) (xy 158.162252 -371.526353) (xy 162.022985 -371.526353) (xy 162.022985 -371.471847)
			(xy 162.030743 -371.417897) (xy 162.0461 -371.365599) (xy 162.068744 -371.31602) (xy 162.098214 -371.270169)
			(xy 162.133909 -371.228978) (xy 162.175104 -371.193287) (xy 162.220959 -371.163823) (xy 162.270541 -371.141185)
			(xy 162.32284 -371.125834) (xy 162.376791 -371.118082) (xy 162.404044 -371.117622) (xy 162.432746 -371.118638)
			(xy 162.445954 -371.119654) (xy 162.469576 -371.108732) (xy 162.536378 -371.018054) (xy 162.53968 -370.992146)
			(xy 162.5346 -370.9797) (xy 162.526067 -370.957188) (xy 162.514062 -370.910566) (xy 162.508028 -370.862802)
			(xy 162.507676 -370.83873) (xy 162.508162 -370.811479) (xy 162.515918 -370.757531) (xy 162.531273 -370.705236)
			(xy 162.553915 -370.655659) (xy 162.583381 -370.609809) (xy 162.619072 -370.568618) (xy 162.660263 -370.532927)
			(xy 162.706113 -370.503461) (xy 162.75569 -370.480819) (xy 162.807985 -370.465464) (xy 162.861933 -370.457708)
			(xy 162.916435 -370.457708) (xy 162.970383 -370.465464) (xy 163.022678 -370.480819) (xy 163.072255 -370.503461)
			(xy 163.118105 -370.532927) (xy 163.159296 -370.568618) (xy 163.194987 -370.609809) (xy 163.224453 -370.655659)
			(xy 163.247095 -370.705236) (xy 163.26245 -370.757531) (xy 163.270206 -370.811479) (xy 163.270692 -370.83873)
			(xy 163.270003 -370.871262) (xy 163.258892 -370.935371) (xy 163.248594 -370.966238) (xy 163.245546 -370.974874)
			(xy 163.2458 -370.992654) (xy 163.275264 -371.07114) (xy 163.286694 -371.084348) (xy 163.294822 -371.08892)
			(xy 163.32708 -371.108732) (xy 163.333471 -371.112791) (xy 163.347958 -371.117172) (xy 163.355528 -371.117368)
			(xy 163.63696 -371.117368) (xy 163.644514 -371.11709) (xy 163.658972 -371.112698) (xy 163.665408 -371.108732)
			(xy 163.697666 -371.08892) (xy 163.705794 -371.084348) (xy 163.717224 -371.07114) (xy 163.746688 -370.992654)
			(xy 163.746942 -370.974874) (xy 163.743894 -370.966238) (xy 163.733599 -370.935371) (xy 163.722495 -370.871261)
			(xy 163.721796 -370.83873) (xy 163.722282 -370.811479) (xy 163.730038 -370.757531) (xy 163.745393 -370.705236)
			(xy 163.768035 -370.655659) (xy 163.797501 -370.609809) (xy 163.833192 -370.568618) (xy 163.874383 -370.532927)
			(xy 163.920233 -370.503461) (xy 163.96981 -370.480819) (xy 164.022105 -370.465464) (xy 164.076053 -370.457708)
			(xy 164.130555 -370.457708) (xy 164.184503 -370.465464) (xy 164.236798 -370.480819) (xy 164.286375 -370.503461)
			(xy 164.332225 -370.532927) (xy 164.373416 -370.568618) (xy 164.409107 -370.609809) (xy 164.438573 -370.655659)
			(xy 164.461215 -370.705236) (xy 164.47657 -370.757531) (xy 164.484326 -370.811479) (xy 164.484812 -370.83873)
			(xy 164.484454 -370.862802) (xy 164.478415 -370.910564) (xy 164.466425 -370.95719) (xy 164.457888 -370.9797)
			(xy 164.452808 -370.992146) (xy 164.45611 -371.018054) (xy 164.522912 -371.108732) (xy 164.546534 -371.119654)
			(xy 164.559742 -371.118638) (xy 164.588444 -371.117622) (xy 164.615695 -371.118051) (xy 164.669643 -371.125813)
			(xy 164.721936 -371.141173) (xy 164.771512 -371.163819) (xy 164.81736 -371.193288) (xy 164.858548 -371.228983)
			(xy 164.894238 -371.270175) (xy 164.923702 -371.316027) (xy 164.946342 -371.365605) (xy 164.961696 -371.417901)
			(xy 164.969452 -371.471849) (xy 164.969452 -371.526351) (xy 164.961696 -371.580299) (xy 164.946342 -371.632595)
			(xy 164.923702 -371.682173) (xy 164.894238 -371.728025) (xy 164.858548 -371.769217) (xy 164.81736 -371.804912)
			(xy 164.771512 -371.834381) (xy 164.721936 -371.857027) (xy 164.669643 -371.872387) (xy 164.615695 -371.880149)
			(xy 164.588444 -371.880638) (xy 164.559742 -371.879622) (xy 164.546534 -371.878606) (xy 164.522912 -371.889528)
			(xy 164.45611 -371.980206) (xy 164.452808 -372.006114) (xy 164.457888 -372.01856) (xy 164.466438 -372.041066)
			(xy 164.478437 -372.087691) (xy 164.484464 -372.135457) (xy 164.484812 -372.15953) (xy 164.484326 -372.186781)
			(xy 164.47657 -372.240729) (xy 164.461215 -372.293024) (xy 164.438573 -372.342601) (xy 164.409107 -372.388451)
			(xy 164.373416 -372.429642) (xy 164.332225 -372.465333) (xy 164.286375 -372.494799) (xy 164.236798 -372.517441)
			(xy 164.184503 -372.532796) (xy 164.130555 -372.540552) (xy 164.076053 -372.540552) (xy 164.022105 -372.532796)
			(xy 163.96981 -372.517441) (xy 163.920233 -372.494799) (xy 163.874383 -372.465333) (xy 163.833192 -372.429642)
			(xy 163.797501 -372.388451) (xy 163.768035 -372.342601) (xy 163.745393 -372.293024) (xy 163.730038 -372.240729)
			(xy 163.722282 -372.186781) (xy 163.721796 -372.15953) (xy 163.722475 -372.126998) (xy 163.733593 -372.062888)
			(xy 163.743894 -372.032022) (xy 163.746942 -372.023386) (xy 163.746688 -372.005606) (xy 163.717224 -371.92712)
			(xy 163.705794 -371.913912) (xy 163.697666 -371.90934) (xy 163.665408 -371.889528) (xy 163.658995 -371.885508)
			(xy 163.644525 -371.881102) (xy 163.63696 -371.880892) (xy 163.355528 -371.880892) (xy 163.347972 -371.881156)
			(xy 163.333514 -371.885557) (xy 163.32708 -371.889528) (xy 163.294822 -371.90934) (xy 163.286694 -371.913912)
			(xy 163.275264 -371.92712) (xy 163.2458 -372.005606) (xy 163.245546 -372.023386) (xy 163.248594 -372.032022)
			(xy 163.258878 -372.062892) (xy 163.269989 -372.126999) (xy 163.270692 -372.15953) (xy 163.270206 -372.186781)
			(xy 163.26245 -372.240729) (xy 163.247095 -372.293024) (xy 163.224453 -372.342601) (xy 163.194987 -372.388451)
			(xy 163.159296 -372.429642) (xy 163.118105 -372.465333) (xy 163.072255 -372.494799) (xy 163.022678 -372.517441)
			(xy 162.970383 -372.532796) (xy 162.916435 -372.540552) (xy 162.861933 -372.540552) (xy 162.807985 -372.532796)
			(xy 162.75569 -372.517441) (xy 162.706113 -372.494799) (xy 162.660263 -372.465333) (xy 162.619072 -372.429642)
			(xy 162.583381 -372.388451) (xy 162.553915 -372.342601) (xy 162.531273 -372.293024) (xy 162.515918 -372.240729)
			(xy 162.508162 -372.186781) (xy 162.507676 -372.15953) (xy 162.508023 -372.135458) (xy 162.514066 -372.087695)
			(xy 162.526061 -372.041069) (xy 162.5346 -372.01856) (xy 162.53968 -372.006114) (xy 162.536378 -371.980206)
			(xy 162.469576 -371.889528) (xy 162.445954 -371.878606) (xy 162.432746 -371.879622) (xy 162.404044 -371.880638)
			(xy 162.376791 -371.880118) (xy 162.32284 -371.872366) (xy 162.270541 -371.857015) (xy 162.220959 -371.834377)
			(xy 162.175104 -371.804913) (xy 162.133909 -371.769222) (xy 162.098214 -371.728031) (xy 162.068744 -371.68218)
			(xy 162.0461 -371.632601) (xy 162.030743 -371.580303) (xy 162.022985 -371.526353) (xy 158.162252 -371.526353)
			(xy 158.154496 -371.580299) (xy 158.139142 -371.632595) (xy 158.116502 -371.682173) (xy 158.087038 -371.728025)
			(xy 158.051348 -371.769217) (xy 158.01016 -371.804912) (xy 157.964312 -371.834381) (xy 157.914736 -371.857027)
			(xy 157.862443 -371.872387) (xy 157.808495 -371.880149) (xy 157.781244 -371.880638) (xy 157.752542 -371.879622)
			(xy 157.739334 -371.878606) (xy 157.715712 -371.889528) (xy 157.64891 -371.980206) (xy 157.645608 -372.006114)
			(xy 157.650688 -372.01856) (xy 157.659238 -372.041066) (xy 157.671237 -372.087691) (xy 157.677264 -372.135457)
			(xy 157.677612 -372.15953) (xy 157.677126 -372.186781) (xy 157.66937 -372.240729) (xy 157.654015 -372.293024)
			(xy 157.631373 -372.342601) (xy 157.601907 -372.388451) (xy 157.566216 -372.429642) (xy 157.525025 -372.465333)
			(xy 157.479175 -372.494799) (xy 157.429598 -372.517441) (xy 157.377303 -372.532796) (xy 157.323355 -372.540552)
			(xy 157.268853 -372.540552) (xy 157.214905 -372.532796) (xy 157.16261 -372.517441) (xy 157.113033 -372.494799)
			(xy 157.067183 -372.465333) (xy 157.025992 -372.429642) (xy 156.990301 -372.388451) (xy 156.960835 -372.342601)
			(xy 156.938193 -372.293024) (xy 156.922838 -372.240729) (xy 156.915082 -372.186781) (xy 156.914596 -372.15953)
			(xy 156.915275 -372.126998) (xy 156.926393 -372.062888) (xy 156.936694 -372.032022) (xy 156.939742 -372.023386)
			(xy 156.939488 -372.005606) (xy 156.910024 -371.92712) (xy 156.898594 -371.913912) (xy 156.890466 -371.90934)
			(xy 156.858208 -371.889528) (xy 156.851795 -371.885508) (xy 156.837325 -371.881102) (xy 156.82976 -371.880892)
			(xy 156.548328 -371.880892) (xy 156.540772 -371.881156) (xy 156.526314 -371.885557) (xy 156.51988 -371.889528)
			(xy 156.487622 -371.90934) (xy 156.479494 -371.913912) (xy 156.468064 -371.92712) (xy 156.4386 -372.005606)
			(xy 156.438346 -372.023386) (xy 156.441394 -372.032022) (xy 156.451678 -372.062892) (xy 156.462789 -372.126999)
			(xy 156.463492 -372.15953) (xy 156.463006 -372.186781) (xy 156.45525 -372.240729) (xy 156.439895 -372.293024)
			(xy 156.417253 -372.342601) (xy 156.387787 -372.388451) (xy 156.352096 -372.429642) (xy 156.310905 -372.465333)
			(xy 156.265055 -372.494799) (xy 156.215478 -372.517441) (xy 156.163183 -372.532796) (xy 156.109235 -372.540552)
			(xy 156.054733 -372.540552) (xy 156.000785 -372.532796) (xy 155.94849 -372.517441) (xy 155.898913 -372.494799)
			(xy 155.853063 -372.465333) (xy 155.811872 -372.429642) (xy 155.776181 -372.388451) (xy 155.746715 -372.342601)
			(xy 155.724073 -372.293024) (xy 155.708718 -372.240729) (xy 155.700962 -372.186781) (xy 155.700476 -372.15953)
			(xy 155.700823 -372.135458) (xy 155.706866 -372.087695) (xy 155.718861 -372.041069) (xy 155.7274 -372.01856)
			(xy 155.73248 -372.006114) (xy 155.729178 -371.980206) (xy 155.662376 -371.889528) (xy 155.638754 -371.878606)
			(xy 155.625546 -371.879622) (xy 155.596844 -371.880638) (xy 155.569591 -371.880118) (xy 155.51564 -371.872366)
			(xy 155.463341 -371.857015) (xy 155.413759 -371.834377) (xy 155.367904 -371.804913) (xy 155.326709 -371.769222)
			(xy 155.291014 -371.728031) (xy 155.261544 -371.68218) (xy 155.2389 -371.632601) (xy 155.223543 -371.580303)
			(xy 155.215785 -371.526353) (xy 151.355052 -371.526353) (xy 151.347296 -371.580299) (xy 151.331942 -371.632595)
			(xy 151.309302 -371.682173) (xy 151.279838 -371.728025) (xy 151.244148 -371.769217) (xy 151.20296 -371.804912)
			(xy 151.157112 -371.834381) (xy 151.107536 -371.857027) (xy 151.055243 -371.872387) (xy 151.001295 -371.880149)
			(xy 150.974044 -371.880638) (xy 150.945342 -371.879622) (xy 150.932134 -371.878606) (xy 150.908512 -371.889528)
			(xy 150.84171 -371.980206) (xy 150.838408 -372.006114) (xy 150.843488 -372.01856) (xy 150.852038 -372.041066)
			(xy 150.864037 -372.087691) (xy 150.870064 -372.135457) (xy 150.870412 -372.15953) (xy 150.869926 -372.186781)
			(xy 150.86217 -372.240729) (xy 150.846815 -372.293024) (xy 150.824173 -372.342601) (xy 150.794707 -372.388451)
			(xy 150.759016 -372.429642) (xy 150.717825 -372.465333) (xy 150.671975 -372.494799) (xy 150.622398 -372.517441)
			(xy 150.570103 -372.532796) (xy 150.516155 -372.540552) (xy 150.461653 -372.540552) (xy 150.407705 -372.532796)
			(xy 150.35541 -372.517441) (xy 150.305833 -372.494799) (xy 150.259983 -372.465333) (xy 150.218792 -372.429642)
			(xy 150.183101 -372.388451) (xy 150.153635 -372.342601) (xy 150.130993 -372.293024) (xy 150.115638 -372.240729)
			(xy 150.107882 -372.186781) (xy 150.107396 -372.15953) (xy 150.108075 -372.126998) (xy 150.119193 -372.062888)
			(xy 150.129494 -372.032022) (xy 150.132542 -372.023386) (xy 150.132288 -372.005606) (xy 150.102824 -371.92712)
			(xy 150.091394 -371.913912) (xy 150.083266 -371.90934) (xy 150.051008 -371.889528) (xy 150.044595 -371.885508)
			(xy 150.030125 -371.881102) (xy 150.02256 -371.880892) (xy 149.741128 -371.880892) (xy 149.733572 -371.881156)
			(xy 149.719114 -371.885557) (xy 149.71268 -371.889528) (xy 149.680422 -371.90934) (xy 149.672294 -371.913912)
			(xy 149.660864 -371.92712) (xy 149.6314 -372.005606) (xy 149.631146 -372.023386) (xy 149.634194 -372.032022)
			(xy 149.644478 -372.062892) (xy 149.655589 -372.126999) (xy 149.656292 -372.15953) (xy 149.655806 -372.186781)
			(xy 149.64805 -372.240729) (xy 149.632695 -372.293024) (xy 149.610053 -372.342601) (xy 149.580587 -372.388451)
			(xy 149.544896 -372.429642) (xy 149.503705 -372.465333) (xy 149.457855 -372.494799) (xy 149.408278 -372.517441)
			(xy 149.355983 -372.532796) (xy 149.302035 -372.540552) (xy 149.247533 -372.540552) (xy 149.193585 -372.532796)
			(xy 149.14129 -372.517441) (xy 149.091713 -372.494799) (xy 149.045863 -372.465333) (xy 149.004672 -372.429642)
			(xy 148.968981 -372.388451) (xy 148.939515 -372.342601) (xy 148.916873 -372.293024) (xy 148.901518 -372.240729)
			(xy 148.893762 -372.186781) (xy 148.893276 -372.15953) (xy 148.893623 -372.135458) (xy 148.899666 -372.087695)
			(xy 148.911661 -372.041069) (xy 148.9202 -372.01856) (xy 148.92528 -372.006114) (xy 148.921978 -371.980206)
			(xy 148.855176 -371.889528) (xy 148.831554 -371.878606) (xy 148.818346 -371.879622) (xy 148.789644 -371.880638)
			(xy 148.762391 -371.880118) (xy 148.70844 -371.872366) (xy 148.656141 -371.857015) (xy 148.606559 -371.834377)
			(xy 148.560704 -371.804913) (xy 148.519509 -371.769222) (xy 148.483814 -371.728031) (xy 148.454344 -371.68218)
			(xy 148.4317 -371.632601) (xy 148.416343 -371.580303) (xy 148.408585 -371.526353) (xy 144.547852 -371.526353)
			(xy 144.540096 -371.580299) (xy 144.524742 -371.632595) (xy 144.502102 -371.682173) (xy 144.472638 -371.728025)
			(xy 144.436948 -371.769217) (xy 144.39576 -371.804912) (xy 144.349912 -371.834381) (xy 144.300336 -371.857027)
			(xy 144.248043 -371.872387) (xy 144.194095 -371.880149) (xy 144.166844 -371.880638) (xy 144.138142 -371.879622)
			(xy 144.124934 -371.878606) (xy 144.101312 -371.889528) (xy 144.03451 -371.980206) (xy 144.031208 -372.006114)
			(xy 144.036288 -372.01856) (xy 144.044838 -372.041066) (xy 144.056837 -372.087691) (xy 144.062864 -372.135457)
			(xy 144.063212 -372.15953) (xy 144.062726 -372.186781) (xy 144.05497 -372.240729) (xy 144.039615 -372.293024)
			(xy 144.016973 -372.342601) (xy 143.987507 -372.388451) (xy 143.951816 -372.429642) (xy 143.910625 -372.465333)
			(xy 143.864775 -372.494799) (xy 143.815198 -372.517441) (xy 143.762903 -372.532796) (xy 143.708955 -372.540552)
			(xy 143.654453 -372.540552) (xy 143.600505 -372.532796) (xy 143.54821 -372.517441) (xy 143.498633 -372.494799)
			(xy 143.452783 -372.465333) (xy 143.411592 -372.429642) (xy 143.375901 -372.388451) (xy 143.346435 -372.342601)
			(xy 143.323793 -372.293024) (xy 143.308438 -372.240729) (xy 143.300682 -372.186781) (xy 143.300196 -372.15953)
			(xy 143.300875 -372.126998) (xy 143.311993 -372.062888) (xy 143.322294 -372.032022) (xy 143.325342 -372.023386)
			(xy 143.325088 -372.005606) (xy 143.295624 -371.92712) (xy 143.284194 -371.913912) (xy 143.276066 -371.90934)
			(xy 143.243808 -371.889528) (xy 143.237395 -371.885508) (xy 143.222925 -371.881102) (xy 143.21536 -371.880892)
			(xy 142.933928 -371.880892) (xy 142.926372 -371.881156) (xy 142.911914 -371.885557) (xy 142.90548 -371.889528)
			(xy 142.873222 -371.90934) (xy 142.865094 -371.913912) (xy 142.853664 -371.92712) (xy 142.8242 -372.005606)
			(xy 142.823946 -372.023386) (xy 142.826994 -372.032022) (xy 142.837278 -372.062892) (xy 142.848389 -372.126999)
			(xy 142.849092 -372.15953) (xy 142.848606 -372.186781) (xy 142.84085 -372.240729) (xy 142.825495 -372.293024)
			(xy 142.802853 -372.342601) (xy 142.773387 -372.388451) (xy 142.737696 -372.429642) (xy 142.696505 -372.465333)
			(xy 142.650655 -372.494799) (xy 142.601078 -372.517441) (xy 142.548783 -372.532796) (xy 142.494835 -372.540552)
			(xy 142.440333 -372.540552) (xy 142.386385 -372.532796) (xy 142.33409 -372.517441) (xy 142.284513 -372.494799)
			(xy 142.238663 -372.465333) (xy 142.197472 -372.429642) (xy 142.161781 -372.388451) (xy 142.132315 -372.342601)
			(xy 142.109673 -372.293024) (xy 142.094318 -372.240729) (xy 142.086562 -372.186781) (xy 142.086076 -372.15953)
			(xy 142.086423 -372.135458) (xy 142.092466 -372.087695) (xy 142.104461 -372.041069) (xy 142.113 -372.01856)
			(xy 142.11808 -372.006114) (xy 142.114778 -371.980206) (xy 142.047976 -371.889528) (xy 142.024354 -371.878606)
			(xy 142.011146 -371.879622) (xy 141.982444 -371.880638) (xy 141.955191 -371.880118) (xy 141.90124 -371.872366)
			(xy 141.848941 -371.857015) (xy 141.799359 -371.834377) (xy 141.753504 -371.804913) (xy 141.712309 -371.769222)
			(xy 141.676614 -371.728031) (xy 141.647144 -371.68218) (xy 141.6245 -371.632601) (xy 141.609143 -371.580303)
			(xy 141.601385 -371.526353) (xy 141.601385 -371.471847) (xy 141.609143 -371.417897) (xy 141.6245 -371.365599)
			(xy 141.647144 -371.31602) (xy 141.676614 -371.270169) (xy 141.712309 -371.228978) (xy 141.753504 -371.193287)
			(xy 141.799359 -371.163823) (xy 141.848941 -371.141185) (xy 141.90124 -371.125834) (xy 141.955191 -371.118082)
			(xy 141.982444 -371.117622) (xy 142.011146 -371.118638) (xy 142.024354 -371.119654) (xy 142.047976 -371.108732)
			(xy 142.114778 -371.018054) (xy 142.11808 -370.992146) (xy 142.113 -370.9797) (xy 142.10665 -370.962682)
			(xy 142.103523 -370.954565) (xy 142.092743 -370.940929) (xy 142.085568 -370.936012) (xy 142.059914 -370.92001)
			(xy 142.052187 -370.915562) (xy 142.034742 -370.911932) (xy 142.025878 -370.912898) (xy 142.00813 -370.915272)
			(xy 141.972409 -370.917816) (xy 141.954504 -370.917978) (xy 141.923771 -370.917559) (xy 141.862753 -370.91015)
			(xy 141.803072 -370.89544) (xy 141.745601 -370.873643) (xy 141.691175 -370.845078) (xy 141.64059 -370.81016)
			(xy 141.594583 -370.769399) (xy 141.553824 -370.72339) (xy 141.518909 -370.672803) (xy 141.490346 -370.618376)
			(xy 141.468553 -370.560903) (xy 141.453846 -370.501222) (xy 141.44644 -370.440203) (xy 141.445996 -370.40947)
			(xy 139.214351 -370.40947) (xy 139.209023 -370.422961) (xy 139.178377 -370.478865) (xy 139.140985 -370.5305)
			(xy 139.097431 -370.577057) (xy 139.048399 -370.617804) (xy 138.994659 -370.652104) (xy 138.937053 -370.679416)
			(xy 138.876485 -370.699315) (xy 138.84529 -370.705888) (xy 138.836146 -370.707666) (xy 138.820398 -370.717572)
			(xy 138.768074 -370.785644) (xy 138.76274 -370.803424) (xy 138.763248 -370.812568) (xy 138.764264 -370.83873)
			(xy 138.763778 -370.865981) (xy 138.756022 -370.919929) (xy 138.740667 -370.972224) (xy 138.718025 -371.021801)
			(xy 138.688559 -371.067651) (xy 138.652868 -371.108842) (xy 138.611677 -371.144533) (xy 138.565827 -371.173999)
			(xy 138.51625 -371.196641) (xy 138.463955 -371.211996) (xy 138.410007 -371.219752) (xy 138.355505 -371.219752)
			(xy 138.301557 -371.211996) (xy 138.249262 -371.196641) (xy 138.199685 -371.173999) (xy 138.153835 -371.144533)
			(xy 138.112644 -371.108842) (xy 138.076953 -371.067651) (xy 138.047487 -371.021801) (xy 138.024845 -370.972224)
			(xy 138.00949 -370.919929) (xy 138.001734 -370.865981) (xy 138.001248 -370.83873) (xy 131.957064 -370.83873)
			(xy 131.956702 -370.862801) (xy 131.950665 -370.910564) (xy 131.938676 -370.95719) (xy 131.93014 -370.9797)
			(xy 131.92506 -370.992146) (xy 131.928362 -371.018054) (xy 131.995164 -371.108732) (xy 132.018786 -371.119654)
			(xy 132.031994 -371.118638) (xy 132.060696 -371.117622) (xy 132.087951 -371.118025) (xy 132.141907 -371.125782)
			(xy 132.194209 -371.141139) (xy 132.243794 -371.163783) (xy 132.289651 -371.193253) (xy 132.330848 -371.228949)
			(xy 132.366545 -371.270146) (xy 132.396015 -371.316003) (xy 132.41866 -371.365587) (xy 132.434017 -371.417889)
			(xy 132.441775 -371.471845) (xy 132.441775 -371.526355) (xy 132.434017 -371.580311) (xy 132.41866 -371.632613)
			(xy 132.396015 -371.682197) (xy 132.366545 -371.728054) (xy 132.330848 -371.769251) (xy 132.289651 -371.804947)
			(xy 132.243794 -371.834417) (xy 132.194209 -371.857061) (xy 132.141907 -371.872418) (xy 132.087951 -371.880175)
			(xy 132.060696 -371.880638) (xy 132.031994 -371.879622) (xy 132.018786 -371.878606) (xy 131.995164 -371.889528)
			(xy 131.928362 -371.980206) (xy 131.92506 -372.006114) (xy 131.93014 -372.01856) (xy 131.938692 -372.041065)
			(xy 131.95069 -372.087691) (xy 131.956716 -372.135457) (xy 131.957064 -372.15953) (xy 131.956578 -372.186781)
			(xy 131.948822 -372.240729) (xy 131.933467 -372.293024) (xy 131.910825 -372.342601) (xy 131.881359 -372.388451)
			(xy 131.845668 -372.429642) (xy 131.804477 -372.465333) (xy 131.758627 -372.494799) (xy 131.70905 -372.517441)
			(xy 131.656755 -372.532796) (xy 131.602807 -372.540552) (xy 131.548305 -372.540552) (xy 131.494357 -372.532796)
			(xy 131.442062 -372.517441) (xy 131.392485 -372.494799) (xy 131.346635 -372.465333) (xy 131.305444 -372.429642)
			(xy 131.269753 -372.388451) (xy 131.240287 -372.342601) (xy 131.217645 -372.293024) (xy 131.20229 -372.240729)
			(xy 131.194534 -372.186781) (xy 131.194048 -372.15953) (xy 131.19473 -372.126998) (xy 131.205846 -372.062889)
			(xy 131.216146 -372.032022) (xy 131.219194 -372.023386) (xy 131.21894 -372.005606) (xy 131.189476 -371.92712)
			(xy 131.178046 -371.913912) (xy 131.169918 -371.90934) (xy 131.13766 -371.889528) (xy 131.131258 -371.885489)
			(xy 131.116779 -371.881095) (xy 131.109212 -371.880892) (xy 130.82778 -371.880892) (xy 130.820226 -371.881177)
			(xy 130.805768 -371.885563) (xy 130.799332 -371.889528) (xy 130.767074 -371.90934) (xy 130.758946 -371.913912)
			(xy 130.747516 -371.92712) (xy 130.718052 -372.005606) (xy 130.717798 -372.023386) (xy 130.720846 -372.032022)
			(xy 130.731132 -372.062892) (xy 130.742241 -372.126999) (xy 130.742944 -372.15953) (xy 130.742458 -372.186781)
			(xy 130.734702 -372.240729) (xy 130.719347 -372.293024) (xy 130.696705 -372.342601) (xy 130.667239 -372.388451)
			(xy 130.631548 -372.429642) (xy 130.590357 -372.465333) (xy 130.544507 -372.494799) (xy 130.49493 -372.517441)
			(xy 130.442635 -372.532796) (xy 130.388687 -372.540552) (xy 130.334185 -372.540552) (xy 130.280237 -372.532796)
			(xy 130.227942 -372.517441) (xy 130.178365 -372.494799) (xy 130.132515 -372.465333) (xy 130.091324 -372.429642)
			(xy 130.055633 -372.388451) (xy 130.026167 -372.342601) (xy 130.003525 -372.293024) (xy 129.98817 -372.240729)
			(xy 129.980414 -372.186781) (xy 129.979928 -372.15953) (xy 129.980278 -372.135458) (xy 129.98632 -372.087695)
			(xy 129.998314 -372.04107) (xy 130.006852 -372.01856) (xy 130.011932 -372.006114) (xy 130.00863 -371.980206)
			(xy 129.941828 -371.889528) (xy 129.918206 -371.878606) (xy 129.904998 -371.879622) (xy 129.876296 -371.880638)
			(xy 129.849047 -371.880092) (xy 129.795104 -371.872335) (xy 129.742814 -371.856981) (xy 129.693241 -371.834341)
			(xy 129.647395 -371.804877) (xy 129.606209 -371.769189) (xy 129.57052 -371.728002) (xy 129.541057 -371.682155)
			(xy 129.518418 -371.632582) (xy 129.503064 -371.580292) (xy 129.495308 -371.526349) (xy 125.634575 -371.526349)
			(xy 125.634575 -371.526355) (xy 125.626817 -371.580311) (xy 125.61146 -371.632613) (xy 125.588815 -371.682197)
			(xy 125.559345 -371.728054) (xy 125.523648 -371.769251) (xy 125.482451 -371.804947) (xy 125.436594 -371.834417)
			(xy 125.387009 -371.857061) (xy 125.334707 -371.872418) (xy 125.280751 -371.880175) (xy 125.253496 -371.880638)
			(xy 125.224794 -371.879622) (xy 125.211586 -371.878606) (xy 125.187964 -371.889528) (xy 125.121162 -371.980206)
			(xy 125.11786 -372.006114) (xy 125.12294 -372.01856) (xy 125.131492 -372.041065) (xy 125.14349 -372.087691)
			(xy 125.149516 -372.135457) (xy 125.149864 -372.15953) (xy 125.149378 -372.186781) (xy 125.141622 -372.240729)
			(xy 125.126267 -372.293024) (xy 125.103625 -372.342601) (xy 125.074159 -372.388451) (xy 125.038468 -372.429642)
			(xy 124.997277 -372.465333) (xy 124.951427 -372.494799) (xy 124.90185 -372.517441) (xy 124.849555 -372.532796)
			(xy 124.795607 -372.540552) (xy 124.741105 -372.540552) (xy 124.687157 -372.532796) (xy 124.634862 -372.517441)
			(xy 124.585285 -372.494799) (xy 124.539435 -372.465333) (xy 124.498244 -372.429642) (xy 124.462553 -372.388451)
			(xy 124.433087 -372.342601) (xy 124.410445 -372.293024) (xy 124.39509 -372.240729) (xy 124.387334 -372.186781)
			(xy 124.386848 -372.15953) (xy 124.38753 -372.126998) (xy 124.398646 -372.062889) (xy 124.408946 -372.032022)
			(xy 124.411994 -372.023386) (xy 124.41174 -372.005606) (xy 124.382276 -371.92712) (xy 124.370846 -371.913912)
			(xy 124.362718 -371.90934) (xy 124.33046 -371.889528) (xy 124.324058 -371.885489) (xy 124.309579 -371.881095)
			(xy 124.302012 -371.880892) (xy 124.02058 -371.880892) (xy 124.013026 -371.881177) (xy 123.998568 -371.885563)
			(xy 123.992132 -371.889528) (xy 123.959874 -371.90934) (xy 123.951746 -371.913912) (xy 123.940316 -371.92712)
			(xy 123.910852 -372.005606) (xy 123.910598 -372.023386) (xy 123.913646 -372.032022) (xy 123.923932 -372.062892)
			(xy 123.935041 -372.126999) (xy 123.935744 -372.15953) (xy 123.935258 -372.186781) (xy 123.927502 -372.240729)
			(xy 123.912147 -372.293024) (xy 123.889505 -372.342601) (xy 123.860039 -372.388451) (xy 123.824348 -372.429642)
			(xy 123.783157 -372.465333) (xy 123.737307 -372.494799) (xy 123.68773 -372.517441) (xy 123.635435 -372.532796)
			(xy 123.581487 -372.540552) (xy 123.526985 -372.540552) (xy 123.473037 -372.532796) (xy 123.420742 -372.517441)
			(xy 123.371165 -372.494799) (xy 123.325315 -372.465333) (xy 123.284124 -372.429642) (xy 123.248433 -372.388451)
			(xy 123.218967 -372.342601) (xy 123.196325 -372.293024) (xy 123.18097 -372.240729) (xy 123.173214 -372.186781)
			(xy 123.172728 -372.15953) (xy 123.173078 -372.135458) (xy 123.17912 -372.087695) (xy 123.191114 -372.04107)
			(xy 123.199652 -372.01856) (xy 123.204732 -372.006114) (xy 123.20143 -371.980206) (xy 123.134628 -371.889528)
			(xy 123.111006 -371.878606) (xy 123.097798 -371.879622) (xy 123.069096 -371.880638) (xy 123.041847 -371.880092)
			(xy 122.987904 -371.872335) (xy 122.935614 -371.856981) (xy 122.886041 -371.834341) (xy 122.840195 -371.804877)
			(xy 122.799009 -371.769189) (xy 122.76332 -371.728002) (xy 122.733857 -371.682155) (xy 122.711218 -371.632582)
			(xy 122.695864 -371.580292) (xy 122.688108 -371.526349) (xy 118.827375 -371.526349) (xy 118.827375 -371.526355)
			(xy 118.819617 -371.580311) (xy 118.80426 -371.632613) (xy 118.781615 -371.682197) (xy 118.752145 -371.728054)
			(xy 118.716448 -371.769251) (xy 118.675251 -371.804947) (xy 118.629394 -371.834417) (xy 118.579809 -371.857061)
			(xy 118.527507 -371.872418) (xy 118.473551 -371.880175) (xy 118.446296 -371.880638) (xy 118.417594 -371.879622)
			(xy 118.404386 -371.878606) (xy 118.380764 -371.889528) (xy 118.313962 -371.980206) (xy 118.31066 -372.006114)
			(xy 118.31574 -372.01856) (xy 118.324292 -372.041065) (xy 118.33629 -372.087691) (xy 118.342316 -372.135457)
			(xy 118.342664 -372.15953) (xy 118.342178 -372.186781) (xy 118.334422 -372.240729) (xy 118.319067 -372.293024)
			(xy 118.296425 -372.342601) (xy 118.266959 -372.388451) (xy 118.231268 -372.429642) (xy 118.190077 -372.465333)
			(xy 118.144227 -372.494799) (xy 118.09465 -372.517441) (xy 118.042355 -372.532796) (xy 117.988407 -372.540552)
			(xy 117.933905 -372.540552) (xy 117.879957 -372.532796) (xy 117.827662 -372.517441) (xy 117.778085 -372.494799)
			(xy 117.732235 -372.465333) (xy 117.691044 -372.429642) (xy 117.655353 -372.388451) (xy 117.625887 -372.342601)
			(xy 117.603245 -372.293024) (xy 117.58789 -372.240729) (xy 117.580134 -372.186781) (xy 117.579648 -372.15953)
			(xy 117.58033 -372.126998) (xy 117.591446 -372.062889) (xy 117.601746 -372.032022) (xy 117.604794 -372.023386)
			(xy 117.60454 -372.005606) (xy 117.575076 -371.92712) (xy 117.563646 -371.913912) (xy 117.555518 -371.90934)
			(xy 117.52326 -371.889528) (xy 117.516858 -371.885489) (xy 117.502379 -371.881095) (xy 117.494812 -371.880892)
			(xy 117.21338 -371.880892) (xy 117.205826 -371.881177) (xy 117.191368 -371.885563) (xy 117.184932 -371.889528)
			(xy 117.152674 -371.90934) (xy 117.144546 -371.913912) (xy 117.133116 -371.92712) (xy 117.103652 -372.005606)
			(xy 117.103398 -372.023386) (xy 117.106446 -372.032022) (xy 117.116732 -372.062892) (xy 117.127841 -372.126999)
			(xy 117.128544 -372.15953) (xy 117.128058 -372.186781) (xy 117.120302 -372.240729) (xy 117.104947 -372.293024)
			(xy 117.082305 -372.342601) (xy 117.052839 -372.388451) (xy 117.017148 -372.429642) (xy 116.975957 -372.465333)
			(xy 116.930107 -372.494799) (xy 116.88053 -372.517441) (xy 116.828235 -372.532796) (xy 116.774287 -372.540552)
			(xy 116.719785 -372.540552) (xy 116.665837 -372.532796) (xy 116.613542 -372.517441) (xy 116.563965 -372.494799)
			(xy 116.518115 -372.465333) (xy 116.476924 -372.429642) (xy 116.441233 -372.388451) (xy 116.411767 -372.342601)
			(xy 116.389125 -372.293024) (xy 116.37377 -372.240729) (xy 116.366014 -372.186781) (xy 116.365528 -372.15953)
			(xy 116.365878 -372.135458) (xy 116.37192 -372.087695) (xy 116.383914 -372.04107) (xy 116.392452 -372.01856)
			(xy 116.397532 -372.006114) (xy 116.39423 -371.980206) (xy 116.327428 -371.889528) (xy 116.303806 -371.878606)
			(xy 116.290598 -371.879622) (xy 116.261896 -371.880638) (xy 116.234647 -371.880092) (xy 116.180704 -371.872335)
			(xy 116.128414 -371.856981) (xy 116.078841 -371.834341) (xy 116.032995 -371.804877) (xy 115.991809 -371.769189)
			(xy 115.95612 -371.728002) (xy 115.926657 -371.682155) (xy 115.904018 -371.632582) (xy 115.888664 -371.580292)
			(xy 115.880908 -371.526349) (xy 112.020175 -371.526349) (xy 112.020175 -371.526355) (xy 112.012417 -371.580311)
			(xy 111.99706 -371.632613) (xy 111.974415 -371.682197) (xy 111.944945 -371.728054) (xy 111.909248 -371.769251)
			(xy 111.868051 -371.804947) (xy 111.822194 -371.834417) (xy 111.772609 -371.857061) (xy 111.720307 -371.872418)
			(xy 111.666351 -371.880175) (xy 111.639096 -371.880638) (xy 111.610394 -371.879622) (xy 111.597186 -371.878606)
			(xy 111.573564 -371.889528) (xy 111.506762 -371.980206) (xy 111.50346 -372.006114) (xy 111.50854 -372.01856)
			(xy 111.517092 -372.041065) (xy 111.52909 -372.087691) (xy 111.535116 -372.135457) (xy 111.535464 -372.15953)
			(xy 111.534978 -372.186781) (xy 111.527222 -372.240729) (xy 111.511867 -372.293024) (xy 111.489225 -372.342601)
			(xy 111.459759 -372.388451) (xy 111.424068 -372.429642) (xy 111.382877 -372.465333) (xy 111.337027 -372.494799)
			(xy 111.28745 -372.517441) (xy 111.235155 -372.532796) (xy 111.181207 -372.540552) (xy 111.126705 -372.540552)
			(xy 111.072757 -372.532796) (xy 111.020462 -372.517441) (xy 110.970885 -372.494799) (xy 110.925035 -372.465333)
			(xy 110.883844 -372.429642) (xy 110.848153 -372.388451) (xy 110.818687 -372.342601) (xy 110.796045 -372.293024)
			(xy 110.78069 -372.240729) (xy 110.772934 -372.186781) (xy 110.772448 -372.15953) (xy 110.77313 -372.126998)
			(xy 110.784246 -372.062889) (xy 110.794546 -372.032022) (xy 110.797594 -372.023386) (xy 110.79734 -372.005606)
			(xy 110.767876 -371.92712) (xy 110.756446 -371.913912) (xy 110.748318 -371.90934) (xy 110.71606 -371.889528)
			(xy 110.709658 -371.885489) (xy 110.695179 -371.881095) (xy 110.687612 -371.880892) (xy 110.40618 -371.880892)
			(xy 110.398626 -371.881177) (xy 110.384168 -371.885563) (xy 110.377732 -371.889528) (xy 110.345474 -371.90934)
			(xy 110.337346 -371.913912) (xy 110.325916 -371.92712) (xy 110.296452 -372.005606) (xy 110.296198 -372.023386)
			(xy 110.299246 -372.032022) (xy 110.309532 -372.062892) (xy 110.320641 -372.126999) (xy 110.321344 -372.15953)
			(xy 110.320858 -372.186781) (xy 110.313102 -372.240729) (xy 110.297747 -372.293024) (xy 110.275105 -372.342601)
			(xy 110.245639 -372.388451) (xy 110.209948 -372.429642) (xy 110.168757 -372.465333) (xy 110.122907 -372.494799)
			(xy 110.07333 -372.517441) (xy 110.021035 -372.532796) (xy 109.967087 -372.540552) (xy 109.912585 -372.540552)
			(xy 109.858637 -372.532796) (xy 109.806342 -372.517441) (xy 109.756765 -372.494799) (xy 109.710915 -372.465333)
			(xy 109.669724 -372.429642) (xy 109.634033 -372.388451) (xy 109.604567 -372.342601) (xy 109.581925 -372.293024)
			(xy 109.56657 -372.240729) (xy 109.558814 -372.186781) (xy 109.558328 -372.15953) (xy 109.558678 -372.135458)
			(xy 109.56472 -372.087695) (xy 109.576714 -372.04107) (xy 109.585252 -372.01856) (xy 109.590332 -372.006114)
			(xy 109.58703 -371.980206) (xy 109.520228 -371.889528) (xy 109.496606 -371.878606) (xy 109.483398 -371.879622)
			(xy 109.454696 -371.880638) (xy 109.427447 -371.880092) (xy 109.373504 -371.872335) (xy 109.321214 -371.856981)
			(xy 109.271641 -371.834341) (xy 109.225795 -371.804877) (xy 109.184609 -371.769189) (xy 109.14892 -371.728002)
			(xy 109.119457 -371.682155) (xy 109.096818 -371.632582) (xy 109.081464 -371.580292) (xy 109.073708 -371.526349)
			(xy 97.869552 -371.526349) (xy 97.869552 -371.526353) (xy 97.861795 -371.580305) (xy 97.846439 -371.632604)
			(xy 97.823796 -371.682185) (xy 97.794328 -371.728039) (xy 97.758634 -371.769232) (xy 97.71744 -371.804926)
			(xy 97.671587 -371.834395) (xy 97.622006 -371.857038) (xy 97.569707 -371.872395) (xy 97.515755 -371.880152)
			(xy 97.488502 -371.880638) (xy 97.4598 -371.879622) (xy 97.446592 -371.878606) (xy 97.42297 -371.889528)
			(xy 97.356168 -371.980206) (xy 97.352866 -372.006114) (xy 97.357946 -372.01856) (xy 97.366498 -372.041065)
			(xy 97.378496 -372.087691) (xy 97.384522 -372.135457) (xy 97.38487 -372.15953) (xy 97.384384 -372.186781)
			(xy 97.376628 -372.240729) (xy 97.361273 -372.293024) (xy 97.338631 -372.342601) (xy 97.309165 -372.388451)
			(xy 97.273474 -372.429642) (xy 97.232283 -372.465333) (xy 97.186433 -372.494799) (xy 97.136856 -372.517441)
			(xy 97.084561 -372.532796) (xy 97.030613 -372.540552) (xy 96.976111 -372.540552) (xy 96.922163 -372.532796)
			(xy 96.869868 -372.517441) (xy 96.820291 -372.494799) (xy 96.774441 -372.465333) (xy 96.73325 -372.429642)
			(xy 96.697559 -372.388451) (xy 96.668093 -372.342601) (xy 96.645451 -372.293024) (xy 96.630096 -372.240729)
			(xy 96.62234 -372.186781) (xy 96.621854 -372.15953) (xy 96.622536 -372.126998) (xy 96.633652 -372.062889)
			(xy 96.643952 -372.032022) (xy 96.647 -372.023386) (xy 96.646746 -372.005606) (xy 96.617282 -371.92712)
			(xy 96.605852 -371.913912) (xy 96.597724 -371.90934) (xy 96.565466 -371.889528) (xy 96.559062 -371.885492)
			(xy 96.544585 -371.881096) (xy 96.537018 -371.880892) (xy 96.255586 -371.880892) (xy 96.248032 -371.88118)
			(xy 96.233574 -371.885564) (xy 96.227138 -371.889528) (xy 96.19488 -371.90934) (xy 96.186752 -371.913912)
			(xy 96.175322 -371.92712) (xy 96.145858 -372.005606) (xy 96.145604 -372.023386) (xy 96.148652 -372.032022)
			(xy 96.158938 -372.062891) (xy 96.170047 -372.126999) (xy 96.17075 -372.15953) (xy 96.170264 -372.186781)
			(xy 96.162508 -372.240729) (xy 96.147153 -372.293024) (xy 96.124511 -372.342601) (xy 96.095045 -372.388451)
			(xy 96.059354 -372.429642) (xy 96.018163 -372.465333) (xy 95.972313 -372.494799) (xy 95.922736 -372.517441)
			(xy 95.870441 -372.532796) (xy 95.816493 -372.540552) (xy 95.761991 -372.540552) (xy 95.708043 -372.532796)
			(xy 95.655748 -372.517441) (xy 95.606171 -372.494799) (xy 95.560321 -372.465333) (xy 95.51913 -372.429642)
			(xy 95.483439 -372.388451) (xy 95.453973 -372.342601) (xy 95.431331 -372.293024) (xy 95.415976 -372.240729)
			(xy 95.40822 -372.186781) (xy 95.407734 -372.15953) (xy 95.408083 -372.135458) (xy 95.414126 -372.087695)
			(xy 95.42612 -372.04107) (xy 95.434658 -372.01856) (xy 95.439738 -372.006114) (xy 95.436436 -371.980206)
			(xy 95.369634 -371.889528) (xy 95.346012 -371.878606) (xy 95.332804 -371.879622) (xy 95.304102 -371.880638)
			(xy 95.276851 -371.880115) (xy 95.222904 -371.872359) (xy 95.17061 -371.857004) (xy 95.121034 -371.834363)
			(xy 95.075184 -371.804898) (xy 95.033994 -371.769207) (xy 94.998303 -371.728018) (xy 94.968837 -371.682168)
			(xy 94.946197 -371.632592) (xy 94.930842 -371.580298) (xy 94.923085 -371.526351) (xy 91.062352 -371.526351)
			(xy 91.062352 -371.526353) (xy 91.054595 -371.580305) (xy 91.039239 -371.632604) (xy 91.016596 -371.682185)
			(xy 90.987128 -371.728039) (xy 90.951434 -371.769232) (xy 90.91024 -371.804926) (xy 90.864387 -371.834395)
			(xy 90.814806 -371.857038) (xy 90.762507 -371.872395) (xy 90.708555 -371.880152) (xy 90.681302 -371.880638)
			(xy 90.6526 -371.879622) (xy 90.639392 -371.878606) (xy 90.61577 -371.889528) (xy 90.548968 -371.980206)
			(xy 90.545666 -372.006114) (xy 90.550746 -372.01856) (xy 90.559298 -372.041065) (xy 90.571296 -372.087691)
			(xy 90.577322 -372.135457) (xy 90.57767 -372.15953) (xy 90.577184 -372.186781) (xy 90.569428 -372.240729)
			(xy 90.554073 -372.293024) (xy 90.531431 -372.342601) (xy 90.501965 -372.388451) (xy 90.466274 -372.429642)
			(xy 90.425083 -372.465333) (xy 90.379233 -372.494799) (xy 90.329656 -372.517441) (xy 90.277361 -372.532796)
			(xy 90.223413 -372.540552) (xy 90.168911 -372.540552) (xy 90.114963 -372.532796) (xy 90.062668 -372.517441)
			(xy 90.013091 -372.494799) (xy 89.967241 -372.465333) (xy 89.92605 -372.429642) (xy 89.890359 -372.388451)
			(xy 89.860893 -372.342601) (xy 89.838251 -372.293024) (xy 89.822896 -372.240729) (xy 89.81514 -372.186781)
			(xy 89.814654 -372.15953) (xy 89.815336 -372.126998) (xy 89.826452 -372.062889) (xy 89.836752 -372.032022)
			(xy 89.8398 -372.023386) (xy 89.839546 -372.005606) (xy 89.810082 -371.92712) (xy 89.798652 -371.913912)
			(xy 89.790524 -371.90934) (xy 89.758266 -371.889528) (xy 89.751862 -371.885492) (xy 89.737385 -371.881096)
			(xy 89.729818 -371.880892) (xy 89.448386 -371.880892) (xy 89.440832 -371.88118) (xy 89.426374 -371.885564)
			(xy 89.419938 -371.889528) (xy 89.38768 -371.90934) (xy 89.379552 -371.913912) (xy 89.368122 -371.92712)
			(xy 89.338658 -372.005606) (xy 89.338404 -372.023386) (xy 89.341452 -372.032022) (xy 89.351738 -372.062891)
			(xy 89.362847 -372.126999) (xy 89.36355 -372.15953) (xy 89.363064 -372.186781) (xy 89.355308 -372.240729)
			(xy 89.339953 -372.293024) (xy 89.317311 -372.342601) (xy 89.287845 -372.388451) (xy 89.252154 -372.429642)
			(xy 89.210963 -372.465333) (xy 89.165113 -372.494799) (xy 89.115536 -372.517441) (xy 89.063241 -372.532796)
			(xy 89.009293 -372.540552) (xy 88.954791 -372.540552) (xy 88.900843 -372.532796) (xy 88.848548 -372.517441)
			(xy 88.798971 -372.494799) (xy 88.753121 -372.465333) (xy 88.71193 -372.429642) (xy 88.676239 -372.388451)
			(xy 88.646773 -372.342601) (xy 88.624131 -372.293024) (xy 88.608776 -372.240729) (xy 88.60102 -372.186781)
			(xy 88.600534 -372.15953) (xy 88.600883 -372.135458) (xy 88.606926 -372.087695) (xy 88.61892 -372.04107)
			(xy 88.627458 -372.01856) (xy 88.632538 -372.006114) (xy 88.629236 -371.980206) (xy 88.562434 -371.889528)
			(xy 88.538812 -371.878606) (xy 88.525604 -371.879622) (xy 88.496902 -371.880638) (xy 88.469651 -371.880115)
			(xy 88.415704 -371.872359) (xy 88.36341 -371.857004) (xy 88.313834 -371.834363) (xy 88.267984 -371.804898)
			(xy 88.226794 -371.769207) (xy 88.191103 -371.728018) (xy 88.161637 -371.682168) (xy 88.138997 -371.632592)
			(xy 88.123642 -371.580298) (xy 88.115885 -371.526351) (xy 84.255152 -371.526351) (xy 84.255152 -371.526353)
			(xy 84.247395 -371.580305) (xy 84.232039 -371.632604) (xy 84.209396 -371.682185) (xy 84.179928 -371.728039)
			(xy 84.144234 -371.769232) (xy 84.10304 -371.804926) (xy 84.057187 -371.834395) (xy 84.007606 -371.857038)
			(xy 83.955307 -371.872395) (xy 83.901355 -371.880152) (xy 83.874102 -371.880638) (xy 83.8454 -371.879622)
			(xy 83.832192 -371.878606) (xy 83.80857 -371.889528) (xy 83.741768 -371.980206) (xy 83.738466 -372.006114)
			(xy 83.743546 -372.01856) (xy 83.752098 -372.041065) (xy 83.764096 -372.087691) (xy 83.770122 -372.135457)
			(xy 83.77047 -372.15953) (xy 83.769984 -372.186781) (xy 83.762228 -372.240729) (xy 83.746873 -372.293024)
			(xy 83.724231 -372.342601) (xy 83.694765 -372.388451) (xy 83.659074 -372.429642) (xy 83.617883 -372.465333)
			(xy 83.572033 -372.494799) (xy 83.522456 -372.517441) (xy 83.470161 -372.532796) (xy 83.416213 -372.540552)
			(xy 83.361711 -372.540552) (xy 83.307763 -372.532796) (xy 83.255468 -372.517441) (xy 83.205891 -372.494799)
			(xy 83.160041 -372.465333) (xy 83.11885 -372.429642) (xy 83.083159 -372.388451) (xy 83.053693 -372.342601)
			(xy 83.031051 -372.293024) (xy 83.015696 -372.240729) (xy 83.00794 -372.186781) (xy 83.007454 -372.15953)
			(xy 83.008136 -372.126998) (xy 83.019252 -372.062889) (xy 83.029552 -372.032022) (xy 83.0326 -372.023386)
			(xy 83.032346 -372.005606) (xy 83.002882 -371.92712) (xy 82.991452 -371.913912) (xy 82.983324 -371.90934)
			(xy 82.951066 -371.889528) (xy 82.944662 -371.885492) (xy 82.930185 -371.881096) (xy 82.922618 -371.880892)
			(xy 82.641186 -371.880892) (xy 82.633632 -371.88118) (xy 82.619174 -371.885564) (xy 82.612738 -371.889528)
			(xy 82.58048 -371.90934) (xy 82.572352 -371.913912) (xy 82.560922 -371.92712) (xy 82.531458 -372.005606)
			(xy 82.531204 -372.023386) (xy 82.534252 -372.032022) (xy 82.544538 -372.062891) (xy 82.555647 -372.126999)
			(xy 82.55635 -372.15953) (xy 82.555864 -372.186781) (xy 82.548108 -372.240729) (xy 82.532753 -372.293024)
			(xy 82.510111 -372.342601) (xy 82.480645 -372.388451) (xy 82.444954 -372.429642) (xy 82.403763 -372.465333)
			(xy 82.357913 -372.494799) (xy 82.308336 -372.517441) (xy 82.256041 -372.532796) (xy 82.202093 -372.540552)
			(xy 82.147591 -372.540552) (xy 82.093643 -372.532796) (xy 82.041348 -372.517441) (xy 81.991771 -372.494799)
			(xy 81.945921 -372.465333) (xy 81.90473 -372.429642) (xy 81.869039 -372.388451) (xy 81.839573 -372.342601)
			(xy 81.816931 -372.293024) (xy 81.801576 -372.240729) (xy 81.79382 -372.186781) (xy 81.793334 -372.15953)
			(xy 81.793683 -372.135458) (xy 81.799726 -372.087695) (xy 81.81172 -372.04107) (xy 81.820258 -372.01856)
			(xy 81.825338 -372.006114) (xy 81.822036 -371.980206) (xy 81.755234 -371.889528) (xy 81.731612 -371.878606)
			(xy 81.718404 -371.879622) (xy 81.689702 -371.880638) (xy 81.662451 -371.880115) (xy 81.608504 -371.872359)
			(xy 81.55621 -371.857004) (xy 81.506634 -371.834363) (xy 81.460784 -371.804898) (xy 81.419594 -371.769207)
			(xy 81.383903 -371.728018) (xy 81.354437 -371.682168) (xy 81.331797 -371.632592) (xy 81.316442 -371.580298)
			(xy 81.308685 -371.526351) (xy 77.447952 -371.526351) (xy 77.447952 -371.526353) (xy 77.440195 -371.580305)
			(xy 77.424839 -371.632604) (xy 77.402196 -371.682185) (xy 77.372728 -371.728039) (xy 77.337034 -371.769232)
			(xy 77.29584 -371.804926) (xy 77.249987 -371.834395) (xy 77.200406 -371.857038) (xy 77.148107 -371.872395)
			(xy 77.094155 -371.880152) (xy 77.066902 -371.880638) (xy 77.0382 -371.879622) (xy 77.024992 -371.878606)
			(xy 77.00137 -371.889528) (xy 76.934568 -371.980206) (xy 76.931266 -372.006114) (xy 76.936346 -372.01856)
			(xy 76.944898 -372.041065) (xy 76.956896 -372.087691) (xy 76.962922 -372.135457) (xy 76.96327 -372.15953)
			(xy 76.962784 -372.186781) (xy 76.955028 -372.240729) (xy 76.939673 -372.293024) (xy 76.917031 -372.342601)
			(xy 76.887565 -372.388451) (xy 76.851874 -372.429642) (xy 76.810683 -372.465333) (xy 76.764833 -372.494799)
			(xy 76.715256 -372.517441) (xy 76.662961 -372.532796) (xy 76.609013 -372.540552) (xy 76.554511 -372.540552)
			(xy 76.500563 -372.532796) (xy 76.448268 -372.517441) (xy 76.398691 -372.494799) (xy 76.352841 -372.465333)
			(xy 76.31165 -372.429642) (xy 76.275959 -372.388451) (xy 76.246493 -372.342601) (xy 76.223851 -372.293024)
			(xy 76.208496 -372.240729) (xy 76.20074 -372.186781) (xy 76.200254 -372.15953) (xy 76.200936 -372.126998)
			(xy 76.212052 -372.062889) (xy 76.222352 -372.032022) (xy 76.2254 -372.023386) (xy 76.225146 -372.005606)
			(xy 76.195682 -371.92712) (xy 76.184252 -371.913912) (xy 76.176124 -371.90934) (xy 76.143866 -371.889528)
			(xy 76.137462 -371.885492) (xy 76.122985 -371.881096) (xy 76.115418 -371.880892) (xy 75.833986 -371.880892)
			(xy 75.826432 -371.88118) (xy 75.811974 -371.885564) (xy 75.805538 -371.889528) (xy 75.77328 -371.90934)
			(xy 75.765152 -371.913912) (xy 75.753722 -371.92712) (xy 75.724258 -372.005606) (xy 75.724004 -372.023386)
			(xy 75.727052 -372.032022) (xy 75.737338 -372.062891) (xy 75.748447 -372.126999) (xy 75.74915 -372.15953)
			(xy 75.748664 -372.186781) (xy 75.740908 -372.240729) (xy 75.725553 -372.293024) (xy 75.702911 -372.342601)
			(xy 75.673445 -372.388451) (xy 75.637754 -372.429642) (xy 75.596563 -372.465333) (xy 75.550713 -372.494799)
			(xy 75.501136 -372.517441) (xy 75.448841 -372.532796) (xy 75.394893 -372.540552) (xy 75.340391 -372.540552)
			(xy 75.286443 -372.532796) (xy 75.234148 -372.517441) (xy 75.184571 -372.494799) (xy 75.138721 -372.465333)
			(xy 75.09753 -372.429642) (xy 75.061839 -372.388451) (xy 75.032373 -372.342601) (xy 75.009731 -372.293024)
			(xy 74.994376 -372.240729) (xy 74.98662 -372.186781) (xy 74.986134 -372.15953) (xy 74.986483 -372.135458)
			(xy 74.992526 -372.087695) (xy 75.00452 -372.04107) (xy 75.013058 -372.01856) (xy 75.018138 -372.006114)
			(xy 75.014836 -371.980206) (xy 74.948034 -371.889528) (xy 74.924412 -371.878606) (xy 74.911204 -371.879622)
			(xy 74.882502 -371.880638) (xy 74.855251 -371.880115) (xy 74.801304 -371.872359) (xy 74.74901 -371.857004)
			(xy 74.699434 -371.834363) (xy 74.653584 -371.804898) (xy 74.612394 -371.769207) (xy 74.576703 -371.728018)
			(xy 74.547237 -371.682168) (xy 74.524597 -371.632592) (xy 74.509242 -371.580298) (xy 74.501485 -371.526351)
			(xy 65.341875 -371.526351) (xy 65.341875 -371.526357) (xy 65.334116 -371.580316) (xy 65.318757 -371.632622)
			(xy 65.296109 -371.682209) (xy 65.266634 -371.728068) (xy 65.230933 -371.769265) (xy 65.189731 -371.804962)
			(xy 65.143869 -371.834431) (xy 65.094279 -371.857073) (xy 65.041971 -371.872426) (xy 64.988011 -371.880178)
			(xy 64.960754 -371.880638) (xy 64.932052 -371.879622) (xy 64.918844 -371.878606) (xy 64.895222 -371.889528)
			(xy 64.82842 -371.980206) (xy 64.825118 -372.006114) (xy 64.830198 -372.01856) (xy 64.838748 -372.041066)
			(xy 64.850747 -372.087691) (xy 64.856774 -372.135457) (xy 64.857122 -372.15953) (xy 64.856636 -372.186781)
			(xy 64.84888 -372.240729) (xy 64.833525 -372.293024) (xy 64.810883 -372.342601) (xy 64.781417 -372.388451)
			(xy 64.745726 -372.429642) (xy 64.704535 -372.465333) (xy 64.658685 -372.494799) (xy 64.609108 -372.517441)
			(xy 64.556813 -372.532796) (xy 64.502865 -372.540552) (xy 64.448363 -372.540552) (xy 64.394415 -372.532796)
			(xy 64.34212 -372.517441) (xy 64.292543 -372.494799) (xy 64.246693 -372.465333) (xy 64.205502 -372.429642)
			(xy 64.169811 -372.388451) (xy 64.140345 -372.342601) (xy 64.117703 -372.293024) (xy 64.102348 -372.240729)
			(xy 64.094592 -372.186781) (xy 64.094106 -372.15953) (xy 64.094785 -372.126998) (xy 64.105903 -372.062888)
			(xy 64.116204 -372.032022) (xy 64.119252 -372.023386) (xy 64.118998 -372.005606) (xy 64.089534 -371.92712)
			(xy 64.078104 -371.913912) (xy 64.069976 -371.90934) (xy 64.037718 -371.889528) (xy 64.031303 -371.885512)
			(xy 64.016834 -371.881104) (xy 64.00927 -371.880892) (xy 63.727838 -371.880892) (xy 63.720283 -371.88116)
			(xy 63.705824 -371.885558) (xy 63.69939 -371.889528) (xy 63.667132 -371.90934) (xy 63.659004 -371.913912)
			(xy 63.647574 -371.92712) (xy 63.61811 -372.005606) (xy 63.617856 -372.023386) (xy 63.620904 -372.032022)
			(xy 63.631189 -372.062892) (xy 63.642299 -372.126999) (xy 63.643002 -372.15953) (xy 63.642516 -372.186781)
			(xy 63.63476 -372.240729) (xy 63.619405 -372.293024) (xy 63.596763 -372.342601) (xy 63.567297 -372.388451)
			(xy 63.531606 -372.429642) (xy 63.490415 -372.465333) (xy 63.444565 -372.494799) (xy 63.394988 -372.517441)
			(xy 63.342693 -372.532796) (xy 63.288745 -372.540552) (xy 63.234243 -372.540552) (xy 63.180295 -372.532796)
			(xy 63.128 -372.517441) (xy 63.078423 -372.494799) (xy 63.032573 -372.465333) (xy 62.991382 -372.429642)
			(xy 62.955691 -372.388451) (xy 62.926225 -372.342601) (xy 62.903583 -372.293024) (xy 62.888228 -372.240729)
			(xy 62.880472 -372.186781) (xy 62.879986 -372.15953) (xy 62.880332 -372.135458) (xy 62.886375 -372.087695)
			(xy 62.898371 -372.041069) (xy 62.90691 -372.01856) (xy 62.91199 -372.006114) (xy 62.908688 -371.980206)
			(xy 62.841886 -371.889528) (xy 62.818264 -371.878606) (xy 62.805056 -371.879622) (xy 62.776354 -371.880638)
			(xy 62.749107 -371.880089) (xy 62.695169 -371.872327) (xy 62.642884 -371.85697) (xy 62.593316 -371.834328)
			(xy 62.547475 -371.804862) (xy 62.506294 -371.769174) (xy 62.47061 -371.727988) (xy 62.44115 -371.682143)
			(xy 62.418514 -371.632573) (xy 62.403163 -371.580286) (xy 62.395408 -371.526347) (xy 58.534675 -371.526347)
			(xy 58.534675 -371.526357) (xy 58.526916 -371.580316) (xy 58.511557 -371.632622) (xy 58.488909 -371.682209)
			(xy 58.459434 -371.728068) (xy 58.423733 -371.769265) (xy 58.382531 -371.804962) (xy 58.336669 -371.834431)
			(xy 58.287079 -371.857073) (xy 58.234771 -371.872426) (xy 58.180811 -371.880178) (xy 58.153554 -371.880638)
			(xy 58.124852 -371.879622) (xy 58.111644 -371.878606) (xy 58.088022 -371.889528) (xy 58.02122 -371.980206)
			(xy 58.017918 -372.006114) (xy 58.022998 -372.01856) (xy 58.031548 -372.041066) (xy 58.043547 -372.087691)
			(xy 58.049574 -372.135457) (xy 58.049922 -372.15953) (xy 58.049436 -372.186781) (xy 58.04168 -372.240729)
			(xy 58.026325 -372.293024) (xy 58.003683 -372.342601) (xy 57.974217 -372.388451) (xy 57.938526 -372.429642)
			(xy 57.897335 -372.465333) (xy 57.851485 -372.494799) (xy 57.801908 -372.517441) (xy 57.749613 -372.532796)
			(xy 57.695665 -372.540552) (xy 57.641163 -372.540552) (xy 57.587215 -372.532796) (xy 57.53492 -372.517441)
			(xy 57.485343 -372.494799) (xy 57.439493 -372.465333) (xy 57.398302 -372.429642) (xy 57.362611 -372.388451)
			(xy 57.333145 -372.342601) (xy 57.310503 -372.293024) (xy 57.295148 -372.240729) (xy 57.287392 -372.186781)
			(xy 57.286906 -372.15953) (xy 57.287585 -372.126998) (xy 57.298703 -372.062888) (xy 57.309004 -372.032022)
			(xy 57.312052 -372.023386) (xy 57.311798 -372.005606) (xy 57.282334 -371.92712) (xy 57.270904 -371.913912)
			(xy 57.262776 -371.90934) (xy 57.230518 -371.889528) (xy 57.224103 -371.885512) (xy 57.209634 -371.881104)
			(xy 57.20207 -371.880892) (xy 56.920638 -371.880892) (xy 56.913083 -371.88116) (xy 56.898624 -371.885558)
			(xy 56.89219 -371.889528) (xy 56.859932 -371.90934) (xy 56.851804 -371.913912) (xy 56.840374 -371.92712)
			(xy 56.81091 -372.005606) (xy 56.810656 -372.023386) (xy 56.813704 -372.032022) (xy 56.823989 -372.062892)
			(xy 56.835099 -372.126999) (xy 56.835802 -372.15953) (xy 56.835316 -372.186781) (xy 56.82756 -372.240729)
			(xy 56.812205 -372.293024) (xy 56.789563 -372.342601) (xy 56.760097 -372.388451) (xy 56.724406 -372.429642)
			(xy 56.683215 -372.465333) (xy 56.637365 -372.494799) (xy 56.587788 -372.517441) (xy 56.535493 -372.532796)
			(xy 56.481545 -372.540552) (xy 56.427043 -372.540552) (xy 56.373095 -372.532796) (xy 56.3208 -372.517441)
			(xy 56.271223 -372.494799) (xy 56.225373 -372.465333) (xy 56.184182 -372.429642) (xy 56.148491 -372.388451)
			(xy 56.119025 -372.342601) (xy 56.096383 -372.293024) (xy 56.081028 -372.240729) (xy 56.073272 -372.186781)
			(xy 56.072786 -372.15953) (xy 56.073132 -372.135458) (xy 56.079175 -372.087695) (xy 56.091171 -372.041069)
			(xy 56.09971 -372.01856) (xy 56.10479 -372.006114) (xy 56.101488 -371.980206) (xy 56.034686 -371.889528)
			(xy 56.011064 -371.878606) (xy 55.997856 -371.879622) (xy 55.969154 -371.880638) (xy 55.941907 -371.880089)
			(xy 55.887969 -371.872327) (xy 55.835684 -371.85697) (xy 55.786116 -371.834328) (xy 55.740275 -371.804862)
			(xy 55.699094 -371.769174) (xy 55.66341 -371.727988) (xy 55.63395 -371.682143) (xy 55.611314 -371.632573)
			(xy 55.595963 -371.580286) (xy 55.588208 -371.526347) (xy 51.727475 -371.526347) (xy 51.727475 -371.526357)
			(xy 51.719716 -371.580316) (xy 51.704357 -371.632622) (xy 51.681709 -371.682209) (xy 51.652234 -371.728068)
			(xy 51.616533 -371.769265) (xy 51.575331 -371.804962) (xy 51.529469 -371.834431) (xy 51.479879 -371.857073)
			(xy 51.427571 -371.872426) (xy 51.373611 -371.880178) (xy 51.346354 -371.880638) (xy 51.317652 -371.879622)
			(xy 51.304444 -371.878606) (xy 51.280822 -371.889528) (xy 51.21402 -371.980206) (xy 51.210718 -372.006114)
			(xy 51.215798 -372.01856) (xy 51.224348 -372.041066) (xy 51.236347 -372.087691) (xy 51.242374 -372.135457)
			(xy 51.242722 -372.15953) (xy 51.242236 -372.186781) (xy 51.23448 -372.240729) (xy 51.219125 -372.293024)
			(xy 51.196483 -372.342601) (xy 51.167017 -372.388451) (xy 51.131326 -372.429642) (xy 51.090135 -372.465333)
			(xy 51.044285 -372.494799) (xy 50.994708 -372.517441) (xy 50.942413 -372.532796) (xy 50.888465 -372.540552)
			(xy 50.833963 -372.540552) (xy 50.780015 -372.532796) (xy 50.72772 -372.517441) (xy 50.678143 -372.494799)
			(xy 50.632293 -372.465333) (xy 50.591102 -372.429642) (xy 50.555411 -372.388451) (xy 50.525945 -372.342601)
			(xy 50.503303 -372.293024) (xy 50.487948 -372.240729) (xy 50.480192 -372.186781) (xy 50.479706 -372.15953)
			(xy 50.480385 -372.126998) (xy 50.491503 -372.062888) (xy 50.501804 -372.032022) (xy 50.504852 -372.023386)
			(xy 50.504598 -372.005606) (xy 50.475134 -371.92712) (xy 50.463704 -371.913912) (xy 50.455576 -371.90934)
			(xy 50.423318 -371.889528) (xy 50.416903 -371.885512) (xy 50.402434 -371.881104) (xy 50.39487 -371.880892)
			(xy 50.113438 -371.880892) (xy 50.105883 -371.88116) (xy 50.091424 -371.885558) (xy 50.08499 -371.889528)
			(xy 50.052732 -371.90934) (xy 50.044604 -371.913912) (xy 50.033174 -371.92712) (xy 50.00371 -372.005606)
			(xy 50.003456 -372.023386) (xy 50.006504 -372.032022) (xy 50.016789 -372.062892) (xy 50.027899 -372.126999)
			(xy 50.028602 -372.15953) (xy 50.028116 -372.186781) (xy 50.02036 -372.240729) (xy 50.005005 -372.293024)
			(xy 49.982363 -372.342601) (xy 49.952897 -372.388451) (xy 49.917206 -372.429642) (xy 49.876015 -372.465333)
			(xy 49.830165 -372.494799) (xy 49.780588 -372.517441) (xy 49.728293 -372.532796) (xy 49.674345 -372.540552)
			(xy 49.619843 -372.540552) (xy 49.565895 -372.532796) (xy 49.5136 -372.517441) (xy 49.464023 -372.494799)
			(xy 49.418173 -372.465333) (xy 49.376982 -372.429642) (xy 49.341291 -372.388451) (xy 49.311825 -372.342601)
			(xy 49.289183 -372.293024) (xy 49.273828 -372.240729) (xy 49.266072 -372.186781) (xy 49.265586 -372.15953)
			(xy 49.265932 -372.135458) (xy 49.271975 -372.087695) (xy 49.283971 -372.041069) (xy 49.29251 -372.01856)
			(xy 49.29759 -372.006114) (xy 49.294288 -371.980206) (xy 49.227486 -371.889528) (xy 49.203864 -371.878606)
			(xy 49.190656 -371.879622) (xy 49.161954 -371.880638) (xy 49.134707 -371.880089) (xy 49.080769 -371.872327)
			(xy 49.028484 -371.85697) (xy 48.978916 -371.834328) (xy 48.933075 -371.804862) (xy 48.891894 -371.769174)
			(xy 48.85621 -371.727988) (xy 48.82675 -371.682143) (xy 48.804114 -371.632573) (xy 48.788763 -371.580286)
			(xy 48.781008 -371.526347) (xy 44.920275 -371.526347) (xy 44.920275 -371.526357) (xy 44.912516 -371.580316)
			(xy 44.897157 -371.632622) (xy 44.874509 -371.682209) (xy 44.845034 -371.728068) (xy 44.809333 -371.769265)
			(xy 44.768131 -371.804962) (xy 44.722269 -371.834431) (xy 44.672679 -371.857073) (xy 44.620371 -371.872426)
			(xy 44.566411 -371.880178) (xy 44.539154 -371.880638) (xy 44.510452 -371.879622) (xy 44.497244 -371.878606)
			(xy 44.473622 -371.889528) (xy 44.40682 -371.980206) (xy 44.403518 -372.006114) (xy 44.408598 -372.01856)
			(xy 44.417148 -372.041066) (xy 44.429147 -372.087691) (xy 44.435174 -372.135457) (xy 44.435522 -372.15953)
			(xy 44.435036 -372.186781) (xy 44.42728 -372.240729) (xy 44.411925 -372.293024) (xy 44.389283 -372.342601)
			(xy 44.359817 -372.388451) (xy 44.324126 -372.429642) (xy 44.282935 -372.465333) (xy 44.237085 -372.494799)
			(xy 44.187508 -372.517441) (xy 44.135213 -372.532796) (xy 44.081265 -372.540552) (xy 44.026763 -372.540552)
			(xy 43.972815 -372.532796) (xy 43.92052 -372.517441) (xy 43.870943 -372.494799) (xy 43.825093 -372.465333)
			(xy 43.783902 -372.429642) (xy 43.748211 -372.388451) (xy 43.718745 -372.342601) (xy 43.696103 -372.293024)
			(xy 43.680748 -372.240729) (xy 43.672992 -372.186781) (xy 43.672506 -372.15953) (xy 43.673185 -372.126998)
			(xy 43.684303 -372.062888) (xy 43.694604 -372.032022) (xy 43.697652 -372.023386) (xy 43.697398 -372.005606)
			(xy 43.667934 -371.92712) (xy 43.656504 -371.913912) (xy 43.648376 -371.90934) (xy 43.616118 -371.889528)
			(xy 43.609703 -371.885512) (xy 43.595234 -371.881104) (xy 43.58767 -371.880892) (xy 43.306238 -371.880892)
			(xy 43.298683 -371.88116) (xy 43.284224 -371.885558) (xy 43.27779 -371.889528) (xy 43.245532 -371.90934)
			(xy 43.237404 -371.913912) (xy 43.225974 -371.92712) (xy 43.19651 -372.005606) (xy 43.196256 -372.023386)
			(xy 43.199304 -372.032022) (xy 43.209589 -372.062892) (xy 43.220699 -372.126999) (xy 43.221402 -372.15953)
			(xy 43.220916 -372.186781) (xy 43.21316 -372.240729) (xy 43.197805 -372.293024) (xy 43.175163 -372.342601)
			(xy 43.145697 -372.388451) (xy 43.110006 -372.429642) (xy 43.068815 -372.465333) (xy 43.022965 -372.494799)
			(xy 42.973388 -372.517441) (xy 42.921093 -372.532796) (xy 42.867145 -372.540552) (xy 42.812643 -372.540552)
			(xy 42.758695 -372.532796) (xy 42.7064 -372.517441) (xy 42.656823 -372.494799) (xy 42.610973 -372.465333)
			(xy 42.569782 -372.429642) (xy 42.534091 -372.388451) (xy 42.504625 -372.342601) (xy 42.481983 -372.293024)
			(xy 42.466628 -372.240729) (xy 42.458872 -372.186781) (xy 42.458386 -372.15953) (xy 42.458732 -372.135458)
			(xy 42.464775 -372.087695) (xy 42.476771 -372.041069) (xy 42.48531 -372.01856) (xy 42.49039 -372.006114)
			(xy 42.487088 -371.980206) (xy 42.420286 -371.889528) (xy 42.396664 -371.878606) (xy 42.383456 -371.879622)
			(xy 42.354754 -371.880638) (xy 42.327507 -371.880089) (xy 42.273569 -371.872327) (xy 42.221284 -371.85697)
			(xy 42.171716 -371.834328) (xy 42.125875 -371.804862) (xy 42.084694 -371.769174) (xy 42.04901 -371.727988)
			(xy 42.01955 -371.682143) (xy 41.996914 -371.632573) (xy 41.981563 -371.580286) (xy 41.973808 -371.526347)
			(xy 41.01338 -371.526347) (xy 41.01338 -373.641366) (xy 41.01382 -373.651398) (xy 41.021395 -373.669971)
			(xy 41.028112 -373.677434) (xy 41.295066 -373.944388) (xy 41.319196 -373.951754) (xy 41.331388 -373.949468)
			(xy 41.358188 -373.944725) (xy 41.412378 -373.939632) (xy 41.439592 -373.939308) (xy 41.474929 -373.93982)
			(xy 41.545089 -373.948338) (xy 41.61371 -373.965251) (xy 41.679357 -373.990147) (xy 47.079208 -373.990147)
			(xy 47.079208 -373.935653) (xy 47.086963 -373.881714) (xy 47.102314 -373.829427) (xy 47.12495 -373.779857)
			(xy 47.15441 -373.734012) (xy 47.190094 -373.692826) (xy 47.231275 -373.657138) (xy 47.277116 -373.627672)
			(xy 47.326684 -373.60503) (xy 47.378969 -373.589673) (xy 47.432907 -373.581911) (xy 47.460154 -373.581422)
			(xy 47.488856 -373.582438) (xy 47.502064 -373.583454) (xy 47.525686 -373.572532) (xy 47.592488 -373.481854)
			(xy 47.59579 -373.455946) (xy 47.59071 -373.4435) (xy 47.582178 -373.420988) (xy 47.570172 -373.374366)
			(xy 47.564138 -373.326602) (xy 47.563786 -373.30253) (xy 47.564272 -373.275279) (xy 47.572028 -373.221331)
			(xy 47.587383 -373.169036) (xy 47.610025 -373.119459) (xy 47.639491 -373.073609) (xy 47.675182 -373.032418)
			(xy 47.716373 -372.996727) (xy 47.762223 -372.967261) (xy 47.8118 -372.944619) (xy 47.864095 -372.929264)
			(xy 47.918043 -372.921508) (xy 47.972545 -372.921508) (xy 48.026493 -372.929264) (xy 48.078788 -372.944619)
			(xy 48.128365 -372.967261) (xy 48.174215 -372.996727) (xy 48.215406 -373.032418) (xy 48.251097 -373.073609)
			(xy 48.280563 -373.119459) (xy 48.303205 -373.169036) (xy 48.31856 -373.221331) (xy 48.326316 -373.275279)
			(xy 48.326802 -373.30253) (xy 48.326113 -373.335062) (xy 48.315002 -373.399171) (xy 48.304704 -373.430038)
			(xy 48.301656 -373.438674) (xy 48.30191 -373.456454) (xy 48.331374 -373.53494) (xy 48.342804 -373.548148)
			(xy 48.350932 -373.55272) (xy 48.38319 -373.572532) (xy 48.3896 -373.576557) (xy 48.404073 -373.580959)
			(xy 48.411638 -373.581168) (xy 48.69307 -373.581168) (xy 48.700625 -373.580894) (xy 48.715083 -373.576499)
			(xy 48.721518 -373.572532) (xy 48.753776 -373.55272) (xy 48.761904 -373.548148) (xy 48.773334 -373.53494)
			(xy 48.802798 -373.456454) (xy 48.803052 -373.438674) (xy 48.800004 -373.430038) (xy 48.78971 -373.399171)
			(xy 48.778606 -373.335061) (xy 48.777906 -373.30253) (xy 48.778392 -373.275279) (xy 48.786148 -373.221331)
			(xy 48.801503 -373.169036) (xy 48.824145 -373.119459) (xy 48.853611 -373.073609) (xy 48.889302 -373.032418)
			(xy 48.930493 -372.996727) (xy 48.976343 -372.967261) (xy 49.02592 -372.944619) (xy 49.078215 -372.929264)
			(xy 49.132163 -372.921508) (xy 49.186665 -372.921508) (xy 49.240613 -372.929264) (xy 49.292908 -372.944619)
			(xy 49.342485 -372.967261) (xy 49.388335 -372.996727) (xy 49.429526 -373.032418) (xy 49.465217 -373.073609)
			(xy 49.494683 -373.119459) (xy 49.517325 -373.169036) (xy 49.53268 -373.221331) (xy 49.540436 -373.275279)
			(xy 49.540922 -373.30253) (xy 49.540563 -373.326602) (xy 49.534525 -373.374364) (xy 49.522535 -373.42099)
			(xy 49.513998 -373.4435) (xy 49.508918 -373.455946) (xy 49.51222 -373.481854) (xy 49.579022 -373.572532)
			(xy 49.602644 -373.583454) (xy 49.615852 -373.582438) (xy 49.644554 -373.581422) (xy 49.671811 -373.581822)
			(xy 49.725771 -373.589574) (xy 49.778079 -373.604927) (xy 49.827669 -373.627569) (xy 49.873531 -373.657038)
			(xy 49.914733 -373.692735) (xy 49.950434 -373.733932) (xy 49.979909 -373.779791) (xy 50.002557 -373.829378)
			(xy 50.017916 -373.881684) (xy 50.025675 -373.935643) (xy 50.025675 -373.990147) (xy 53.886408 -373.990147)
			(xy 53.886408 -373.935653) (xy 53.894163 -373.881714) (xy 53.909514 -373.829427) (xy 53.93215 -373.779857)
			(xy 53.96161 -373.734012) (xy 53.997294 -373.692826) (xy 54.038475 -373.657138) (xy 54.084316 -373.627672)
			(xy 54.133884 -373.60503) (xy 54.186169 -373.589673) (xy 54.240107 -373.581911) (xy 54.267354 -373.581422)
			(xy 54.296056 -373.582438) (xy 54.309264 -373.583454) (xy 54.332886 -373.572532) (xy 54.399688 -373.481854)
			(xy 54.40299 -373.455946) (xy 54.39791 -373.4435) (xy 54.389378 -373.420988) (xy 54.377372 -373.374366)
			(xy 54.371338 -373.326602) (xy 54.370986 -373.30253) (xy 54.371472 -373.275279) (xy 54.379228 -373.221331)
			(xy 54.394583 -373.169036) (xy 54.417225 -373.119459) (xy 54.446691 -373.073609) (xy 54.482382 -373.032418)
			(xy 54.523573 -372.996727) (xy 54.569423 -372.967261) (xy 54.619 -372.944619) (xy 54.671295 -372.929264)
			(xy 54.725243 -372.921508) (xy 54.779745 -372.921508) (xy 54.833693 -372.929264) (xy 54.885988 -372.944619)
			(xy 54.935565 -372.967261) (xy 54.981415 -372.996727) (xy 55.022606 -373.032418) (xy 55.058297 -373.073609)
			(xy 55.087763 -373.119459) (xy 55.110405 -373.169036) (xy 55.12576 -373.221331) (xy 55.133516 -373.275279)
			(xy 55.134002 -373.30253) (xy 55.133313 -373.335062) (xy 55.122202 -373.399171) (xy 55.111904 -373.430038)
			(xy 55.108856 -373.438674) (xy 55.10911 -373.456454) (xy 55.138574 -373.53494) (xy 55.150004 -373.548148)
			(xy 55.158132 -373.55272) (xy 55.19039 -373.572532) (xy 55.1968 -373.576557) (xy 55.211273 -373.580959)
			(xy 55.218838 -373.581168) (xy 55.50027 -373.581168) (xy 55.507825 -373.580894) (xy 55.522283 -373.576499)
			(xy 55.528718 -373.572532) (xy 55.560976 -373.55272) (xy 55.569104 -373.548148) (xy 55.580534 -373.53494)
			(xy 55.609998 -373.456454) (xy 55.610252 -373.438674) (xy 55.607204 -373.430038) (xy 55.59691 -373.399171)
			(xy 55.585806 -373.335061) (xy 55.585106 -373.30253) (xy 55.585592 -373.275279) (xy 55.593348 -373.221331)
			(xy 55.608703 -373.169036) (xy 55.631345 -373.119459) (xy 55.660811 -373.073609) (xy 55.696502 -373.032418)
			(xy 55.737693 -372.996727) (xy 55.783543 -372.967261) (xy 55.83312 -372.944619) (xy 55.885415 -372.929264)
			(xy 55.939363 -372.921508) (xy 55.993865 -372.921508) (xy 56.047813 -372.929264) (xy 56.100108 -372.944619)
			(xy 56.149685 -372.967261) (xy 56.195535 -372.996727) (xy 56.236726 -373.032418) (xy 56.272417 -373.073609)
			(xy 56.301883 -373.119459) (xy 56.324525 -373.169036) (xy 56.33988 -373.221331) (xy 56.347636 -373.275279)
			(xy 56.348122 -373.30253) (xy 56.347763 -373.326602) (xy 56.341725 -373.374364) (xy 56.329735 -373.42099)
			(xy 56.321198 -373.4435) (xy 56.316118 -373.455946) (xy 56.31942 -373.481854) (xy 56.386222 -373.572532)
			(xy 56.409844 -373.583454) (xy 56.423052 -373.582438) (xy 56.451754 -373.581422) (xy 56.479011 -373.581822)
			(xy 56.532971 -373.589574) (xy 56.585279 -373.604927) (xy 56.634869 -373.627569) (xy 56.680731 -373.657038)
			(xy 56.721933 -373.692735) (xy 56.757634 -373.733932) (xy 56.787109 -373.779791) (xy 56.809757 -373.829378)
			(xy 56.825116 -373.881684) (xy 56.832875 -373.935643) (xy 56.832875 -373.990147) (xy 60.693608 -373.990147)
			(xy 60.693608 -373.935653) (xy 60.701363 -373.881714) (xy 60.716714 -373.829427) (xy 60.73935 -373.779857)
			(xy 60.76881 -373.734012) (xy 60.804494 -373.692826) (xy 60.845675 -373.657138) (xy 60.891516 -373.627672)
			(xy 60.941084 -373.60503) (xy 60.993369 -373.589673) (xy 61.047307 -373.581911) (xy 61.074554 -373.581422)
			(xy 61.103256 -373.582438) (xy 61.116464 -373.583454) (xy 61.140086 -373.572532) (xy 61.206888 -373.481854)
			(xy 61.21019 -373.455946) (xy 61.20511 -373.4435) (xy 61.196578 -373.420988) (xy 61.184572 -373.374366)
			(xy 61.178538 -373.326602) (xy 61.178186 -373.30253) (xy 61.178672 -373.275279) (xy 61.186428 -373.221331)
			(xy 61.201783 -373.169036) (xy 61.224425 -373.119459) (xy 61.253891 -373.073609) (xy 61.289582 -373.032418)
			(xy 61.330773 -372.996727) (xy 61.376623 -372.967261) (xy 61.4262 -372.944619) (xy 61.478495 -372.929264)
			(xy 61.532443 -372.921508) (xy 61.586945 -372.921508) (xy 61.640893 -372.929264) (xy 61.693188 -372.944619)
			(xy 61.742765 -372.967261) (xy 61.788615 -372.996727) (xy 61.829806 -373.032418) (xy 61.865497 -373.073609)
			(xy 61.894963 -373.119459) (xy 61.917605 -373.169036) (xy 61.93296 -373.221331) (xy 61.940716 -373.275279)
			(xy 61.941202 -373.30253) (xy 61.940513 -373.335062) (xy 61.929402 -373.399171) (xy 61.919104 -373.430038)
			(xy 61.916056 -373.438674) (xy 61.91631 -373.456454) (xy 61.945774 -373.53494) (xy 61.957204 -373.548148)
			(xy 61.965332 -373.55272) (xy 61.99759 -373.572532) (xy 62.004 -373.576557) (xy 62.018473 -373.580959)
			(xy 62.026038 -373.581168) (xy 62.30747 -373.581168) (xy 62.315025 -373.580894) (xy 62.329483 -373.576499)
			(xy 62.335918 -373.572532) (xy 62.368176 -373.55272) (xy 62.376304 -373.548148) (xy 62.387734 -373.53494)
			(xy 62.417198 -373.456454) (xy 62.417452 -373.438674) (xy 62.414404 -373.430038) (xy 62.40411 -373.399171)
			(xy 62.393006 -373.335061) (xy 62.392306 -373.30253) (xy 62.392792 -373.275279) (xy 62.400548 -373.221331)
			(xy 62.415903 -373.169036) (xy 62.438545 -373.119459) (xy 62.468011 -373.073609) (xy 62.503702 -373.032418)
			(xy 62.544893 -372.996727) (xy 62.590743 -372.967261) (xy 62.64032 -372.944619) (xy 62.692615 -372.929264)
			(xy 62.746563 -372.921508) (xy 62.801065 -372.921508) (xy 62.855013 -372.929264) (xy 62.907308 -372.944619)
			(xy 62.956885 -372.967261) (xy 63.002735 -372.996727) (xy 63.043926 -373.032418) (xy 63.079617 -373.073609)
			(xy 63.109083 -373.119459) (xy 63.131725 -373.169036) (xy 63.14708 -373.221331) (xy 63.154836 -373.275279)
			(xy 63.155322 -373.30253) (xy 63.154963 -373.326602) (xy 63.148925 -373.374364) (xy 63.136935 -373.42099)
			(xy 63.128398 -373.4435) (xy 63.123318 -373.455946) (xy 63.12662 -373.481854) (xy 63.193422 -373.572532)
			(xy 63.217044 -373.583454) (xy 63.230252 -373.582438) (xy 63.258954 -373.581422) (xy 63.286211 -373.581822)
			(xy 63.340171 -373.589574) (xy 63.392479 -373.604927) (xy 63.442069 -373.627569) (xy 63.487931 -373.657038)
			(xy 63.529133 -373.692735) (xy 63.564834 -373.733932) (xy 63.594309 -373.779791) (xy 63.616957 -373.829378)
			(xy 63.632316 -373.881684) (xy 63.640075 -373.935643) (xy 63.640075 -373.990151) (xy 79.606885 -373.990151)
			(xy 79.606885 -373.935649) (xy 79.614642 -373.881702) (xy 79.629997 -373.829408) (xy 79.652637 -373.779832)
			(xy 79.682103 -373.733982) (xy 79.717794 -373.692793) (xy 79.758984 -373.657102) (xy 79.804834 -373.627637)
			(xy 79.85441 -373.604996) (xy 79.906704 -373.589641) (xy 79.960651 -373.581885) (xy 79.987902 -373.581422)
			(xy 80.016604 -373.582438) (xy 80.029812 -373.583454) (xy 80.053434 -373.572532) (xy 80.120236 -373.481854)
			(xy 80.123538 -373.455946) (xy 80.118458 -373.4435) (xy 80.109924 -373.420989) (xy 80.097919 -373.374366)
			(xy 80.091886 -373.326602) (xy 80.091534 -373.30253) (xy 80.09202 -373.275279) (xy 80.099776 -373.221331)
			(xy 80.115131 -373.169036) (xy 80.137773 -373.119459) (xy 80.167239 -373.073609) (xy 80.20293 -373.032418)
			(xy 80.244121 -372.996727) (xy 80.289971 -372.967261) (xy 80.339548 -372.944619) (xy 80.391843 -372.929264)
			(xy 80.445791 -372.921508) (xy 80.500293 -372.921508) (xy 80.554241 -372.929264) (xy 80.606536 -372.944619)
			(xy 80.656113 -372.967261) (xy 80.701963 -372.996727) (xy 80.743154 -373.032418) (xy 80.778845 -373.073609)
			(xy 80.808311 -373.119459) (xy 80.830953 -373.169036) (xy 80.846308 -373.221331) (xy 80.854064 -373.275279)
			(xy 80.85455 -373.30253) (xy 80.853858 -373.335062) (xy 80.842749 -373.399171) (xy 80.832452 -373.430038)
			(xy 80.829404 -373.438674) (xy 80.829658 -373.456454) (xy 80.859122 -373.53494) (xy 80.870552 -373.548148)
			(xy 80.87868 -373.55272) (xy 80.910938 -373.572532) (xy 80.917338 -373.576575) (xy 80.931818 -373.580965)
			(xy 80.939386 -373.581168) (xy 81.220818 -373.581168) (xy 81.228371 -373.580872) (xy 81.242829 -373.576492)
			(xy 81.249266 -373.572532) (xy 81.281524 -373.55272) (xy 81.289652 -373.548148) (xy 81.301082 -373.53494)
			(xy 81.330546 -373.456454) (xy 81.3308 -373.438674) (xy 81.327752 -373.430038) (xy 81.317456 -373.399171)
			(xy 81.306353 -373.335061) (xy 81.305654 -373.30253) (xy 81.30614 -373.275279) (xy 81.313896 -373.221331)
			(xy 81.329251 -373.169036) (xy 81.351893 -373.119459) (xy 81.381359 -373.073609) (xy 81.41705 -373.032418)
			(xy 81.458241 -372.996727) (xy 81.504091 -372.967261) (xy 81.553668 -372.944619) (xy 81.605963 -372.929264)
			(xy 81.659911 -372.921508) (xy 81.714413 -372.921508) (xy 81.768361 -372.929264) (xy 81.820656 -372.944619)
			(xy 81.870233 -372.967261) (xy 81.916083 -372.996727) (xy 81.957274 -373.032418) (xy 81.992965 -373.073609)
			(xy 82.022431 -373.119459) (xy 82.045073 -373.169036) (xy 82.060428 -373.221331) (xy 82.068184 -373.275279)
			(xy 82.06867 -373.30253) (xy 82.068308 -373.326601) (xy 82.06227 -373.374364) (xy 82.050282 -373.42099)
			(xy 82.041746 -373.4435) (xy 82.036666 -373.455946) (xy 82.039968 -373.481854) (xy 82.10677 -373.572532)
			(xy 82.130392 -373.583454) (xy 82.1436 -373.582438) (xy 82.172302 -373.581422) (xy 82.199555 -373.581848)
			(xy 82.253507 -373.589605) (xy 82.305806 -373.604962) (xy 82.355387 -373.627605) (xy 82.40124 -373.657074)
			(xy 82.442434 -373.692768) (xy 82.478128 -373.733961) (xy 82.507596 -373.779815) (xy 82.530239 -373.829396)
			(xy 82.545595 -373.881695) (xy 82.553352 -373.935647) (xy 82.553352 -373.96293) (xy 83.009484 -373.96293)
			(xy 83.013555 -373.907308) (xy 83.025681 -373.852871) (xy 83.045604 -373.80078) (xy 83.0729 -373.752145)
			(xy 83.106986 -373.708002) (xy 83.147135 -373.669293) (xy 83.192493 -373.636842) (xy 83.242093 -373.611341)
			(xy 83.294877 -373.593334) (xy 83.34972 -373.583204) (xy 83.405454 -373.581167) (xy 83.460891 -373.587267)
			(xy 83.514848 -373.601373) (xy 83.566177 -373.623185) (xy 83.613783 -373.652239) (xy 83.656651 -373.687914)
			(xy 83.693868 -373.729451) (xy 83.724641 -373.775964) (xy 83.748313 -373.826461) (xy 83.764381 -373.879868)
			(xy 83.772501 -373.935044) (xy 83.77301 -373.96293) (xy 83.772513 -373.990151) (xy 86.414085 -373.990151)
			(xy 86.414085 -373.935649) (xy 86.421842 -373.881702) (xy 86.437197 -373.829408) (xy 86.459837 -373.779832)
			(xy 86.489303 -373.733982) (xy 86.524994 -373.692793) (xy 86.566184 -373.657102) (xy 86.612034 -373.627637)
			(xy 86.66161 -373.604996) (xy 86.713904 -373.589641) (xy 86.767851 -373.581885) (xy 86.795102 -373.581422)
			(xy 86.823804 -373.582438) (xy 86.837012 -373.583454) (xy 86.860634 -373.572532) (xy 86.927436 -373.481854)
			(xy 86.930738 -373.455946) (xy 86.925658 -373.4435) (xy 86.917124 -373.420989) (xy 86.905119 -373.374366)
			(xy 86.899086 -373.326602) (xy 86.898734 -373.30253) (xy 86.89922 -373.275279) (xy 86.906976 -373.221331)
			(xy 86.922331 -373.169036) (xy 86.944973 -373.119459) (xy 86.974439 -373.073609) (xy 87.01013 -373.032418)
			(xy 87.051321 -372.996727) (xy 87.097171 -372.967261) (xy 87.146748 -372.944619) (xy 87.199043 -372.929264)
			(xy 87.252991 -372.921508) (xy 87.307493 -372.921508) (xy 87.361441 -372.929264) (xy 87.413736 -372.944619)
			(xy 87.463313 -372.967261) (xy 87.509163 -372.996727) (xy 87.550354 -373.032418) (xy 87.586045 -373.073609)
			(xy 87.615511 -373.119459) (xy 87.638153 -373.169036) (xy 87.653508 -373.221331) (xy 87.661264 -373.275279)
			(xy 87.66175 -373.30253) (xy 87.661058 -373.335062) (xy 87.649949 -373.399171) (xy 87.639652 -373.430038)
			(xy 87.636604 -373.438674) (xy 87.636858 -373.456454) (xy 87.666322 -373.53494) (xy 87.677752 -373.548148)
			(xy 87.68588 -373.55272) (xy 87.718138 -373.572532) (xy 87.724538 -373.576575) (xy 87.739018 -373.580965)
			(xy 87.746586 -373.581168) (xy 88.028018 -373.581168) (xy 88.035571 -373.580872) (xy 88.050029 -373.576492)
			(xy 88.056466 -373.572532) (xy 88.088724 -373.55272) (xy 88.096852 -373.548148) (xy 88.108282 -373.53494)
			(xy 88.137746 -373.456454) (xy 88.138 -373.438674) (xy 88.134952 -373.430038) (xy 88.124656 -373.399171)
			(xy 88.113553 -373.335061) (xy 88.112854 -373.30253) (xy 88.11334 -373.275279) (xy 88.121096 -373.221331)
			(xy 88.136451 -373.169036) (xy 88.159093 -373.119459) (xy 88.188559 -373.073609) (xy 88.22425 -373.032418)
			(xy 88.265441 -372.996727) (xy 88.311291 -372.967261) (xy 88.360868 -372.944619) (xy 88.413163 -372.929264)
			(xy 88.467111 -372.921508) (xy 88.521613 -372.921508) (xy 88.575561 -372.929264) (xy 88.627856 -372.944619)
			(xy 88.677433 -372.967261) (xy 88.723283 -372.996727) (xy 88.764474 -373.032418) (xy 88.800165 -373.073609)
			(xy 88.829631 -373.119459) (xy 88.852273 -373.169036) (xy 88.867628 -373.221331) (xy 88.875384 -373.275279)
			(xy 88.87587 -373.30253) (xy 88.875508 -373.326601) (xy 88.86947 -373.374364) (xy 88.857482 -373.42099)
			(xy 88.848946 -373.4435) (xy 88.843866 -373.455946) (xy 88.847168 -373.481854) (xy 88.91397 -373.572532)
			(xy 88.937592 -373.583454) (xy 88.9508 -373.582438) (xy 88.979502 -373.581422) (xy 89.006755 -373.581848)
			(xy 89.060707 -373.589605) (xy 89.113006 -373.604962) (xy 89.162587 -373.627605) (xy 89.20844 -373.657074)
			(xy 89.249634 -373.692768) (xy 89.285328 -373.733961) (xy 89.314796 -373.779815) (xy 89.337439 -373.829396)
			(xy 89.352795 -373.881695) (xy 89.360552 -373.935647) (xy 89.360552 -373.990151) (xy 93.221285 -373.990151)
			(xy 93.221285 -373.935649) (xy 93.229042 -373.881702) (xy 93.244397 -373.829408) (xy 93.267037 -373.779832)
			(xy 93.296503 -373.733982) (xy 93.332194 -373.692793) (xy 93.373384 -373.657102) (xy 93.419234 -373.627637)
			(xy 93.46881 -373.604996) (xy 93.521104 -373.589641) (xy 93.575051 -373.581885) (xy 93.602302 -373.581422)
			(xy 93.631004 -373.582438) (xy 93.644212 -373.583454) (xy 93.667834 -373.572532) (xy 93.734636 -373.481854)
			(xy 93.737938 -373.455946) (xy 93.732858 -373.4435) (xy 93.724324 -373.420989) (xy 93.712319 -373.374366)
			(xy 93.706286 -373.326602) (xy 93.705934 -373.30253) (xy 93.70642 -373.275279) (xy 93.714176 -373.221331)
			(xy 93.729531 -373.169036) (xy 93.752173 -373.119459) (xy 93.781639 -373.073609) (xy 93.81733 -373.032418)
			(xy 93.858521 -372.996727) (xy 93.904371 -372.967261) (xy 93.953948 -372.944619) (xy 94.006243 -372.929264)
			(xy 94.060191 -372.921508) (xy 94.114693 -372.921508) (xy 94.168641 -372.929264) (xy 94.220936 -372.944619)
			(xy 94.270513 -372.967261) (xy 94.316363 -372.996727) (xy 94.357554 -373.032418) (xy 94.393245 -373.073609)
			(xy 94.422711 -373.119459) (xy 94.445353 -373.169036) (xy 94.460708 -373.221331) (xy 94.468464 -373.275279)
			(xy 94.46895 -373.30253) (xy 94.468258 -373.335062) (xy 94.457149 -373.399171) (xy 94.446852 -373.430038)
			(xy 94.443804 -373.438674) (xy 94.444058 -373.456454) (xy 94.473522 -373.53494) (xy 94.484952 -373.548148)
			(xy 94.49308 -373.55272) (xy 94.525338 -373.572532) (xy 94.531738 -373.576575) (xy 94.546218 -373.580965)
			(xy 94.553786 -373.581168) (xy 94.835218 -373.581168) (xy 94.842771 -373.580872) (xy 94.857229 -373.576492)
			(xy 94.863666 -373.572532) (xy 94.895924 -373.55272) (xy 94.904052 -373.548148) (xy 94.915482 -373.53494)
			(xy 94.944946 -373.456454) (xy 94.9452 -373.438674) (xy 94.942152 -373.430038) (xy 94.931856 -373.399171)
			(xy 94.920753 -373.335061) (xy 94.920054 -373.30253) (xy 94.92054 -373.275279) (xy 94.928296 -373.221331)
			(xy 94.943651 -373.169036) (xy 94.966293 -373.119459) (xy 94.995759 -373.073609) (xy 95.03145 -373.032418)
			(xy 95.072641 -372.996727) (xy 95.118491 -372.967261) (xy 95.168068 -372.944619) (xy 95.220363 -372.929264)
			(xy 95.274311 -372.921508) (xy 95.328813 -372.921508) (xy 95.382761 -372.929264) (xy 95.435056 -372.944619)
			(xy 95.484633 -372.967261) (xy 95.530483 -372.996727) (xy 95.571674 -373.032418) (xy 95.607365 -373.073609)
			(xy 95.636831 -373.119459) (xy 95.659473 -373.169036) (xy 95.674828 -373.221331) (xy 95.682584 -373.275279)
			(xy 95.68307 -373.30253) (xy 95.682708 -373.326601) (xy 95.67667 -373.374364) (xy 95.664682 -373.42099)
			(xy 95.656146 -373.4435) (xy 95.651066 -373.455946) (xy 95.654368 -373.481854) (xy 95.72117 -373.572532)
			(xy 95.744792 -373.583454) (xy 95.758 -373.582438) (xy 95.786702 -373.581422) (xy 95.813955 -373.581848)
			(xy 95.867907 -373.589605) (xy 95.920206 -373.604962) (xy 95.969787 -373.627605) (xy 96.01564 -373.657074)
			(xy 96.056834 -373.692768) (xy 96.092528 -373.733961) (xy 96.121996 -373.779815) (xy 96.144639 -373.829396)
			(xy 96.159995 -373.881695) (xy 96.167752 -373.935647) (xy 96.167752 -373.990149) (xy 114.179108 -373.990149)
			(xy 114.179108 -373.935651) (xy 114.186864 -373.881708) (xy 114.202218 -373.829418) (xy 114.224857 -373.779845)
			(xy 114.25432 -373.733998) (xy 114.290009 -373.692811) (xy 114.331195 -373.657123) (xy 114.377041 -373.627659)
			(xy 114.426614 -373.605019) (xy 114.478904 -373.589665) (xy 114.532847 -373.581908) (xy 114.560096 -373.581422)
			(xy 114.588798 -373.582438) (xy 114.602006 -373.583454) (xy 114.625628 -373.572532) (xy 114.69243 -373.481854)
			(xy 114.695732 -373.455946) (xy 114.690652 -373.4435) (xy 114.682117 -373.420989) (xy 114.670113 -373.374366)
			(xy 114.66408 -373.326602) (xy 114.663728 -373.30253) (xy 114.664214 -373.275279) (xy 114.67197 -373.221331)
			(xy 114.687325 -373.169036) (xy 114.709967 -373.119459) (xy 114.739433 -373.073609) (xy 114.775124 -373.032418)
			(xy 114.816315 -372.996727) (xy 114.862165 -372.967261) (xy 114.911742 -372.944619) (xy 114.964037 -372.929264)
			(xy 115.017985 -372.921508) (xy 115.072487 -372.921508) (xy 115.126435 -372.929264) (xy 115.17873 -372.944619)
			(xy 115.228307 -372.967261) (xy 115.274157 -372.996727) (xy 115.315348 -373.032418) (xy 115.351039 -373.073609)
			(xy 115.380505 -373.119459) (xy 115.403147 -373.169036) (xy 115.418502 -373.221331) (xy 115.426258 -373.275279)
			(xy 115.426744 -373.30253) (xy 115.426053 -373.335062) (xy 115.414943 -373.399171) (xy 115.404646 -373.430038)
			(xy 115.401598 -373.438674) (xy 115.401852 -373.456454) (xy 115.431316 -373.53494) (xy 115.442746 -373.548148)
			(xy 115.450874 -373.55272) (xy 115.483132 -373.572532) (xy 115.489533 -373.576573) (xy 115.504013 -373.580965)
			(xy 115.51158 -373.581168) (xy 115.793012 -373.581168) (xy 115.800565 -373.58087) (xy 115.815023 -373.576492)
			(xy 115.82146 -373.572532) (xy 115.853718 -373.55272) (xy 115.861846 -373.548148) (xy 115.873276 -373.53494)
			(xy 115.90274 -373.456454) (xy 115.902994 -373.438674) (xy 115.899946 -373.430038) (xy 115.889653 -373.39917)
			(xy 115.878548 -373.335061) (xy 115.877848 -373.30253) (xy 115.878334 -373.275279) (xy 115.88609 -373.221331)
			(xy 115.901445 -373.169036) (xy 115.924087 -373.119459) (xy 115.953553 -373.073609) (xy 115.989244 -373.032418)
			(xy 116.030435 -372.996727) (xy 116.076285 -372.967261) (xy 116.125862 -372.944619) (xy 116.178157 -372.929264)
			(xy 116.232105 -372.921508) (xy 116.286607 -372.921508) (xy 116.340555 -372.929264) (xy 116.39285 -372.944619)
			(xy 116.442427 -372.967261) (xy 116.488277 -372.996727) (xy 116.529468 -373.032418) (xy 116.565159 -373.073609)
			(xy 116.594625 -373.119459) (xy 116.617267 -373.169036) (xy 116.632622 -373.221331) (xy 116.640378 -373.275279)
			(xy 116.640864 -373.30253) (xy 116.640502 -373.326601) (xy 116.634465 -373.374364) (xy 116.622476 -373.42099)
			(xy 116.61394 -373.4435) (xy 116.60886 -373.455946) (xy 116.612162 -373.481854) (xy 116.678964 -373.572532)
			(xy 116.702586 -373.583454) (xy 116.715794 -373.582438) (xy 116.744496 -373.581422) (xy 116.771751 -373.581825)
			(xy 116.825707 -373.589582) (xy 116.878009 -373.604939) (xy 116.927594 -373.627583) (xy 116.973451 -373.657053)
			(xy 117.014648 -373.692749) (xy 117.050345 -373.733946) (xy 117.079815 -373.779803) (xy 117.10246 -373.829387)
			(xy 117.117817 -373.881689) (xy 117.125575 -373.935645) (xy 117.125575 -373.990149) (xy 120.986308 -373.990149)
			(xy 120.986308 -373.935651) (xy 120.994064 -373.881708) (xy 121.009418 -373.829418) (xy 121.032057 -373.779845)
			(xy 121.06152 -373.733998) (xy 121.097209 -373.692811) (xy 121.138395 -373.657123) (xy 121.184241 -373.627659)
			(xy 121.233814 -373.605019) (xy 121.286104 -373.589665) (xy 121.340047 -373.581908) (xy 121.367296 -373.581422)
			(xy 121.395998 -373.582438) (xy 121.409206 -373.583454) (xy 121.432828 -373.572532) (xy 121.49963 -373.481854)
			(xy 121.502932 -373.455946) (xy 121.497852 -373.4435) (xy 121.489317 -373.420989) (xy 121.477313 -373.374366)
			(xy 121.47128 -373.326602) (xy 121.470928 -373.30253) (xy 121.471414 -373.275279) (xy 121.47917 -373.221331)
			(xy 121.494525 -373.169036) (xy 121.517167 -373.119459) (xy 121.546633 -373.073609) (xy 121.582324 -373.032418)
			(xy 121.623515 -372.996727) (xy 121.669365 -372.967261) (xy 121.718942 -372.944619) (xy 121.771237 -372.929264)
			(xy 121.825185 -372.921508) (xy 121.879687 -372.921508) (xy 121.933635 -372.929264) (xy 121.98593 -372.944619)
			(xy 122.035507 -372.967261) (xy 122.081357 -372.996727) (xy 122.122548 -373.032418) (xy 122.158239 -373.073609)
			(xy 122.187705 -373.119459) (xy 122.210347 -373.169036) (xy 122.225702 -373.221331) (xy 122.233458 -373.275279)
			(xy 122.233944 -373.30253) (xy 122.233253 -373.335062) (xy 122.222143 -373.399171) (xy 122.211846 -373.430038)
			(xy 122.208798 -373.438674) (xy 122.209052 -373.456454) (xy 122.238516 -373.53494) (xy 122.249946 -373.548148)
			(xy 122.258074 -373.55272) (xy 122.290332 -373.572532) (xy 122.296733 -373.576573) (xy 122.311213 -373.580965)
			(xy 122.31878 -373.581168) (xy 122.600212 -373.581168) (xy 122.607765 -373.58087) (xy 122.622223 -373.576492)
			(xy 122.62866 -373.572532) (xy 122.660918 -373.55272) (xy 122.669046 -373.548148) (xy 122.680476 -373.53494)
			(xy 122.70994 -373.456454) (xy 122.710194 -373.438674) (xy 122.707146 -373.430038) (xy 122.696853 -373.39917)
			(xy 122.685748 -373.335061) (xy 122.685048 -373.30253) (xy 122.685534 -373.275279) (xy 122.69329 -373.221331)
			(xy 122.708645 -373.169036) (xy 122.731287 -373.119459) (xy 122.760753 -373.073609) (xy 122.796444 -373.032418)
			(xy 122.837635 -372.996727) (xy 122.883485 -372.967261) (xy 122.933062 -372.944619) (xy 122.985357 -372.929264)
			(xy 123.039305 -372.921508) (xy 123.093807 -372.921508) (xy 123.147755 -372.929264) (xy 123.20005 -372.944619)
			(xy 123.249627 -372.967261) (xy 123.295477 -372.996727) (xy 123.336668 -373.032418) (xy 123.372359 -373.073609)
			(xy 123.401825 -373.119459) (xy 123.424467 -373.169036) (xy 123.439822 -373.221331) (xy 123.447578 -373.275279)
			(xy 123.448064 -373.30253) (xy 123.447702 -373.326601) (xy 123.441665 -373.374364) (xy 123.429676 -373.42099)
			(xy 123.42114 -373.4435) (xy 123.41606 -373.455946) (xy 123.419362 -373.481854) (xy 123.486164 -373.572532)
			(xy 123.509786 -373.583454) (xy 123.522994 -373.582438) (xy 123.551696 -373.581422) (xy 123.578951 -373.581825)
			(xy 123.632907 -373.589582) (xy 123.685209 -373.604939) (xy 123.734794 -373.627583) (xy 123.780651 -373.657053)
			(xy 123.821848 -373.692749) (xy 123.857545 -373.733946) (xy 123.887015 -373.779803) (xy 123.90966 -373.829387)
			(xy 123.925017 -373.881689) (xy 123.932775 -373.935645) (xy 123.932775 -373.990149) (xy 127.793508 -373.990149)
			(xy 127.793508 -373.935651) (xy 127.801264 -373.881708) (xy 127.816618 -373.829418) (xy 127.839257 -373.779845)
			(xy 127.86872 -373.733998) (xy 127.904409 -373.692811) (xy 127.945595 -373.657123) (xy 127.991441 -373.627659)
			(xy 128.041014 -373.605019) (xy 128.093304 -373.589665) (xy 128.147247 -373.581908) (xy 128.174496 -373.581422)
			(xy 128.203198 -373.582438) (xy 128.216406 -373.583454) (xy 128.240028 -373.572532) (xy 128.30683 -373.481854)
			(xy 128.310132 -373.455946) (xy 128.305052 -373.4435) (xy 128.296517 -373.420989) (xy 128.284513 -373.374366)
			(xy 128.27848 -373.326602) (xy 128.278128 -373.30253) (xy 128.278614 -373.275279) (xy 128.28637 -373.221331)
			(xy 128.301725 -373.169036) (xy 128.324367 -373.119459) (xy 128.353833 -373.073609) (xy 128.389524 -373.032418)
			(xy 128.430715 -372.996727) (xy 128.476565 -372.967261) (xy 128.526142 -372.944619) (xy 128.578437 -372.929264)
			(xy 128.632385 -372.921508) (xy 128.686887 -372.921508) (xy 128.740835 -372.929264) (xy 128.79313 -372.944619)
			(xy 128.842707 -372.967261) (xy 128.888557 -372.996727) (xy 128.929748 -373.032418) (xy 128.965439 -373.073609)
			(xy 128.994905 -373.119459) (xy 129.017547 -373.169036) (xy 129.032902 -373.221331) (xy 129.040658 -373.275279)
			(xy 129.041144 -373.30253) (xy 129.040453 -373.335062) (xy 129.029343 -373.399171) (xy 129.019046 -373.430038)
			(xy 129.015998 -373.438674) (xy 129.016252 -373.456454) (xy 129.045716 -373.53494) (xy 129.057146 -373.548148)
			(xy 129.065274 -373.55272) (xy 129.097532 -373.572532) (xy 129.103933 -373.576573) (xy 129.118413 -373.580965)
			(xy 129.12598 -373.581168) (xy 129.407412 -373.581168) (xy 129.414965 -373.58087) (xy 129.429423 -373.576492)
			(xy 129.43586 -373.572532) (xy 129.468118 -373.55272) (xy 129.476246 -373.548148) (xy 129.487676 -373.53494)
			(xy 129.51714 -373.456454) (xy 129.517394 -373.438674) (xy 129.514346 -373.430038) (xy 129.504053 -373.39917)
			(xy 129.492948 -373.335061) (xy 129.492248 -373.30253) (xy 129.492734 -373.275279) (xy 129.50049 -373.221331)
			(xy 129.515845 -373.169036) (xy 129.538487 -373.119459) (xy 129.567953 -373.073609) (xy 129.603644 -373.032418)
			(xy 129.644835 -372.996727) (xy 129.690685 -372.967261) (xy 129.740262 -372.944619) (xy 129.792557 -372.929264)
			(xy 129.846505 -372.921508) (xy 129.901007 -372.921508) (xy 129.954955 -372.929264) (xy 130.00725 -372.944619)
			(xy 130.056827 -372.967261) (xy 130.102677 -372.996727) (xy 130.143868 -373.032418) (xy 130.179559 -373.073609)
			(xy 130.209025 -373.119459) (xy 130.231667 -373.169036) (xy 130.247022 -373.221331) (xy 130.254778 -373.275279)
			(xy 130.255264 -373.30253) (xy 130.254902 -373.326601) (xy 130.248865 -373.374364) (xy 130.236876 -373.42099)
			(xy 130.22834 -373.4435) (xy 130.22326 -373.455946) (xy 130.226562 -373.481854) (xy 130.293364 -373.572532)
			(xy 130.316986 -373.583454) (xy 130.330194 -373.582438) (xy 130.358896 -373.581422) (xy 130.386151 -373.581825)
			(xy 130.440107 -373.589582) (xy 130.492409 -373.604939) (xy 130.541994 -373.627583) (xy 130.587851 -373.657053)
			(xy 130.629048 -373.692749) (xy 130.664745 -373.733946) (xy 130.694215 -373.779803) (xy 130.71686 -373.829387)
			(xy 130.732217 -373.881689) (xy 130.739975 -373.935645) (xy 130.739975 -373.990153) (xy 146.706785 -373.990153)
			(xy 146.706785 -373.935647) (xy 146.714543 -373.881697) (xy 146.7299 -373.829399) (xy 146.752544 -373.77982)
			(xy 146.782014 -373.733969) (xy 146.817709 -373.692778) (xy 146.858904 -373.657087) (xy 146.904759 -373.627623)
			(xy 146.954341 -373.604985) (xy 147.00664 -373.589634) (xy 147.060591 -373.581882) (xy 147.087844 -373.581422)
			(xy 147.116546 -373.582438) (xy 147.129754 -373.583454) (xy 147.153376 -373.572532) (xy 147.220178 -373.481854)
			(xy 147.22348 -373.455946) (xy 147.2184 -373.4435) (xy 147.209867 -373.420988) (xy 147.197862 -373.374366)
			(xy 147.191828 -373.326602) (xy 147.191476 -373.30253) (xy 147.191962 -373.275279) (xy 147.199718 -373.221331)
			(xy 147.215073 -373.169036) (xy 147.237715 -373.119459) (xy 147.267181 -373.073609) (xy 147.302872 -373.032418)
			(xy 147.344063 -372.996727) (xy 147.389913 -372.967261) (xy 147.43949 -372.944619) (xy 147.491785 -372.929264)
			(xy 147.545733 -372.921508) (xy 147.600235 -372.921508) (xy 147.654183 -372.929264) (xy 147.706478 -372.944619)
			(xy 147.756055 -372.967261) (xy 147.801905 -372.996727) (xy 147.843096 -373.032418) (xy 147.878787 -373.073609)
			(xy 147.908253 -373.119459) (xy 147.930895 -373.169036) (xy 147.94625 -373.221331) (xy 147.954006 -373.275279)
			(xy 147.954492 -373.30253) (xy 147.953803 -373.335062) (xy 147.942692 -373.399171) (xy 147.932394 -373.430038)
			(xy 147.929346 -373.438674) (xy 147.9296 -373.456454) (xy 147.959064 -373.53494) (xy 147.970494 -373.548148)
			(xy 147.978622 -373.55272) (xy 148.01088 -373.572532) (xy 148.017271 -373.576591) (xy 148.031758 -373.580972)
			(xy 148.039328 -373.581168) (xy 148.32076 -373.581168) (xy 148.328314 -373.58089) (xy 148.342772 -373.576498)
			(xy 148.349208 -373.572532) (xy 148.381466 -373.55272) (xy 148.389594 -373.548148) (xy 148.401024 -373.53494)
			(xy 148.430488 -373.456454) (xy 148.430742 -373.438674) (xy 148.427694 -373.430038) (xy 148.417399 -373.399171)
			(xy 148.406295 -373.335061) (xy 148.405596 -373.30253) (xy 148.406082 -373.275279) (xy 148.413838 -373.221331)
			(xy 148.429193 -373.169036) (xy 148.451835 -373.119459) (xy 148.481301 -373.073609) (xy 148.516992 -373.032418)
			(xy 148.558183 -372.996727) (xy 148.604033 -372.967261) (xy 148.65361 -372.944619) (xy 148.705905 -372.929264)
			(xy 148.759853 -372.921508) (xy 148.814355 -372.921508) (xy 148.868303 -372.929264) (xy 148.920598 -372.944619)
			(xy 148.970175 -372.967261) (xy 149.016025 -372.996727) (xy 149.057216 -373.032418) (xy 149.092907 -373.073609)
			(xy 149.122373 -373.119459) (xy 149.145015 -373.169036) (xy 149.16037 -373.221331) (xy 149.168126 -373.275279)
			(xy 149.168612 -373.30253) (xy 149.168254 -373.326602) (xy 149.162215 -373.374364) (xy 149.150225 -373.42099)
			(xy 149.141688 -373.4435) (xy 149.136608 -373.455946) (xy 149.13991 -373.481854) (xy 149.206712 -373.572532)
			(xy 149.230334 -373.583454) (xy 149.243542 -373.582438) (xy 149.272244 -373.581422) (xy 149.299495 -373.581851)
			(xy 149.353443 -373.589613) (xy 149.405736 -373.604973) (xy 149.455312 -373.627619) (xy 149.50116 -373.657088)
			(xy 149.542348 -373.692783) (xy 149.578038 -373.733975) (xy 149.607502 -373.779827) (xy 149.630142 -373.829405)
			(xy 149.645496 -373.881701) (xy 149.653252 -373.935649) (xy 149.653252 -373.990151) (xy 149.653252 -373.990153)
			(xy 153.513985 -373.990153) (xy 153.513985 -373.935647) (xy 153.521743 -373.881697) (xy 153.5371 -373.829399)
			(xy 153.559744 -373.77982) (xy 153.589214 -373.733969) (xy 153.624909 -373.692778) (xy 153.666104 -373.657087)
			(xy 153.711959 -373.627623) (xy 153.761541 -373.604985) (xy 153.81384 -373.589634) (xy 153.867791 -373.581882)
			(xy 153.895044 -373.581422) (xy 153.923746 -373.582438) (xy 153.936954 -373.583454) (xy 153.960576 -373.572532)
			(xy 154.027378 -373.481854) (xy 154.03068 -373.455946) (xy 154.0256 -373.4435) (xy 154.017067 -373.420988)
			(xy 154.005062 -373.374366) (xy 153.999028 -373.326602) (xy 153.998676 -373.30253) (xy 153.999162 -373.275279)
			(xy 154.006918 -373.221331) (xy 154.022273 -373.169036) (xy 154.044915 -373.119459) (xy 154.074381 -373.073609)
			(xy 154.110072 -373.032418) (xy 154.151263 -372.996727) (xy 154.197113 -372.967261) (xy 154.24669 -372.944619)
			(xy 154.298985 -372.929264) (xy 154.352933 -372.921508) (xy 154.407435 -372.921508) (xy 154.461383 -372.929264)
			(xy 154.513678 -372.944619) (xy 154.563255 -372.967261) (xy 154.609105 -372.996727) (xy 154.650296 -373.032418)
			(xy 154.685987 -373.073609) (xy 154.715453 -373.119459) (xy 154.738095 -373.169036) (xy 154.75345 -373.221331)
			(xy 154.761206 -373.275279) (xy 154.761692 -373.30253) (xy 154.761003 -373.335062) (xy 154.749892 -373.399171)
			(xy 154.739594 -373.430038) (xy 154.736546 -373.438674) (xy 154.7368 -373.456454) (xy 154.766264 -373.53494)
			(xy 154.777694 -373.548148) (xy 154.785822 -373.55272) (xy 154.81808 -373.572532) (xy 154.824471 -373.576591)
			(xy 154.838958 -373.580972) (xy 154.846528 -373.581168) (xy 155.12796 -373.581168) (xy 155.135514 -373.58089)
			(xy 155.149972 -373.576498) (xy 155.156408 -373.572532) (xy 155.188666 -373.55272) (xy 155.196794 -373.548148)
			(xy 155.208224 -373.53494) (xy 155.237688 -373.456454) (xy 155.237942 -373.438674) (xy 155.234894 -373.430038)
			(xy 155.224599 -373.399171) (xy 155.213495 -373.335061) (xy 155.212796 -373.30253) (xy 155.213282 -373.275279)
			(xy 155.221038 -373.221331) (xy 155.236393 -373.169036) (xy 155.259035 -373.119459) (xy 155.288501 -373.073609)
			(xy 155.324192 -373.032418) (xy 155.365383 -372.996727) (xy 155.411233 -372.967261) (xy 155.46081 -372.944619)
			(xy 155.513105 -372.929264) (xy 155.567053 -372.921508) (xy 155.621555 -372.921508) (xy 155.675503 -372.929264)
			(xy 155.727798 -372.944619) (xy 155.777375 -372.967261) (xy 155.823225 -372.996727) (xy 155.864416 -373.032418)
			(xy 155.900107 -373.073609) (xy 155.929573 -373.119459) (xy 155.952215 -373.169036) (xy 155.96757 -373.221331)
			(xy 155.975326 -373.275279) (xy 155.975812 -373.30253) (xy 155.975454 -373.326602) (xy 155.969415 -373.374364)
			(xy 155.957425 -373.42099) (xy 155.948888 -373.4435) (xy 155.943808 -373.455946) (xy 155.94711 -373.481854)
			(xy 156.013912 -373.572532) (xy 156.037534 -373.583454) (xy 156.050742 -373.582438) (xy 156.079444 -373.581422)
			(xy 156.106695 -373.581851) (xy 156.160643 -373.589613) (xy 156.212936 -373.604973) (xy 156.262512 -373.627619)
			(xy 156.30836 -373.657088) (xy 156.349548 -373.692783) (xy 156.385238 -373.733975) (xy 156.414702 -373.779827)
			(xy 156.437342 -373.829405) (xy 156.452696 -373.881701) (xy 156.460452 -373.935649) (xy 156.460452 -373.990151)
			(xy 156.460452 -373.990153) (xy 160.321185 -373.990153) (xy 160.321185 -373.935647) (xy 160.328943 -373.881697)
			(xy 160.3443 -373.829399) (xy 160.366944 -373.77982) (xy 160.396414 -373.733969) (xy 160.432109 -373.692778)
			(xy 160.473304 -373.657087) (xy 160.519159 -373.627623) (xy 160.568741 -373.604985) (xy 160.62104 -373.589634)
			(xy 160.674991 -373.581882) (xy 160.702244 -373.581422) (xy 160.730946 -373.582438) (xy 160.744154 -373.583454)
			(xy 160.767776 -373.572532) (xy 160.834578 -373.481854) (xy 160.83788 -373.455946) (xy 160.8328 -373.4435)
			(xy 160.824267 -373.420988) (xy 160.812262 -373.374366) (xy 160.806228 -373.326602) (xy 160.805876 -373.30253)
			(xy 160.806362 -373.275279) (xy 160.814118 -373.221331) (xy 160.829473 -373.169036) (xy 160.852115 -373.119459)
			(xy 160.881581 -373.073609) (xy 160.917272 -373.032418) (xy 160.958463 -372.996727) (xy 161.004313 -372.967261)
			(xy 161.05389 -372.944619) (xy 161.106185 -372.929264) (xy 161.160133 -372.921508) (xy 161.214635 -372.921508)
			(xy 161.268583 -372.929264) (xy 161.320878 -372.944619) (xy 161.370455 -372.967261) (xy 161.416305 -372.996727)
			(xy 161.457496 -373.032418) (xy 161.493187 -373.073609) (xy 161.522653 -373.119459) (xy 161.545295 -373.169036)
			(xy 161.56065 -373.221331) (xy 161.568406 -373.275279) (xy 161.568892 -373.30253) (xy 161.568203 -373.335062)
			(xy 161.557092 -373.399171) (xy 161.546794 -373.430038) (xy 161.543746 -373.438674) (xy 161.544 -373.456454)
			(xy 161.573464 -373.53494) (xy 161.584894 -373.548148) (xy 161.593022 -373.55272) (xy 161.62528 -373.572532)
			(xy 161.631671 -373.576591) (xy 161.646158 -373.580972) (xy 161.653728 -373.581168) (xy 161.93516 -373.581168)
			(xy 161.942714 -373.58089) (xy 161.957172 -373.576498) (xy 161.963608 -373.572532) (xy 161.995866 -373.55272)
			(xy 162.003994 -373.548148) (xy 162.015424 -373.53494) (xy 162.044888 -373.456454) (xy 162.045142 -373.438674)
			(xy 162.042094 -373.430038) (xy 162.031799 -373.399171) (xy 162.020695 -373.335061) (xy 162.019996 -373.30253)
			(xy 162.020482 -373.275279) (xy 162.028238 -373.221331) (xy 162.043593 -373.169036) (xy 162.066235 -373.119459)
			(xy 162.095701 -373.073609) (xy 162.131392 -373.032418) (xy 162.172583 -372.996727) (xy 162.218433 -372.967261)
			(xy 162.26801 -372.944619) (xy 162.320305 -372.929264) (xy 162.374253 -372.921508) (xy 162.428755 -372.921508)
			(xy 162.482703 -372.929264) (xy 162.534998 -372.944619) (xy 162.584575 -372.967261) (xy 162.630425 -372.996727)
			(xy 162.671616 -373.032418) (xy 162.707307 -373.073609) (xy 162.736773 -373.119459) (xy 162.759415 -373.169036)
			(xy 162.77477 -373.221331) (xy 162.782526 -373.275279) (xy 162.783012 -373.30253) (xy 162.782654 -373.326602)
			(xy 162.776615 -373.374364) (xy 162.764625 -373.42099) (xy 162.756088 -373.4435) (xy 162.751008 -373.455946)
			(xy 162.75431 -373.481854) (xy 162.821112 -373.572532) (xy 162.844734 -373.583454) (xy 162.857942 -373.582438)
			(xy 162.886644 -373.581422) (xy 162.913895 -373.581851) (xy 162.967843 -373.589613) (xy 163.020136 -373.604973)
			(xy 163.069712 -373.627619) (xy 163.11556 -373.657088) (xy 163.156748 -373.692783) (xy 163.192438 -373.733975)
			(xy 163.221902 -373.779827) (xy 163.244542 -373.829405) (xy 163.259896 -373.881701) (xy 163.267652 -373.935649)
			(xy 163.267652 -373.990151) (xy 163.259896 -374.044099) (xy 163.244542 -374.096395) (xy 163.221902 -374.145973)
			(xy 163.192438 -374.191825) (xy 163.156748 -374.233017) (xy 163.11556 -374.268712) (xy 163.069712 -374.298181)
			(xy 163.020136 -374.320827) (xy 162.967843 -374.336187) (xy 162.913895 -374.343949) (xy 162.886644 -374.344438)
			(xy 162.857942 -374.343422) (xy 162.844734 -374.342406) (xy 162.821112 -374.353328) (xy 162.75431 -374.444006)
			(xy 162.751008 -374.469914) (xy 162.756088 -374.48236) (xy 162.764638 -374.504866) (xy 162.776637 -374.551491)
			(xy 162.782664 -374.599257) (xy 162.783012 -374.62333) (xy 162.782526 -374.650581) (xy 162.77477 -374.704529)
			(xy 162.759415 -374.756824) (xy 162.736773 -374.806401) (xy 162.707307 -374.852251) (xy 162.671616 -374.893442)
			(xy 162.630425 -374.929133) (xy 162.584575 -374.958599) (xy 162.534998 -374.981241) (xy 162.482703 -374.996596)
			(xy 162.428755 -375.004352) (xy 162.374253 -375.004352) (xy 162.320305 -374.996596) (xy 162.26801 -374.981241)
			(xy 162.218433 -374.958599) (xy 162.172583 -374.929133) (xy 162.131392 -374.893442) (xy 162.095701 -374.852251)
			(xy 162.066235 -374.806401) (xy 162.043593 -374.756824) (xy 162.028238 -374.704529) (xy 162.020482 -374.650581)
			(xy 162.019996 -374.62333) (xy 162.020675 -374.590798) (xy 162.031793 -374.526688) (xy 162.042094 -374.495822)
			(xy 162.045142 -374.487186) (xy 162.044888 -374.469406) (xy 162.015424 -374.39092) (xy 162.003994 -374.377712)
			(xy 161.995866 -374.37314) (xy 161.963608 -374.353328) (xy 161.957195 -374.349308) (xy 161.942725 -374.344902)
			(xy 161.93516 -374.344692) (xy 161.653728 -374.344692) (xy 161.646172 -374.344956) (xy 161.631714 -374.349357)
			(xy 161.62528 -374.353328) (xy 161.593022 -374.37314) (xy 161.584894 -374.377712) (xy 161.573464 -374.39092)
			(xy 161.544 -374.469406) (xy 161.543746 -374.487186) (xy 161.546794 -374.495822) (xy 161.557078 -374.526692)
			(xy 161.568189 -374.590799) (xy 161.568892 -374.62333) (xy 161.568406 -374.650581) (xy 161.56065 -374.704529)
			(xy 161.545295 -374.756824) (xy 161.522653 -374.806401) (xy 161.493187 -374.852251) (xy 161.457496 -374.893442)
			(xy 161.416305 -374.929133) (xy 161.370455 -374.958599) (xy 161.320878 -374.981241) (xy 161.268583 -374.996596)
			(xy 161.214635 -375.004352) (xy 161.160133 -375.004352) (xy 161.106185 -374.996596) (xy 161.05389 -374.981241)
			(xy 161.004313 -374.958599) (xy 160.958463 -374.929133) (xy 160.917272 -374.893442) (xy 160.881581 -374.852251)
			(xy 160.852115 -374.806401) (xy 160.829473 -374.756824) (xy 160.814118 -374.704529) (xy 160.806362 -374.650581)
			(xy 160.805876 -374.62333) (xy 160.806223 -374.599258) (xy 160.812266 -374.551495) (xy 160.824261 -374.504869)
			(xy 160.8328 -374.48236) (xy 160.83788 -374.469914) (xy 160.834578 -374.444006) (xy 160.767776 -374.353328)
			(xy 160.744154 -374.342406) (xy 160.730946 -374.343422) (xy 160.702244 -374.344438) (xy 160.674991 -374.343918)
			(xy 160.62104 -374.336166) (xy 160.568741 -374.320815) (xy 160.519159 -374.298177) (xy 160.473304 -374.268713)
			(xy 160.432109 -374.233022) (xy 160.396414 -374.191831) (xy 160.366944 -374.14598) (xy 160.3443 -374.096401)
			(xy 160.328943 -374.044103) (xy 160.321185 -373.990153) (xy 156.460452 -373.990153) (xy 156.452696 -374.044099)
			(xy 156.437342 -374.096395) (xy 156.414702 -374.145973) (xy 156.385238 -374.191825) (xy 156.349548 -374.233017)
			(xy 156.30836 -374.268712) (xy 156.262512 -374.298181) (xy 156.212936 -374.320827) (xy 156.160643 -374.336187)
			(xy 156.106695 -374.343949) (xy 156.079444 -374.344438) (xy 156.050742 -374.343422) (xy 156.037534 -374.342406)
			(xy 156.013912 -374.353328) (xy 155.94711 -374.444006) (xy 155.943808 -374.469914) (xy 155.948888 -374.48236)
			(xy 155.957438 -374.504866) (xy 155.969437 -374.551491) (xy 155.975464 -374.599257) (xy 155.975812 -374.62333)
			(xy 155.975326 -374.650581) (xy 155.96757 -374.704529) (xy 155.952215 -374.756824) (xy 155.929573 -374.806401)
			(xy 155.900107 -374.852251) (xy 155.864416 -374.893442) (xy 155.823225 -374.929133) (xy 155.777375 -374.958599)
			(xy 155.727798 -374.981241) (xy 155.675503 -374.996596) (xy 155.621555 -375.004352) (xy 155.567053 -375.004352)
			(xy 155.513105 -374.996596) (xy 155.46081 -374.981241) (xy 155.411233 -374.958599) (xy 155.365383 -374.929133)
			(xy 155.324192 -374.893442) (xy 155.288501 -374.852251) (xy 155.259035 -374.806401) (xy 155.236393 -374.756824)
			(xy 155.221038 -374.704529) (xy 155.213282 -374.650581) (xy 155.212796 -374.62333) (xy 155.213475 -374.590798)
			(xy 155.224593 -374.526688) (xy 155.234894 -374.495822) (xy 155.237942 -374.487186) (xy 155.237688 -374.469406)
			(xy 155.208224 -374.39092) (xy 155.196794 -374.377712) (xy 155.188666 -374.37314) (xy 155.156408 -374.353328)
			(xy 155.149995 -374.349308) (xy 155.135525 -374.344902) (xy 155.12796 -374.344692) (xy 154.846528 -374.344692)
			(xy 154.838972 -374.344956) (xy 154.824514 -374.349357) (xy 154.81808 -374.353328) (xy 154.785822 -374.37314)
			(xy 154.777694 -374.377712) (xy 154.766264 -374.39092) (xy 154.7368 -374.469406) (xy 154.736546 -374.487186)
			(xy 154.739594 -374.495822) (xy 154.749878 -374.526692) (xy 154.760989 -374.590799) (xy 154.761692 -374.62333)
			(xy 154.761206 -374.650581) (xy 154.75345 -374.704529) (xy 154.738095 -374.756824) (xy 154.715453 -374.806401)
			(xy 154.685987 -374.852251) (xy 154.650296 -374.893442) (xy 154.609105 -374.929133) (xy 154.563255 -374.958599)
			(xy 154.513678 -374.981241) (xy 154.461383 -374.996596) (xy 154.407435 -375.004352) (xy 154.352933 -375.004352)
			(xy 154.298985 -374.996596) (xy 154.24669 -374.981241) (xy 154.197113 -374.958599) (xy 154.151263 -374.929133)
			(xy 154.110072 -374.893442) (xy 154.074381 -374.852251) (xy 154.044915 -374.806401) (xy 154.022273 -374.756824)
			(xy 154.006918 -374.704529) (xy 153.999162 -374.650581) (xy 153.998676 -374.62333) (xy 153.999023 -374.599258)
			(xy 154.005066 -374.551495) (xy 154.017061 -374.504869) (xy 154.0256 -374.48236) (xy 154.03068 -374.469914)
			(xy 154.027378 -374.444006) (xy 153.960576 -374.353328) (xy 153.936954 -374.342406) (xy 153.923746 -374.343422)
			(xy 153.895044 -374.344438) (xy 153.867791 -374.343918) (xy 153.81384 -374.336166) (xy 153.761541 -374.320815)
			(xy 153.711959 -374.298177) (xy 153.666104 -374.268713) (xy 153.624909 -374.233022) (xy 153.589214 -374.191831)
			(xy 153.559744 -374.14598) (xy 153.5371 -374.096401) (xy 153.521743 -374.044103) (xy 153.513985 -373.990153)
			(xy 149.653252 -373.990153) (xy 149.645496 -374.044099) (xy 149.630142 -374.096395) (xy 149.607502 -374.145973)
			(xy 149.578038 -374.191825) (xy 149.542348 -374.233017) (xy 149.50116 -374.268712) (xy 149.455312 -374.298181)
			(xy 149.405736 -374.320827) (xy 149.353443 -374.336187) (xy 149.299495 -374.343949) (xy 149.272244 -374.344438)
			(xy 149.243542 -374.343422) (xy 149.230334 -374.342406) (xy 149.206712 -374.353328) (xy 149.13991 -374.444006)
			(xy 149.136608 -374.469914) (xy 149.141688 -374.48236) (xy 149.150238 -374.504866) (xy 149.162237 -374.551491)
			(xy 149.168264 -374.599257) (xy 149.168612 -374.62333) (xy 149.168126 -374.650581) (xy 149.16037 -374.704529)
			(xy 149.145015 -374.756824) (xy 149.122373 -374.806401) (xy 149.092907 -374.852251) (xy 149.057216 -374.893442)
			(xy 149.016025 -374.929133) (xy 148.970175 -374.958599) (xy 148.920598 -374.981241) (xy 148.868303 -374.996596)
			(xy 148.814355 -375.004352) (xy 148.759853 -375.004352) (xy 148.705905 -374.996596) (xy 148.65361 -374.981241)
			(xy 148.604033 -374.958599) (xy 148.558183 -374.929133) (xy 148.516992 -374.893442) (xy 148.481301 -374.852251)
			(xy 148.451835 -374.806401) (xy 148.429193 -374.756824) (xy 148.413838 -374.704529) (xy 148.406082 -374.650581)
			(xy 148.405596 -374.62333) (xy 148.406275 -374.590798) (xy 148.417393 -374.526688) (xy 148.427694 -374.495822)
			(xy 148.430742 -374.487186) (xy 148.430488 -374.469406) (xy 148.401024 -374.39092) (xy 148.389594 -374.377712)
			(xy 148.381466 -374.37314) (xy 148.349208 -374.353328) (xy 148.342795 -374.349308) (xy 148.328325 -374.344902)
			(xy 148.32076 -374.344692) (xy 148.039328 -374.344692) (xy 148.031772 -374.344956) (xy 148.017314 -374.349357)
			(xy 148.01088 -374.353328) (xy 147.978622 -374.37314) (xy 147.970494 -374.377712) (xy 147.959064 -374.39092)
			(xy 147.9296 -374.469406) (xy 147.929346 -374.487186) (xy 147.932394 -374.495822) (xy 147.942678 -374.526692)
			(xy 147.953789 -374.590799) (xy 147.954492 -374.62333) (xy 147.954006 -374.650581) (xy 147.94625 -374.704529)
			(xy 147.930895 -374.756824) (xy 147.908253 -374.806401) (xy 147.878787 -374.852251) (xy 147.843096 -374.893442)
			(xy 147.801905 -374.929133) (xy 147.756055 -374.958599) (xy 147.706478 -374.981241) (xy 147.654183 -374.996596)
			(xy 147.600235 -375.004352) (xy 147.545733 -375.004352) (xy 147.491785 -374.996596) (xy 147.43949 -374.981241)
			(xy 147.389913 -374.958599) (xy 147.344063 -374.929133) (xy 147.302872 -374.893442) (xy 147.267181 -374.852251)
			(xy 147.237715 -374.806401) (xy 147.215073 -374.756824) (xy 147.199718 -374.704529) (xy 147.191962 -374.650581)
			(xy 147.191476 -374.62333) (xy 147.191823 -374.599258) (xy 147.197866 -374.551495) (xy 147.209861 -374.504869)
			(xy 147.2184 -374.48236) (xy 147.22348 -374.469914) (xy 147.220178 -374.444006) (xy 147.153376 -374.353328)
			(xy 147.129754 -374.342406) (xy 147.116546 -374.343422) (xy 147.087844 -374.344438) (xy 147.060591 -374.343918)
			(xy 147.00664 -374.336166) (xy 146.954341 -374.320815) (xy 146.904759 -374.298177) (xy 146.858904 -374.268713)
			(xy 146.817709 -374.233022) (xy 146.782014 -374.191831) (xy 146.752544 -374.14598) (xy 146.7299 -374.096401)
			(xy 146.714543 -374.044103) (xy 146.706785 -373.990153) (xy 130.739975 -373.990153) (xy 130.739975 -373.990155)
			(xy 130.732217 -374.044111) (xy 130.71686 -374.096413) (xy 130.694215 -374.145997) (xy 130.664745 -374.191854)
			(xy 130.629048 -374.233051) (xy 130.587851 -374.268747) (xy 130.541994 -374.298217) (xy 130.492409 -374.320861)
			(xy 130.440107 -374.336218) (xy 130.386151 -374.343975) (xy 130.358896 -374.344438) (xy 130.330194 -374.343422)
			(xy 130.316986 -374.342406) (xy 130.293364 -374.353328) (xy 130.226562 -374.444006) (xy 130.22326 -374.469914)
			(xy 130.22834 -374.48236) (xy 130.236892 -374.504865) (xy 130.24889 -374.551491) (xy 130.254916 -374.599257)
			(xy 130.255264 -374.62333) (xy 130.254778 -374.650581) (xy 130.247022 -374.704529) (xy 130.231667 -374.756824)
			(xy 130.209025 -374.806401) (xy 130.179559 -374.852251) (xy 130.143868 -374.893442) (xy 130.102677 -374.929133)
			(xy 130.056827 -374.958599) (xy 130.00725 -374.981241) (xy 129.954955 -374.996596) (xy 129.901007 -375.004352)
			(xy 129.846505 -375.004352) (xy 129.792557 -374.996596) (xy 129.740262 -374.981241) (xy 129.690685 -374.958599)
			(xy 129.644835 -374.929133) (xy 129.603644 -374.893442) (xy 129.567953 -374.852251) (xy 129.538487 -374.806401)
			(xy 129.515845 -374.756824) (xy 129.50049 -374.704529) (xy 129.492734 -374.650581) (xy 129.492248 -374.62333)
			(xy 129.49293 -374.590798) (xy 129.504046 -374.526689) (xy 129.514346 -374.495822) (xy 129.517394 -374.487186)
			(xy 129.51714 -374.469406) (xy 129.487676 -374.39092) (xy 129.476246 -374.377712) (xy 129.468118 -374.37314)
			(xy 129.43586 -374.353328) (xy 129.429458 -374.349289) (xy 129.414979 -374.344895) (xy 129.407412 -374.344692)
			(xy 129.12598 -374.344692) (xy 129.118426 -374.344977) (xy 129.103968 -374.349363) (xy 129.097532 -374.353328)
			(xy 129.065274 -374.37314) (xy 129.057146 -374.377712) (xy 129.045716 -374.39092) (xy 129.016252 -374.469406)
			(xy 129.015998 -374.487186) (xy 129.019046 -374.495822) (xy 129.029332 -374.526692) (xy 129.040441 -374.590799)
			(xy 129.041144 -374.62333) (xy 129.040658 -374.650581) (xy 129.032902 -374.704529) (xy 129.017547 -374.756824)
			(xy 128.994905 -374.806401) (xy 128.965439 -374.852251) (xy 128.929748 -374.893442) (xy 128.888557 -374.929133)
			(xy 128.842707 -374.958599) (xy 128.79313 -374.981241) (xy 128.740835 -374.996596) (xy 128.686887 -375.004352)
			(xy 128.632385 -375.004352) (xy 128.578437 -374.996596) (xy 128.526142 -374.981241) (xy 128.476565 -374.958599)
			(xy 128.430715 -374.929133) (xy 128.389524 -374.893442) (xy 128.353833 -374.852251) (xy 128.324367 -374.806401)
			(xy 128.301725 -374.756824) (xy 128.28637 -374.704529) (xy 128.278614 -374.650581) (xy 128.278128 -374.62333)
			(xy 128.278478 -374.599258) (xy 128.28452 -374.551495) (xy 128.296514 -374.50487) (xy 128.305052 -374.48236)
			(xy 128.310132 -374.469914) (xy 128.30683 -374.444006) (xy 128.240028 -374.353328) (xy 128.216406 -374.342406)
			(xy 128.203198 -374.343422) (xy 128.174496 -374.344438) (xy 128.147247 -374.343892) (xy 128.093304 -374.336135)
			(xy 128.041014 -374.320781) (xy 127.991441 -374.298141) (xy 127.945595 -374.268677) (xy 127.904409 -374.232989)
			(xy 127.86872 -374.191802) (xy 127.839257 -374.145955) (xy 127.816618 -374.096382) (xy 127.801264 -374.044092)
			(xy 127.793508 -373.990149) (xy 123.932775 -373.990149) (xy 123.932775 -373.990155) (xy 123.925017 -374.044111)
			(xy 123.90966 -374.096413) (xy 123.887015 -374.145997) (xy 123.857545 -374.191854) (xy 123.821848 -374.233051)
			(xy 123.780651 -374.268747) (xy 123.734794 -374.298217) (xy 123.685209 -374.320861) (xy 123.632907 -374.336218)
			(xy 123.578951 -374.343975) (xy 123.551696 -374.344438) (xy 123.522994 -374.343422) (xy 123.509786 -374.342406)
			(xy 123.486164 -374.353328) (xy 123.419362 -374.444006) (xy 123.41606 -374.469914) (xy 123.42114 -374.48236)
			(xy 123.429692 -374.504865) (xy 123.44169 -374.551491) (xy 123.447716 -374.599257) (xy 123.448064 -374.62333)
			(xy 123.447578 -374.650581) (xy 123.439822 -374.704529) (xy 123.424467 -374.756824) (xy 123.401825 -374.806401)
			(xy 123.372359 -374.852251) (xy 123.336668 -374.893442) (xy 123.295477 -374.929133) (xy 123.249627 -374.958599)
			(xy 123.20005 -374.981241) (xy 123.147755 -374.996596) (xy 123.093807 -375.004352) (xy 123.039305 -375.004352)
			(xy 122.985357 -374.996596) (xy 122.933062 -374.981241) (xy 122.883485 -374.958599) (xy 122.837635 -374.929133)
			(xy 122.796444 -374.893442) (xy 122.760753 -374.852251) (xy 122.731287 -374.806401) (xy 122.708645 -374.756824)
			(xy 122.69329 -374.704529) (xy 122.685534 -374.650581) (xy 122.685048 -374.62333) (xy 122.68573 -374.590798)
			(xy 122.696846 -374.526689) (xy 122.707146 -374.495822) (xy 122.710194 -374.487186) (xy 122.70994 -374.469406)
			(xy 122.680476 -374.39092) (xy 122.669046 -374.377712) (xy 122.660918 -374.37314) (xy 122.62866 -374.353328)
			(xy 122.622258 -374.349289) (xy 122.607779 -374.344895) (xy 122.600212 -374.344692) (xy 122.31878 -374.344692)
			(xy 122.311226 -374.344977) (xy 122.296768 -374.349363) (xy 122.290332 -374.353328) (xy 122.258074 -374.37314)
			(xy 122.249946 -374.377712) (xy 122.238516 -374.39092) (xy 122.209052 -374.469406) (xy 122.208798 -374.487186)
			(xy 122.211846 -374.495822) (xy 122.222132 -374.526692) (xy 122.233241 -374.590799) (xy 122.233944 -374.62333)
			(xy 122.233458 -374.650581) (xy 122.225702 -374.704529) (xy 122.210347 -374.756824) (xy 122.187705 -374.806401)
			(xy 122.158239 -374.852251) (xy 122.122548 -374.893442) (xy 122.081357 -374.929133) (xy 122.035507 -374.958599)
			(xy 121.98593 -374.981241) (xy 121.933635 -374.996596) (xy 121.879687 -375.004352) (xy 121.825185 -375.004352)
			(xy 121.771237 -374.996596) (xy 121.718942 -374.981241) (xy 121.669365 -374.958599) (xy 121.623515 -374.929133)
			(xy 121.582324 -374.893442) (xy 121.546633 -374.852251) (xy 121.517167 -374.806401) (xy 121.494525 -374.756824)
			(xy 121.47917 -374.704529) (xy 121.471414 -374.650581) (xy 121.470928 -374.62333) (xy 121.471278 -374.599258)
			(xy 121.47732 -374.551495) (xy 121.489314 -374.50487) (xy 121.497852 -374.48236) (xy 121.502932 -374.469914)
			(xy 121.49963 -374.444006) (xy 121.432828 -374.353328) (xy 121.409206 -374.342406) (xy 121.395998 -374.343422)
			(xy 121.367296 -374.344438) (xy 121.340047 -374.343892) (xy 121.286104 -374.336135) (xy 121.233814 -374.320781)
			(xy 121.184241 -374.298141) (xy 121.138395 -374.268677) (xy 121.097209 -374.232989) (xy 121.06152 -374.191802)
			(xy 121.032057 -374.145955) (xy 121.009418 -374.096382) (xy 120.994064 -374.044092) (xy 120.986308 -373.990149)
			(xy 117.125575 -373.990149) (xy 117.125575 -373.990155) (xy 117.117817 -374.044111) (xy 117.10246 -374.096413)
			(xy 117.079815 -374.145997) (xy 117.050345 -374.191854) (xy 117.014648 -374.233051) (xy 116.973451 -374.268747)
			(xy 116.927594 -374.298217) (xy 116.878009 -374.320861) (xy 116.825707 -374.336218) (xy 116.771751 -374.343975)
			(xy 116.744496 -374.344438) (xy 116.715794 -374.343422) (xy 116.702586 -374.342406) (xy 116.678964 -374.353328)
			(xy 116.612162 -374.444006) (xy 116.60886 -374.469914) (xy 116.61394 -374.48236) (xy 116.622492 -374.504865)
			(xy 116.63449 -374.551491) (xy 116.640516 -374.599257) (xy 116.640864 -374.62333) (xy 116.640378 -374.650581)
			(xy 116.632622 -374.704529) (xy 116.617267 -374.756824) (xy 116.594625 -374.806401) (xy 116.565159 -374.852251)
			(xy 116.529468 -374.893442) (xy 116.488277 -374.929133) (xy 116.442427 -374.958599) (xy 116.39285 -374.981241)
			(xy 116.340555 -374.996596) (xy 116.286607 -375.004352) (xy 116.232105 -375.004352) (xy 116.178157 -374.996596)
			(xy 116.125862 -374.981241) (xy 116.076285 -374.958599) (xy 116.030435 -374.929133) (xy 115.989244 -374.893442)
			(xy 115.953553 -374.852251) (xy 115.924087 -374.806401) (xy 115.901445 -374.756824) (xy 115.88609 -374.704529)
			(xy 115.878334 -374.650581) (xy 115.877848 -374.62333) (xy 115.87853 -374.590798) (xy 115.889646 -374.526689)
			(xy 115.899946 -374.495822) (xy 115.902994 -374.487186) (xy 115.90274 -374.469406) (xy 115.873276 -374.39092)
			(xy 115.861846 -374.377712) (xy 115.853718 -374.37314) (xy 115.82146 -374.353328) (xy 115.815058 -374.349289)
			(xy 115.800579 -374.344895) (xy 115.793012 -374.344692) (xy 115.51158 -374.344692) (xy 115.504026 -374.344977)
			(xy 115.489568 -374.349363) (xy 115.483132 -374.353328) (xy 115.450874 -374.37314) (xy 115.442746 -374.377712)
			(xy 115.431316 -374.39092) (xy 115.401852 -374.469406) (xy 115.401598 -374.487186) (xy 115.404646 -374.495822)
			(xy 115.414932 -374.526692) (xy 115.426041 -374.590799) (xy 115.426744 -374.62333) (xy 115.426258 -374.650581)
			(xy 115.418502 -374.704529) (xy 115.403147 -374.756824) (xy 115.380505 -374.806401) (xy 115.351039 -374.852251)
			(xy 115.315348 -374.893442) (xy 115.274157 -374.929133) (xy 115.228307 -374.958599) (xy 115.17873 -374.981241)
			(xy 115.126435 -374.996596) (xy 115.072487 -375.004352) (xy 115.017985 -375.004352) (xy 114.964037 -374.996596)
			(xy 114.911742 -374.981241) (xy 114.862165 -374.958599) (xy 114.816315 -374.929133) (xy 114.775124 -374.893442)
			(xy 114.739433 -374.852251) (xy 114.709967 -374.806401) (xy 114.687325 -374.756824) (xy 114.67197 -374.704529)
			(xy 114.664214 -374.650581) (xy 114.663728 -374.62333) (xy 114.664078 -374.599258) (xy 114.67012 -374.551495)
			(xy 114.682114 -374.50487) (xy 114.690652 -374.48236) (xy 114.695732 -374.469914) (xy 114.69243 -374.444006)
			(xy 114.625628 -374.353328) (xy 114.602006 -374.342406) (xy 114.588798 -374.343422) (xy 114.560096 -374.344438)
			(xy 114.532847 -374.343892) (xy 114.478904 -374.336135) (xy 114.426614 -374.320781) (xy 114.377041 -374.298141)
			(xy 114.331195 -374.268677) (xy 114.290009 -374.232989) (xy 114.25432 -374.191802) (xy 114.224857 -374.145955)
			(xy 114.202218 -374.096382) (xy 114.186864 -374.044092) (xy 114.179108 -373.990149) (xy 96.167752 -373.990149)
			(xy 96.167752 -373.990153) (xy 96.159995 -374.044105) (xy 96.144639 -374.096404) (xy 96.121996 -374.145985)
			(xy 96.092528 -374.191839) (xy 96.056834 -374.233032) (xy 96.01564 -374.268726) (xy 95.969787 -374.298195)
			(xy 95.920206 -374.320838) (xy 95.867907 -374.336195) (xy 95.813955 -374.343952) (xy 95.786702 -374.344438)
			(xy 95.758 -374.343422) (xy 95.744792 -374.342406) (xy 95.72117 -374.353328) (xy 95.654368 -374.444006)
			(xy 95.651066 -374.469914) (xy 95.656146 -374.48236) (xy 95.664698 -374.504865) (xy 95.676696 -374.551491)
			(xy 95.682722 -374.599257) (xy 95.68307 -374.62333) (xy 95.682584 -374.650581) (xy 95.674828 -374.704529)
			(xy 95.659473 -374.756824) (xy 95.636831 -374.806401) (xy 95.607365 -374.852251) (xy 95.571674 -374.893442)
			(xy 95.530483 -374.929133) (xy 95.484633 -374.958599) (xy 95.435056 -374.981241) (xy 95.382761 -374.996596)
			(xy 95.328813 -375.004352) (xy 95.274311 -375.004352) (xy 95.220363 -374.996596) (xy 95.168068 -374.981241)
			(xy 95.118491 -374.958599) (xy 95.072641 -374.929133) (xy 95.03145 -374.893442) (xy 94.995759 -374.852251)
			(xy 94.966293 -374.806401) (xy 94.943651 -374.756824) (xy 94.928296 -374.704529) (xy 94.92054 -374.650581)
			(xy 94.920054 -374.62333) (xy 94.920736 -374.590798) (xy 94.931852 -374.526689) (xy 94.942152 -374.495822)
			(xy 94.9452 -374.487186) (xy 94.944946 -374.469406) (xy 94.915482 -374.39092) (xy 94.904052 -374.377712)
			(xy 94.895924 -374.37314) (xy 94.863666 -374.353328) (xy 94.857262 -374.349292) (xy 94.842785 -374.344896)
			(xy 94.835218 -374.344692) (xy 94.553786 -374.344692) (xy 94.546232 -374.34498) (xy 94.531774 -374.349364)
			(xy 94.525338 -374.353328) (xy 94.49308 -374.37314) (xy 94.484952 -374.377712) (xy 94.473522 -374.39092)
			(xy 94.444058 -374.469406) (xy 94.443804 -374.487186) (xy 94.446852 -374.495822) (xy 94.457138 -374.526691)
			(xy 94.468247 -374.590799) (xy 94.46895 -374.62333) (xy 94.468464 -374.650581) (xy 94.460708 -374.704529)
			(xy 94.445353 -374.756824) (xy 94.422711 -374.806401) (xy 94.393245 -374.852251) (xy 94.357554 -374.893442)
			(xy 94.316363 -374.929133) (xy 94.270513 -374.958599) (xy 94.220936 -374.981241) (xy 94.168641 -374.996596)
			(xy 94.114693 -375.004352) (xy 94.060191 -375.004352) (xy 94.006243 -374.996596) (xy 93.953948 -374.981241)
			(xy 93.904371 -374.958599) (xy 93.858521 -374.929133) (xy 93.81733 -374.893442) (xy 93.781639 -374.852251)
			(xy 93.752173 -374.806401) (xy 93.729531 -374.756824) (xy 93.714176 -374.704529) (xy 93.70642 -374.650581)
			(xy 93.705934 -374.62333) (xy 93.706283 -374.599258) (xy 93.712326 -374.551495) (xy 93.72432 -374.50487)
			(xy 93.732858 -374.48236) (xy 93.737938 -374.469914) (xy 93.734636 -374.444006) (xy 93.667834 -374.353328)
			(xy 93.644212 -374.342406) (xy 93.631004 -374.343422) (xy 93.602302 -374.344438) (xy 93.575051 -374.343915)
			(xy 93.521104 -374.336159) (xy 93.46881 -374.320804) (xy 93.419234 -374.298163) (xy 93.373384 -374.268698)
			(xy 93.332194 -374.233007) (xy 93.296503 -374.191818) (xy 93.267037 -374.145968) (xy 93.244397 -374.096392)
			(xy 93.229042 -374.044098) (xy 93.221285 -373.990151) (xy 89.360552 -373.990151) (xy 89.360552 -373.990153)
			(xy 89.352795 -374.044105) (xy 89.337439 -374.096404) (xy 89.314796 -374.145985) (xy 89.285328 -374.191839)
			(xy 89.249634 -374.233032) (xy 89.20844 -374.268726) (xy 89.162587 -374.298195) (xy 89.113006 -374.320838)
			(xy 89.060707 -374.336195) (xy 89.006755 -374.343952) (xy 88.979502 -374.344438) (xy 88.9508 -374.343422)
			(xy 88.937592 -374.342406) (xy 88.91397 -374.353328) (xy 88.847168 -374.444006) (xy 88.843866 -374.469914)
			(xy 88.848946 -374.48236) (xy 88.857498 -374.504865) (xy 88.869496 -374.551491) (xy 88.875522 -374.599257)
			(xy 88.87587 -374.62333) (xy 88.875384 -374.650581) (xy 88.867628 -374.704529) (xy 88.852273 -374.756824)
			(xy 88.829631 -374.806401) (xy 88.800165 -374.852251) (xy 88.764474 -374.893442) (xy 88.723283 -374.929133)
			(xy 88.677433 -374.958599) (xy 88.627856 -374.981241) (xy 88.575561 -374.996596) (xy 88.521613 -375.004352)
			(xy 88.467111 -375.004352) (xy 88.413163 -374.996596) (xy 88.360868 -374.981241) (xy 88.311291 -374.958599)
			(xy 88.265441 -374.929133) (xy 88.22425 -374.893442) (xy 88.188559 -374.852251) (xy 88.159093 -374.806401)
			(xy 88.136451 -374.756824) (xy 88.121096 -374.704529) (xy 88.11334 -374.650581) (xy 88.112854 -374.62333)
			(xy 88.113536 -374.590798) (xy 88.124652 -374.526689) (xy 88.134952 -374.495822) (xy 88.138 -374.487186)
			(xy 88.137746 -374.469406) (xy 88.108282 -374.39092) (xy 88.096852 -374.377712) (xy 88.088724 -374.37314)
			(xy 88.056466 -374.353328) (xy 88.050062 -374.349292) (xy 88.035585 -374.344896) (xy 88.028018 -374.344692)
			(xy 87.746586 -374.344692) (xy 87.739032 -374.34498) (xy 87.724574 -374.349364) (xy 87.718138 -374.353328)
			(xy 87.68588 -374.37314) (xy 87.677752 -374.377712) (xy 87.666322 -374.39092) (xy 87.636858 -374.469406)
			(xy 87.636604 -374.487186) (xy 87.639652 -374.495822) (xy 87.649938 -374.526691) (xy 87.661047 -374.590799)
			(xy 87.66175 -374.62333) (xy 87.661264 -374.650581) (xy 87.653508 -374.704529) (xy 87.638153 -374.756824)
			(xy 87.615511 -374.806401) (xy 87.586045 -374.852251) (xy 87.550354 -374.893442) (xy 87.509163 -374.929133)
			(xy 87.463313 -374.958599) (xy 87.413736 -374.981241) (xy 87.361441 -374.996596) (xy 87.307493 -375.004352)
			(xy 87.252991 -375.004352) (xy 87.199043 -374.996596) (xy 87.146748 -374.981241) (xy 87.097171 -374.958599)
			(xy 87.051321 -374.929133) (xy 87.01013 -374.893442) (xy 86.974439 -374.852251) (xy 86.944973 -374.806401)
			(xy 86.922331 -374.756824) (xy 86.906976 -374.704529) (xy 86.89922 -374.650581) (xy 86.898734 -374.62333)
			(xy 86.899083 -374.599258) (xy 86.905126 -374.551495) (xy 86.91712 -374.50487) (xy 86.925658 -374.48236)
			(xy 86.930738 -374.469914) (xy 86.927436 -374.444006) (xy 86.860634 -374.353328) (xy 86.837012 -374.342406)
			(xy 86.823804 -374.343422) (xy 86.795102 -374.344438) (xy 86.767851 -374.343915) (xy 86.713904 -374.336159)
			(xy 86.66161 -374.320804) (xy 86.612034 -374.298163) (xy 86.566184 -374.268698) (xy 86.524994 -374.233007)
			(xy 86.489303 -374.191818) (xy 86.459837 -374.145968) (xy 86.437197 -374.096392) (xy 86.421842 -374.044098)
			(xy 86.414085 -373.990151) (xy 83.772513 -373.990151) (xy 83.772501 -373.990816) (xy 83.764381 -374.045992)
			(xy 83.748313 -374.099399) (xy 83.724641 -374.149896) (xy 83.693868 -374.196409) (xy 83.656651 -374.237946)
			(xy 83.613783 -374.273621) (xy 83.566177 -374.302675) (xy 83.514848 -374.324487) (xy 83.460891 -374.338593)
			(xy 83.405454 -374.344693) (xy 83.34972 -374.342656) (xy 83.294877 -374.332526) (xy 83.242093 -374.314519)
			(xy 83.192493 -374.289018) (xy 83.147135 -374.256567) (xy 83.106986 -374.217858) (xy 83.0729 -374.173715)
			(xy 83.045604 -374.12508) (xy 83.025681 -374.072989) (xy 83.013555 -374.018552) (xy 83.009484 -373.96293)
			(xy 82.553352 -373.96293) (xy 82.553352 -373.990153) (xy 82.545595 -374.044105) (xy 82.530239 -374.096404)
			(xy 82.507596 -374.145985) (xy 82.478128 -374.191839) (xy 82.442434 -374.233032) (xy 82.40124 -374.268726)
			(xy 82.355387 -374.298195) (xy 82.305806 -374.320838) (xy 82.253507 -374.336195) (xy 82.199555 -374.343952)
			(xy 82.172302 -374.344438) (xy 82.1436 -374.343422) (xy 82.130392 -374.342406) (xy 82.10677 -374.353328)
			(xy 82.039968 -374.444006) (xy 82.036666 -374.469914) (xy 82.041746 -374.48236) (xy 82.050298 -374.504865)
			(xy 82.062296 -374.551491) (xy 82.068322 -374.599257) (xy 82.06867 -374.62333) (xy 82.068184 -374.650581)
			(xy 82.060428 -374.704529) (xy 82.045073 -374.756824) (xy 82.022431 -374.806401) (xy 81.992965 -374.852251)
			(xy 81.957274 -374.893442) (xy 81.916083 -374.929133) (xy 81.870233 -374.958599) (xy 81.820656 -374.981241)
			(xy 81.768361 -374.996596) (xy 81.714413 -375.004352) (xy 81.659911 -375.004352) (xy 81.605963 -374.996596)
			(xy 81.553668 -374.981241) (xy 81.504091 -374.958599) (xy 81.458241 -374.929133) (xy 81.41705 -374.893442)
			(xy 81.381359 -374.852251) (xy 81.351893 -374.806401) (xy 81.329251 -374.756824) (xy 81.313896 -374.704529)
			(xy 81.30614 -374.650581) (xy 81.305654 -374.62333) (xy 81.306336 -374.590798) (xy 81.317452 -374.526689)
			(xy 81.327752 -374.495822) (xy 81.3308 -374.487186) (xy 81.330546 -374.469406) (xy 81.301082 -374.39092)
			(xy 81.289652 -374.377712) (xy 81.281524 -374.37314) (xy 81.249266 -374.353328) (xy 81.242862 -374.349292)
			(xy 81.228385 -374.344896) (xy 81.220818 -374.344692) (xy 80.939386 -374.344692) (xy 80.931832 -374.34498)
			(xy 80.917374 -374.349364) (xy 80.910938 -374.353328) (xy 80.87868 -374.37314) (xy 80.870552 -374.377712)
			(xy 80.859122 -374.39092) (xy 80.829658 -374.469406) (xy 80.829404 -374.487186) (xy 80.832452 -374.495822)
			(xy 80.842738 -374.526691) (xy 80.853847 -374.590799) (xy 80.85455 -374.62333) (xy 80.854064 -374.650581)
			(xy 80.846308 -374.704529) (xy 80.830953 -374.756824) (xy 80.808311 -374.806401) (xy 80.778845 -374.852251)
			(xy 80.743154 -374.893442) (xy 80.701963 -374.929133) (xy 80.656113 -374.958599) (xy 80.606536 -374.981241)
			(xy 80.554241 -374.996596) (xy 80.500293 -375.004352) (xy 80.445791 -375.004352) (xy 80.391843 -374.996596)
			(xy 80.339548 -374.981241) (xy 80.289971 -374.958599) (xy 80.244121 -374.929133) (xy 80.20293 -374.893442)
			(xy 80.167239 -374.852251) (xy 80.137773 -374.806401) (xy 80.115131 -374.756824) (xy 80.099776 -374.704529)
			(xy 80.09202 -374.650581) (xy 80.091534 -374.62333) (xy 80.091883 -374.599258) (xy 80.097926 -374.551495)
			(xy 80.10992 -374.50487) (xy 80.118458 -374.48236) (xy 80.123538 -374.469914) (xy 80.120236 -374.444006)
			(xy 80.053434 -374.353328) (xy 80.029812 -374.342406) (xy 80.016604 -374.343422) (xy 79.987902 -374.344438)
			(xy 79.960651 -374.343915) (xy 79.906704 -374.336159) (xy 79.85441 -374.320804) (xy 79.804834 -374.298163)
			(xy 79.758984 -374.268698) (xy 79.717794 -374.233007) (xy 79.682103 -374.191818) (xy 79.652637 -374.145968)
			(xy 79.629997 -374.096392) (xy 79.614642 -374.044098) (xy 79.606885 -373.990151) (xy 63.640075 -373.990151)
			(xy 63.640075 -373.990157) (xy 63.632316 -374.044116) (xy 63.616957 -374.096422) (xy 63.594309 -374.146009)
			(xy 63.564834 -374.191868) (xy 63.529133 -374.233065) (xy 63.487931 -374.268762) (xy 63.442069 -374.298231)
			(xy 63.392479 -374.320873) (xy 63.340171 -374.336226) (xy 63.286211 -374.343978) (xy 63.258954 -374.344438)
			(xy 63.230252 -374.343422) (xy 63.217044 -374.342406) (xy 63.193422 -374.353328) (xy 63.12662 -374.444006)
			(xy 63.123318 -374.469914) (xy 63.128398 -374.48236) (xy 63.136948 -374.504866) (xy 63.148947 -374.551491)
			(xy 63.154974 -374.599257) (xy 63.155322 -374.62333) (xy 63.154836 -374.650581) (xy 63.14708 -374.704529)
			(xy 63.131725 -374.756824) (xy 63.109083 -374.806401) (xy 63.079617 -374.852251) (xy 63.043926 -374.893442)
			(xy 63.002735 -374.929133) (xy 62.956885 -374.958599) (xy 62.907308 -374.981241) (xy 62.855013 -374.996596)
			(xy 62.801065 -375.004352) (xy 62.746563 -375.004352) (xy 62.692615 -374.996596) (xy 62.64032 -374.981241)
			(xy 62.590743 -374.958599) (xy 62.544893 -374.929133) (xy 62.503702 -374.893442) (xy 62.468011 -374.852251)
			(xy 62.438545 -374.806401) (xy 62.415903 -374.756824) (xy 62.400548 -374.704529) (xy 62.392792 -374.650581)
			(xy 62.392306 -374.62333) (xy 62.392985 -374.590798) (xy 62.404103 -374.526688) (xy 62.414404 -374.495822)
			(xy 62.417452 -374.487186) (xy 62.417198 -374.469406) (xy 62.387734 -374.39092) (xy 62.376304 -374.377712)
			(xy 62.368176 -374.37314) (xy 62.335918 -374.353328) (xy 62.329503 -374.349312) (xy 62.315034 -374.344904)
			(xy 62.30747 -374.344692) (xy 62.026038 -374.344692) (xy 62.018483 -374.34496) (xy 62.004024 -374.349358)
			(xy 61.99759 -374.353328) (xy 61.965332 -374.37314) (xy 61.957204 -374.377712) (xy 61.945774 -374.39092)
			(xy 61.91631 -374.469406) (xy 61.916056 -374.487186) (xy 61.919104 -374.495822) (xy 61.929389 -374.526692)
			(xy 61.940499 -374.590799) (xy 61.941202 -374.62333) (xy 61.940716 -374.650581) (xy 61.93296 -374.704529)
			(xy 61.917605 -374.756824) (xy 61.894963 -374.806401) (xy 61.865497 -374.852251) (xy 61.829806 -374.893442)
			(xy 61.788615 -374.929133) (xy 61.742765 -374.958599) (xy 61.693188 -374.981241) (xy 61.640893 -374.996596)
			(xy 61.586945 -375.004352) (xy 61.532443 -375.004352) (xy 61.478495 -374.996596) (xy 61.4262 -374.981241)
			(xy 61.376623 -374.958599) (xy 61.330773 -374.929133) (xy 61.289582 -374.893442) (xy 61.253891 -374.852251)
			(xy 61.224425 -374.806401) (xy 61.201783 -374.756824) (xy 61.186428 -374.704529) (xy 61.178672 -374.650581)
			(xy 61.178186 -374.62333) (xy 61.178532 -374.599258) (xy 61.184575 -374.551495) (xy 61.196571 -374.504869)
			(xy 61.20511 -374.48236) (xy 61.21019 -374.469914) (xy 61.206888 -374.444006) (xy 61.140086 -374.353328)
			(xy 61.116464 -374.342406) (xy 61.103256 -374.343422) (xy 61.074554 -374.344438) (xy 61.047307 -374.343889)
			(xy 60.993369 -374.336127) (xy 60.941084 -374.32077) (xy 60.891516 -374.298128) (xy 60.845675 -374.268662)
			(xy 60.804494 -374.232974) (xy 60.76881 -374.191788) (xy 60.73935 -374.145943) (xy 60.716714 -374.096373)
			(xy 60.701363 -374.044086) (xy 60.693608 -373.990147) (xy 56.832875 -373.990147) (xy 56.832875 -373.990157)
			(xy 56.825116 -374.044116) (xy 56.809757 -374.096422) (xy 56.787109 -374.146009) (xy 56.757634 -374.191868)
			(xy 56.721933 -374.233065) (xy 56.680731 -374.268762) (xy 56.634869 -374.298231) (xy 56.585279 -374.320873)
			(xy 56.532971 -374.336226) (xy 56.479011 -374.343978) (xy 56.451754 -374.344438) (xy 56.423052 -374.343422)
			(xy 56.409844 -374.342406) (xy 56.386222 -374.353328) (xy 56.31942 -374.444006) (xy 56.316118 -374.469914)
			(xy 56.321198 -374.48236) (xy 56.329748 -374.504866) (xy 56.341747 -374.551491) (xy 56.347774 -374.599257)
			(xy 56.348122 -374.62333) (xy 56.347636 -374.650581) (xy 56.33988 -374.704529) (xy 56.324525 -374.756824)
			(xy 56.301883 -374.806401) (xy 56.272417 -374.852251) (xy 56.236726 -374.893442) (xy 56.195535 -374.929133)
			(xy 56.149685 -374.958599) (xy 56.100108 -374.981241) (xy 56.047813 -374.996596) (xy 55.993865 -375.004352)
			(xy 55.939363 -375.004352) (xy 55.885415 -374.996596) (xy 55.83312 -374.981241) (xy 55.783543 -374.958599)
			(xy 55.737693 -374.929133) (xy 55.696502 -374.893442) (xy 55.660811 -374.852251) (xy 55.631345 -374.806401)
			(xy 55.608703 -374.756824) (xy 55.593348 -374.704529) (xy 55.585592 -374.650581) (xy 55.585106 -374.62333)
			(xy 55.585785 -374.590798) (xy 55.596903 -374.526688) (xy 55.607204 -374.495822) (xy 55.610252 -374.487186)
			(xy 55.609998 -374.469406) (xy 55.580534 -374.39092) (xy 55.569104 -374.377712) (xy 55.560976 -374.37314)
			(xy 55.528718 -374.353328) (xy 55.522303 -374.349312) (xy 55.507834 -374.344904) (xy 55.50027 -374.344692)
			(xy 55.218838 -374.344692) (xy 55.211283 -374.34496) (xy 55.196824 -374.349358) (xy 55.19039 -374.353328)
			(xy 55.158132 -374.37314) (xy 55.150004 -374.377712) (xy 55.138574 -374.39092) (xy 55.10911 -374.469406)
			(xy 55.108856 -374.487186) (xy 55.111904 -374.495822) (xy 55.122189 -374.526692) (xy 55.133299 -374.590799)
			(xy 55.134002 -374.62333) (xy 55.133516 -374.650581) (xy 55.12576 -374.704529) (xy 55.110405 -374.756824)
			(xy 55.087763 -374.806401) (xy 55.058297 -374.852251) (xy 55.022606 -374.893442) (xy 54.981415 -374.929133)
			(xy 54.935565 -374.958599) (xy 54.885988 -374.981241) (xy 54.833693 -374.996596) (xy 54.779745 -375.004352)
			(xy 54.725243 -375.004352) (xy 54.671295 -374.996596) (xy 54.619 -374.981241) (xy 54.569423 -374.958599)
			(xy 54.523573 -374.929133) (xy 54.482382 -374.893442) (xy 54.446691 -374.852251) (xy 54.417225 -374.806401)
			(xy 54.394583 -374.756824) (xy 54.379228 -374.704529) (xy 54.371472 -374.650581) (xy 54.370986 -374.62333)
			(xy 54.371332 -374.599258) (xy 54.377375 -374.551495) (xy 54.389371 -374.504869) (xy 54.39791 -374.48236)
			(xy 54.40299 -374.469914) (xy 54.399688 -374.444006) (xy 54.332886 -374.353328) (xy 54.309264 -374.342406)
			(xy 54.296056 -374.343422) (xy 54.267354 -374.344438) (xy 54.240107 -374.343889) (xy 54.186169 -374.336127)
			(xy 54.133884 -374.32077) (xy 54.084316 -374.298128) (xy 54.038475 -374.268662) (xy 53.997294 -374.232974)
			(xy 53.96161 -374.191788) (xy 53.93215 -374.145943) (xy 53.909514 -374.096373) (xy 53.894163 -374.044086)
			(xy 53.886408 -373.990147) (xy 50.025675 -373.990147) (xy 50.025675 -373.990157) (xy 50.017916 -374.044116)
			(xy 50.002557 -374.096422) (xy 49.979909 -374.146009) (xy 49.950434 -374.191868) (xy 49.914733 -374.233065)
			(xy 49.873531 -374.268762) (xy 49.827669 -374.298231) (xy 49.778079 -374.320873) (xy 49.725771 -374.336226)
			(xy 49.671811 -374.343978) (xy 49.644554 -374.344438) (xy 49.615852 -374.343422) (xy 49.602644 -374.342406)
			(xy 49.579022 -374.353328) (xy 49.51222 -374.444006) (xy 49.508918 -374.469914) (xy 49.513998 -374.48236)
			(xy 49.522548 -374.504866) (xy 49.534547 -374.551491) (xy 49.540574 -374.599257) (xy 49.540922 -374.62333)
			(xy 49.540436 -374.650581) (xy 49.53268 -374.704529) (xy 49.517325 -374.756824) (xy 49.494683 -374.806401)
			(xy 49.465217 -374.852251) (xy 49.429526 -374.893442) (xy 49.388335 -374.929133) (xy 49.342485 -374.958599)
			(xy 49.292908 -374.981241) (xy 49.240613 -374.996596) (xy 49.186665 -375.004352) (xy 49.132163 -375.004352)
			(xy 49.078215 -374.996596) (xy 49.02592 -374.981241) (xy 48.976343 -374.958599) (xy 48.930493 -374.929133)
			(xy 48.889302 -374.893442) (xy 48.853611 -374.852251) (xy 48.824145 -374.806401) (xy 48.801503 -374.756824)
			(xy 48.786148 -374.704529) (xy 48.778392 -374.650581) (xy 48.777906 -374.62333) (xy 48.778585 -374.590798)
			(xy 48.789703 -374.526688) (xy 48.800004 -374.495822) (xy 48.803052 -374.487186) (xy 48.802798 -374.469406)
			(xy 48.773334 -374.39092) (xy 48.761904 -374.377712) (xy 48.753776 -374.37314) (xy 48.721518 -374.353328)
			(xy 48.715103 -374.349312) (xy 48.700634 -374.344904) (xy 48.69307 -374.344692) (xy 48.411638 -374.344692)
			(xy 48.404083 -374.34496) (xy 48.389624 -374.349358) (xy 48.38319 -374.353328) (xy 48.350932 -374.37314)
			(xy 48.342804 -374.377712) (xy 48.331374 -374.39092) (xy 48.30191 -374.469406) (xy 48.301656 -374.487186)
			(xy 48.304704 -374.495822) (xy 48.314989 -374.526692) (xy 48.326099 -374.590799) (xy 48.326802 -374.62333)
			(xy 48.326316 -374.650581) (xy 48.31856 -374.704529) (xy 48.303205 -374.756824) (xy 48.280563 -374.806401)
			(xy 48.251097 -374.852251) (xy 48.215406 -374.893442) (xy 48.174215 -374.929133) (xy 48.128365 -374.958599)
			(xy 48.078788 -374.981241) (xy 48.026493 -374.996596) (xy 47.972545 -375.004352) (xy 47.918043 -375.004352)
			(xy 47.864095 -374.996596) (xy 47.8118 -374.981241) (xy 47.762223 -374.958599) (xy 47.716373 -374.929133)
			(xy 47.675182 -374.893442) (xy 47.639491 -374.852251) (xy 47.610025 -374.806401) (xy 47.587383 -374.756824)
			(xy 47.572028 -374.704529) (xy 47.564272 -374.650581) (xy 47.563786 -374.62333) (xy 47.564132 -374.599258)
			(xy 47.570175 -374.551495) (xy 47.582171 -374.504869) (xy 47.59071 -374.48236) (xy 47.59579 -374.469914)
			(xy 47.592488 -374.444006) (xy 47.525686 -374.353328) (xy 47.502064 -374.342406) (xy 47.488856 -374.343422)
			(xy 47.460154 -374.344438) (xy 47.432907 -374.343889) (xy 47.378969 -374.336127) (xy 47.326684 -374.32077)
			(xy 47.277116 -374.298128) (xy 47.231275 -374.268662) (xy 47.190094 -374.232974) (xy 47.15441 -374.191788)
			(xy 47.12495 -374.145943) (xy 47.102314 -374.096373) (xy 47.086963 -374.044086) (xy 47.079208 -373.990147)
			(xy 41.679357 -373.990147) (xy 41.679792 -373.990312) (xy 41.742371 -374.023156) (xy 41.800535 -374.063304)
			(xy 41.853435 -374.11017) (xy 41.900301 -374.163071) (xy 41.940448 -374.221236) (xy 41.973291 -374.283816)
			(xy 41.998351 -374.349898) (xy 42.015263 -374.418519) (xy 42.023781 -374.488679) (xy 42.0243 -374.524016)
			(xy 42.023822 -374.557842) (xy 42.016024 -374.625043) (xy 42.000522 -374.690896) (xy 41.977523 -374.754519)
			(xy 41.947335 -374.815062) (xy 41.910361 -374.871717) (xy 41.867096 -374.923726) (xy 41.818117 -374.970394)
			(xy 41.791382 -374.991122) (xy 41.783762 -374.99671) (xy 41.77411 -375.01195) (xy 41.756584 -375.09577)
			(xy 41.759124 -375.11355) (xy 41.763696 -375.121678) (xy 41.775234 -375.143092) (xy 41.793387 -375.188221)
			(xy 41.805657 -375.235291) (xy 41.811845 -375.283539) (xy 41.81221 -375.30786) (xy 41.811194 -375.336562)
			(xy 41.810178 -375.34977) (xy 41.8211 -375.373392) (xy 41.911778 -375.440194) (xy 41.937686 -375.443496)
			(xy 41.950132 -375.438416) (xy 41.972642 -375.429881) (xy 42.019268 -375.417894) (xy 42.067031 -375.411859)
			(xy 42.091102 -375.411492) (xy 42.118353 -375.411978) (xy 42.172301 -375.419735) (xy 42.224595 -375.43509)
			(xy 42.274172 -375.457731) (xy 42.320022 -375.487198) (xy 42.361212 -375.522889) (xy 42.396904 -375.564079)
			(xy 42.42637 -375.60993) (xy 42.449011 -375.659507) (xy 42.464366 -375.711801) (xy 42.472122 -375.765749)
			(xy 42.472122 -375.820251) (xy 42.464366 -375.874199) (xy 42.449011 -375.926493) (xy 42.440442 -375.945257)
			(xy 70.236223 -375.945257) (xy 70.236223 -375.890743) (xy 70.243982 -375.836785) (xy 70.259341 -375.78448)
			(xy 70.281987 -375.734893) (xy 70.311461 -375.689035) (xy 70.347162 -375.647837) (xy 70.388362 -375.612141)
			(xy 70.434223 -375.582671) (xy 70.483812 -375.560029) (xy 70.536118 -375.544674) (xy 70.590077 -375.536921)
			(xy 70.617334 -375.53646) (xy 70.641406 -375.536819) (xy 70.689168 -375.542857) (xy 70.735794 -375.554847)
			(xy 70.758304 -375.563384) (xy 70.77075 -375.568464) (xy 70.796658 -375.565162) (xy 70.887336 -375.49836)
			(xy 70.898258 -375.474738) (xy 70.897242 -375.46153) (xy 70.896226 -375.432828) (xy 70.896712 -375.405577)
			(xy 70.904468 -375.351629) (xy 70.919823 -375.299334) (xy 70.942465 -375.249757) (xy 70.971931 -375.203907)
			(xy 71.007622 -375.162716) (xy 71.048813 -375.127025) (xy 71.094663 -375.097559) (xy 71.14424 -375.074917)
			(xy 71.196535 -375.059562) (xy 71.250483 -375.051806) (xy 71.304985 -375.051806) (xy 71.358933 -375.059562)
			(xy 71.411228 -375.074917) (xy 71.460805 -375.097559) (xy 71.506655 -375.127025) (xy 71.547846 -375.162716)
			(xy 71.583537 -375.203907) (xy 71.613003 -375.249757) (xy 71.635645 -375.299334) (xy 71.651 -375.351629)
			(xy 71.658756 -375.405577) (xy 71.659242 -375.432828) (xy 71.658226 -375.46153) (xy 71.65721 -375.474738)
			(xy 71.668132 -375.49836) (xy 71.75881 -375.565162) (xy 71.784718 -375.568464) (xy 71.797164 -375.563384)
			(xy 71.819669 -375.554832) (xy 71.866295 -375.542834) (xy 71.914061 -375.536808) (xy 71.938134 -375.53646)
			(xy 71.965381 -375.537013) (xy 72.019321 -375.544772) (xy 72.071607 -375.560129) (xy 72.121176 -375.58277)
			(xy 72.167018 -375.612235) (xy 72.208201 -375.647923) (xy 72.243885 -375.689109) (xy 72.273346 -375.734954)
			(xy 72.295983 -375.784525) (xy 72.306472 -375.820249) (xy 72.917078 -375.820249) (xy 72.917078 -375.765751)
			(xy 72.924833 -375.711808) (xy 72.940185 -375.659517) (xy 72.962823 -375.609943) (xy 72.992285 -375.564095)
			(xy 73.027971 -375.522906) (xy 73.069155 -375.487215) (xy 73.114999 -375.457747) (xy 73.16457 -375.435103)
			(xy 73.216859 -375.419743) (xy 73.270801 -375.411981) (xy 73.29805 -375.411492) (xy 73.322122 -375.411844)
			(xy 73.369885 -375.417885) (xy 73.41651 -375.429878) (xy 73.43902 -375.438416) (xy 73.451466 -375.443496)
			(xy 73.477374 -375.440194) (xy 73.568052 -375.373392) (xy 73.578974 -375.34977) (xy 73.577958 -375.336562)
			(xy 73.576942 -375.30786) (xy 73.577428 -375.280609) (xy 73.585184 -375.226661) (xy 73.600539 -375.174366)
			(xy 73.623181 -375.124789) (xy 73.652647 -375.078939) (xy 73.688338 -375.037748) (xy 73.729529 -375.002057)
			(xy 73.775379 -374.972591) (xy 73.824956 -374.949949) (xy 73.877251 -374.934594) (xy 73.931199 -374.926838)
			(xy 73.985701 -374.926838) (xy 74.039649 -374.934594) (xy 74.091944 -374.949949) (xy 74.141521 -374.972591)
			(xy 74.187371 -375.002057) (xy 74.228562 -375.037748) (xy 74.264253 -375.078939) (xy 74.293719 -375.124789)
			(xy 74.316361 -375.174366) (xy 74.331716 -375.226661) (xy 74.339472 -375.280609) (xy 74.339958 -375.30786)
			(xy 74.338942 -375.336562) (xy 74.337926 -375.34977) (xy 74.348848 -375.373392) (xy 74.439526 -375.440194)
			(xy 74.465434 -375.443496) (xy 74.47788 -375.438416) (xy 74.500384 -375.429861) (xy 74.54701 -375.417863)
			(xy 74.594777 -375.411839) (xy 74.61885 -375.411492) (xy 74.646105 -375.411952) (xy 74.700062 -375.419703)
			(xy 74.752365 -375.435055) (xy 74.801952 -375.457694) (xy 74.847811 -375.487161) (xy 74.88901 -375.522855)
			(xy 74.924709 -375.564049) (xy 74.954182 -375.609904) (xy 74.976828 -375.659488) (xy 74.992186 -375.71179)
			(xy 74.999945 -375.765745) (xy 74.999945 -375.820255) (xy 74.992186 -375.87421) (xy 74.976828 -375.926512)
			(xy 74.968269 -375.945253) (xy 102.764046 -375.945253) (xy 102.764046 -375.890747) (xy 102.771803 -375.836797)
			(xy 102.787158 -375.784499) (xy 102.8098 -375.734919) (xy 102.839267 -375.689065) (xy 102.874959 -375.647872)
			(xy 102.916151 -375.612178) (xy 102.962003 -375.582708) (xy 103.011582 -375.560064) (xy 103.063879 -375.544706)
			(xy 103.117829 -375.536947) (xy 103.145082 -375.53646) (xy 103.169153 -375.536835) (xy 103.216915 -375.542867)
			(xy 103.263542 -375.55485) (xy 103.286052 -375.563384) (xy 103.298498 -375.568464) (xy 103.324406 -375.565162)
			(xy 103.415084 -375.49836) (xy 103.426006 -375.474738) (xy 103.42499 -375.46153) (xy 103.423974 -375.432828)
			(xy 103.42446 -375.405577) (xy 103.432216 -375.351629) (xy 103.447571 -375.299334) (xy 103.470213 -375.249757)
			(xy 103.499679 -375.203907) (xy 103.53537 -375.162716) (xy 103.576561 -375.127025) (xy 103.622411 -375.097559)
			(xy 103.671988 -375.074917) (xy 103.724283 -375.059562) (xy 103.778231 -375.051806) (xy 103.832733 -375.051806)
			(xy 103.886681 -375.059562) (xy 103.938976 -375.074917) (xy 103.988553 -375.097559) (xy 104.034403 -375.127025)
			(xy 104.075594 -375.162716) (xy 104.111285 -375.203907) (xy 104.140751 -375.249757) (xy 104.163393 -375.299334)
			(xy 104.178748 -375.351629) (xy 104.186504 -375.405577) (xy 104.18699 -375.432828) (xy 104.185974 -375.46153)
			(xy 104.184958 -375.474738) (xy 104.19588 -375.49836) (xy 104.286558 -375.565162) (xy 104.312466 -375.568464)
			(xy 104.324912 -375.563384) (xy 104.347423 -375.554847) (xy 104.394046 -375.542843) (xy 104.44181 -375.536811)
			(xy 104.465882 -375.53646) (xy 104.493133 -375.536986) (xy 104.547082 -375.54474) (xy 104.599377 -375.560093)
			(xy 104.648956 -375.582733) (xy 104.694807 -375.612198) (xy 104.735999 -375.647889) (xy 104.771691 -375.689078)
			(xy 104.801158 -375.734929) (xy 104.8238 -375.784506) (xy 104.834297 -375.820255) (xy 107.489155 -375.820255)
			(xy 107.489155 -375.765745) (xy 107.496914 -375.71179) (xy 107.512272 -375.659489) (xy 107.534918 -375.609906)
			(xy 107.56439 -375.564051) (xy 107.600088 -375.522857) (xy 107.641286 -375.487163) (xy 107.687145 -375.457696)
			(xy 107.73673 -375.435056) (xy 107.789033 -375.419704) (xy 107.842989 -375.411952) (xy 107.870244 -375.411492)
			(xy 107.894316 -375.411845) (xy 107.942079 -375.417886) (xy 107.988704 -375.429878) (xy 108.011214 -375.438416)
			(xy 108.02366 -375.443496) (xy 108.049568 -375.440194) (xy 108.140246 -375.373392) (xy 108.151168 -375.34977)
			(xy 108.150152 -375.336562) (xy 108.149136 -375.30786) (xy 108.149622 -375.280609) (xy 108.157378 -375.226661)
			(xy 108.172733 -375.174366) (xy 108.195375 -375.124789) (xy 108.224841 -375.078939) (xy 108.260532 -375.037748)
			(xy 108.301723 -375.002057) (xy 108.347573 -374.972591) (xy 108.39715 -374.949949) (xy 108.449445 -374.934594)
			(xy 108.503393 -374.926838) (xy 108.557895 -374.926838) (xy 108.611843 -374.934594) (xy 108.664138 -374.949949)
			(xy 108.713715 -374.972591) (xy 108.759565 -375.002057) (xy 108.800756 -375.037748) (xy 108.836447 -375.078939)
			(xy 108.865913 -375.124789) (xy 108.888555 -375.174366) (xy 108.90391 -375.226661) (xy 108.911666 -375.280609)
			(xy 108.912152 -375.30786) (xy 108.911136 -375.336562) (xy 108.91012 -375.34977) (xy 108.921042 -375.373392)
			(xy 109.01172 -375.440194) (xy 109.037628 -375.443496) (xy 109.050074 -375.438416) (xy 109.072579 -375.429863)
			(xy 109.119205 -375.417864) (xy 109.166971 -375.411839) (xy 109.191044 -375.411492) (xy 109.218293 -375.411981)
			(xy 109.272236 -375.419742) (xy 109.324526 -375.435101) (xy 109.374097 -375.457745) (xy 109.419942 -375.487212)
			(xy 109.461127 -375.522904) (xy 109.496814 -375.564093) (xy 109.526276 -375.609941) (xy 109.548914 -375.659516)
			(xy 109.564267 -375.711807) (xy 109.572022 -375.765751) (xy 109.572022 -375.820249) (xy 109.564267 -375.874193)
			(xy 109.548914 -375.926484) (xy 109.540344 -375.945252) (xy 137.336246 -375.945252) (xy 137.336246 -375.890748)
			(xy 137.344002 -375.836797) (xy 137.359358 -375.7845) (xy 137.381999 -375.73492) (xy 137.411465 -375.689067)
			(xy 137.447157 -375.647874) (xy 137.488348 -375.61218) (xy 137.534199 -375.58271) (xy 137.583778 -375.560066)
			(xy 137.636074 -375.544707) (xy 137.690024 -375.536947) (xy 137.717276 -375.53646) (xy 137.741348 -375.536806)
			(xy 137.789111 -375.54285) (xy 137.835737 -375.554845) (xy 137.858246 -375.563384) (xy 137.870692 -375.568464)
			(xy 137.8966 -375.565162) (xy 137.987278 -375.49836) (xy 137.9982 -375.474738) (xy 137.997184 -375.46153)
			(xy 137.996168 -375.432828) (xy 137.996654 -375.405577) (xy 138.00441 -375.351629) (xy 138.019765 -375.299334)
			(xy 138.042407 -375.249757) (xy 138.071873 -375.203907) (xy 138.107564 -375.162716) (xy 138.148755 -375.127025)
			(xy 138.194605 -375.097559) (xy 138.244182 -375.074917) (xy 138.296477 -375.059562) (xy 138.350425 -375.051806)
			(xy 138.404927 -375.051806) (xy 138.458875 -375.059562) (xy 138.51117 -375.074917) (xy 138.560747 -375.097559)
			(xy 138.606597 -375.127025) (xy 138.647788 -375.162716) (xy 138.683479 -375.203907) (xy 138.712945 -375.249757)
			(xy 138.735587 -375.299334) (xy 138.750942 -375.351629) (xy 138.758698 -375.405577) (xy 138.759184 -375.432828)
			(xy 138.758168 -375.46153) (xy 138.757152 -375.474738) (xy 138.768074 -375.49836) (xy 138.858752 -375.565162)
			(xy 138.88466 -375.568464) (xy 138.897106 -375.563384) (xy 138.919617 -375.554849) (xy 138.96624 -375.542844)
			(xy 139.014004 -375.536811) (xy 139.038076 -375.53646) (xy 139.065328 -375.536986) (xy 139.119277 -375.544739)
			(xy 139.171573 -375.560092) (xy 139.221152 -375.582731) (xy 139.267004 -375.612196) (xy 139.308196 -375.647887)
			(xy 139.34389 -375.689076) (xy 139.373357 -375.734927) (xy 139.396 -375.784504) (xy 139.406497 -375.820251)
			(xy 140.016978 -375.820251) (xy 140.016978 -375.765749) (xy 140.024734 -375.711802) (xy 140.040089 -375.659508)
			(xy 140.062729 -375.609931) (xy 140.092195 -375.564081) (xy 140.127886 -375.522891) (xy 140.169075 -375.4872)
			(xy 140.214924 -375.457733) (xy 140.2645 -375.435092) (xy 140.316794 -375.419736) (xy 140.370741 -375.411978)
			(xy 140.397992 -375.411492) (xy 140.422063 -375.411861) (xy 140.469826 -375.417895) (xy 140.516452 -375.429881)
			(xy 140.538962 -375.438416) (xy 140.551408 -375.443496) (xy 140.577316 -375.440194) (xy 140.667994 -375.373392)
			(xy 140.678916 -375.34977) (xy 140.6779 -375.336562) (xy 140.676884 -375.30786) (xy 140.67737 -375.280609)
			(xy 140.685126 -375.226661) (xy 140.700481 -375.174366) (xy 140.723123 -375.124789) (xy 140.752589 -375.078939)
			(xy 140.78828 -375.037748) (xy 140.829471 -375.002057) (xy 140.875321 -374.972591) (xy 140.924898 -374.949949)
			(xy 140.977193 -374.934594) (xy 141.031141 -374.926838) (xy 141.085643 -374.926838) (xy 141.139591 -374.934594)
			(xy 141.191886 -374.949949) (xy 141.241463 -374.972591) (xy 141.287313 -375.002057) (xy 141.328504 -375.037748)
			(xy 141.364195 -375.078939) (xy 141.393661 -375.124789) (xy 141.416303 -375.174366) (xy 141.431658 -375.226661)
			(xy 141.439414 -375.280609) (xy 141.4399 -375.30786) (xy 141.438884 -375.336562) (xy 141.437868 -375.34977)
			(xy 141.44879 -375.373392) (xy 141.539468 -375.440194) (xy 141.565376 -375.443496) (xy 141.577822 -375.438416)
			(xy 141.600332 -375.429878) (xy 141.646955 -375.417874) (xy 141.69472 -375.411842) (xy 141.718792 -375.411492)
			(xy 141.746045 -375.411955) (xy 141.799997 -375.419711) (xy 141.852296 -375.435066) (xy 141.901877 -375.457708)
			(xy 141.947731 -375.487176) (xy 141.988925 -375.52287) (xy 142.024619 -375.564063) (xy 142.054088 -375.609916)
			(xy 142.076731 -375.659497) (xy 142.092087 -375.711795) (xy 142.099845 -375.765747) (xy 142.099845 -375.820253)
			(xy 142.092087 -375.874205) (xy 142.076731 -375.926503) (xy 142.068167 -375.945256) (xy 169.863923 -375.945256)
			(xy 169.863923 -375.890744) (xy 169.871681 -375.836786) (xy 169.88704 -375.784482) (xy 169.909686 -375.734896)
			(xy 169.939159 -375.689038) (xy 169.974858 -375.647841) (xy 170.016057 -375.612144) (xy 170.061917 -375.582674)
			(xy 170.111504 -375.560031) (xy 170.16381 -375.544676) (xy 170.217768 -375.536921) (xy 170.245024 -375.53646)
			(xy 170.269095 -375.536822) (xy 170.316858 -375.542859) (xy 170.363484 -375.554848) (xy 170.385994 -375.563384)
			(xy 170.39844 -375.568464) (xy 170.424348 -375.565162) (xy 170.515026 -375.49836) (xy 170.525948 -375.474738)
			(xy 170.524932 -375.46153) (xy 170.523916 -375.432828) (xy 170.524381 -375.405575) (xy 170.532135 -375.351623)
			(xy 170.547489 -375.299323) (xy 170.57013 -375.249742) (xy 170.599597 -375.203887) (xy 170.635291 -375.162694)
			(xy 170.676484 -375.127) (xy 170.722338 -375.097532) (xy 170.77192 -375.07489) (xy 170.824219 -375.059536)
			(xy 170.878171 -375.051782) (xy 170.905424 -375.05132) (xy 170.931932 -375.051808) (xy 170.984434 -375.059165)
			(xy 171.035413 -375.073719) (xy 171.083886 -375.095191) (xy 171.12892 -375.123167) (xy 171.169646 -375.157108)
			(xy 171.205282 -375.19636) (xy 171.235141 -375.240168) (xy 171.258647 -375.287688) (xy 171.275348 -375.338004)
			(xy 171.280582 -375.363994) (xy 171.282614 -375.374408) (xy 171.293536 -375.391172) (xy 171.37126 -375.443496)
			(xy 171.391072 -375.447306) (xy 171.401232 -375.445274) (xy 171.420325 -375.441603) (xy 171.459007 -375.437654)
			(xy 171.478448 -375.4374) (xy 171.505698 -375.437873) (xy 171.559641 -375.445635) (xy 171.611931 -375.460995)
			(xy 171.661504 -375.483639) (xy 171.707349 -375.513107) (xy 171.748534 -375.5488) (xy 171.784221 -375.58999)
			(xy 171.813684 -375.635839) (xy 171.836322 -375.685414) (xy 171.851675 -375.737706) (xy 171.85943 -375.79165)
			(xy 171.85943 -375.84615) (xy 171.851675 -375.900094) (xy 171.836322 -375.952386) (xy 171.813684 -376.001961)
			(xy 171.784221 -376.04781) (xy 171.748534 -376.089) (xy 171.707349 -376.124693) (xy 171.661504 -376.154161)
			(xy 171.611931 -376.176805) (xy 171.559641 -376.192165) (xy 171.505698 -376.199927) (xy 171.478448 -376.200416)
			(xy 171.46635 -376.200322) (xy 171.442202 -376.198794) (xy 171.430188 -376.197368) (xy 171.421517 -376.196562)
			(xy 171.404501 -376.200204) (xy 171.396914 -376.20448) (xy 171.371514 -376.220228) (xy 171.364206 -376.225099)
			(xy 171.353161 -376.238735) (xy 171.349924 -376.246898) (xy 171.339546 -376.275594) (xy 171.312409 -376.33025)
			(xy 171.295822 -376.355864) (xy 171.291782 -376.36228) (xy 171.287254 -376.376738) (xy 171.286932 -376.384312)
			(xy 171.286932 -376.49658) (xy 173.226991 -376.49658) (xy 173.230998 -376.311676) (xy 173.243011 -376.127118)
			(xy 173.263007 -375.943254) (xy 173.290949 -375.76043) (xy 173.326785 -375.578987) (xy 173.370447 -375.399266)
			(xy 173.421854 -375.221606) (xy 173.480908 -375.04634) (xy 173.547499 -374.873796) (xy 173.621502 -374.704299)
			(xy 173.702778 -374.538167) (xy 173.791174 -374.375711) (xy 173.886525 -374.217237) (xy 173.988651 -374.063042)
			(xy 174.09736 -373.913416) (xy 174.212449 -373.76864) (xy 174.333702 -373.628985) (xy 174.460891 -373.494714)
			(xy 174.593776 -373.366078) (xy 174.73211 -373.243319) (xy 174.875631 -373.126669) (xy 175.02407 -373.016345)
			(xy 175.17715 -372.912554) (xy 175.334581 -372.815492) (xy 175.49607 -372.725342) (xy 175.661312 -372.642271)
			(xy 175.829998 -372.566436) (xy 176.00181 -372.49798) (xy 176.176426 -372.43703) (xy 176.353519 -372.383703)
			(xy 176.532756 -372.338096) (xy 176.7138 -372.300297) (xy 176.896311 -372.270376) (xy 177.079948 -372.248389)
			(xy 177.264364 -372.234377) (xy 177.449214 -372.228367) (xy 177.634151 -372.230371) (xy 177.818828 -372.240384)
			(xy 178.002898 -372.258387) (xy 178.186014 -372.284348) (xy 178.367835 -372.318216) (xy 178.548018 -372.359928)
			(xy 178.726224 -372.409407) (xy 178.90212 -372.466559) (xy 179.075375 -372.531277) (xy 179.245664 -372.60344)
			(xy 179.412667 -372.682911) (xy 179.576071 -372.769542) (xy 179.735568 -372.863171) (xy 179.89086 -372.96362)
			(xy 180.041655 -373.070703) (xy 180.18767 -373.184217) (xy 180.32863 -373.303949) (xy 180.464271 -373.429676)
			(xy 180.594339 -373.56116) (xy 180.718589 -373.698156) (xy 180.836787 -373.840405) (xy 180.948713 -373.98764)
			(xy 181.054156 -374.139586) (xy 181.152917 -374.295957) (xy 181.244812 -374.45646) (xy 181.329668 -374.620792)
			(xy 181.407326 -374.788647) (xy 181.477639 -374.959707) (xy 181.540476 -375.133653) (xy 181.59572 -375.310158)
			(xy 181.643265 -375.48889) (xy 181.683023 -375.669514) (xy 181.71492 -375.851691) (xy 181.738895 -376.035078)
			(xy 181.754903 -376.219332) (xy 181.762915 -376.404106) (xy 181.763416 -376.49658) (xy 181.762915 -376.589054)
			(xy 181.754903 -376.773828) (xy 181.738895 -376.958082) (xy 181.71492 -377.141469) (xy 181.683023 -377.323646)
			(xy 181.643265 -377.50427) (xy 181.59572 -377.683002) (xy 181.540476 -377.859507) (xy 181.477639 -378.033453)
			(xy 181.407326 -378.204513) (xy 181.329668 -378.372368) (xy 181.244812 -378.5367) (xy 181.152917 -378.697203)
			(xy 181.054156 -378.853574) (xy 180.948713 -379.00552) (xy 180.836787 -379.152755) (xy 180.718589 -379.295004)
			(xy 180.594339 -379.432) (xy 180.464271 -379.563484) (xy 180.32863 -379.689211) (xy 180.18767 -379.808943)
			(xy 180.041655 -379.922457) (xy 179.89086 -380.02954) (xy 179.735568 -380.129989) (xy 179.576071 -380.223618)
			(xy 179.412667 -380.310249) (xy 179.245664 -380.38972) (xy 179.075375 -380.461883) (xy 178.90212 -380.526601)
			(xy 178.726224 -380.583753) (xy 178.548018 -380.633232) (xy 178.367835 -380.674944) (xy 178.186014 -380.708812)
			(xy 178.002898 -380.734773) (xy 177.818828 -380.752776) (xy 177.634151 -380.762789) (xy 177.449214 -380.764793)
			(xy 177.264364 -380.758783) (xy 177.079948 -380.744771) (xy 176.896311 -380.722784) (xy 176.7138 -380.692863)
			(xy 176.532756 -380.655064) (xy 176.353519 -380.609457) (xy 176.176426 -380.55613) (xy 176.00181 -380.49518)
			(xy 175.829998 -380.426724) (xy 175.661312 -380.350889) (xy 175.49607 -380.267818) (xy 175.334581 -380.177668)
			(xy 175.17715 -380.080606) (xy 175.02407 -379.976815) (xy 174.875631 -379.866491) (xy 174.73211 -379.749841)
			(xy 174.593776 -379.627082) (xy 174.460891 -379.498446) (xy 174.333702 -379.364175) (xy 174.212449 -379.22452)
			(xy 174.09736 -379.079744) (xy 173.988651 -378.930118) (xy 173.886525 -378.775923) (xy 173.791174 -378.617449)
			(xy 173.702778 -378.454993) (xy 173.621502 -378.288861) (xy 173.547499 -378.119364) (xy 173.480908 -377.94682)
			(xy 173.421854 -377.771554) (xy 173.370447 -377.593894) (xy 173.326785 -377.414173) (xy 173.290949 -377.23273)
			(xy 173.263007 -377.049906) (xy 173.243011 -376.866042) (xy 173.230998 -376.681484) (xy 173.226991 -376.49658)
			(xy 171.286932 -376.49658) (xy 171.286932 -376.665744) (xy 171.287267 -376.673318) (xy 171.291776 -376.687782)
			(xy 171.295822 -376.694192) (xy 171.315634 -376.72645) (xy 171.320206 -376.734578) (xy 171.333414 -376.746008)
			(xy 171.4119 -376.775472) (xy 171.42968 -376.775726) (xy 171.438316 -376.772678) (xy 171.469186 -376.762394)
			(xy 171.533294 -376.751283) (xy 171.565824 -376.75058) (xy 171.593073 -376.751092) (xy 171.647017 -376.758851)
			(xy 171.699307 -376.774208) (xy 171.748879 -376.796849) (xy 171.794725 -376.826315) (xy 171.835911 -376.862006)
			(xy 171.871599 -376.903194) (xy 171.901062 -376.949042) (xy 171.923701 -376.998616) (xy 171.939054 -377.050907)
			(xy 171.94681 -377.104851) (xy 171.94681 -377.159349) (xy 171.939054 -377.213293) (xy 171.923701 -377.265584)
			(xy 171.901062 -377.315158) (xy 171.871599 -377.361006) (xy 171.835911 -377.402194) (xy 171.794725 -377.437885)
			(xy 171.748879 -377.467351) (xy 171.699307 -377.489992) (xy 171.647017 -377.505349) (xy 171.593073 -377.513108)
			(xy 171.565824 -377.513596) (xy 171.541752 -377.513246) (xy 171.493989 -377.507203) (xy 171.447364 -377.49521)
			(xy 171.424854 -377.486672) (xy 171.412408 -377.481592) (xy 171.3865 -377.484894) (xy 171.295822 -377.551696)
			(xy 171.2849 -377.575318) (xy 171.285916 -377.588526) (xy 171.286932 -377.617228) (xy 171.286446 -377.644479)
			(xy 171.27869 -377.698427) (xy 171.263335 -377.750722) (xy 171.240693 -377.800299) (xy 171.211227 -377.846149)
			(xy 171.175536 -377.88734) (xy 171.134345 -377.923031) (xy 171.088495 -377.952497) (xy 171.038918 -377.975139)
			(xy 170.986623 -377.990494) (xy 170.932675 -377.99825) (xy 170.878173 -377.99825) (xy 170.824225 -377.990494)
			(xy 170.77193 -377.975139) (xy 170.722353 -377.952497) (xy 170.676503 -377.923031) (xy 170.635312 -377.88734)
			(xy 170.599621 -377.846149) (xy 170.570155 -377.800299) (xy 170.547513 -377.750722) (xy 170.532158 -377.698427)
			(xy 170.524402 -377.644479) (xy 170.523916 -377.617228) (xy 170.524932 -377.588526) (xy 170.525948 -377.575318)
			(xy 170.515026 -377.551696) (xy 170.424348 -377.484894) (xy 170.39844 -377.481592) (xy 170.385994 -377.486672)
			(xy 170.363484 -377.49521) (xy 170.31686 -377.507213) (xy 170.269096 -377.513245) (xy 170.245024 -377.513596)
			(xy 170.217769 -377.513159) (xy 170.163814 -377.505404) (xy 170.111511 -377.49005) (xy 170.061927 -377.467408)
			(xy 170.016069 -377.43794) (xy 169.974872 -377.402245) (xy 169.939175 -377.36105) (xy 169.909704 -377.315194)
			(xy 169.887059 -377.265611) (xy 169.871701 -377.21331) (xy 169.863943 -377.159355) (xy 169.863943 -377.104845)
			(xy 169.871701 -377.05089) (xy 169.887059 -376.998589) (xy 169.909704 -376.949006) (xy 169.939175 -376.90315)
			(xy 169.974872 -376.861955) (xy 170.016069 -376.82626) (xy 170.061927 -376.796792) (xy 170.111511 -376.77415)
			(xy 170.163814 -376.758796) (xy 170.217769 -376.751041) (xy 170.245024 -376.75058) (xy 170.277556 -376.751272)
			(xy 170.341665 -376.762381) (xy 170.372532 -376.772678) (xy 170.381168 -376.775726) (xy 170.398948 -376.775472)
			(xy 170.477434 -376.746008) (xy 170.490642 -376.734578) (xy 170.495214 -376.72645) (xy 170.515026 -376.694192)
			(xy 170.519078 -376.687783) (xy 170.5236 -376.67332) (xy 170.523916 -376.665744) (xy 170.523916 -376.384312)
			(xy 170.523607 -376.376736) (xy 170.519081 -376.362272) (xy 170.515026 -376.355864) (xy 170.495214 -376.323606)
			(xy 170.490642 -376.315478) (xy 170.477434 -376.304048) (xy 170.398948 -376.274584) (xy 170.381168 -376.27433)
			(xy 170.372532 -376.277378) (xy 170.341665 -376.287673) (xy 170.277555 -376.298777) (xy 170.245024 -376.299476)
			(xy 170.217768 -376.299079) (xy 170.16381 -376.291324) (xy 170.111504 -376.275969) (xy 170.061917 -376.253326)
			(xy 170.016057 -376.223856) (xy 169.974858 -376.188159) (xy 169.939159 -376.146962) (xy 169.909686 -376.101104)
			(xy 169.88704 -376.051518) (xy 169.871681 -375.999214) (xy 169.863923 -375.945256) (xy 142.068167 -375.945256)
			(xy 142.054088 -375.976084) (xy 142.024619 -376.021937) (xy 141.988925 -376.06313) (xy 141.947731 -376.098824)
			(xy 141.901877 -376.128292) (xy 141.852296 -376.150934) (xy 141.799997 -376.166289) (xy 141.746045 -376.174045)
			(xy 141.718792 -376.174508) (xy 141.68626 -376.173813) (xy 141.622151 -376.162706) (xy 141.591284 -376.15241)
			(xy 141.582648 -376.149362) (xy 141.564868 -376.149616) (xy 141.486382 -376.17908) (xy 141.473174 -376.19051)
			(xy 141.468602 -376.198638) (xy 141.44879 -376.230896) (xy 141.444735 -376.237303) (xy 141.440216 -376.251768)
			(xy 141.4399 -376.259344) (xy 141.4399 -376.540776) (xy 141.440227 -376.54835) (xy 141.444742 -376.562814)
			(xy 141.44879 -376.569224) (xy 141.468602 -376.601482) (xy 141.473174 -376.60961) (xy 141.486382 -376.62104)
			(xy 141.564868 -376.650504) (xy 141.582648 -376.650758) (xy 141.591284 -376.64771) (xy 141.622157 -376.637435)
			(xy 141.686262 -376.626318) (xy 141.718792 -376.625612) (xy 141.746047 -376.626034) (xy 141.800001 -376.633791)
			(xy 141.852303 -376.649147) (xy 141.901887 -376.67179) (xy 141.947743 -376.70126) (xy 141.988939 -376.736955)
			(xy 142.024636 -376.77815) (xy 142.054106 -376.824006) (xy 142.07675 -376.87359) (xy 142.092107 -376.925891)
			(xy 142.099865 -376.979845) (xy 142.099865 -377.034355) (xy 142.092107 -377.088309) (xy 142.07675 -377.14061)
			(xy 142.054106 -377.190194) (xy 142.024636 -377.23605) (xy 141.988939 -377.277245) (xy 141.947743 -377.31294)
			(xy 141.901887 -377.34241) (xy 141.852303 -377.365053) (xy 141.800001 -377.380409) (xy 141.746047 -377.388166)
			(xy 141.718792 -377.388628) (xy 141.694721 -377.388262) (xy 141.646958 -377.382227) (xy 141.600332 -377.370239)
			(xy 141.577822 -377.361704) (xy 141.565376 -377.356624) (xy 141.539468 -377.359926) (xy 141.44879 -377.426728)
			(xy 141.437868 -377.45035) (xy 141.438884 -377.463558) (xy 141.4399 -377.49226) (xy 141.439414 -377.519511)
			(xy 141.431658 -377.573459) (xy 141.416303 -377.625754) (xy 141.393661 -377.675331) (xy 141.364195 -377.721181)
			(xy 141.328504 -377.762372) (xy 141.287313 -377.798063) (xy 141.241463 -377.827529) (xy 141.191886 -377.850171)
			(xy 141.139591 -377.865526) (xy 141.085643 -377.873282) (xy 141.031141 -377.873282) (xy 140.977193 -377.865526)
			(xy 140.924898 -377.850171) (xy 140.875321 -377.827529) (xy 140.829471 -377.798063) (xy 140.78828 -377.762372)
			(xy 140.752589 -377.721181) (xy 140.723123 -377.675331) (xy 140.700481 -377.625754) (xy 140.685126 -377.573459)
			(xy 140.67737 -377.519511) (xy 140.676884 -377.49226) (xy 140.6779 -377.463558) (xy 140.678916 -377.45035)
			(xy 140.667994 -377.426728) (xy 140.577316 -377.359926) (xy 140.551408 -377.356624) (xy 140.538962 -377.361704)
			(xy 140.516454 -377.370248) (xy 140.46983 -377.382249) (xy 140.422064 -377.388279) (xy 140.397992 -377.388628)
			(xy 140.370743 -377.388101) (xy 140.316799 -377.380344) (xy 140.264508 -377.364989) (xy 140.214934 -377.342349)
			(xy 140.169087 -377.312884) (xy 140.1279 -377.277194) (xy 140.092211 -377.236006) (xy 140.062747 -377.190159)
			(xy 140.040108 -377.140585) (xy 140.024754 -377.088294) (xy 140.016998 -377.034349) (xy 140.016998 -376.979851)
			(xy 140.024754 -376.925906) (xy 140.040108 -376.873615) (xy 140.062747 -376.824041) (xy 140.092211 -376.778194)
			(xy 140.1279 -376.737006) (xy 140.169087 -376.701316) (xy 140.214934 -376.671851) (xy 140.264508 -376.649211)
			(xy 140.316799 -376.633856) (xy 140.370743 -376.626099) (xy 140.397992 -376.625612) (xy 140.430523 -376.62631)
			(xy 140.494633 -376.637415) (xy 140.5255 -376.64771) (xy 140.534136 -376.650758) (xy 140.551916 -376.650504)
			(xy 140.630402 -376.62104) (xy 140.64361 -376.60961) (xy 140.648182 -376.601482) (xy 140.667994 -376.569224)
			(xy 140.67204 -376.562812) (xy 140.676565 -376.548351) (xy 140.676884 -376.540776) (xy 140.676884 -376.259344)
			(xy 140.676551 -376.25177) (xy 140.672041 -376.237306) (xy 140.667994 -376.230896) (xy 140.648182 -376.198638)
			(xy 140.64361 -376.19051) (xy 140.630402 -376.17908) (xy 140.551916 -376.149616) (xy 140.534136 -376.149362)
			(xy 140.5255 -376.15241) (xy 140.494629 -376.16269) (xy 140.430522 -376.173803) (xy 140.397992 -376.174508)
			(xy 140.370741 -376.174022) (xy 140.316794 -376.166264) (xy 140.2645 -376.150908) (xy 140.214924 -376.128267)
			(xy 140.169075 -376.0988) (xy 140.127886 -376.063109) (xy 140.092195 -376.021919) (xy 140.062729 -375.976069)
			(xy 140.040089 -375.926492) (xy 140.024734 -375.874198) (xy 140.016978 -375.820251) (xy 139.406497 -375.820251)
			(xy 139.411356 -375.8368) (xy 139.419113 -375.890748) (xy 139.419113 -375.945252) (xy 139.411356 -375.9992)
			(xy 139.396 -376.051496) (xy 139.373357 -376.101073) (xy 139.34389 -376.146924) (xy 139.308196 -376.188113)
			(xy 139.267004 -376.223804) (xy 139.221152 -376.253269) (xy 139.171573 -376.275908) (xy 139.119277 -376.291261)
			(xy 139.065328 -376.299014) (xy 139.038076 -376.299476) (xy 139.005544 -376.298787) (xy 138.941435 -376.287676)
			(xy 138.910568 -376.277378) (xy 138.901932 -376.27433) (xy 138.884152 -376.274584) (xy 138.805666 -376.304048)
			(xy 138.792458 -376.315478) (xy 138.787886 -376.323606) (xy 138.768074 -376.355864) (xy 138.764039 -376.362282)
			(xy 138.759506 -376.376739) (xy 138.759184 -376.384312) (xy 138.759184 -376.665744) (xy 138.759511 -376.673319)
			(xy 138.764025 -376.687783) (xy 138.768074 -376.694192) (xy 138.787886 -376.72645) (xy 138.792458 -376.734578)
			(xy 138.805666 -376.746008) (xy 138.884152 -376.775472) (xy 138.901932 -376.775726) (xy 138.910568 -376.772678)
			(xy 138.941434 -376.762382) (xy 139.005545 -376.751279) (xy 139.038076 -376.75058) (xy 139.065329 -376.751066)
			(xy 139.119281 -376.75882) (xy 139.17158 -376.774173) (xy 139.221162 -376.796814) (xy 139.267016 -376.82628)
			(xy 139.308211 -376.861972) (xy 139.343906 -376.903164) (xy 139.373375 -376.949017) (xy 139.396019 -376.998597)
			(xy 139.411375 -377.050896) (xy 139.419133 -377.104847) (xy 139.419133 -377.159353) (xy 139.411375 -377.213304)
			(xy 139.396019 -377.265603) (xy 139.373375 -377.315183) (xy 139.343906 -377.361036) (xy 139.308211 -377.402228)
			(xy 139.267016 -377.43792) (xy 139.221162 -377.467386) (xy 139.17158 -377.490027) (xy 139.119281 -377.50538)
			(xy 139.065329 -377.513134) (xy 139.038076 -377.513596) (xy 139.014005 -377.51323) (xy 138.966242 -377.507194)
			(xy 138.919616 -377.495207) (xy 138.897106 -377.486672) (xy 138.88466 -377.481592) (xy 138.858752 -377.484894)
			(xy 138.768074 -377.551696) (xy 138.757152 -377.575318) (xy 138.758168 -377.588526) (xy 138.759184 -377.617228)
			(xy 138.758698 -377.644479) (xy 138.750942 -377.698427) (xy 138.735587 -377.750722) (xy 138.712945 -377.800299)
			(xy 138.683479 -377.846149) (xy 138.647788 -377.88734) (xy 138.606597 -377.923031) (xy 138.560747 -377.952497)
			(xy 138.51117 -377.975139) (xy 138.458875 -377.990494) (xy 138.404927 -377.99825) (xy 138.350425 -377.99825)
			(xy 138.296477 -377.990494) (xy 138.244182 -377.975139) (xy 138.194605 -377.952497) (xy 138.148755 -377.923031)
			(xy 138.107564 -377.88734) (xy 138.071873 -377.846149) (xy 138.042407 -377.800299) (xy 138.019765 -377.750722)
			(xy 138.00441 -377.698427) (xy 137.996654 -377.644479) (xy 137.996168 -377.617228) (xy 137.997184 -377.588526)
			(xy 137.9982 -377.575318) (xy 137.987278 -377.551696) (xy 137.8966 -377.484894) (xy 137.870692 -377.481592)
			(xy 137.858246 -377.486672) (xy 137.835741 -377.495224) (xy 137.789115 -377.507221) (xy 137.741349 -377.513248)
			(xy 137.717276 -377.513596) (xy 137.690025 -377.513133) (xy 137.636078 -377.505373) (xy 137.583785 -377.490015)
			(xy 137.534209 -377.467372) (xy 137.48836 -377.437904) (xy 137.447171 -377.402212) (xy 137.411481 -377.361021)
			(xy 137.382016 -377.31517) (xy 137.359376 -377.265593) (xy 137.344022 -377.213298) (xy 137.336266 -377.159351)
			(xy 137.336266 -377.104849) (xy 137.344022 -377.050902) (xy 137.359376 -376.998607) (xy 137.382016 -376.94903)
			(xy 137.411481 -376.903179) (xy 137.447171 -376.861988) (xy 137.48836 -376.826296) (xy 137.534209 -376.796828)
			(xy 137.583785 -376.774185) (xy 137.636078 -376.758827) (xy 137.690025 -376.751067) (xy 137.717276 -376.75058)
			(xy 137.749808 -376.751259) (xy 137.813918 -376.762377) (xy 137.844784 -376.772678) (xy 137.85342 -376.775726)
			(xy 137.8712 -376.775472) (xy 137.949686 -376.746008) (xy 137.962894 -376.734578) (xy 137.967466 -376.72645)
			(xy 137.987278 -376.694192) (xy 137.991334 -376.687786) (xy 137.995853 -376.67332) (xy 137.996168 -376.665744)
			(xy 137.996168 -376.384312) (xy 137.995851 -376.376737) (xy 137.99133 -376.362273) (xy 137.987278 -376.355864)
			(xy 137.967466 -376.323606) (xy 137.962894 -376.315478) (xy 137.949686 -376.304048) (xy 137.8712 -376.274584)
			(xy 137.85342 -376.27433) (xy 137.844784 -376.277378) (xy 137.813913 -376.287661) (xy 137.749806 -376.298773)
			(xy 137.717276 -376.299476) (xy 137.690024 -376.299053) (xy 137.636074 -376.291293) (xy 137.583778 -376.275934)
			(xy 137.534199 -376.25329) (xy 137.488348 -376.22382) (xy 137.447157 -376.188126) (xy 137.411465 -376.146933)
			(xy 137.381999 -376.10108) (xy 137.359358 -376.0515) (xy 137.344002 -375.999203) (xy 137.336246 -375.945252)
			(xy 109.540344 -375.945252) (xy 109.526276 -375.976059) (xy 109.496814 -376.021907) (xy 109.461127 -376.063096)
			(xy 109.419942 -376.098788) (xy 109.374097 -376.128255) (xy 109.324526 -376.150899) (xy 109.272236 -376.166258)
			(xy 109.218293 -376.174019) (xy 109.191044 -376.174508) (xy 109.158512 -376.173825) (xy 109.094403 -376.16271)
			(xy 109.063536 -376.15241) (xy 109.0549 -376.149362) (xy 109.03712 -376.149616) (xy 108.958634 -376.17908)
			(xy 108.945426 -376.19051) (xy 108.940854 -376.198638) (xy 108.921042 -376.230896) (xy 108.916992 -376.237306)
			(xy 108.912469 -376.251769) (xy 108.912152 -376.259344) (xy 108.912152 -376.540776) (xy 108.912471 -376.548351)
			(xy 108.916991 -376.562815) (xy 108.921042 -376.569224) (xy 108.940854 -376.601482) (xy 108.945426 -376.60961)
			(xy 108.958634 -376.62104) (xy 109.03712 -376.650504) (xy 109.0549 -376.650758) (xy 109.063536 -376.64771)
			(xy 109.094405 -376.637422) (xy 109.158513 -376.626314) (xy 109.191044 -376.625612) (xy 109.218295 -376.626061)
			(xy 109.27224 -376.633823) (xy 109.324533 -376.649183) (xy 109.374107 -376.671827) (xy 109.419954 -376.701296)
			(xy 109.461141 -376.73699) (xy 109.49683 -376.778181) (xy 109.526294 -376.824032) (xy 109.548933 -376.873609)
			(xy 109.564287 -376.925903) (xy 109.572042 -376.979849) (xy 109.572042 -377.034351) (xy 109.564287 -377.088297)
			(xy 109.548933 -377.140591) (xy 109.526294 -377.190168) (xy 109.49683 -377.236019) (xy 109.461141 -377.27721)
			(xy 109.419954 -377.312904) (xy 109.374107 -377.342373) (xy 109.324533 -377.365017) (xy 109.27224 -377.380377)
			(xy 109.218295 -377.388139) (xy 109.191044 -377.388628) (xy 109.166972 -377.388277) (xy 109.119209 -377.382235)
			(xy 109.072584 -377.370242) (xy 109.050074 -377.361704) (xy 109.037628 -377.356624) (xy 109.01172 -377.359926)
			(xy 108.921042 -377.426728) (xy 108.91012 -377.45035) (xy 108.911136 -377.463558) (xy 108.912152 -377.49226)
			(xy 108.911666 -377.519511) (xy 108.90391 -377.573459) (xy 108.888555 -377.625754) (xy 108.865913 -377.675331)
			(xy 108.836447 -377.721181) (xy 108.800756 -377.762372) (xy 108.759565 -377.798063) (xy 108.713715 -377.827529)
			(xy 108.664138 -377.850171) (xy 108.611843 -377.865526) (xy 108.557895 -377.873282) (xy 108.503393 -377.873282)
			(xy 108.449445 -377.865526) (xy 108.39715 -377.850171) (xy 108.347573 -377.827529) (xy 108.301723 -377.798063)
			(xy 108.260532 -377.762372) (xy 108.224841 -377.721181) (xy 108.195375 -377.675331) (xy 108.172733 -377.625754)
			(xy 108.157378 -377.573459) (xy 108.149622 -377.519511) (xy 108.149136 -377.49226) (xy 108.150152 -377.463558)
			(xy 108.151168 -377.45035) (xy 108.140246 -377.426728) (xy 108.049568 -377.359926) (xy 108.02366 -377.356624)
			(xy 108.011214 -377.361704) (xy 107.988711 -377.370262) (xy 107.942084 -377.382258) (xy 107.894317 -377.388282)
			(xy 107.870244 -377.388628) (xy 107.842991 -377.388128) (xy 107.789038 -377.380376) (xy 107.736737 -377.365025)
			(xy 107.687154 -377.342386) (xy 107.641298 -377.312921) (xy 107.600102 -377.277229) (xy 107.564406 -377.236037)
			(xy 107.534935 -377.190184) (xy 107.512291 -377.140604) (xy 107.496933 -377.088305) (xy 107.489175 -377.034353)
			(xy 107.489175 -376.979847) (xy 107.496933 -376.925895) (xy 107.512291 -376.873596) (xy 107.534935 -376.824016)
			(xy 107.564406 -376.778163) (xy 107.600102 -376.736971) (xy 107.641298 -376.701279) (xy 107.687154 -376.671814)
			(xy 107.736737 -376.649175) (xy 107.789038 -376.633824) (xy 107.842991 -376.626072) (xy 107.870244 -376.625612)
			(xy 107.902776 -376.626297) (xy 107.966885 -376.637411) (xy 107.997752 -376.64771) (xy 108.006388 -376.650758)
			(xy 108.024168 -376.650504) (xy 108.102654 -376.62104) (xy 108.115862 -376.60961) (xy 108.120434 -376.601482)
			(xy 108.140246 -376.569224) (xy 108.144288 -376.562809) (xy 108.148816 -376.54835) (xy 108.149136 -376.540776)
			(xy 108.149136 -376.259344) (xy 108.148811 -376.251769) (xy 108.144295 -376.237305) (xy 108.140246 -376.230896)
			(xy 108.120434 -376.198638) (xy 108.115862 -376.19051) (xy 108.102654 -376.17908) (xy 108.024168 -376.149616)
			(xy 108.006388 -376.149362) (xy 107.997752 -376.15241) (xy 107.966884 -376.162701) (xy 107.902775 -376.173807)
			(xy 107.870244 -376.174508) (xy 107.842989 -376.174048) (xy 107.789033 -376.166296) (xy 107.73673 -376.150944)
			(xy 107.687145 -376.128304) (xy 107.641286 -376.098837) (xy 107.600088 -376.063143) (xy 107.56439 -376.021949)
			(xy 107.534918 -375.976094) (xy 107.512272 -375.926511) (xy 107.496914 -375.87421) (xy 107.489155 -375.820255)
			(xy 104.834297 -375.820255) (xy 104.839156 -375.836801) (xy 104.846913 -375.890749) (xy 104.846913 -375.945251)
			(xy 104.839156 -375.999199) (xy 104.8238 -376.051494) (xy 104.801158 -376.101071) (xy 104.771691 -376.146922)
			(xy 104.735999 -376.188111) (xy 104.694807 -376.223802) (xy 104.648956 -376.253267) (xy 104.599377 -376.275907)
			(xy 104.547082 -376.29126) (xy 104.493133 -376.299014) (xy 104.465882 -376.299476) (xy 104.43335 -376.298785)
			(xy 104.369241 -376.287675) (xy 104.338374 -376.277378) (xy 104.329738 -376.27433) (xy 104.311958 -376.274584)
			(xy 104.233472 -376.304048) (xy 104.220264 -376.315478) (xy 104.215692 -376.323606) (xy 104.19588 -376.355864)
			(xy 104.191828 -376.362259) (xy 104.187443 -376.376743) (xy 104.187244 -376.384312) (xy 104.187244 -376.665744)
			(xy 104.187527 -376.673298) (xy 104.191916 -376.687756) (xy 104.19588 -376.694192) (xy 104.215692 -376.72645)
			(xy 104.220264 -376.734578) (xy 104.233472 -376.746008) (xy 104.311958 -376.775472) (xy 104.329738 -376.775726)
			(xy 104.338374 -376.772678) (xy 104.369247 -376.762404) (xy 104.433352 -376.751287) (xy 104.465882 -376.75058)
			(xy 104.493135 -376.751066) (xy 104.547086 -376.758821) (xy 104.599384 -376.774175) (xy 104.648965 -376.796815)
			(xy 104.694819 -376.826282) (xy 104.736013 -376.861975) (xy 104.771707 -376.903166) (xy 104.801176 -376.949019)
			(xy 104.823819 -376.998599) (xy 104.839175 -377.050896) (xy 104.846933 -377.104847) (xy 104.846933 -377.159353)
			(xy 104.839175 -377.213304) (xy 104.823819 -377.265601) (xy 104.801176 -377.315181) (xy 104.771707 -377.361034)
			(xy 104.736013 -377.402225) (xy 104.694819 -377.437918) (xy 104.648965 -377.467385) (xy 104.599384 -377.490025)
			(xy 104.547086 -377.505379) (xy 104.493135 -377.513134) (xy 104.465882 -377.513596) (xy 104.441811 -377.513229)
			(xy 104.394048 -377.507193) (xy 104.347422 -377.495207) (xy 104.324912 -377.486672) (xy 104.312466 -377.481592)
			(xy 104.286558 -377.484894) (xy 104.19588 -377.551696) (xy 104.184958 -377.575318) (xy 104.185974 -377.588526)
			(xy 104.18699 -377.617228) (xy 104.186504 -377.644479) (xy 104.178748 -377.698427) (xy 104.163393 -377.750722)
			(xy 104.140751 -377.800299) (xy 104.111285 -377.846149) (xy 104.075594 -377.88734) (xy 104.034403 -377.923031)
			(xy 103.988553 -377.952497) (xy 103.938976 -377.975139) (xy 103.886681 -377.990494) (xy 103.832733 -377.99825)
			(xy 103.778231 -377.99825) (xy 103.724283 -377.990494) (xy 103.671988 -377.975139) (xy 103.622411 -377.952497)
			(xy 103.576561 -377.923031) (xy 103.53537 -377.88734) (xy 103.499679 -377.846149) (xy 103.470213 -377.800299)
			(xy 103.447571 -377.750722) (xy 103.432216 -377.698427) (xy 103.42446 -377.644479) (xy 103.423974 -377.617228)
			(xy 103.42499 -377.588526) (xy 103.426006 -377.575318) (xy 103.415084 -377.551696) (xy 103.324406 -377.484894)
			(xy 103.298498 -377.481592) (xy 103.286052 -377.486672) (xy 103.263546 -377.495222) (xy 103.216921 -377.50722)
			(xy 103.169155 -377.513247) (xy 103.145082 -377.513596) (xy 103.117831 -377.513133) (xy 103.063883 -377.505374)
			(xy 103.011589 -377.490017) (xy 102.962013 -377.467374) (xy 102.916163 -377.437906) (xy 102.874974 -377.402214)
			(xy 102.839283 -377.361023) (xy 102.809817 -377.315172) (xy 102.787177 -377.265594) (xy 102.771822 -377.213299)
			(xy 102.764066 -377.159351) (xy 102.764066 -377.104849) (xy 102.771822 -377.050901) (xy 102.787177 -376.998606)
			(xy 102.809817 -376.949028) (xy 102.839283 -376.903177) (xy 102.874974 -376.861986) (xy 102.916163 -376.826294)
			(xy 102.962013 -376.796826) (xy 103.011589 -376.774183) (xy 103.063883 -376.758826) (xy 103.117831 -376.751067)
			(xy 103.145082 -376.75058) (xy 103.177613 -376.751282) (xy 103.241723 -376.762385) (xy 103.27259 -376.772678)
			(xy 103.281226 -376.775726) (xy 103.299006 -376.775472) (xy 103.377492 -376.746008) (xy 103.3907 -376.734578)
			(xy 103.395272 -376.72645) (xy 103.415084 -376.694192) (xy 103.419111 -376.687783) (xy 103.423512 -376.67331)
			(xy 103.42372 -376.665744) (xy 103.42372 -376.384312) (xy 103.42346 -376.376756) (xy 103.419056 -376.362298)
			(xy 103.415084 -376.355864) (xy 103.395272 -376.323606) (xy 103.3907 -376.315478) (xy 103.377492 -376.304048)
			(xy 103.299006 -376.274584) (xy 103.281226 -376.27433) (xy 103.27259 -376.277378) (xy 103.241719 -376.287659)
			(xy 103.177612 -376.298772) (xy 103.145082 -376.299476) (xy 103.117829 -376.299053) (xy 103.063879 -376.291294)
			(xy 103.011582 -376.275936) (xy 102.962003 -376.253292) (xy 102.916151 -376.223822) (xy 102.874959 -376.188128)
			(xy 102.839267 -376.146935) (xy 102.8098 -376.101081) (xy 102.787158 -376.051501) (xy 102.771803 -375.999203)
			(xy 102.764046 -375.945253) (xy 74.968269 -375.945253) (xy 74.954182 -375.976096) (xy 74.924709 -376.021951)
			(xy 74.88901 -376.063145) (xy 74.847811 -376.098839) (xy 74.801952 -376.128306) (xy 74.752365 -376.150945)
			(xy 74.700062 -376.166297) (xy 74.646105 -376.174048) (xy 74.61885 -376.174508) (xy 74.586318 -376.173824)
			(xy 74.522209 -376.162709) (xy 74.491342 -376.15241) (xy 74.482706 -376.149362) (xy 74.464926 -376.149616)
			(xy 74.38644 -376.17908) (xy 74.373232 -376.19051) (xy 74.36866 -376.198638) (xy 74.348848 -376.230896)
			(xy 74.344828 -376.237309) (xy 74.340422 -376.251779) (xy 74.340212 -376.259344) (xy 74.340212 -376.540776)
			(xy 74.340472 -376.548332) (xy 74.344875 -376.56279) (xy 74.348848 -376.569224) (xy 74.36866 -376.601482)
			(xy 74.373232 -376.60961) (xy 74.38644 -376.62104) (xy 74.464926 -376.650504) (xy 74.482706 -376.650758)
			(xy 74.491342 -376.64771) (xy 74.522211 -376.637421) (xy 74.586319 -376.626313) (xy 74.61885 -376.625612)
			(xy 74.646107 -376.626031) (xy 74.700066 -376.633783) (xy 74.752373 -376.649136) (xy 74.801962 -376.671776)
			(xy 74.847823 -376.701245) (xy 74.889024 -376.73694) (xy 74.924725 -376.778136) (xy 74.9542 -376.823994)
			(xy 74.976847 -376.873581) (xy 74.992206 -376.925885) (xy 74.999965 -376.979843) (xy 74.999965 -377.034357)
			(xy 74.992206 -377.088315) (xy 74.976847 -377.140619) (xy 74.9542 -377.190206) (xy 74.924725 -377.236064)
			(xy 74.889024 -377.27726) (xy 74.847823 -377.312955) (xy 74.801962 -377.342424) (xy 74.752373 -377.365064)
			(xy 74.700066 -377.380417) (xy 74.646107 -377.388169) (xy 74.61885 -377.388628) (xy 74.594778 -377.388275)
			(xy 74.547015 -377.382234) (xy 74.50039 -377.370242) (xy 74.47788 -377.361704) (xy 74.465434 -377.356624)
			(xy 74.439526 -377.359926) (xy 74.348848 -377.426728) (xy 74.337926 -377.45035) (xy 74.338942 -377.463558)
			(xy 74.339958 -377.49226) (xy 74.339472 -377.519511) (xy 74.331716 -377.573459) (xy 74.316361 -377.625754)
			(xy 74.293719 -377.675331) (xy 74.264253 -377.721181) (xy 74.228562 -377.762372) (xy 74.187371 -377.798063)
			(xy 74.141521 -377.827529) (xy 74.091944 -377.850171) (xy 74.039649 -377.865526) (xy 73.985701 -377.873282)
			(xy 73.931199 -377.873282) (xy 73.877251 -377.865526) (xy 73.824956 -377.850171) (xy 73.775379 -377.827529)
			(xy 73.729529 -377.798063) (xy 73.688338 -377.762372) (xy 73.652647 -377.721181) (xy 73.623181 -377.675331)
			(xy 73.600539 -377.625754) (xy 73.585184 -377.573459) (xy 73.577428 -377.519511) (xy 73.576942 -377.49226)
			(xy 73.577958 -377.463558) (xy 73.578974 -377.45035) (xy 73.568052 -377.426728) (xy 73.477374 -377.359926)
			(xy 73.451466 -377.356624) (xy 73.43902 -377.361704) (xy 73.416516 -377.37026) (xy 73.36989 -377.382257)
			(xy 73.322123 -377.388281) (xy 73.29805 -377.388628) (xy 73.270803 -377.388098) (xy 73.216863 -377.380336)
			(xy 73.164577 -377.364978) (xy 73.115009 -377.342335) (xy 73.069167 -377.312869) (xy 73.027985 -377.277179)
			(xy 72.992301 -377.235993) (xy 72.962841 -377.190147) (xy 72.940205 -377.140576) (xy 72.924853 -377.088288)
			(xy 72.917098 -377.034348) (xy 72.917098 -376.979852) (xy 72.924853 -376.925912) (xy 72.940205 -376.873624)
			(xy 72.962841 -376.824053) (xy 72.992301 -376.778207) (xy 73.027985 -376.737021) (xy 73.069167 -376.701331)
			(xy 73.115009 -376.671865) (xy 73.164577 -376.649222) (xy 73.216863 -376.633864) (xy 73.270803 -376.626102)
			(xy 73.29805 -376.625612) (xy 73.330582 -376.626295) (xy 73.394692 -376.63741) (xy 73.425558 -376.64771)
			(xy 73.434194 -376.650758) (xy 73.451974 -376.650504) (xy 73.53046 -376.62104) (xy 73.543668 -376.60961)
			(xy 73.54824 -376.601482) (xy 73.568052 -376.569224) (xy 73.572103 -376.562828) (xy 73.57649 -376.548345)
			(xy 73.576688 -376.540776) (xy 73.576688 -376.259344) (xy 73.57642 -376.251789) (xy 73.572023 -376.23733)
			(xy 73.568052 -376.230896) (xy 73.54824 -376.198638) (xy 73.543668 -376.19051) (xy 73.53046 -376.17908)
			(xy 73.451974 -376.149616) (xy 73.434194 -376.149362) (xy 73.425558 -376.15241) (xy 73.39469 -376.1627)
			(xy 73.330581 -376.173807) (xy 73.29805 -376.174508) (xy 73.270801 -376.174019) (xy 73.216859 -376.166257)
			(xy 73.16457 -376.150897) (xy 73.114999 -376.128253) (xy 73.069155 -376.098785) (xy 73.027971 -376.063094)
			(xy 72.992285 -376.021905) (xy 72.962823 -375.976057) (xy 72.940185 -375.926483) (xy 72.924833 -375.874192)
			(xy 72.917078 -375.820249) (xy 72.306472 -375.820249) (xy 72.311335 -375.836812) (xy 72.31909 -375.890753)
			(xy 72.31909 -375.945247) (xy 72.311335 -375.999188) (xy 72.295983 -376.051475) (xy 72.273346 -376.101046)
			(xy 72.243885 -376.146891) (xy 72.208201 -376.188077) (xy 72.167018 -376.223765) (xy 72.121176 -376.25323)
			(xy 72.071607 -376.275871) (xy 72.019321 -376.291228) (xy 71.965381 -376.298987) (xy 71.938134 -376.299476)
			(xy 71.905602 -376.298797) (xy 71.841492 -376.287679) (xy 71.810626 -376.277378) (xy 71.80199 -376.27433)
			(xy 71.78421 -376.274584) (xy 71.705724 -376.304048) (xy 71.692516 -376.315478) (xy 71.687944 -376.323606)
			(xy 71.668132 -376.355864) (xy 71.664085 -376.362262) (xy 71.659696 -376.376744) (xy 71.659496 -376.384312)
			(xy 71.659496 -376.665744) (xy 71.659771 -376.673299) (xy 71.664164 -376.687757) (xy 71.668132 -376.694192)
			(xy 71.687944 -376.72645) (xy 71.692516 -376.734578) (xy 71.705724 -376.746008) (xy 71.78421 -376.775472)
			(xy 71.80199 -376.775726) (xy 71.810626 -376.772678) (xy 71.841495 -376.762392) (xy 71.905603 -376.751282)
			(xy 71.938134 -376.75058) (xy 71.965383 -376.751093) (xy 72.019325 -376.758853) (xy 72.071614 -376.77421)
			(xy 72.121185 -376.796853) (xy 72.16703 -376.826319) (xy 72.208215 -376.862009) (xy 72.243901 -376.903197)
			(xy 72.273364 -376.949045) (xy 72.296002 -376.998618) (xy 72.311354 -377.050908) (xy 72.31911 -377.104851)
			(xy 72.31911 -377.159349) (xy 72.311354 -377.213292) (xy 72.296002 -377.265582) (xy 72.273364 -377.315155)
			(xy 72.243901 -377.361003) (xy 72.208215 -377.402191) (xy 72.16703 -377.437881) (xy 72.121185 -377.467347)
			(xy 72.071614 -377.48999) (xy 72.019325 -377.505347) (xy 71.965383 -377.513107) (xy 71.938134 -377.513596)
			(xy 71.914062 -377.513243) (xy 71.8663 -377.507202) (xy 71.819674 -377.495209) (xy 71.797164 -377.486672)
			(xy 71.784718 -377.481592) (xy 71.75881 -377.484894) (xy 71.668132 -377.551696) (xy 71.65721 -377.575318)
			(xy 71.658226 -377.588526) (xy 71.659242 -377.617228) (xy 71.658756 -377.644479) (xy 71.651 -377.698427)
			(xy 71.635645 -377.750722) (xy 71.613003 -377.800299) (xy 71.583537 -377.846149) (xy 71.547846 -377.88734)
			(xy 71.506655 -377.923031) (xy 71.460805 -377.952497) (xy 71.411228 -377.975139) (xy 71.358933 -377.990494)
			(xy 71.304985 -377.99825) (xy 71.250483 -377.99825) (xy 71.196535 -377.990494) (xy 71.14424 -377.975139)
			(xy 71.094663 -377.952497) (xy 71.048813 -377.923031) (xy 71.007622 -377.88734) (xy 70.971931 -377.846149)
			(xy 70.942465 -377.800299) (xy 70.919823 -377.750722) (xy 70.904468 -377.698427) (xy 70.896712 -377.644479)
			(xy 70.896226 -377.617228) (xy 70.897242 -377.588526) (xy 70.898258 -377.575318) (xy 70.887336 -377.551696)
			(xy 70.796658 -377.484894) (xy 70.77075 -377.481592) (xy 70.758304 -377.486672) (xy 70.735803 -377.495236)
			(xy 70.689175 -377.507229) (xy 70.641407 -377.51325) (xy 70.617334 -377.513596) (xy 70.590079 -377.513159)
			(xy 70.536122 -377.505406) (xy 70.483819 -377.490053) (xy 70.434233 -377.467411) (xy 70.388374 -377.437943)
			(xy 70.347176 -377.402248) (xy 70.311477 -377.361053) (xy 70.282005 -377.315197) (xy 70.259359 -377.265613)
			(xy 70.244001 -377.213311) (xy 70.236243 -377.159355) (xy 70.236243 -377.104845) (xy 70.244001 -377.050889)
			(xy 70.259359 -376.998587) (xy 70.282005 -376.949003) (xy 70.311477 -376.903147) (xy 70.347176 -376.861952)
			(xy 70.388374 -376.826257) (xy 70.434233 -376.796789) (xy 70.483819 -376.774147) (xy 70.536122 -376.758794)
			(xy 70.590079 -376.751041) (xy 70.617334 -376.75058) (xy 70.649866 -376.751269) (xy 70.713975 -376.76238)
			(xy 70.744842 -376.772678) (xy 70.753478 -376.775726) (xy 70.771258 -376.775472) (xy 70.849744 -376.746008)
			(xy 70.862952 -376.734578) (xy 70.867524 -376.72645) (xy 70.887336 -376.694192) (xy 70.891368 -376.687786)
			(xy 70.895765 -376.67331) (xy 70.895972 -376.665744) (xy 70.895972 -376.384312) (xy 70.895705 -376.376757)
			(xy 70.891305 -376.362299) (xy 70.887336 -376.355864) (xy 70.867524 -376.323606) (xy 70.862952 -376.315478)
			(xy 70.849744 -376.304048) (xy 70.771258 -376.274584) (xy 70.753478 -376.27433) (xy 70.744842 -376.277378)
			(xy 70.713974 -376.287671) (xy 70.649865 -376.298776) (xy 70.617334 -376.299476) (xy 70.590077 -376.299079)
			(xy 70.536118 -376.291326) (xy 70.483812 -376.275971) (xy 70.434223 -376.253329) (xy 70.388362 -376.223859)
			(xy 70.347162 -376.188163) (xy 70.311461 -376.146965) (xy 70.281987 -376.101107) (xy 70.259341 -376.05152)
			(xy 70.243982 -375.999215) (xy 70.236223 -375.945257) (xy 42.440442 -375.945257) (xy 42.42637 -375.97607)
			(xy 42.396904 -376.021921) (xy 42.361212 -376.063111) (xy 42.320022 -376.098802) (xy 42.274172 -376.128269)
			(xy 42.224595 -376.15091) (xy 42.172301 -376.166265) (xy 42.118353 -376.174022) (xy 42.091102 -376.174508)
			(xy 42.058572 -376.173803) (xy 41.994466 -376.162688) (xy 41.963594 -376.15241) (xy 41.954958 -376.149362)
			(xy 41.937178 -376.149616) (xy 41.858692 -376.17908) (xy 41.845484 -376.19051) (xy 41.840912 -376.198638)
			(xy 41.8211 -376.230896) (xy 41.817133 -376.237331) (xy 41.812739 -376.251789) (xy 41.812464 -376.259344)
			(xy 41.812464 -376.540776) (xy 41.812662 -376.548345) (xy 41.817045 -376.562831) (xy 41.8211 -376.569224)
			(xy 41.840912 -376.601482) (xy 41.845484 -376.60961) (xy 41.858692 -376.62104) (xy 41.937178 -376.650504)
			(xy 41.954958 -376.650758) (xy 41.963594 -376.64771) (xy 41.994461 -376.637414) (xy 42.05857 -376.626308)
			(xy 42.091102 -376.625612) (xy 42.118352 -376.626098) (xy 42.172296 -376.633855) (xy 42.224588 -376.649209)
			(xy 42.274162 -376.671849) (xy 42.32001 -376.701314) (xy 42.361198 -376.737004) (xy 42.396887 -376.778192)
			(xy 42.426352 -376.824039) (xy 42.448992 -376.873614) (xy 42.464346 -376.925906) (xy 42.472102 -376.97985)
			(xy 42.472102 -377.03435) (xy 42.464346 -377.088294) (xy 42.448992 -377.140586) (xy 42.426352 -377.190161)
			(xy 42.396887 -377.236008) (xy 42.361198 -377.277196) (xy 42.32001 -377.312886) (xy 42.274162 -377.342351)
			(xy 42.224588 -377.364991) (xy 42.172296 -377.380345) (xy 42.118352 -377.388102) (xy 42.091102 -377.388628)
			(xy 42.06703 -377.388278) (xy 42.019265 -377.382248) (xy 41.972641 -377.370246) (xy 41.950132 -377.361704)
			(xy 41.937686 -377.356624) (xy 41.911778 -377.359926) (xy 41.8211 -377.426728) (xy 41.810178 -377.45035)
			(xy 41.811194 -377.463558) (xy 41.81221 -377.49226) (xy 41.811724 -377.519511) (xy 41.803968 -377.573459)
			(xy 41.788613 -377.625754) (xy 41.765971 -377.675331) (xy 41.736505 -377.721181) (xy 41.700814 -377.762372)
			(xy 41.659623 -377.798063) (xy 41.613773 -377.827529) (xy 41.564196 -377.850171) (xy 41.511901 -377.865526)
			(xy 41.457953 -377.873282) (xy 41.403451 -377.873282) (xy 41.349503 -377.865526) (xy 41.297208 -377.850171)
			(xy 41.247631 -377.827529) (xy 41.201781 -377.798063) (xy 41.16059 -377.762372) (xy 41.124899 -377.721181)
			(xy 41.095433 -377.675331) (xy 41.072791 -377.625754) (xy 41.057436 -377.573459) (xy 41.04968 -377.519511)
			(xy 41.049194 -377.49226) (xy 41.05021 -377.463558) (xy 41.051226 -377.45035) (xy 41.040304 -377.426728)
			(xy 40.949626 -377.359926) (xy 40.923718 -377.356624) (xy 40.911272 -377.361704) (xy 40.888762 -377.370239)
			(xy 40.842136 -377.382226) (xy 40.794373 -377.38826) (xy 40.770302 -377.388628) (xy 40.746096 -377.38825)
			(xy 40.698073 -377.382133) (xy 40.674544 -377.376436) (xy 40.66286 -377.373388) (xy 40.640254 -377.37796)
			(xy 40.567102 -377.434602) (xy 40.558276 -377.442193) (xy 40.548102 -377.463104) (xy 40.547544 -377.474734)
			(xy 40.547544 -378.616464) (xy 40.547023 -378.648095) (xy 40.538762 -378.710814) (xy 40.522388 -378.77192)
			(xy 40.498183 -378.830367) (xy 40.466559 -378.885157) (xy 40.428057 -378.935353) (xy 40.406066 -378.958094)
			(xy 39.801598 -379.56236) (xy 40.974772 -379.56236) (xy 40.975339 -379.528079) (xy 40.984561 -379.460139)
			(xy 41.00283 -379.394055) (xy 41.029817 -379.331026) (xy 41.065031 -379.272197) (xy 41.107833 -379.218636)
			(xy 41.132252 -379.194568) (xy 41.139618 -379.187456) (xy 41.147492 -379.16993) (xy 41.151302 -379.079506)
			(xy 41.144698 -379.061218) (xy 41.138094 -379.053598) (xy 41.118103 -379.030275) (xy 41.083219 -378.979713)
			(xy 41.054679 -378.925317) (xy 41.032902 -378.867878) (xy 41.018203 -378.808234) (xy 41.010798 -378.747254)
			(xy 41.010332 -378.71654) (xy 41.010834 -378.684579) (xy 41.018845 -378.621161) (xy 41.034742 -378.559247)
			(xy 41.058274 -378.499814) (xy 41.089068 -378.443799) (xy 41.126641 -378.392084) (xy 41.170398 -378.345487)
			(xy 41.219651 -378.304742) (xy 41.273622 -378.270491) (xy 41.331461 -378.243274) (xy 41.392254 -378.223521)
			(xy 41.455044 -378.211543) (xy 41.51884 -378.20753) (xy 41.582636 -378.211543) (xy 41.645426 -378.223521)
			(xy 41.706219 -378.243274) (xy 41.764058 -378.270491) (xy 41.818029 -378.304742) (xy 41.867282 -378.345487)
			(xy 41.911039 -378.392084) (xy 41.948612 -378.443799) (xy 41.979406 -378.499814) (xy 41.998234 -378.547367)
			(xy 43.149507 -378.547367) (xy 43.149507 -378.479313) (xy 43.157407 -378.41172) (xy 43.173101 -378.345502)
			(xy 43.196377 -378.281553) (xy 43.226919 -378.220738) (xy 43.264315 -378.163881) (xy 43.308058 -378.111749)
			(xy 43.357558 -378.065048) (xy 43.412145 -378.02441) (xy 43.471081 -377.990383) (xy 43.533569 -377.963429)
			(xy 43.598763 -377.943911) (xy 43.665782 -377.932093) (xy 43.73372 -377.928137) (xy 43.801658 -377.932093)
			(xy 43.868677 -377.943911) (xy 43.933871 -377.963429) (xy 43.996359 -377.990383) (xy 44.055295 -378.02441)
			(xy 44.109882 -378.065048) (xy 44.159382 -378.111749) (xy 44.203125 -378.163881) (xy 44.240521 -378.220738)
			(xy 44.271063 -378.281553) (xy 44.294339 -378.345502) (xy 44.310033 -378.41172) (xy 44.317933 -378.479313)
			(xy 44.318428 -378.51334) (xy 44.317933 -378.547367) (xy 44.310033 -378.61496) (xy 44.294339 -378.681178)
			(xy 44.271063 -378.745127) (xy 44.240521 -378.805942) (xy 44.203125 -378.862799) (xy 44.159382 -378.914931)
			(xy 44.109882 -378.961632) (xy 44.055295 -379.00227) (xy 43.996359 -379.036297) (xy 43.933871 -379.063251)
			(xy 43.868677 -379.082769) (xy 43.801658 -379.094587) (xy 43.73372 -379.098544) (xy 43.665782 -379.094587)
			(xy 43.598763 -379.082769) (xy 43.533569 -379.063251) (xy 43.471081 -379.036297) (xy 43.412145 -379.00227)
			(xy 43.357558 -378.961632) (xy 43.308058 -378.914931) (xy 43.264315 -378.862799) (xy 43.226919 -378.805942)
			(xy 43.196377 -378.745127) (xy 43.173101 -378.681178) (xy 43.157407 -378.61496) (xy 43.149507 -378.547367)
			(xy 41.998234 -378.547367) (xy 42.002938 -378.559247) (xy 42.018835 -378.621161) (xy 42.026846 -378.684579)
			(xy 42.027348 -378.71654) (xy 42.026805 -378.750822) (xy 42.017582 -378.818764) (xy 41.999309 -378.88485)
			(xy 41.972318 -378.947879) (xy 41.937099 -379.006707) (xy 41.89429 -379.060266) (xy 41.869868 -379.084332)
			(xy 41.862502 -379.091444) (xy 41.854628 -379.10897) (xy 41.850818 -379.199394) (xy 41.857422 -379.217682)
			(xy 41.864026 -379.225302) (xy 41.88402 -379.248623) (xy 41.918904 -379.299185) (xy 41.947442 -379.353582)
			(xy 41.969219 -379.411021) (xy 41.983917 -379.470665) (xy 41.991322 -379.531646) (xy 41.991788 -379.56236)
			(xy 41.991286 -379.594321) (xy 41.983275 -379.657739) (xy 41.967378 -379.719653) (xy 41.943846 -379.779086)
			(xy 41.913052 -379.835101) (xy 41.875479 -379.886816) (xy 41.859599 -379.903727) (xy 43.121567 -379.903727)
			(xy 43.121567 -379.835673) (xy 43.129467 -379.76808) (xy 43.145161 -379.701862) (xy 43.168437 -379.637913)
			(xy 43.198979 -379.577098) (xy 43.236375 -379.520241) (xy 43.280118 -379.468109) (xy 43.329618 -379.421408)
			(xy 43.384205 -379.38077) (xy 43.443141 -379.346743) (xy 43.505629 -379.319789) (xy 43.570823 -379.300271)
			(xy 43.637842 -379.288453) (xy 43.70578 -379.284497) (xy 43.773718 -379.288453) (xy 43.840737 -379.300271)
			(xy 43.905931 -379.319789) (xy 43.968419 -379.346743) (xy 44.027355 -379.38077) (xy 44.081942 -379.421408)
			(xy 44.131442 -379.468109) (xy 44.175185 -379.520241) (xy 44.212581 -379.577098) (xy 44.243123 -379.637913)
			(xy 44.266399 -379.701862) (xy 44.282093 -379.76808) (xy 44.289993 -379.835673) (xy 44.290488 -379.8697)
			(xy 44.289993 -379.903727) (xy 44.282093 -379.97132) (xy 44.266399 -380.037538) (xy 44.243123 -380.101487)
			(xy 44.212581 -380.162302) (xy 44.175185 -380.219159) (xy 44.131442 -380.271291) (xy 44.081942 -380.317992)
			(xy 44.027355 -380.35863) (xy 43.968419 -380.392657) (xy 43.905931 -380.419611) (xy 43.840737 -380.439129)
			(xy 43.773718 -380.450947) (xy 43.70578 -380.454904) (xy 43.637842 -380.450947) (xy 43.570823 -380.439129)
			(xy 43.505629 -380.419611) (xy 43.443141 -380.392657) (xy 43.384205 -380.35863) (xy 43.329618 -380.317992)
			(xy 43.280118 -380.271291) (xy 43.236375 -380.219159) (xy 43.198979 -380.162302) (xy 43.168437 -380.101487)
			(xy 43.145161 -380.037538) (xy 43.129467 -379.97132) (xy 43.121567 -379.903727) (xy 41.859599 -379.903727)
			(xy 41.831722 -379.933413) (xy 41.782469 -379.974158) (xy 41.728498 -380.008409) (xy 41.670659 -380.035626)
			(xy 41.609866 -380.055379) (xy 41.547076 -380.067357) (xy 41.48328 -380.071371) (xy 41.419484 -380.067357)
			(xy 41.356694 -380.055379) (xy 41.295901 -380.035626) (xy 41.238062 -380.008409) (xy 41.184091 -379.974158)
			(xy 41.134838 -379.933413) (xy 41.091081 -379.886816) (xy 41.053508 -379.835101) (xy 41.022714 -379.779086)
			(xy 40.999182 -379.719653) (xy 40.983285 -379.657739) (xy 40.975274 -379.594321) (xy 40.974772 -379.56236)
			(xy 39.801598 -379.56236) (xy 39.645336 -379.71857) (xy 39.638643 -379.725976) (xy 39.631045 -379.744413)
			(xy 39.630604 -379.754384) (xy 39.630604 -381.357453) (xy 40.389255 -381.357453) (xy 40.389255 -381.302947)
			(xy 40.397012 -381.248996) (xy 40.412368 -381.196698) (xy 40.435011 -381.147118) (xy 40.464479 -381.101264)
			(xy 40.500173 -381.060072) (xy 40.541366 -381.024378) (xy 40.587219 -380.99491) (xy 40.6368 -380.972268)
			(xy 40.689098 -380.956912) (xy 40.743049 -380.949155) (xy 40.770302 -380.948692) (xy 40.79424 -380.949038)
			(xy 40.84174 -380.955014) (xy 40.888117 -380.966896) (xy 40.91051 -380.975362) (xy 40.922448 -380.980188)
			(xy 40.94734 -380.97714) (xy 41.038272 -380.913894) (xy 41.049448 -380.891796) (xy 41.049194 -380.878588)
			(xy 41.049194 -380.87046) (xy 41.04968 -380.843209) (xy 41.057436 -380.789261) (xy 41.072791 -380.736966)
			(xy 41.095433 -380.687389) (xy 41.124899 -380.641539) (xy 41.16059 -380.600348) (xy 41.201781 -380.564657)
			(xy 41.247631 -380.535191) (xy 41.297208 -380.512549) (xy 41.349503 -380.497194) (xy 41.403451 -380.489438)
			(xy 41.457953 -380.489438) (xy 41.511901 -380.497194) (xy 41.564196 -380.512549) (xy 41.613773 -380.535191)
			(xy 41.659623 -380.564657) (xy 41.700814 -380.600348) (xy 41.736505 -380.641539) (xy 41.765971 -380.687389)
			(xy 41.788613 -380.736966) (xy 41.803968 -380.789261) (xy 41.811724 -380.843209) (xy 41.81221 -380.87046)
			(xy 41.81221 -380.878588) (xy 41.811956 -380.891796) (xy 41.823132 -380.913894) (xy 41.914064 -380.97714)
			(xy 41.938956 -380.980188) (xy 41.950894 -380.975362) (xy 41.973299 -380.966934) (xy 42.019673 -380.95506)
			(xy 42.067167 -380.94907) (xy 42.091102 -380.948692) (xy 42.118353 -380.949178) (xy 42.172301 -380.956935)
			(xy 42.224595 -380.97229) (xy 42.274172 -380.994931) (xy 42.320022 -381.024398) (xy 42.361212 -381.060089)
			(xy 42.396904 -381.101279) (xy 42.42637 -381.14713) (xy 42.449011 -381.196707) (xy 42.464366 -381.249001)
			(xy 42.472122 -381.302949) (xy 42.472122 -381.357451) (xy 42.464366 -381.411399) (xy 42.449011 -381.463693)
			(xy 42.42637 -381.51327) (xy 42.396904 -381.559121) (xy 42.361212 -381.600311) (xy 42.320022 -381.636002)
			(xy 42.274172 -381.665469) (xy 42.224595 -381.68811) (xy 42.172301 -381.703465) (xy 42.118353 -381.711222)
			(xy 42.091102 -381.711708) (xy 42.05857 -381.711011) (xy 41.994461 -381.699905) (xy 41.963594 -381.68961)
			(xy 41.954958 -381.686562) (xy 41.937178 -381.686816) (xy 41.858692 -381.71628) (xy 41.845484 -381.72771)
			(xy 41.840912 -381.735838) (xy 41.8211 -381.768096) (xy 41.817076 -381.774506) (xy 41.812673 -381.788979)
			(xy 41.812464 -381.796544) (xy 41.812464 -382.077976) (xy 41.812731 -382.085531) (xy 41.81713 -382.099989)
			(xy 41.8211 -382.106424) (xy 41.840912 -382.138682) (xy 41.845484 -382.14681) (xy 41.858692 -382.15824)
			(xy 41.937178 -382.187704) (xy 41.954958 -382.187958) (xy 41.963594 -382.18491) (xy 41.994466 -382.174632)
			(xy 42.058572 -382.163517) (xy 42.091102 -382.162812) (xy 42.118355 -382.163258) (xy 42.172305 -382.171015)
			(xy 42.224602 -382.186371) (xy 42.274182 -382.209014) (xy 42.320034 -382.238482) (xy 42.361226 -382.274175)
			(xy 42.39692 -382.315367) (xy 42.426387 -382.36122) (xy 42.449029 -382.4108) (xy 42.464385 -382.463097)
			(xy 42.472142 -382.517047) (xy 42.472142 -382.571553) (xy 42.464385 -382.625503) (xy 42.449029 -382.6778)
			(xy 42.426387 -382.72738) (xy 42.39692 -382.773233) (xy 42.361226 -382.814425) (xy 42.320034 -382.850118)
			(xy 42.274182 -382.879586) (xy 42.224602 -382.902229) (xy 42.172305 -382.917585) (xy 42.118355 -382.925342)
			(xy 42.091102 -382.925828) (xy 42.067031 -382.925459) (xy 42.019268 -382.919425) (xy 41.972642 -382.907439)
			(xy 41.950132 -382.898904) (xy 41.937686 -382.893824) (xy 41.912032 -382.897126) (xy 41.8211 -382.963674)
			(xy 41.810432 -382.987042) (xy 41.811194 -383.000504) (xy 41.81221 -383.027428) (xy 41.811724 -383.054679)
			(xy 41.803968 -383.108627) (xy 41.788613 -383.160922) (xy 41.765971 -383.210499) (xy 41.736505 -383.256349)
			(xy 41.700814 -383.29754) (xy 41.659623 -383.333231) (xy 41.613773 -383.362697) (xy 41.564196 -383.385339)
			(xy 41.511901 -383.400694) (xy 41.457953 -383.40845) (xy 41.403451 -383.40845) (xy 41.349503 -383.400694)
			(xy 41.297208 -383.385339) (xy 41.247631 -383.362697) (xy 41.201781 -383.333231) (xy 41.16059 -383.29754)
			(xy 41.124899 -383.256349) (xy 41.095433 -383.210499) (xy 41.072791 -383.160922) (xy 41.057436 -383.108627)
			(xy 41.04968 -383.054679) (xy 41.049194 -383.027428) (xy 41.05021 -383.000504) (xy 41.050972 -382.987042)
			(xy 41.040304 -382.963674) (xy 40.949372 -382.897126) (xy 40.923718 -382.893824) (xy 40.911272 -382.898904)
			(xy 40.888763 -382.907445) (xy 40.842139 -382.919448) (xy 40.794374 -382.925478) (xy 40.770302 -382.925828)
			(xy 40.74305 -382.925325) (xy 40.689102 -382.917569) (xy 40.636807 -382.902213) (xy 40.587229 -382.879572)
			(xy 40.541378 -382.850106) (xy 40.500187 -382.814414) (xy 40.464495 -382.773224) (xy 40.435029 -382.727373)
			(xy 40.412387 -382.677795) (xy 40.397032 -382.6255) (xy 40.389275 -382.571552) (xy 40.389275 -382.517048)
			(xy 40.397032 -382.4631) (xy 40.412387 -382.410805) (xy 40.435029 -382.361227) (xy 40.464495 -382.315376)
			(xy 40.500187 -382.274186) (xy 40.541378 -382.238494) (xy 40.587229 -382.209028) (xy 40.636807 -382.186387)
			(xy 40.689102 -382.171031) (xy 40.74305 -382.163275) (xy 40.770302 -382.162812) (xy 40.802834 -382.163507)
			(xy 40.866943 -382.174614) (xy 40.89781 -382.18491) (xy 40.906446 -382.187958) (xy 40.924226 -382.187704)
			(xy 41.002712 -382.15824) (xy 41.01592 -382.14681) (xy 41.020492 -382.138682) (xy 41.040304 -382.106424)
			(xy 41.04436 -382.100031) (xy 41.048743 -382.085545) (xy 41.04894 -382.077976) (xy 41.04894 -381.796544)
			(xy 41.048664 -381.788989) (xy 41.044271 -381.774531) (xy 41.040304 -381.768096) (xy 41.020492 -381.735838)
			(xy 41.01592 -381.72771) (xy 41.002712 -381.71628) (xy 40.924226 -381.686816) (xy 40.906446 -381.686562)
			(xy 40.89781 -381.68961) (xy 40.866938 -381.699887) (xy 40.802832 -381.711002) (xy 40.770302 -381.711708)
			(xy 40.743049 -381.711245) (xy 40.689098 -381.703488) (xy 40.6368 -381.688132) (xy 40.587219 -381.66549)
			(xy 40.541366 -381.636022) (xy 40.500173 -381.600328) (xy 40.464479 -381.559136) (xy 40.435011 -381.513282)
			(xy 40.412368 -381.463702) (xy 40.397012 -381.411404) (xy 40.389255 -381.357453) (xy 39.630604 -381.357453)
			(xy 39.630604 -386.391658) (xy 39.631089 -386.401621) (xy 39.638675 -386.420047) (xy 39.645336 -386.427472)
			(xy 40.140382 -386.922518) (xy 40.169084 -386.928614) (xy 40.183308 -386.923534) (xy 40.215848 -386.912029)
			(xy 40.28295 -386.895867) (xy 40.35149 -386.887729) (xy 40.386 -386.887212) (xy 40.417539 -386.887648)
			(xy 40.480247 -386.894462) (xy 40.541859 -386.907979) (xy 40.601661 -386.928042) (xy 40.658959 -386.954418)
			(xy 40.686228 -386.97027) (xy 40.69207 -386.973826) (xy 40.705278 -386.977382) (xy 40.723566 -386.977382)
			(xy 40.733591 -386.976968) (xy 40.752116 -386.969304) (xy 40.766295 -386.95513) (xy 40.773965 -386.936606)
			(xy 40.774366 -386.926582) (xy 40.774366 -386.926074) (xy 40.774832 -386.895343) (xy 40.782243 -386.834331)
			(xy 40.796953 -386.774656) (xy 40.818749 -386.71719) (xy 40.847313 -386.662769) (xy 40.882227 -386.612188)
			(xy 40.922984 -386.566184) (xy 40.968988 -386.525427) (xy 41.019569 -386.490513) (xy 41.07399 -386.461949)
			(xy 41.131456 -386.440153) (xy 41.191131 -386.425443) (xy 41.252143 -386.418032) (xy 41.282874 -386.417566)
			(xy 41.303799 -386.41778) (xy 41.345508 -386.421212) (xy 41.366186 -386.424424) (xy 41.37533 -386.425948)
			(xy 41.39311 -386.422646) (xy 41.465246 -386.378958) (xy 41.476422 -386.364988) (xy 41.47947 -386.356352)
			(xy 41.488238 -386.331333) (xy 41.51172 -386.283803) (xy 41.541563 -386.239986) (xy 41.57719 -386.200727)
			(xy 41.617914 -386.166784) (xy 41.662948 -386.138813) (xy 41.711425 -386.117352) (xy 41.762407 -386.102816)
			(xy 41.814913 -386.095486) (xy 41.84142 -386.094986) (xy 41.86867 -386.095473) (xy 41.922616 -386.103232)
			(xy 41.974909 -386.118589) (xy 42.024484 -386.141231) (xy 42.070332 -386.170698) (xy 42.111521 -386.206389)
			(xy 42.147211 -386.247579) (xy 42.176676 -386.293428) (xy 42.199316 -386.343004) (xy 42.214671 -386.395297)
			(xy 42.222428 -386.449244) (xy 42.222928 -386.476494) (xy 42.222389 -386.505482) (xy 42.213618 -386.562791)
			(xy 42.196278 -386.618113) (xy 42.170767 -386.670175) (xy 42.137672 -386.717778) (xy 42.097757 -386.759826)
			(xy 42.05194 -386.79535) (xy 42.001275 -386.823534) (xy 41.946929 -386.843727) (xy 41.890154 -386.855466)
			(xy 41.861232 -386.857494) (xy 41.851721 -386.858421) (xy 41.83437 -386.866395) (xy 41.82745 -386.872988)
			(xy 41.791128 -386.910326) (xy 41.791382 -386.926074) (xy 41.791382 -386.926582) (xy 41.791866 -386.936593)
			(xy 41.799522 -386.955095) (xy 41.813675 -386.969258) (xy 41.832171 -386.976926) (xy 41.842182 -386.977382)
			(xy 43.073066 -386.977382) (xy 43.08313 -386.976946) (xy 43.101716 -386.969213) (xy 43.109134 -386.962396)
			(xy 43.153076 -386.918454) (xy 43.159918 -386.911054) (xy 43.167639 -386.892456) (xy 43.168062 -386.882386)
			(xy 43.168062 -386.722366) (xy 43.167517 -386.712382) (xy 43.159791 -386.693963) (xy 43.153076 -386.686552)
			(xy 42.781474 -386.31495) (xy 42.764708 -386.297508) (xy 42.736279 -386.258364) (xy 42.714321 -386.215256)
			(xy 42.699378 -386.169244) (xy 42.691815 -386.121461) (xy 42.691304 -386.097272) (xy 42.691304 -385.91236)
			(xy 42.692054 -385.881743) (xy 42.704207 -385.821728) (xy 42.715434 -385.793234) (xy 42.719244 -385.783836)
			(xy 42.719244 -385.72186) (xy 42.719794 -385.705146) (xy 42.728452 -385.672859) (xy 42.745168 -385.643911)
			(xy 42.768805 -385.620273) (xy 42.797752 -385.603555) (xy 42.830038 -385.594895) (xy 42.846752 -385.594352)
			(xy 43.117262 -385.594352) (xy 43.127285 -385.593938) (xy 43.145806 -385.586273) (xy 43.159979 -385.572098)
			(xy 43.16764 -385.553575) (xy 43.168062 -385.543552) (xy 43.168062 -385.093718) (xy 43.167527 -385.08373)
			(xy 43.159814 -385.065297) (xy 43.153076 -385.057904) (xy 42.781474 -384.686302) (xy 42.764705 -384.668861)
			(xy 42.736269 -384.629719) (xy 42.714305 -384.586611) (xy 42.699353 -384.540599) (xy 42.691782 -384.492814)
			(xy 42.691304 -384.468624) (xy 42.691304 -384.28676) (xy 42.692054 -384.256143) (xy 42.704207 -384.196128)
			(xy 42.715434 -384.167634) (xy 42.719244 -384.158236) (xy 42.719244 -384.09626) (xy 42.719794 -384.079546)
			(xy 42.728452 -384.047259) (xy 42.745168 -384.018311) (xy 42.768805 -383.994673) (xy 42.797752 -383.977955)
			(xy 42.830038 -383.969295) (xy 42.846752 -383.968752) (xy 43.117262 -383.968752) (xy 43.127285 -383.968338)
			(xy 43.145806 -383.960673) (xy 43.159979 -383.946498) (xy 43.16764 -383.927975) (xy 43.168062 -383.917952)
			(xy 43.168062 -383.868168) (xy 43.167636 -383.858154) (xy 43.159959 -383.839654) (xy 43.145787 -383.825501)
			(xy 43.127277 -383.81785) (xy 43.117262 -383.817368) (xy 42.846752 -383.817368) (xy 42.830043 -383.816817)
			(xy 42.797767 -383.808156) (xy 42.768832 -383.791436) (xy 42.74521 -383.767798) (xy 42.728511 -383.738851)
			(xy 42.719872 -383.706569) (xy 42.719244 -383.68986) (xy 42.719244 -383.627884) (xy 42.715434 -383.618486)
			(xy 42.704233 -383.589984) (xy 42.692074 -383.529974) (xy 42.691304 -383.49936) (xy 42.691304 -383.315972)
			(xy 42.691756 -383.291781) (xy 42.69933 -383.243994) (xy 42.714287 -383.197981) (xy 42.736259 -383.154875)
			(xy 42.764704 -383.115737) (xy 42.781474 -383.098294) (xy 43.153076 -382.726692) (xy 43.159888 -382.719347)
			(xy 43.167621 -382.700885) (xy 43.168062 -382.690878) (xy 43.168062 -381.77724) (xy 43.168498 -381.767176)
			(xy 43.176234 -381.748593) (xy 43.183048 -381.741172) (xy 43.759374 -381.164846) (xy 43.766774 -381.158006)
			(xy 43.785373 -381.150291) (xy 43.795442 -381.14986) (xy 44.35348 -381.14986) (xy 44.363501 -381.149443)
			(xy 44.382018 -381.141775) (xy 44.396187 -381.127601) (xy 44.403847 -381.109081) (xy 44.40428 -381.09906)
			(xy 44.40428 -380.9873) (xy 44.404826 -380.970585) (xy 44.413478 -380.938293) (xy 44.430192 -380.90934)
			(xy 44.45383 -380.8857) (xy 44.482781 -380.868982) (xy 44.515073 -380.860327) (xy 44.531788 -380.859792)
			(xy 44.63288 -380.859792) (xy 44.642915 -380.859407) (xy 44.661472 -380.851769) (xy 44.675663 -380.837582)
			(xy 44.683305 -380.819027) (xy 44.68368 -380.808992) (xy 44.68368 -380.710694) (xy 44.680886 -380.702312)
			(xy 44.670382 -380.671091) (xy 44.659022 -380.606212) (xy 44.65828 -380.57328) (xy 44.658766 -380.546029)
			(xy 44.666522 -380.492081) (xy 44.681877 -380.439786) (xy 44.704519 -380.390209) (xy 44.733985 -380.344359)
			(xy 44.769676 -380.303168) (xy 44.810867 -380.267477) (xy 44.856717 -380.238011) (xy 44.906294 -380.215369)
			(xy 44.958589 -380.200014) (xy 45.012537 -380.192258) (xy 45.067039 -380.192258) (xy 45.120987 -380.200014)
			(xy 45.173282 -380.215369) (xy 45.222859 -380.238011) (xy 45.268709 -380.267477) (xy 45.3099 -380.303168)
			(xy 45.345591 -380.344359) (xy 45.375057 -380.390209) (xy 45.397699 -380.439786) (xy 45.413054 -380.492081)
			(xy 45.42081 -380.546029) (xy 45.421296 -380.57328) (xy 45.420582 -380.606214) (xy 45.409212 -380.671095)
			(xy 45.39869 -380.702312) (xy 45.395896 -380.710694) (xy 45.395896 -380.808992) (xy 45.396251 -380.819038)
			(xy 45.403861 -380.837627) (xy 45.418063 -380.851832) (xy 45.43665 -380.859447) (xy 45.446696 -380.859792)
			(xy 45.547788 -380.859792) (xy 45.555487 -380.859942) (xy 45.570768 -380.861856) (xy 45.578268 -380.863602)
			(xy 45.584364 -380.865126) (xy 45.59046 -380.865126) (xy 45.600488 -380.864714) (xy 45.619023 -380.857052)
			(xy 45.633215 -380.842879) (xy 45.640901 -380.824354) (xy 45.64126 -380.814326) (xy 45.64126 -379.352302)
			(xy 45.641684 -379.342233) (xy 45.649405 -379.323634) (xy 45.656246 -379.316234) (xy 45.880274 -379.092206)
			(xy 45.887676 -379.085371) (xy 45.906275 -379.077662) (xy 45.916342 -379.07722) (xy 66.798698 -379.07722)
			(xy 66.808768 -379.077643) (xy 66.827371 -379.085359) (xy 66.834766 -379.092206) (xy 67.091417 -379.348857)
			(xy 70.236223 -379.348857) (xy 70.236223 -379.294343) (xy 70.243982 -379.240385) (xy 70.259341 -379.18808)
			(xy 70.281987 -379.138493) (xy 70.311461 -379.092635) (xy 70.347162 -379.051437) (xy 70.388362 -379.015741)
			(xy 70.434223 -378.986271) (xy 70.483812 -378.963629) (xy 70.536118 -378.948274) (xy 70.590077 -378.940521)
			(xy 70.617334 -378.94006) (xy 70.641406 -378.940419) (xy 70.689168 -378.946457) (xy 70.735794 -378.958447)
			(xy 70.758304 -378.966984) (xy 70.77075 -378.972064) (xy 70.796658 -378.968762) (xy 70.887336 -378.90196)
			(xy 70.898258 -378.878338) (xy 70.897242 -378.86513) (xy 70.896226 -378.836428) (xy 70.896712 -378.809177)
			(xy 70.904468 -378.755229) (xy 70.919823 -378.702934) (xy 70.942465 -378.653357) (xy 70.971931 -378.607507)
			(xy 71.007622 -378.566316) (xy 71.048813 -378.530625) (xy 71.094663 -378.501159) (xy 71.14424 -378.478517)
			(xy 71.196535 -378.463162) (xy 71.250483 -378.455406) (xy 71.304985 -378.455406) (xy 71.358933 -378.463162)
			(xy 71.411228 -378.478517) (xy 71.460805 -378.501159) (xy 71.506655 -378.530625) (xy 71.547846 -378.566316)
			(xy 71.583537 -378.607507) (xy 71.613003 -378.653357) (xy 71.635645 -378.702934) (xy 71.651 -378.755229)
			(xy 71.658756 -378.809177) (xy 71.659242 -378.836428) (xy 71.658226 -378.86513) (xy 71.65721 -378.878338)
			(xy 71.668132 -378.90196) (xy 71.75881 -378.968762) (xy 71.784718 -378.972064) (xy 71.797164 -378.966984)
			(xy 71.819669 -378.958432) (xy 71.866295 -378.946434) (xy 71.914061 -378.940408) (xy 71.938134 -378.94006)
			(xy 71.965381 -378.940613) (xy 72.019321 -378.948372) (xy 72.071607 -378.963729) (xy 72.121176 -378.98637)
			(xy 72.167018 -379.015835) (xy 72.208201 -379.051523) (xy 72.243885 -379.092709) (xy 72.273346 -379.138554)
			(xy 72.295983 -379.188125) (xy 72.311335 -379.240412) (xy 72.31909 -379.294353) (xy 72.31909 -379.348847)
			(xy 72.311335 -379.402788) (xy 72.295983 -379.455075) (xy 72.273346 -379.504646) (xy 72.243885 -379.550491)
			(xy 72.208201 -379.591677) (xy 72.167018 -379.627365) (xy 72.121176 -379.65683) (xy 72.071607 -379.679471)
			(xy 72.019321 -379.694828) (xy 71.965381 -379.702587) (xy 71.938134 -379.703076) (xy 71.905602 -379.702397)
			(xy 71.841492 -379.691279) (xy 71.810626 -379.680978) (xy 71.80199 -379.67793) (xy 71.78421 -379.678184)
			(xy 71.705724 -379.707648) (xy 71.692516 -379.719078) (xy 71.687944 -379.727206) (xy 71.668132 -379.759464)
			(xy 71.664085 -379.765862) (xy 71.659696 -379.780344) (xy 71.659496 -379.787912) (xy 71.659496 -380.069344)
			(xy 71.659771 -380.076899) (xy 71.664164 -380.091357) (xy 71.668132 -380.097792) (xy 71.687944 -380.13005)
			(xy 71.692516 -380.138178) (xy 71.705724 -380.149608) (xy 71.78421 -380.179072) (xy 71.80199 -380.179326)
			(xy 71.810626 -380.176278) (xy 71.841495 -380.165992) (xy 71.905603 -380.154882) (xy 71.938134 -380.15418)
			(xy 71.965383 -380.154693) (xy 72.019325 -380.162453) (xy 72.071614 -380.17781) (xy 72.121185 -380.200453)
			(xy 72.16703 -380.229919) (xy 72.208215 -380.265609) (xy 72.243901 -380.306797) (xy 72.273364 -380.352645)
			(xy 72.296002 -380.402218) (xy 72.311354 -380.454508) (xy 72.31911 -380.508451) (xy 72.31911 -380.562949)
			(xy 72.311354 -380.616892) (xy 72.296002 -380.669182) (xy 72.273364 -380.718755) (xy 72.243901 -380.764603)
			(xy 72.208215 -380.805791) (xy 72.16703 -380.841481) (xy 72.121185 -380.870947) (xy 72.071614 -380.89359)
			(xy 72.019325 -380.908947) (xy 71.965383 -380.916707) (xy 71.938134 -380.917196) (xy 71.914062 -380.916843)
			(xy 71.8663 -380.910802) (xy 71.819674 -380.898809) (xy 71.797164 -380.890272) (xy 71.784718 -380.885192)
			(xy 71.75881 -380.888494) (xy 71.668132 -380.955296) (xy 71.65721 -380.978918) (xy 71.658226 -380.992126)
			(xy 71.659242 -381.020828) (xy 71.658756 -381.048079) (xy 71.651 -381.102027) (xy 71.635645 -381.154322)
			(xy 71.613003 -381.203899) (xy 71.583537 -381.249749) (xy 71.547846 -381.29094) (xy 71.506655 -381.326631)
			(xy 71.460805 -381.356097) (xy 71.411228 -381.378739) (xy 71.358933 -381.394094) (xy 71.304985 -381.40185)
			(xy 71.250483 -381.40185) (xy 71.196535 -381.394094) (xy 71.14424 -381.378739) (xy 71.094663 -381.356097)
			(xy 71.048813 -381.326631) (xy 71.007622 -381.29094) (xy 70.971931 -381.249749) (xy 70.942465 -381.203899)
			(xy 70.919823 -381.154322) (xy 70.904468 -381.102027) (xy 70.896712 -381.048079) (xy 70.896226 -381.020828)
			(xy 70.897242 -380.992126) (xy 70.898258 -380.978918) (xy 70.887336 -380.955296) (xy 70.796658 -380.888494)
			(xy 70.77075 -380.885192) (xy 70.758304 -380.890272) (xy 70.735803 -380.898836) (xy 70.689175 -380.910829)
			(xy 70.641407 -380.91685) (xy 70.617334 -380.917196) (xy 70.590079 -380.916759) (xy 70.536122 -380.909006)
			(xy 70.483819 -380.893653) (xy 70.434233 -380.871011) (xy 70.388374 -380.841543) (xy 70.347176 -380.805848)
			(xy 70.311477 -380.764653) (xy 70.282005 -380.718797) (xy 70.259359 -380.669213) (xy 70.244001 -380.616911)
			(xy 70.236243 -380.562955) (xy 70.236243 -380.508445) (xy 70.244001 -380.454489) (xy 70.259359 -380.402187)
			(xy 70.282005 -380.352603) (xy 70.311477 -380.306747) (xy 70.347176 -380.265552) (xy 70.388374 -380.229857)
			(xy 70.434233 -380.200389) (xy 70.483819 -380.177747) (xy 70.536122 -380.162394) (xy 70.590079 -380.154641)
			(xy 70.617334 -380.15418) (xy 70.649866 -380.154869) (xy 70.713975 -380.16598) (xy 70.744842 -380.176278)
			(xy 70.753478 -380.179326) (xy 70.771258 -380.179072) (xy 70.849744 -380.149608) (xy 70.862952 -380.138178)
			(xy 70.867524 -380.13005) (xy 70.887336 -380.097792) (xy 70.891368 -380.091386) (xy 70.895765 -380.07691)
			(xy 70.895972 -380.069344) (xy 70.895972 -379.787912) (xy 70.895705 -379.780357) (xy 70.891305 -379.765899)
			(xy 70.887336 -379.759464) (xy 70.867524 -379.727206) (xy 70.862952 -379.719078) (xy 70.849744 -379.707648)
			(xy 70.771258 -379.678184) (xy 70.753478 -379.67793) (xy 70.744842 -379.680978) (xy 70.713974 -379.691271)
			(xy 70.649865 -379.702376) (xy 70.617334 -379.703076) (xy 70.590077 -379.702679) (xy 70.536118 -379.694926)
			(xy 70.483812 -379.679571) (xy 70.434223 -379.656929) (xy 70.388362 -379.627459) (xy 70.347162 -379.591763)
			(xy 70.311461 -379.550565) (xy 70.281987 -379.504707) (xy 70.259341 -379.45512) (xy 70.243982 -379.402815)
			(xy 70.236223 -379.348857) (xy 67.091417 -379.348857) (xy 67.104514 -379.361954) (xy 67.111361 -379.369351)
			(xy 67.119089 -379.387951) (xy 67.1195 -379.398022) (xy 67.1195 -380.966218) (xy 67.119927 -380.976287)
			(xy 67.127646 -380.994886) (xy 67.134486 -381.002286) (xy 67.267074 -381.134874) (xy 67.274475 -381.141712)
			(xy 67.293074 -381.149423) (xy 67.303142 -381.14986) (xy 69.902578 -381.14986) (xy 69.912641 -381.150299)
			(xy 69.931219 -381.15804) (xy 69.938646 -381.164846) (xy 70.546468 -381.772668) (xy 70.553307 -381.780069)
			(xy 70.561022 -381.798667) (xy 70.561454 -381.808736) (xy 70.561454 -382.5875) (xy 70.567042 -382.603502)
			(xy 70.572376 -382.61036) (xy 70.580854 -382.621724) (xy 70.593083 -382.647294) (xy 70.599386 -382.674929)
			(xy 70.599808 -382.6891) (xy 70.599808 -383.0701) (xy 70.599213 -383.087347) (xy 70.58995 -383.120575)
			(xy 70.58152 -383.135632) (xy 70.577964 -383.141728) (xy 70.574408 -383.154936) (xy 70.574408 -383.257806)
			(xy 70.574042 -383.276309) (xy 70.568566 -383.312909) (xy 70.563486 -383.330704) (xy 70.561454 -383.337816)
			(xy 70.561454 -383.667508) (xy 70.562091 -383.678922) (xy 70.571999 -383.699489) (xy 70.580504 -383.707132)
			(xy 70.605558 -383.727875) (xy 70.65071 -383.774694) (xy 70.689523 -383.826889) (xy 70.721363 -383.883608)
			(xy 70.74571 -383.943924) (xy 70.762166 -384.006852) (xy 70.770462 -384.071365) (xy 70.770464 -384.13641)
			(xy 70.76217 -384.200923) (xy 70.745718 -384.263852) (xy 70.721374 -384.32417) (xy 70.689537 -384.38089)
			(xy 70.650727 -384.433087) (xy 70.605577 -384.479909) (xy 70.580504 -384.500628) (xy 70.572002 -384.508264)
			(xy 70.562131 -384.528842) (xy 70.561454 -384.540252) (xy 70.561454 -384.658108) (xy 70.562091 -384.669522)
			(xy 70.571999 -384.690089) (xy 70.580504 -384.697732) (xy 70.605554 -384.718478) (xy 70.650698 -384.765301)
			(xy 70.689506 -384.817497) (xy 70.721343 -384.874214) (xy 70.745691 -384.934526) (xy 70.762153 -384.99745)
			(xy 70.770459 -385.061959) (xy 70.771004 -385.09448) (xy 70.77056 -385.125213) (xy 70.763153 -385.186231)
			(xy 70.748445 -385.24591) (xy 70.726651 -385.303382) (xy 70.698088 -385.357808) (xy 70.663172 -385.408394)
			(xy 70.622414 -385.454402) (xy 70.576407 -385.495162) (xy 70.525822 -385.530079) (xy 70.471397 -385.558644)
			(xy 70.413926 -385.58044) (xy 70.354246 -385.59515) (xy 70.293229 -385.602559) (xy 70.262496 -385.602988)
			(xy 70.230396 -385.602476) (xy 70.166711 -385.594364) (xy 70.104549 -385.578317) (xy 70.074536 -385.56692)
			(xy 70.070022 -385.565236) (xy 70.060557 -385.563449) (xy 70.05574 -385.563364) (xy 70.050406 -385.563364)
			(xy 69.976746 -385.637024) (xy 69.969898 -385.644421) (xy 69.962165 -385.66302) (xy 69.96176 -385.673092)
			(xy 69.96176 -385.841748) (xy 69.965316 -385.850892) (xy 69.976957 -385.881156) (xy 69.993342 -385.943895)
			(xy 70.001619 -386.008209) (xy 70.002146 -386.04063) (xy 70.001621 -386.073052) (xy 69.993347 -386.137366)
			(xy 69.976964 -386.200106) (xy 69.965316 -386.230368) (xy 69.96176 -386.239512) (xy 69.96176 -386.612638)
			(xy 69.962192 -386.622704) (xy 69.969922 -386.641293) (xy 69.976746 -386.648706) (xy 70.032118 -386.704078)
			(xy 70.039516 -386.710924) (xy 70.058115 -386.718655) (xy 70.068186 -386.719064) (xy 70.154546 -386.719064)
			(xy 70.161404 -386.717032) (xy 70.186967 -386.71025) (xy 70.239354 -386.702991) (xy 70.265798 -386.702554)
			(xy 70.292242 -386.702989) (xy 70.344627 -386.710256) (xy 70.370192 -386.717032) (xy 70.37705 -386.719064)
			(xy 73.162414 -386.719064) (xy 73.172482 -386.718638) (xy 73.19108 -386.710916) (xy 73.198482 -386.704078)
			(xy 73.445116 -386.457444) (xy 73.452513 -386.450595) (xy 73.471112 -386.44286) (xy 73.481184 -386.442458)
			(xy 73.653396 -386.442458) (xy 73.660508 -386.440172) (xy 73.697138 -386.429624) (xy 73.77251 -386.41827)
			(xy 73.810622 -386.417566) (xy 73.831547 -386.417782) (xy 73.873255 -386.421218) (xy 73.893934 -386.424424)
			(xy 73.903078 -386.425948) (xy 73.920858 -386.422646) (xy 73.992994 -386.378958) (xy 74.00417 -386.364988)
			(xy 74.007218 -386.356352) (xy 74.016573 -386.329783) (xy 74.041993 -386.279517) (xy 74.074527 -386.233535)
			(xy 74.113468 -386.192837) (xy 74.15797 -386.158306) (xy 74.207066 -386.130693) (xy 74.259687 -386.110599)
			(xy 74.314691 -386.098461) (xy 74.342752 -386.096002) (xy 74.351974 -386.094963) (xy 74.368788 -386.087151)
			(xy 74.375518 -386.080762) (xy 74.396854 -386.059172) (xy 74.40344 -386.051792) (xy 74.410899 -386.033493)
			(xy 74.411332 -386.023612) (xy 74.411332 -386.010404) (xy 74.41311 -386.008626) (xy 74.41311 -383.359152)
			(xy 74.412666 -383.348972) (xy 74.404763 -383.33021) (xy 74.390181 -383.316002) (xy 74.380852 -383.311908)
			(xy 74.278236 -383.271522) (xy 74.24801 -383.27838) (xy 74.237342 -383.28981) (xy 74.21924 -383.308584)
			(xy 74.178795 -383.341509) (xy 74.134242 -383.368617) (xy 74.08641 -383.3894) (xy 74.036193 -383.403473)
			(xy 73.984526 -383.410572) (xy 73.95845 -383.410968) (xy 73.931196 -383.410508) (xy 73.877242 -383.402757)
			(xy 73.82494 -383.387405) (xy 73.775356 -383.364764) (xy 73.7295 -383.335297) (xy 73.688304 -383.299603)
			(xy 73.652609 -383.258408) (xy 73.62314 -383.212553) (xy 73.600499 -383.162969) (xy 73.585145 -383.110668)
			(xy 73.577393 -383.056714) (xy 73.576942 -383.02946) (xy 73.577958 -383.000758) (xy 73.578974 -382.98755)
			(xy 73.568052 -382.963928) (xy 73.477374 -382.897126) (xy 73.451466 -382.893824) (xy 73.43902 -382.898904)
			(xy 73.41651 -382.907442) (xy 73.369885 -382.919434) (xy 73.322122 -382.925475) (xy 73.29805 -382.925828)
			(xy 73.2708 -382.925339) (xy 73.216855 -382.917576) (xy 73.164563 -382.902216) (xy 73.114989 -382.879571)
			(xy 73.069143 -382.850101) (xy 73.027957 -382.814408) (xy 72.992269 -382.773217) (xy 72.962805 -382.727367)
			(xy 72.940167 -382.67779) (xy 72.924813 -382.625497) (xy 72.917058 -382.57155) (xy 72.917058 -382.51705)
			(xy 72.924813 -382.463103) (xy 72.940167 -382.41081) (xy 72.962805 -382.361233) (xy 72.992269 -382.315383)
			(xy 73.027957 -382.274192) (xy 73.069143 -382.238499) (xy 73.114989 -382.209029) (xy 73.164563 -382.186384)
			(xy 73.216855 -382.171024) (xy 73.2708 -382.163261) (xy 73.29805 -382.162812) (xy 73.330581 -382.163513)
			(xy 73.394689 -382.174621) (xy 73.425558 -382.18491) (xy 73.434194 -382.187958) (xy 73.451974 -382.187704)
			(xy 73.53046 -382.15824) (xy 73.543668 -382.14681) (xy 73.54824 -382.138682) (xy 73.568052 -382.106424)
			(xy 73.572025 -382.09999) (xy 73.576428 -382.085532) (xy 73.576688 -382.077976) (xy 73.576688 -381.796544)
			(xy 73.576478 -381.788979) (xy 73.572072 -381.774509) (xy 73.568052 -381.768096) (xy 73.54824 -381.735838)
			(xy 73.543668 -381.72771) (xy 73.53046 -381.71628) (xy 73.451974 -381.686816) (xy 73.434194 -381.686562)
			(xy 73.425558 -381.68961) (xy 73.394691 -381.699909) (xy 73.330582 -381.711024) (xy 73.29805 -381.711708)
			(xy 73.270801 -381.711219) (xy 73.216859 -381.703457) (xy 73.16457 -381.688097) (xy 73.114999 -381.665453)
			(xy 73.069155 -381.635985) (xy 73.027971 -381.600294) (xy 72.992285 -381.559105) (xy 72.962823 -381.513257)
			(xy 72.940185 -381.463683) (xy 72.924833 -381.411392) (xy 72.917078 -381.357449) (xy 72.917078 -381.302951)
			(xy 72.924833 -381.249008) (xy 72.940185 -381.196717) (xy 72.962823 -381.147143) (xy 72.992285 -381.101295)
			(xy 73.027971 -381.060106) (xy 73.069155 -381.024415) (xy 73.114999 -380.994947) (xy 73.16457 -380.972303)
			(xy 73.216859 -380.956943) (xy 73.270801 -380.949181) (xy 73.29805 -380.948692) (xy 73.321986 -380.949067)
			(xy 73.369481 -380.955051) (xy 73.415858 -380.96692) (xy 73.438258 -380.975362) (xy 73.450196 -380.980188)
			(xy 73.475088 -380.97714) (xy 73.56602 -380.913894) (xy 73.577196 -380.891796) (xy 73.576942 -380.878588)
			(xy 73.576942 -380.87046) (xy 73.577428 -380.843209) (xy 73.585184 -380.789261) (xy 73.600539 -380.736966)
			(xy 73.623181 -380.687389) (xy 73.652647 -380.641539) (xy 73.688338 -380.600348) (xy 73.729529 -380.564657)
			(xy 73.775379 -380.535191) (xy 73.824956 -380.512549) (xy 73.877251 -380.497194) (xy 73.931199 -380.489438)
			(xy 73.985701 -380.489438) (xy 74.039649 -380.497194) (xy 74.091944 -380.512549) (xy 74.141521 -380.535191)
			(xy 74.187371 -380.564657) (xy 74.228562 -380.600348) (xy 74.264253 -380.641539) (xy 74.293719 -380.687389)
			(xy 74.316361 -380.736966) (xy 74.331716 -380.789261) (xy 74.339472 -380.843209) (xy 74.339958 -380.87046)
			(xy 74.339958 -380.878588) (xy 74.339704 -380.891796) (xy 74.35088 -380.913894) (xy 74.441812 -380.97714)
			(xy 74.466704 -380.980188) (xy 74.478642 -380.975362) (xy 74.501036 -380.966899) (xy 74.547413 -380.955023)
			(xy 74.594913 -380.949053) (xy 74.61885 -380.948692) (xy 74.646105 -380.949152) (xy 74.700062 -380.956903)
			(xy 74.752365 -380.972255) (xy 74.801952 -380.994894) (xy 74.847811 -381.024361) (xy 74.88901 -381.060055)
			(xy 74.924709 -381.101249) (xy 74.954182 -381.147104) (xy 74.976828 -381.196688) (xy 74.992186 -381.24899)
			(xy 74.999945 -381.302945) (xy 74.999945 -381.357455) (xy 74.992186 -381.41141) (xy 74.976828 -381.463712)
			(xy 74.954182 -381.513296) (xy 74.924709 -381.559151) (xy 74.88901 -381.600345) (xy 74.847811 -381.636039)
			(xy 74.801952 -381.665506) (xy 74.752365 -381.688145) (xy 74.700062 -381.703497) (xy 74.646105 -381.711248)
			(xy 74.61885 -381.711708) (xy 74.586319 -381.711007) (xy 74.52221 -381.6999) (xy 74.491342 -381.68961)
			(xy 74.482706 -381.686562) (xy 74.464926 -381.686816) (xy 74.38644 -381.71628) (xy 74.373232 -381.72771)
			(xy 74.36866 -381.735838) (xy 74.348848 -381.768096) (xy 74.344877 -381.77453) (xy 74.34048 -381.788989)
			(xy 74.340212 -381.796544) (xy 74.340212 -382.077976) (xy 74.34041 -382.085545) (xy 74.344797 -382.100028)
			(xy 74.348848 -382.106424) (xy 74.36866 -382.138682) (xy 74.373232 -382.14681) (xy 74.38644 -382.15824)
			(xy 74.464926 -382.187704) (xy 74.482706 -382.187958) (xy 74.491342 -382.18491) (xy 74.522208 -382.17461)
			(xy 74.586318 -382.163495) (xy 74.61885 -382.162812) (xy 74.643742 -382.163574) (xy 74.654664 -382.164336)
			(xy 74.674984 -382.156716) (xy 75.628754 -381.202946) (xy 75.636153 -381.196103) (xy 75.654752 -381.188381)
			(xy 75.664822 -381.18796) (xy 75.709018 -381.18796) (xy 75.719086 -381.187532) (xy 75.737682 -381.179809)
			(xy 75.745086 -381.172974) (xy 75.841098 -381.076962) (xy 75.846686 -381.04572) (xy 75.840082 -381.031242)
			(xy 75.829258 -381.00628) (xy 75.813988 -380.95406) (xy 75.806274 -380.900203) (xy 75.805792 -380.873)
			(xy 75.806278 -380.845749) (xy 75.814034 -380.791801) (xy 75.829389 -380.739506) (xy 75.852031 -380.689929)
			(xy 75.881497 -380.644079) (xy 75.917188 -380.602888) (xy 75.958379 -380.567197) (xy 76.004229 -380.537731)
			(xy 76.053806 -380.515089) (xy 76.106101 -380.499734) (xy 76.160049 -380.491978) (xy 76.1873 -380.491492)
			(xy 76.214506 -380.491934) (xy 76.26837 -380.499638) (xy 76.320589 -380.514932) (xy 76.345542 -380.525782)
			(xy 76.36002 -380.532386) (xy 76.391262 -380.526798) (xy 77.838554 -379.079506) (xy 77.845955 -379.072667)
			(xy 77.864553 -379.064952) (xy 77.874622 -379.06452) (xy 99.010978 -379.06452) (xy 99.021041 -379.064958)
			(xy 99.039623 -379.072694) (xy 99.047046 -379.079506) (xy 99.316393 -379.348853) (xy 102.764046 -379.348853)
			(xy 102.764046 -379.294347) (xy 102.771803 -379.240397) (xy 102.787158 -379.188099) (xy 102.8098 -379.138519)
			(xy 102.839267 -379.092665) (xy 102.874959 -379.051472) (xy 102.916151 -379.015778) (xy 102.962003 -378.986308)
			(xy 103.011582 -378.963664) (xy 103.063879 -378.948306) (xy 103.117829 -378.940547) (xy 103.145082 -378.94006)
			(xy 103.169153 -378.940435) (xy 103.216915 -378.946467) (xy 103.263542 -378.95845) (xy 103.286052 -378.966984)
			(xy 103.298498 -378.972064) (xy 103.324406 -378.968762) (xy 103.415084 -378.90196) (xy 103.426006 -378.878338)
			(xy 103.42499 -378.86513) (xy 103.423974 -378.836428) (xy 103.42446 -378.809177) (xy 103.432216 -378.755229)
			(xy 103.447571 -378.702934) (xy 103.470213 -378.653357) (xy 103.499679 -378.607507) (xy 103.53537 -378.566316)
			(xy 103.576561 -378.530625) (xy 103.622411 -378.501159) (xy 103.671988 -378.478517) (xy 103.724283 -378.463162)
			(xy 103.778231 -378.455406) (xy 103.832733 -378.455406) (xy 103.886681 -378.463162) (xy 103.938976 -378.478517)
			(xy 103.988553 -378.501159) (xy 104.034403 -378.530625) (xy 104.075594 -378.566316) (xy 104.111285 -378.607507)
			(xy 104.140751 -378.653357) (xy 104.163393 -378.702934) (xy 104.178748 -378.755229) (xy 104.186504 -378.809177)
			(xy 104.18699 -378.836428) (xy 104.185974 -378.86513) (xy 104.184958 -378.878338) (xy 104.19588 -378.90196)
			(xy 104.286558 -378.968762) (xy 104.312466 -378.972064) (xy 104.324912 -378.966984) (xy 104.347423 -378.958447)
			(xy 104.394046 -378.946443) (xy 104.44181 -378.940411) (xy 104.465882 -378.94006) (xy 104.493133 -378.940586)
			(xy 104.547082 -378.94834) (xy 104.599377 -378.963693) (xy 104.648956 -378.986333) (xy 104.694807 -379.015798)
			(xy 104.735999 -379.051489) (xy 104.771691 -379.092678) (xy 104.801158 -379.138529) (xy 104.8238 -379.188106)
			(xy 104.839156 -379.240401) (xy 104.846913 -379.294349) (xy 104.846913 -379.348851) (xy 104.839156 -379.402799)
			(xy 104.8238 -379.455094) (xy 104.801158 -379.504671) (xy 104.771691 -379.550522) (xy 104.735999 -379.591711)
			(xy 104.694807 -379.627402) (xy 104.648956 -379.656867) (xy 104.599377 -379.679507) (xy 104.547082 -379.69486)
			(xy 104.493133 -379.702614) (xy 104.465882 -379.703076) (xy 104.43335 -379.702385) (xy 104.369241 -379.691275)
			(xy 104.338374 -379.680978) (xy 104.329738 -379.67793) (xy 104.311958 -379.678184) (xy 104.233472 -379.707648)
			(xy 104.220264 -379.719078) (xy 104.215692 -379.727206) (xy 104.19588 -379.759464) (xy 104.191828 -379.765859)
			(xy 104.187443 -379.780343) (xy 104.187244 -379.787912) (xy 104.187244 -380.069344) (xy 104.187527 -380.076898)
			(xy 104.191916 -380.091356) (xy 104.19588 -380.097792) (xy 104.215692 -380.13005) (xy 104.220264 -380.138178)
			(xy 104.233472 -380.149608) (xy 104.311958 -380.179072) (xy 104.329738 -380.179326) (xy 104.338374 -380.176278)
			(xy 104.369247 -380.166004) (xy 104.433352 -380.154887) (xy 104.465882 -380.15418) (xy 104.493135 -380.154666)
			(xy 104.547086 -380.162421) (xy 104.599384 -380.177775) (xy 104.648965 -380.200415) (xy 104.694819 -380.229882)
			(xy 104.736013 -380.265575) (xy 104.771707 -380.306766) (xy 104.801176 -380.352619) (xy 104.823819 -380.402199)
			(xy 104.839175 -380.454496) (xy 104.846933 -380.508447) (xy 104.846933 -380.562953) (xy 104.839175 -380.616904)
			(xy 104.823819 -380.669201) (xy 104.801176 -380.718781) (xy 104.771707 -380.764634) (xy 104.736013 -380.805825)
			(xy 104.694819 -380.841518) (xy 104.648965 -380.870985) (xy 104.599384 -380.893625) (xy 104.547086 -380.908979)
			(xy 104.493135 -380.916734) (xy 104.465882 -380.917196) (xy 104.441811 -380.916829) (xy 104.394048 -380.910793)
			(xy 104.347422 -380.898807) (xy 104.324912 -380.890272) (xy 104.312466 -380.885192) (xy 104.286558 -380.888494)
			(xy 104.19588 -380.955296) (xy 104.184958 -380.978918) (xy 104.185974 -380.992126) (xy 104.18699 -381.020828)
			(xy 104.186504 -381.048079) (xy 104.178748 -381.102027) (xy 104.163393 -381.154322) (xy 104.140751 -381.203899)
			(xy 104.111285 -381.249749) (xy 104.075594 -381.29094) (xy 104.034403 -381.326631) (xy 103.988553 -381.356097)
			(xy 103.938976 -381.378739) (xy 103.886681 -381.394094) (xy 103.832733 -381.40185) (xy 103.778231 -381.40185)
			(xy 103.724283 -381.394094) (xy 103.671988 -381.378739) (xy 103.622411 -381.356097) (xy 103.576561 -381.326631)
			(xy 103.53537 -381.29094) (xy 103.499679 -381.249749) (xy 103.470213 -381.203899) (xy 103.447571 -381.154322)
			(xy 103.432216 -381.102027) (xy 103.42446 -381.048079) (xy 103.423974 -381.020828) (xy 103.42499 -380.992126)
			(xy 103.426006 -380.978918) (xy 103.415084 -380.955296) (xy 103.324406 -380.888494) (xy 103.298498 -380.885192)
			(xy 103.286052 -380.890272) (xy 103.263546 -380.898822) (xy 103.216921 -380.91082) (xy 103.169155 -380.916847)
			(xy 103.145082 -380.917196) (xy 103.117831 -380.916733) (xy 103.063883 -380.908974) (xy 103.011589 -380.893617)
			(xy 102.962013 -380.870974) (xy 102.916163 -380.841506) (xy 102.874974 -380.805814) (xy 102.839283 -380.764623)
			(xy 102.809817 -380.718772) (xy 102.787177 -380.669194) (xy 102.771822 -380.616899) (xy 102.764066 -380.562951)
			(xy 102.764066 -380.508449) (xy 102.771822 -380.454501) (xy 102.787177 -380.402206) (xy 102.809817 -380.352628)
			(xy 102.839283 -380.306777) (xy 102.874974 -380.265586) (xy 102.916163 -380.229894) (xy 102.962013 -380.200426)
			(xy 103.011589 -380.177783) (xy 103.063883 -380.162426) (xy 103.117831 -380.154667) (xy 103.145082 -380.15418)
			(xy 103.177613 -380.154882) (xy 103.241723 -380.165985) (xy 103.27259 -380.176278) (xy 103.281226 -380.179326)
			(xy 103.299006 -380.179072) (xy 103.377492 -380.149608) (xy 103.3907 -380.138178) (xy 103.395272 -380.13005)
			(xy 103.415084 -380.097792) (xy 103.419111 -380.091383) (xy 103.423512 -380.07691) (xy 103.42372 -380.069344)
			(xy 103.42372 -379.787912) (xy 103.42346 -379.780356) (xy 103.419056 -379.765898) (xy 103.415084 -379.759464)
			(xy 103.395272 -379.727206) (xy 103.3907 -379.719078) (xy 103.377492 -379.707648) (xy 103.299006 -379.678184)
			(xy 103.281226 -379.67793) (xy 103.27259 -379.680978) (xy 103.241719 -379.691259) (xy 103.177612 -379.702372)
			(xy 103.145082 -379.703076) (xy 103.117829 -379.702653) (xy 103.063879 -379.694894) (xy 103.011582 -379.679536)
			(xy 102.962003 -379.656892) (xy 102.916151 -379.627422) (xy 102.874959 -379.591728) (xy 102.839267 -379.550535)
			(xy 102.8098 -379.504681) (xy 102.787158 -379.455101) (xy 102.771803 -379.402803) (xy 102.764046 -379.348853)
			(xy 99.316393 -379.348853) (xy 99.405694 -379.438154) (xy 99.412533 -379.445555) (xy 99.420248 -379.464153)
			(xy 99.42068 -379.474222) (xy 99.42068 -380.948438) (xy 99.421109 -380.958506) (xy 99.428831 -380.977102)
			(xy 99.435666 -380.984506) (xy 99.624134 -381.172974) (xy 99.631533 -381.179818) (xy 99.650131 -381.187544)
			(xy 99.660202 -381.18796) (xy 102.277418 -381.18796) (xy 102.287485 -381.188388) (xy 102.306079 -381.196114)
			(xy 102.313486 -381.202946) (xy 103.05415 -381.94361) (xy 105.24693 -381.94361) (xy 105.251001 -381.887988)
			(xy 105.263127 -381.833551) (xy 105.28305 -381.78146) (xy 105.310346 -381.732825) (xy 105.344432 -381.688682)
			(xy 105.384581 -381.649973) (xy 105.429939 -381.617522) (xy 105.479539 -381.592021) (xy 105.532323 -381.574014)
			(xy 105.587166 -381.563884) (xy 105.6429 -381.561847) (xy 105.698337 -381.567947) (xy 105.752294 -381.582053)
			(xy 105.803623 -381.603865) (xy 105.851229 -381.632919) (xy 105.894097 -381.668594) (xy 105.931314 -381.710131)
			(xy 105.962087 -381.756644) (xy 105.985759 -381.807141) (xy 106.001827 -381.860548) (xy 106.009947 -381.915724)
			(xy 106.010456 -381.94361) (xy 106.009947 -381.971496) (xy 106.001827 -382.026672) (xy 105.985759 -382.080079)
			(xy 105.962087 -382.130576) (xy 105.931314 -382.177089) (xy 105.894097 -382.218626) (xy 105.851229 -382.254301)
			(xy 105.803623 -382.283355) (xy 105.752294 -382.305167) (xy 105.698337 -382.319273) (xy 105.6429 -382.325373)
			(xy 105.587166 -382.323336) (xy 105.532323 -382.313206) (xy 105.479539 -382.295199) (xy 105.429939 -382.269698)
			(xy 105.384581 -382.237247) (xy 105.344432 -382.198538) (xy 105.310346 -382.154395) (xy 105.28305 -382.10576)
			(xy 105.263127 -382.053669) (xy 105.251001 -381.999232) (xy 105.24693 -381.94361) (xy 103.05415 -381.94361)
			(xy 103.074216 -381.963676) (xy 103.08106 -381.971075) (xy 103.08878 -381.989674) (xy 103.089202 -381.999744)
			(xy 103.089202 -382.5875) (xy 103.09479 -382.603502) (xy 103.100124 -382.61036) (xy 103.108599 -382.621724)
			(xy 103.120824 -382.647295) (xy 103.127124 -382.674929) (xy 103.127556 -382.6891) (xy 103.127556 -383.0701)
			(xy 103.126961 -383.087347) (xy 103.117701 -383.120577) (xy 103.109268 -383.135632) (xy 103.105712 -383.141728)
			(xy 103.102156 -383.154936) (xy 103.102156 -383.257806) (xy 103.10179 -383.276309) (xy 103.096313 -383.312908)
			(xy 103.091234 -383.330704) (xy 103.089202 -383.337816) (xy 103.089202 -383.667508) (xy 103.089837 -383.678924)
			(xy 103.099738 -383.699498) (xy 103.108252 -383.707132) (xy 103.133304 -383.727876) (xy 103.178452 -383.774697)
			(xy 103.217262 -383.826893) (xy 103.249098 -383.883612) (xy 103.273442 -383.943927) (xy 103.289897 -384.006854)
			(xy 103.298192 -384.071366) (xy 103.298194 -384.136409) (xy 103.289901 -384.200921) (xy 103.27345 -384.263849)
			(xy 103.249109 -384.324166) (xy 103.217275 -384.380886) (xy 103.178469 -384.433084) (xy 103.133323 -384.479907)
			(xy 103.108252 -384.500628) (xy 103.099743 -384.508261) (xy 103.089863 -384.528839) (xy 103.089202 -384.540252)
			(xy 103.089202 -384.658108) (xy 103.089837 -384.669524) (xy 103.099738 -384.690098) (xy 103.108252 -384.697732)
			(xy 103.133304 -384.718476) (xy 103.178453 -384.765298) (xy 103.217264 -384.817493) (xy 103.249105 -384.874209)
			(xy 103.273456 -384.934522) (xy 103.289919 -384.997448) (xy 103.298226 -385.061958) (xy 103.298752 -385.09448)
			(xy 103.29829 -385.125213) (xy 103.290883 -385.18623) (xy 103.276176 -385.245911) (xy 103.254383 -385.303383)
			(xy 103.225822 -385.357809) (xy 103.190908 -385.408397) (xy 103.150152 -385.454407) (xy 103.104147 -385.495169)
			(xy 103.053564 -385.530089) (xy 102.999141 -385.558657) (xy 102.941672 -385.580457) (xy 102.881993 -385.595172)
			(xy 102.820977 -385.602586) (xy 102.790244 -385.602988) (xy 102.758144 -385.602479) (xy 102.694457 -385.594372)
			(xy 102.632292 -385.578331) (xy 102.602284 -385.56692) (xy 102.597771 -385.565232) (xy 102.588306 -385.563435)
			(xy 102.583488 -385.563364) (xy 102.578154 -385.563364) (xy 102.504494 -385.637024) (xy 102.497652 -385.644424)
			(xy 102.489927 -385.663022) (xy 102.489508 -385.673092) (xy 102.489508 -385.841748) (xy 102.493064 -385.850892)
			(xy 102.504704 -385.881156) (xy 102.521087 -385.943896) (xy 102.529363 -386.008209) (xy 102.529894 -386.04063)
			(xy 102.529369 -386.073052) (xy 102.521095 -386.137366) (xy 102.504709 -386.200105) (xy 102.493064 -386.230368)
			(xy 102.489508 -386.239512) (xy 102.489508 -386.612638) (xy 102.489938 -386.622705) (xy 102.497663 -386.641299)
			(xy 102.504494 -386.648706) (xy 102.559866 -386.704078) (xy 102.567267 -386.710916) (xy 102.585866 -386.71863)
			(xy 102.595934 -386.719064) (xy 102.682294 -386.719064) (xy 102.689152 -386.717032) (xy 102.714715 -386.710247)
			(xy 102.767101 -386.70298) (xy 102.793546 -386.702554) (xy 102.81999 -386.702985) (xy 102.872378 -386.710245)
			(xy 102.89794 -386.717032) (xy 102.904798 -386.719064) (xy 106.639614 -386.719064) (xy 106.649682 -386.718638)
			(xy 106.66828 -386.710916) (xy 106.675682 -386.704078) (xy 107.508294 -385.871466) (xy 107.515689 -385.864611)
			(xy 107.534288 -385.856864) (xy 107.544362 -385.85648) (xy 108.906564 -385.85648) (xy 108.916629 -385.856045)
			(xy 108.935214 -385.848312) (xy 108.942632 -385.841494) (xy 108.975398 -385.808728) (xy 108.982233 -385.801326)
			(xy 108.989942 -385.782727) (xy 108.990384 -385.77266) (xy 108.990384 -383.353564) (xy 108.989871 -383.343372)
			(xy 108.981857 -383.324622) (xy 108.967211 -383.310434) (xy 108.957872 -383.30632) (xy 108.854748 -383.266442)
			(xy 108.824014 -383.273808) (xy 108.8136 -383.285492) (xy 108.795422 -383.304874) (xy 108.75463 -383.338925)
			(xy 108.709509 -383.366989) (xy 108.660931 -383.388524) (xy 108.609837 -383.403114) (xy 108.557212 -383.410476)
			(xy 108.530644 -383.410968) (xy 108.50339 -383.410508) (xy 108.449437 -383.402756) (xy 108.397136 -383.387403)
			(xy 108.347553 -383.364762) (xy 108.301697 -383.335295) (xy 108.260502 -383.299601) (xy 108.224807 -383.258406)
			(xy 108.19534 -383.212551) (xy 108.172698 -383.162968) (xy 108.157345 -383.110667) (xy 108.149593 -383.056714)
			(xy 108.149136 -383.02946) (xy 108.150152 -383.000758) (xy 108.151168 -382.98755) (xy 108.140246 -382.963928)
			(xy 108.049568 -382.897126) (xy 108.02366 -382.893824) (xy 108.011214 -382.898904) (xy 107.988704 -382.907442)
			(xy 107.942078 -382.919433) (xy 107.894316 -382.925473) (xy 107.870244 -382.925828) (xy 107.842988 -382.925368)
			(xy 107.789029 -382.917616) (xy 107.736723 -382.902263) (xy 107.687135 -382.879622) (xy 107.641274 -382.850153)
			(xy 107.600074 -382.814458) (xy 107.564373 -382.773262) (xy 107.5349 -382.727404) (xy 107.512253 -382.677818)
			(xy 107.496894 -382.625514) (xy 107.489135 -382.571556) (xy 107.489135 -382.517044) (xy 107.496894 -382.463086)
			(xy 107.512253 -382.410782) (xy 107.5349 -382.361196) (xy 107.564373 -382.315338) (xy 107.600074 -382.274142)
			(xy 107.641274 -382.238447) (xy 107.687135 -382.208978) (xy 107.736723 -382.186337) (xy 107.789029 -382.170984)
			(xy 107.842988 -382.163232) (xy 107.870244 -382.162812) (xy 107.902775 -382.163513) (xy 107.966884 -382.174619)
			(xy 107.997752 -382.18491) (xy 108.006388 -382.187958) (xy 108.024168 -382.187704) (xy 108.102654 -382.15824)
			(xy 108.115862 -382.14681) (xy 108.120434 -382.138682) (xy 108.140246 -382.106424) (xy 108.144298 -382.100015)
			(xy 108.148819 -382.085551) (xy 108.149136 -382.077976) (xy 108.149136 -381.796544) (xy 108.148819 -381.788969)
			(xy 108.144295 -381.774506) (xy 108.140246 -381.768096) (xy 108.120434 -381.735838) (xy 108.115862 -381.72771)
			(xy 108.102654 -381.71628) (xy 108.024168 -381.686816) (xy 108.006388 -381.686562) (xy 107.997752 -381.68961)
			(xy 107.966885 -381.699909) (xy 107.902776 -381.711022) (xy 107.870244 -381.711708) (xy 107.842989 -381.711248)
			(xy 107.789033 -381.703496) (xy 107.73673 -381.688144) (xy 107.687145 -381.665504) (xy 107.641286 -381.636037)
			(xy 107.600088 -381.600343) (xy 107.56439 -381.559149) (xy 107.534918 -381.513294) (xy 107.512272 -381.463711)
			(xy 107.496914 -381.41141) (xy 107.489155 -381.357455) (xy 107.489155 -381.302945) (xy 107.496914 -381.24899)
			(xy 107.512272 -381.196689) (xy 107.534918 -381.147106) (xy 107.56439 -381.101251) (xy 107.600088 -381.060057)
			(xy 107.641286 -381.024363) (xy 107.687145 -380.994896) (xy 107.73673 -380.972256) (xy 107.789033 -380.956904)
			(xy 107.842989 -380.949152) (xy 107.870244 -380.948692) (xy 107.89418 -380.949066) (xy 107.941675 -380.95505)
			(xy 107.988052 -380.966918) (xy 108.010452 -380.975362) (xy 108.02239 -380.980188) (xy 108.047282 -380.97714)
			(xy 108.138214 -380.913894) (xy 108.14939 -380.891796) (xy 108.149136 -380.878588) (xy 108.149136 -380.87046)
			(xy 108.149622 -380.843209) (xy 108.157378 -380.789261) (xy 108.172733 -380.736966) (xy 108.195375 -380.687389)
			(xy 108.224841 -380.641539) (xy 108.260532 -380.600348) (xy 108.301723 -380.564657) (xy 108.347573 -380.535191)
			(xy 108.39715 -380.512549) (xy 108.449445 -380.497194) (xy 108.503393 -380.489438) (xy 108.557895 -380.489438)
			(xy 108.611843 -380.497194) (xy 108.664138 -380.512549) (xy 108.713715 -380.535191) (xy 108.759565 -380.564657)
			(xy 108.800756 -380.600348) (xy 108.836447 -380.641539) (xy 108.865913 -380.687389) (xy 108.888555 -380.736966)
			(xy 108.90391 -380.789261) (xy 108.911666 -380.843209) (xy 108.912152 -380.87046) (xy 108.912152 -380.878588)
			(xy 108.911898 -380.891796) (xy 108.923074 -380.913894) (xy 109.014006 -380.97714) (xy 109.038898 -380.980188)
			(xy 109.050836 -380.975362) (xy 109.07323 -380.966899) (xy 109.119607 -380.955022) (xy 109.167107 -380.949052)
			(xy 109.191044 -380.948692) (xy 109.217484 -380.949145) (xy 109.269856 -380.956452) (xy 109.320718 -380.97092)
			(xy 109.369095 -380.992273) (xy 109.414061 -381.0201) (xy 109.454754 -381.053869) (xy 109.490395 -381.092933)
			(xy 109.520301 -381.136544) (xy 109.543899 -381.183866) (xy 109.55274 -381.208788) (xy 109.557058 -381.221488)
			(xy 109.576362 -381.239014) (xy 109.67339 -381.261874) (xy 109.681857 -381.263534) (xy 109.699002 -381.261707)
			(xy 109.71456 -381.254276) (xy 109.720888 -381.248412) (xy 109.941614 -381.027686) (xy 109.949009 -381.020832)
			(xy 109.967608 -381.01309) (xy 109.977682 -381.0127) (xy 110.303818 -381.0127) (xy 110.314929 -381.012143)
			(xy 110.335092 -381.0028) (xy 110.34268 -380.994666) (xy 110.400084 -380.926086) (xy 110.405926 -380.90475)
			(xy 110.403894 -380.893574) (xy 110.401163 -380.877137) (xy 110.398243 -380.843942) (xy 110.398052 -380.82728)
			(xy 110.398539 -380.800029) (xy 110.406298 -380.746081) (xy 110.421654 -380.693786) (xy 110.444296 -380.644209)
			(xy 110.473762 -380.598358) (xy 110.509453 -380.557167) (xy 110.550642 -380.521474) (xy 110.596491 -380.492006)
			(xy 110.646068 -380.469361) (xy 110.698361 -380.454002) (xy 110.752309 -380.446241) (xy 110.77956 -380.445772)
			(xy 110.805856 -380.446217) (xy 110.857949 -380.453451) (xy 110.908554 -380.467773) (xy 110.956712 -380.488912)
			(xy 111.001508 -380.516467) (xy 111.042094 -380.549915) (xy 111.06023 -380.568962) (xy 111.066907 -380.575663)
			(xy 111.083868 -380.584011) (xy 111.09325 -380.585218) (xy 111.125762 -380.588012) (xy 111.134188 -380.588341)
			(xy 111.150524 -380.584203) (xy 111.157766 -380.579884) (xy 111.173511 -380.570422) (xy 111.208746 -380.560088)
			(xy 111.227108 -380.559564) (xy 112.243108 -380.559564) (xy 112.253116 -380.559707) (xy 112.272896 -380.562765)
			(xy 112.282478 -380.56566) (xy 112.294162 -380.56947) (xy 112.317784 -380.56566) (xy 112.394492 -380.510034)
			(xy 112.403807 -380.502386) (xy 112.414696 -380.48092) (xy 112.41532 -380.468886) (xy 112.41532 -379.349762)
			(xy 112.415751 -379.339695) (xy 112.423477 -379.321103) (xy 112.430306 -379.313694) (xy 112.738154 -379.005846)
			(xy 112.745553 -378.999003) (xy 112.764152 -378.991281) (xy 112.774222 -378.99086) (xy 133.565138 -378.99086)
			(xy 133.575204 -378.991292) (xy 133.593793 -378.999022) (xy 133.601206 -379.005846) (xy 133.944212 -379.348852)
			(xy 137.336246 -379.348852) (xy 137.336246 -379.294348) (xy 137.344002 -379.240397) (xy 137.359358 -379.1881)
			(xy 137.381999 -379.13852) (xy 137.411465 -379.092667) (xy 137.447157 -379.051474) (xy 137.488348 -379.01578)
			(xy 137.534199 -378.98631) (xy 137.583778 -378.963666) (xy 137.636074 -378.948307) (xy 137.690024 -378.940547)
			(xy 137.717276 -378.94006) (xy 137.741348 -378.940406) (xy 137.789111 -378.94645) (xy 137.835737 -378.958445)
			(xy 137.858246 -378.966984) (xy 137.870692 -378.972064) (xy 137.8966 -378.968762) (xy 137.987278 -378.90196)
			(xy 137.9982 -378.878338) (xy 137.997184 -378.86513) (xy 137.996168 -378.836428) (xy 137.996654 -378.809177)
			(xy 138.00441 -378.755229) (xy 138.019765 -378.702934) (xy 138.042407 -378.653357) (xy 138.071873 -378.607507)
			(xy 138.107564 -378.566316) (xy 138.148755 -378.530625) (xy 138.194605 -378.501159) (xy 138.244182 -378.478517)
			(xy 138.296477 -378.463162) (xy 138.350425 -378.455406) (xy 138.404927 -378.455406) (xy 138.458875 -378.463162)
			(xy 138.51117 -378.478517) (xy 138.560747 -378.501159) (xy 138.606597 -378.530625) (xy 138.647788 -378.566316)
			(xy 138.683479 -378.607507) (xy 138.712945 -378.653357) (xy 138.735587 -378.702934) (xy 138.750942 -378.755229)
			(xy 138.758698 -378.809177) (xy 138.759184 -378.836428) (xy 138.758168 -378.86513) (xy 138.757152 -378.878338)
			(xy 138.768074 -378.90196) (xy 138.858752 -378.968762) (xy 138.88466 -378.972064) (xy 138.897106 -378.966984)
			(xy 138.919617 -378.958449) (xy 138.96624 -378.946444) (xy 139.014004 -378.940411) (xy 139.038076 -378.94006)
			(xy 139.065328 -378.940586) (xy 139.119277 -378.948339) (xy 139.171573 -378.963692) (xy 139.221152 -378.986331)
			(xy 139.267004 -379.015796) (xy 139.308196 -379.051487) (xy 139.34389 -379.092676) (xy 139.373357 -379.138527)
			(xy 139.396 -379.188104) (xy 139.411356 -379.2404) (xy 139.419113 -379.294348) (xy 139.419113 -379.348852)
			(xy 139.411356 -379.4028) (xy 139.396 -379.455096) (xy 139.373357 -379.504673) (xy 139.34389 -379.550524)
			(xy 139.308196 -379.591713) (xy 139.267004 -379.627404) (xy 139.221152 -379.656869) (xy 139.171573 -379.679508)
			(xy 139.119277 -379.694861) (xy 139.065328 -379.702614) (xy 139.038076 -379.703076) (xy 139.005544 -379.702387)
			(xy 138.941435 -379.691276) (xy 138.910568 -379.680978) (xy 138.901932 -379.67793) (xy 138.884152 -379.678184)
			(xy 138.805666 -379.707648) (xy 138.792458 -379.719078) (xy 138.787886 -379.727206) (xy 138.768074 -379.759464)
			(xy 138.764039 -379.765882) (xy 138.759506 -379.780339) (xy 138.759184 -379.787912) (xy 138.759184 -380.069344)
			(xy 138.759511 -380.076919) (xy 138.764025 -380.091383) (xy 138.768074 -380.097792) (xy 138.787886 -380.13005)
			(xy 138.792458 -380.138178) (xy 138.805666 -380.149608) (xy 138.884152 -380.179072) (xy 138.901932 -380.179326)
			(xy 138.910568 -380.176278) (xy 138.941434 -380.165982) (xy 139.005545 -380.154879) (xy 139.038076 -380.15418)
			(xy 139.065329 -380.154666) (xy 139.119281 -380.16242) (xy 139.17158 -380.177773) (xy 139.221162 -380.200414)
			(xy 139.267016 -380.22988) (xy 139.308211 -380.265572) (xy 139.343906 -380.306764) (xy 139.373375 -380.352617)
			(xy 139.396019 -380.402197) (xy 139.411375 -380.454496) (xy 139.419133 -380.508447) (xy 139.419133 -380.562953)
			(xy 139.411375 -380.616904) (xy 139.396019 -380.669203) (xy 139.373375 -380.718783) (xy 139.343906 -380.764636)
			(xy 139.308211 -380.805828) (xy 139.267016 -380.84152) (xy 139.221162 -380.870986) (xy 139.17158 -380.893627)
			(xy 139.119281 -380.90898) (xy 139.065329 -380.916734) (xy 139.038076 -380.917196) (xy 139.014005 -380.91683)
			(xy 138.966242 -380.910794) (xy 138.919616 -380.898807) (xy 138.897106 -380.890272) (xy 138.88466 -380.885192)
			(xy 138.858752 -380.888494) (xy 138.768074 -380.955296) (xy 138.757152 -380.978918) (xy 138.758168 -380.992126)
			(xy 138.759184 -381.020828) (xy 138.758698 -381.048079) (xy 138.750942 -381.102027) (xy 138.735587 -381.154322)
			(xy 138.712945 -381.203899) (xy 138.683479 -381.249749) (xy 138.647788 -381.29094) (xy 138.606597 -381.326631)
			(xy 138.560747 -381.356097) (xy 138.51117 -381.378739) (xy 138.458875 -381.394094) (xy 138.404927 -381.40185)
			(xy 138.350425 -381.40185) (xy 138.296477 -381.394094) (xy 138.244182 -381.378739) (xy 138.194605 -381.356097)
			(xy 138.148755 -381.326631) (xy 138.107564 -381.29094) (xy 138.071873 -381.249749) (xy 138.042407 -381.203899)
			(xy 138.019765 -381.154322) (xy 138.00441 -381.102027) (xy 137.996654 -381.048079) (xy 137.996168 -381.020828)
			(xy 137.997184 -380.992126) (xy 137.9982 -380.978918) (xy 137.987278 -380.955296) (xy 137.8966 -380.888494)
			(xy 137.870692 -380.885192) (xy 137.858246 -380.890272) (xy 137.835741 -380.898824) (xy 137.789115 -380.910821)
			(xy 137.741349 -380.916848) (xy 137.717276 -380.917196) (xy 137.690025 -380.916733) (xy 137.636078 -380.908973)
			(xy 137.583785 -380.893615) (xy 137.534209 -380.870972) (xy 137.48836 -380.841504) (xy 137.447171 -380.805812)
			(xy 137.411481 -380.764621) (xy 137.382016 -380.71877) (xy 137.359376 -380.669193) (xy 137.344022 -380.616898)
			(xy 137.336266 -380.562951) (xy 137.336266 -380.508449) (xy 137.344022 -380.454502) (xy 137.359376 -380.402207)
			(xy 137.382016 -380.35263) (xy 137.411481 -380.306779) (xy 137.447171 -380.265588) (xy 137.48836 -380.229896)
			(xy 137.534209 -380.200428) (xy 137.583785 -380.177785) (xy 137.636078 -380.162427) (xy 137.690025 -380.154667)
			(xy 137.717276 -380.15418) (xy 137.749808 -380.154859) (xy 137.813918 -380.165977) (xy 137.844784 -380.176278)
			(xy 137.85342 -380.179326) (xy 137.8712 -380.179072) (xy 137.949686 -380.149608) (xy 137.962894 -380.138178)
			(xy 137.967466 -380.13005) (xy 137.987278 -380.097792) (xy 137.991334 -380.091386) (xy 137.995853 -380.07692)
			(xy 137.996168 -380.069344) (xy 137.996168 -379.787912) (xy 137.995851 -379.780337) (xy 137.99133 -379.765873)
			(xy 137.987278 -379.759464) (xy 137.967466 -379.727206) (xy 137.962894 -379.719078) (xy 137.949686 -379.707648)
			(xy 137.8712 -379.678184) (xy 137.85342 -379.67793) (xy 137.844784 -379.680978) (xy 137.813913 -379.691261)
			(xy 137.749806 -379.702373) (xy 137.717276 -379.703076) (xy 137.690024 -379.702653) (xy 137.636074 -379.694893)
			(xy 137.583778 -379.679534) (xy 137.534199 -379.65689) (xy 137.488348 -379.62742) (xy 137.447157 -379.591726)
			(xy 137.411465 -379.550533) (xy 137.381999 -379.50468) (xy 137.359358 -379.4551) (xy 137.344002 -379.402803)
			(xy 137.336246 -379.348852) (xy 133.944212 -379.348852) (xy 134.030974 -379.435614) (xy 134.037821 -379.443012)
			(xy 134.045554 -379.46161) (xy 134.04596 -379.471682) (xy 134.04596 -380.277878) (xy 134.045521 -380.287941)
			(xy 134.037783 -380.306521) (xy 134.030974 -380.313946) (xy 133.987286 -380.357634) (xy 133.980435 -380.36503)
			(xy 133.9727 -380.383629) (xy 133.9723 -380.393702) (xy 133.9723 -380.798578) (xy 133.972738 -380.808642)
			(xy 133.980472 -380.827226) (xy 133.987286 -380.834646) (xy 134.150354 -380.997714) (xy 134.157751 -381.004561)
			(xy 134.176351 -381.012289) (xy 134.186422 -381.0127) (xy 136.831578 -381.0127) (xy 136.841642 -381.013138)
			(xy 136.860226 -381.020872) (xy 136.867646 -381.027686) (xy 137.64641 -381.80645) (xy 137.653258 -381.813847)
			(xy 137.660989 -381.832446) (xy 137.661396 -381.842518) (xy 137.661396 -382.487932) (xy 137.663428 -382.495044)
			(xy 137.668408 -382.512856) (xy 137.673765 -382.54945) (xy 137.674096 -382.567942) (xy 137.674096 -382.604264)
			(xy 137.677906 -382.617472) (xy 137.681462 -382.623568) (xy 137.689796 -382.638654) (xy 137.698925 -382.671874)
			(xy 137.699496 -382.6891) (xy 137.699496 -383.0701) (xy 137.699107 -383.084257) (xy 137.69288 -383.111878)
			(xy 137.68075 -383.137462) (xy 137.672318 -383.14884) (xy 137.666984 -383.155698) (xy 137.661396 -383.1717)
			(xy 137.661396 -383.667508) (xy 137.662031 -383.678924) (xy 137.671932 -383.699499) (xy 137.680446 -383.707132)
			(xy 137.705498 -383.727876) (xy 137.750647 -383.774697) (xy 137.789457 -383.826892) (xy 137.821294 -383.883611)
			(xy 137.845638 -383.943927) (xy 137.862093 -384.006854) (xy 137.870389 -384.071366) (xy 137.87039 -384.136409)
			(xy 137.862098 -384.200921) (xy 137.845646 -384.26385) (xy 137.821305 -384.324166) (xy 137.789471 -384.380887)
			(xy 137.750663 -384.433084) (xy 137.705517 -384.479907) (xy 137.680446 -384.500628) (xy 137.671938 -384.508262)
			(xy 137.662059 -384.528839) (xy 137.661396 -384.540252) (xy 137.661396 -384.658108) (xy 137.662031 -384.669524)
			(xy 137.671932 -384.690099) (xy 137.680446 -384.697732) (xy 137.705498 -384.718476) (xy 137.750647 -384.765297)
			(xy 137.789459 -384.817492) (xy 137.821301 -384.874209) (xy 137.845652 -384.934522) (xy 137.862115 -384.997447)
			(xy 137.870422 -385.061958) (xy 137.870946 -385.09448) (xy 137.870484 -385.125213) (xy 137.863077 -385.18623)
			(xy 137.84837 -385.24591) (xy 137.826577 -385.303382) (xy 137.798016 -385.357808) (xy 137.763102 -385.408395)
			(xy 137.722346 -385.454405) (xy 137.676341 -385.495166) (xy 137.625758 -385.530086) (xy 137.571335 -385.558653)
			(xy 137.513865 -385.580453) (xy 137.454187 -385.595167) (xy 137.393171 -385.60258) (xy 137.362438 -385.602988)
			(xy 137.330338 -385.602479) (xy 137.266651 -385.594371) (xy 137.204486 -385.57833) (xy 137.174478 -385.56692)
			(xy 137.169965 -385.565233) (xy 137.1605 -385.563437) (xy 137.155682 -385.563364) (xy 137.150348 -385.563364)
			(xy 137.076688 -385.637024) (xy 137.069836 -385.64442) (xy 137.062096 -385.663019) (xy 137.061702 -385.673092)
			(xy 137.061702 -385.841748) (xy 137.065258 -385.850892) (xy 137.076898 -385.881156) (xy 137.093282 -385.943896)
			(xy 137.101558 -386.008209) (xy 137.102088 -386.04063) (xy 137.101563 -386.073052) (xy 137.093288 -386.137366)
			(xy 137.076903 -386.200105) (xy 137.065258 -386.230368) (xy 137.061702 -386.239512) (xy 137.061702 -386.612638)
			(xy 137.062132 -386.622705) (xy 137.069857 -386.641299) (xy 137.076688 -386.648706) (xy 137.13206 -386.704078)
			(xy 137.139461 -386.710917) (xy 137.158059 -386.718633) (xy 137.168128 -386.719064) (xy 137.254488 -386.719064)
			(xy 137.261346 -386.717032) (xy 137.286909 -386.710246) (xy 137.339295 -386.702979) (xy 137.36574 -386.702554)
			(xy 137.392184 -386.702985) (xy 137.444572 -386.710244) (xy 137.470134 -386.717032) (xy 137.476992 -386.719064)
			(xy 140.262356 -386.719064) (xy 140.272421 -386.71863) (xy 140.291007 -386.710897) (xy 140.298424 -386.704078)
			(xy 140.545058 -386.457444) (xy 140.552458 -386.450602) (xy 140.571056 -386.442882) (xy 140.581126 -386.442458)
			(xy 140.753338 -386.442458) (xy 140.76045 -386.440172) (xy 140.79708 -386.429627) (xy 140.872453 -386.418279)
			(xy 140.910564 -386.417566) (xy 140.931489 -386.417779) (xy 140.973198 -386.421211) (xy 140.993876 -386.424424)
			(xy 141.00302 -386.425948) (xy 141.0208 -386.422646) (xy 141.092936 -386.378958) (xy 141.104112 -386.364988)
			(xy 141.10716 -386.356352) (xy 141.116516 -386.329784) (xy 141.141937 -386.279522) (xy 141.174472 -386.233543)
			(xy 141.213414 -386.192849) (xy 141.257917 -386.158323) (xy 141.307012 -386.130715) (xy 141.359634 -386.110627)
			(xy 141.414637 -386.098494) (xy 141.442694 -386.096002) (xy 141.451912 -386.094956) (xy 141.468717 -386.087134)
			(xy 141.47546 -386.080762) (xy 141.496796 -386.059172) (xy 141.503378 -386.05179) (xy 141.510831 -386.033492)
			(xy 141.511274 -386.023612) (xy 141.511274 -386.010404) (xy 141.513052 -386.008626) (xy 141.513052 -383.359152)
			(xy 141.512607 -383.348975) (xy 141.504699 -383.33022) (xy 141.490111 -383.316026) (xy 141.480794 -383.311908)
			(xy 141.378178 -383.271522) (xy 141.347952 -383.27838) (xy 141.337284 -383.28981) (xy 141.319181 -383.308581)
			(xy 141.278735 -383.3415) (xy 141.23418 -383.368601) (xy 141.186348 -383.389377) (xy 141.136132 -383.403443)
			(xy 141.084467 -383.410534) (xy 141.058392 -383.410968) (xy 141.031141 -383.410504) (xy 140.977193 -383.402746)
			(xy 140.924898 -383.387389) (xy 140.875321 -383.364745) (xy 140.829472 -383.335276) (xy 140.788284 -383.299582)
			(xy 140.752595 -383.258389) (xy 140.723132 -383.212536) (xy 140.700494 -383.162957) (xy 140.685144 -383.11066)
			(xy 140.677392 -383.056712) (xy 140.676884 -383.02946) (xy 140.6779 -383.000758) (xy 140.678916 -382.98755)
			(xy 140.667994 -382.963928) (xy 140.577316 -382.897126) (xy 140.551408 -382.893824) (xy 140.538962 -382.898904)
			(xy 140.516452 -382.907439) (xy 140.469826 -382.919424) (xy 140.422063 -382.925457) (xy 140.397992 -382.925828)
			(xy 140.37074 -382.925342) (xy 140.31679 -382.917584) (xy 140.264493 -382.902227) (xy 140.214915 -382.879584)
			(xy 140.169063 -382.850116) (xy 140.127871 -382.814423) (xy 140.092179 -382.773231) (xy 140.062712 -382.727378)
			(xy 140.04007 -382.677799) (xy 140.024715 -382.625502) (xy 140.016958 -382.571552) (xy 140.016958 -382.517048)
			(xy 140.024715 -382.463098) (xy 140.04007 -382.410801) (xy 140.062712 -382.361222) (xy 140.092179 -382.315369)
			(xy 140.127871 -382.274177) (xy 140.169063 -382.238484) (xy 140.214915 -382.209016) (xy 140.264493 -382.186373)
			(xy 140.31679 -382.171016) (xy 140.37074 -382.163258) (xy 140.397992 -382.162812) (xy 140.430522 -382.163517)
			(xy 140.494628 -382.174631) (xy 140.5255 -382.18491) (xy 140.534136 -382.187958) (xy 140.551916 -382.187704)
			(xy 140.630402 -382.15824) (xy 140.64361 -382.14681) (xy 140.648182 -382.138682) (xy 140.667994 -382.106424)
			(xy 140.672043 -382.100014) (xy 140.67656 -382.085551) (xy 140.676884 -382.077976) (xy 140.676884 -381.796544)
			(xy 140.676568 -381.788968) (xy 140.672048 -381.774504) (xy 140.667994 -381.768096) (xy 140.648182 -381.735838)
			(xy 140.64361 -381.72771) (xy 140.630402 -381.71628) (xy 140.551916 -381.686816) (xy 140.534136 -381.686562)
			(xy 140.5255 -381.68961) (xy 140.494633 -381.699905) (xy 140.430523 -381.711009) (xy 140.397992 -381.711708)
			(xy 140.370741 -381.711222) (xy 140.316794 -381.703464) (xy 140.2645 -381.688108) (xy 140.214924 -381.665467)
			(xy 140.169075 -381.636) (xy 140.127886 -381.600309) (xy 140.092195 -381.559119) (xy 140.062729 -381.513269)
			(xy 140.040089 -381.463692) (xy 140.024734 -381.411398) (xy 140.016978 -381.357451) (xy 140.016978 -381.302949)
			(xy 140.024734 -381.249002) (xy 140.040089 -381.196708) (xy 140.062729 -381.147131) (xy 140.092195 -381.101281)
			(xy 140.127886 -381.060091) (xy 140.169075 -381.0244) (xy 140.214924 -380.994933) (xy 140.2645 -380.972292)
			(xy 140.316794 -380.956936) (xy 140.370741 -380.949178) (xy 140.397992 -380.948692) (xy 140.421927 -380.949069)
			(xy 140.469421 -380.955059) (xy 140.515795 -380.966932) (xy 140.5382 -380.975362) (xy 140.550138 -380.980188)
			(xy 140.57503 -380.97714) (xy 140.665962 -380.913894) (xy 140.677138 -380.891796) (xy 140.676884 -380.878588)
			(xy 140.676884 -380.87046) (xy 140.67737 -380.843209) (xy 140.685126 -380.789261) (xy 140.700481 -380.736966)
			(xy 140.723123 -380.687389) (xy 140.752589 -380.641539) (xy 140.78828 -380.600348) (xy 140.829471 -380.564657)
			(xy 140.875321 -380.535191) (xy 140.924898 -380.512549) (xy 140.977193 -380.497194) (xy 141.031141 -380.489438)
			(xy 141.085643 -380.489438) (xy 141.139591 -380.497194) (xy 141.191886 -380.512549) (xy 141.241463 -380.535191)
			(xy 141.287313 -380.564657) (xy 141.328504 -380.600348) (xy 141.364195 -380.641539) (xy 141.393661 -380.687389)
			(xy 141.416303 -380.736966) (xy 141.431658 -380.789261) (xy 141.439414 -380.843209) (xy 141.4399 -380.87046)
			(xy 141.4399 -380.878588) (xy 141.439646 -380.891796) (xy 141.450822 -380.913894) (xy 141.541754 -380.97714)
			(xy 141.566646 -380.980188) (xy 141.578584 -380.975362) (xy 141.600977 -380.966896) (xy 141.647354 -380.955012)
			(xy 141.694854 -380.949036) (xy 141.718792 -380.948692) (xy 141.746874 -380.949191) (xy 141.80243 -380.957426)
			(xy 141.856178 -380.973719) (xy 141.906956 -380.997719) (xy 141.953665 -381.028905) (xy 141.995296 -381.066604)
			(xy 142.030948 -381.110001) (xy 142.059851 -381.158156) (xy 142.07109 -381.183896) (xy 142.075916 -381.19558)
			(xy 142.095474 -381.211582) (xy 142.190978 -381.230632) (xy 142.203403 -381.232372) (xy 142.22737 -381.225052)
			(xy 142.236698 -381.216662) (xy 142.463774 -380.989586) (xy 142.471172 -380.982742) (xy 142.489772 -380.975021)
			(xy 142.499842 -380.9746) (xy 142.5067 -380.9746) (xy 142.579852 -380.896114) (xy 142.58671 -380.876302)
			(xy 142.585948 -380.865634) (xy 142.584932 -380.83744) (xy 142.585393 -380.810186) (xy 142.593145 -380.756233)
			(xy 142.608498 -380.703933) (xy 142.631139 -380.65435) (xy 142.660606 -380.608495) (xy 142.696301 -380.567301)
			(xy 142.737495 -380.531606) (xy 142.78335 -380.502139) (xy 142.832933 -380.479498) (xy 142.885233 -380.464145)
			(xy 142.939186 -380.456393) (xy 142.96644 -380.455932) (xy 142.993413 -380.4564) (xy 143.04682 -380.464002)
			(xy 143.098625 -380.479048) (xy 143.147795 -380.501239) (xy 143.19335 -380.530132) (xy 143.234384 -380.565153)
			(xy 143.270077 -380.605602) (xy 143.299719 -380.650674) (xy 143.311626 -380.67488) (xy 143.315436 -380.683008)
			(xy 143.585946 -380.953518) (xy 143.593309 -380.960349) (xy 143.611822 -380.968099) (xy 143.631891 -380.968156)
			(xy 143.641318 -380.964694) (xy 143.655796 -380.958598) (xy 143.67256 -380.933198) (xy 143.67256 -380.86919)
			(xy 143.67306 -380.852482) (xy 143.681722 -380.820209) (xy 143.698451 -380.791284) (xy 143.722105 -380.767681)
			(xy 143.751067 -380.751015) (xy 143.783359 -380.742424) (xy 143.800068 -380.741936) (xy 144.816068 -380.741936)
			(xy 144.832763 -380.742475) (xy 144.865018 -380.751101) (xy 144.893945 -380.767775) (xy 144.917577 -380.791362)
			(xy 144.934306 -380.820258) (xy 144.942993 -380.852497) (xy 144.943576 -380.86919) (xy 144.943576 -380.9238)
			(xy 144.944064 -380.933809) (xy 144.951722 -380.952305) (xy 144.965874 -380.966464) (xy 144.984367 -380.974132)
			(xy 144.994376 -380.9746) (xy 145.02638 -380.9746) (xy 145.036404 -380.974184) (xy 145.054928 -380.966518)
			(xy 145.069106 -380.952345) (xy 145.07678 -380.933824) (xy 145.07718 -380.9238) (xy 145.07718 -379.619002)
			(xy 145.077602 -379.608931) (xy 145.085314 -379.590324) (xy 145.092166 -379.582934) (xy 145.620994 -379.054106)
			(xy 145.628392 -379.047258) (xy 145.64699 -379.03952) (xy 145.657062 -379.03912) (xy 166.066978 -379.03912)
			(xy 166.077041 -379.039558) (xy 166.095623 -379.047294) (xy 166.103046 -379.054106) (xy 166.397796 -379.348856)
			(xy 169.863923 -379.348856) (xy 169.863923 -379.294344) (xy 169.871681 -379.240386) (xy 169.88704 -379.188082)
			(xy 169.909686 -379.138496) (xy 169.939159 -379.092638) (xy 169.974858 -379.051441) (xy 170.016057 -379.015744)
			(xy 170.061917 -378.986274) (xy 170.111504 -378.963631) (xy 170.16381 -378.948276) (xy 170.217768 -378.940521)
			(xy 170.245024 -378.94006) (xy 170.269095 -378.940422) (xy 170.316858 -378.946459) (xy 170.363484 -378.958448)
			(xy 170.385994 -378.966984) (xy 170.39844 -378.972064) (xy 170.424348 -378.968762) (xy 170.515026 -378.90196)
			(xy 170.525948 -378.878338) (xy 170.524932 -378.86513) (xy 170.523916 -378.836428) (xy 170.524402 -378.809177)
			(xy 170.532158 -378.755229) (xy 170.547513 -378.702934) (xy 170.570155 -378.653357) (xy 170.599621 -378.607507)
			(xy 170.635312 -378.566316) (xy 170.676503 -378.530625) (xy 170.722353 -378.501159) (xy 170.77193 -378.478517)
			(xy 170.824225 -378.463162) (xy 170.878173 -378.455406) (xy 170.932675 -378.455406) (xy 170.986623 -378.463162)
			(xy 171.038918 -378.478517) (xy 171.088495 -378.501159) (xy 171.134345 -378.530625) (xy 171.175536 -378.566316)
			(xy 171.211227 -378.607507) (xy 171.240693 -378.653357) (xy 171.263335 -378.702934) (xy 171.27869 -378.755229)
			(xy 171.286446 -378.809177) (xy 171.286932 -378.836428) (xy 171.285916 -378.86513) (xy 171.2849 -378.878338)
			(xy 171.295822 -378.90196) (xy 171.3865 -378.968762) (xy 171.412408 -378.972064) (xy 171.424854 -378.966984)
			(xy 171.44736 -378.958435) (xy 171.493985 -378.946436) (xy 171.541751 -378.940408) (xy 171.565824 -378.94006)
			(xy 171.593072 -378.940612) (xy 171.647012 -378.94837) (xy 171.6993 -378.963726) (xy 171.74887 -378.986367)
			(xy 171.794713 -379.015831) (xy 171.835897 -379.05152) (xy 171.871583 -379.092706) (xy 171.901045 -379.138551)
			(xy 171.923682 -379.188123) (xy 171.939035 -379.240411) (xy 171.94679 -379.294352) (xy 171.94679 -379.348848)
			(xy 171.939035 -379.402789) (xy 171.923682 -379.455077) (xy 171.901045 -379.504649) (xy 171.871583 -379.550494)
			(xy 171.835897 -379.59168) (xy 171.794713 -379.627369) (xy 171.74887 -379.656833) (xy 171.6993 -379.679474)
			(xy 171.647012 -379.69483) (xy 171.593072 -379.702588) (xy 171.565824 -379.703076) (xy 171.533291 -379.7024)
			(xy 171.469182 -379.69128) (xy 171.438316 -379.680978) (xy 171.42968 -379.67793) (xy 171.4119 -379.678184)
			(xy 171.333414 -379.707648) (xy 171.320206 -379.719078) (xy 171.315634 -379.727206) (xy 171.295822 -379.759464)
			(xy 171.291782 -379.76588) (xy 171.287254 -379.780338) (xy 171.286932 -379.787912) (xy 171.286932 -380.069344)
			(xy 171.287267 -380.076918) (xy 171.291776 -380.091382) (xy 171.295822 -380.097792) (xy 171.315634 -380.13005)
			(xy 171.320206 -380.138178) (xy 171.333414 -380.149608) (xy 171.4119 -380.179072) (xy 171.42968 -380.179326)
			(xy 171.438316 -380.176278) (xy 171.469186 -380.165994) (xy 171.533294 -380.154883) (xy 171.565824 -380.15418)
			(xy 171.593073 -380.154692) (xy 171.647017 -380.162451) (xy 171.699307 -380.177808) (xy 171.748879 -380.200449)
			(xy 171.794725 -380.229915) (xy 171.835911 -380.265606) (xy 171.871599 -380.306794) (xy 171.901062 -380.352642)
			(xy 171.923701 -380.402216) (xy 171.939054 -380.454507) (xy 171.94681 -380.508451) (xy 171.94681 -380.562949)
			(xy 171.939054 -380.616893) (xy 171.923701 -380.669184) (xy 171.901062 -380.718758) (xy 171.871599 -380.764606)
			(xy 171.835911 -380.805794) (xy 171.794725 -380.841485) (xy 171.748879 -380.870951) (xy 171.699307 -380.893592)
			(xy 171.647017 -380.908949) (xy 171.593073 -380.916708) (xy 171.565824 -380.917196) (xy 171.541752 -380.916846)
			(xy 171.493989 -380.910803) (xy 171.447364 -380.89881) (xy 171.424854 -380.890272) (xy 171.412408 -380.885192)
			(xy 171.3865 -380.888494) (xy 171.295822 -380.955296) (xy 171.2849 -380.978918) (xy 171.285916 -380.992126)
			(xy 171.286932 -381.020828) (xy 171.286446 -381.048079) (xy 171.27869 -381.102027) (xy 171.263335 -381.154322)
			(xy 171.240693 -381.203899) (xy 171.211227 -381.249749) (xy 171.175536 -381.29094) (xy 171.134345 -381.326631)
			(xy 171.088495 -381.356097) (xy 171.038918 -381.378739) (xy 170.986623 -381.394094) (xy 170.932675 -381.40185)
			(xy 170.878173 -381.40185) (xy 170.824225 -381.394094) (xy 170.77193 -381.378739) (xy 170.722353 -381.356097)
			(xy 170.676503 -381.326631) (xy 170.635312 -381.29094) (xy 170.599621 -381.249749) (xy 170.570155 -381.203899)
			(xy 170.547513 -381.154322) (xy 170.532158 -381.102027) (xy 170.524402 -381.048079) (xy 170.523916 -381.020828)
			(xy 170.524932 -380.992126) (xy 170.525948 -380.978918) (xy 170.515026 -380.955296) (xy 170.424348 -380.888494)
			(xy 170.39844 -380.885192) (xy 170.385994 -380.890272) (xy 170.363484 -380.89881) (xy 170.31686 -380.910813)
			(xy 170.269096 -380.916845) (xy 170.245024 -380.917196) (xy 170.217769 -380.916759) (xy 170.163814 -380.909004)
			(xy 170.111511 -380.89365) (xy 170.061927 -380.871008) (xy 170.016069 -380.84154) (xy 169.974872 -380.805845)
			(xy 169.939175 -380.76465) (xy 169.909704 -380.718794) (xy 169.887059 -380.669211) (xy 169.871701 -380.61691)
			(xy 169.863943 -380.562955) (xy 169.863943 -380.508445) (xy 169.871701 -380.45449) (xy 169.887059 -380.402189)
			(xy 169.909704 -380.352606) (xy 169.939175 -380.30675) (xy 169.974872 -380.265555) (xy 170.016069 -380.22986)
			(xy 170.061927 -380.200392) (xy 170.111511 -380.17775) (xy 170.163814 -380.162396) (xy 170.217769 -380.154641)
			(xy 170.245024 -380.15418) (xy 170.277556 -380.154872) (xy 170.341665 -380.165981) (xy 170.372532 -380.176278)
			(xy 170.381168 -380.179326) (xy 170.398948 -380.179072) (xy 170.477434 -380.149608) (xy 170.490642 -380.138178)
			(xy 170.495214 -380.13005) (xy 170.515026 -380.097792) (xy 170.519078 -380.091383) (xy 170.5236 -380.07692)
			(xy 170.523916 -380.069344) (xy 170.523916 -379.787912) (xy 170.523607 -379.780336) (xy 170.519081 -379.765872)
			(xy 170.515026 -379.759464) (xy 170.495214 -379.727206) (xy 170.490642 -379.719078) (xy 170.477434 -379.707648)
			(xy 170.398948 -379.678184) (xy 170.381168 -379.67793) (xy 170.372532 -379.680978) (xy 170.341665 -379.691273)
			(xy 170.277555 -379.702377) (xy 170.245024 -379.703076) (xy 170.217768 -379.702679) (xy 170.16381 -379.694924)
			(xy 170.111504 -379.679569) (xy 170.061917 -379.656926) (xy 170.016057 -379.627456) (xy 169.974858 -379.591759)
			(xy 169.939159 -379.550562) (xy 169.909686 -379.504704) (xy 169.88704 -379.455118) (xy 169.871681 -379.402814)
			(xy 169.863923 -379.348856) (xy 166.397796 -379.348856) (xy 166.545514 -379.496574) (xy 166.552358 -379.503972)
			(xy 166.560079 -379.522572) (xy 166.5605 -379.532642) (xy 166.5605 -380.808738) (xy 166.56093 -380.818805)
			(xy 166.568654 -380.837399) (xy 166.575486 -380.844806) (xy 166.690294 -380.959614) (xy 166.697688 -380.966471)
			(xy 166.716287 -380.974221) (xy 166.726362 -380.9746) (xy 169.503598 -380.9746) (xy 169.513668 -380.975023)
			(xy 169.532273 -380.982737) (xy 169.539666 -380.989586) (xy 170.330114 -381.780034) (xy 170.336965 -381.78743)
			(xy 170.3447 -381.806029) (xy 170.3451 -381.816102) (xy 170.3451 -386.010404) (xy 170.98848 -386.010404)
			(xy 170.992551 -385.954782) (xy 171.004677 -385.900345) (xy 171.0246 -385.848254) (xy 171.051896 -385.799619)
			(xy 171.085982 -385.755476) (xy 171.126131 -385.716767) (xy 171.171489 -385.684316) (xy 171.221089 -385.658815)
			(xy 171.273873 -385.640808) (xy 171.328716 -385.630678) (xy 171.38445 -385.628641) (xy 171.439887 -385.634741)
			(xy 171.493844 -385.648847) (xy 171.545173 -385.670659) (xy 171.592779 -385.699713) (xy 171.635647 -385.735388)
			(xy 171.672864 -385.776925) (xy 171.703637 -385.823438) (xy 171.727309 -385.873935) (xy 171.743377 -385.927342)
			(xy 171.751497 -385.982518) (xy 171.752006 -386.010404) (xy 171.751497 -386.03829) (xy 171.743377 -386.093466)
			(xy 171.727309 -386.146873) (xy 171.724842 -386.152136) (xy 172.518322 -386.152136) (xy 172.522393 -386.096514)
			(xy 172.534519 -386.042077) (xy 172.554442 -385.989986) (xy 172.581738 -385.941351) (xy 172.615824 -385.897208)
			(xy 172.655973 -385.858499) (xy 172.701331 -385.826048) (xy 172.750931 -385.800547) (xy 172.803715 -385.78254)
			(xy 172.858558 -385.77241) (xy 172.914292 -385.770373) (xy 172.969729 -385.776473) (xy 173.023686 -385.790579)
			(xy 173.075015 -385.812391) (xy 173.122621 -385.841445) (xy 173.165489 -385.87712) (xy 173.202706 -385.918657)
			(xy 173.233479 -385.96517) (xy 173.2398 -385.978654) (xy 174.400462 -385.978654) (xy 174.404533 -385.923032)
			(xy 174.416659 -385.868595) (xy 174.436582 -385.816504) (xy 174.463878 -385.767869) (xy 174.497964 -385.723726)
			(xy 174.538113 -385.685017) (xy 174.583471 -385.652566) (xy 174.633071 -385.627065) (xy 174.685855 -385.609058)
			(xy 174.740698 -385.598928) (xy 174.796432 -385.596891) (xy 174.851869 -385.602991) (xy 174.905826 -385.617097)
			(xy 174.957155 -385.638909) (xy 175.004761 -385.667963) (xy 175.047629 -385.703638) (xy 175.084846 -385.745175)
			(xy 175.115619 -385.791688) (xy 175.139291 -385.842185) (xy 175.155359 -385.895592) (xy 175.163479 -385.950768)
			(xy 175.163988 -385.978654) (xy 175.163479 -386.00654) (xy 175.155359 -386.061716) (xy 175.139291 -386.115123)
			(xy 175.115619 -386.16562) (xy 175.084846 -386.212133) (xy 175.047629 -386.25367) (xy 175.004761 -386.289345)
			(xy 174.957155 -386.318399) (xy 174.905826 -386.340211) (xy 174.851869 -386.354317) (xy 174.796432 -386.360417)
			(xy 174.740698 -386.35838) (xy 174.685855 -386.34825) (xy 174.633071 -386.330243) (xy 174.583471 -386.304742)
			(xy 174.538113 -386.272291) (xy 174.497964 -386.233582) (xy 174.463878 -386.189439) (xy 174.436582 -386.140804)
			(xy 174.416659 -386.088713) (xy 174.404533 -386.034276) (xy 174.400462 -385.978654) (xy 173.2398 -385.978654)
			(xy 173.257151 -386.015667) (xy 173.273219 -386.069074) (xy 173.281339 -386.12425) (xy 173.281848 -386.152136)
			(xy 173.281339 -386.180022) (xy 173.273219 -386.235198) (xy 173.257151 -386.288605) (xy 173.233479 -386.339102)
			(xy 173.202706 -386.385615) (xy 173.165489 -386.427152) (xy 173.122621 -386.462827) (xy 173.075015 -386.491881)
			(xy 173.023686 -386.513693) (xy 172.969729 -386.527799) (xy 172.914292 -386.533899) (xy 172.858558 -386.531862)
			(xy 172.803715 -386.521732) (xy 172.750931 -386.503725) (xy 172.701331 -386.478224) (xy 172.655973 -386.445773)
			(xy 172.615824 -386.407064) (xy 172.581738 -386.362921) (xy 172.554442 -386.314286) (xy 172.534519 -386.262195)
			(xy 172.522393 -386.207758) (xy 172.518322 -386.152136) (xy 171.724842 -386.152136) (xy 171.703637 -386.19737)
			(xy 171.672864 -386.243883) (xy 171.635647 -386.28542) (xy 171.592779 -386.321095) (xy 171.545173 -386.350149)
			(xy 171.493844 -386.371961) (xy 171.439887 -386.386067) (xy 171.38445 -386.392167) (xy 171.328716 -386.39013)
			(xy 171.273873 -386.38) (xy 171.221089 -386.361993) (xy 171.171489 -386.336492) (xy 171.126131 -386.304041)
			(xy 171.085982 -386.265332) (xy 171.051896 -386.221189) (xy 171.0246 -386.172554) (xy 171.004677 -386.120463)
			(xy 170.992551 -386.066026) (xy 170.98848 -386.010404) (xy 170.3451 -386.010404) (xy 170.3451 -386.244338)
			(xy 170.34553 -386.254405) (xy 170.353254 -386.272999) (xy 170.360086 -386.280406) (xy 170.561762 -386.482082)
			(xy 170.601132 -386.48386) (xy 170.616372 -386.47116) (xy 170.637077 -386.45435) (xy 170.682292 -386.426069)
			(xy 170.731003 -386.404355) (xy 170.782261 -386.389633) (xy 170.835071 -386.382187) (xy 170.861736 -386.381752)
			(xy 170.888987 -386.38224) (xy 170.942933 -386.390001) (xy 170.995225 -386.405358) (xy 171.044801 -386.428001)
			(xy 171.090649 -386.457468) (xy 171.131838 -386.493159) (xy 171.16753 -386.534348) (xy 171.196997 -386.580196)
			(xy 171.21964 -386.629771) (xy 171.228782 -386.660898) (xy 173.271178 -386.660898) (xy 173.275249 -386.605276)
			(xy 173.287375 -386.550839) (xy 173.307298 -386.498748) (xy 173.334594 -386.450113) (xy 173.36868 -386.40597)
			(xy 173.408829 -386.367261) (xy 173.454187 -386.33481) (xy 173.503787 -386.309309) (xy 173.556571 -386.291302)
			(xy 173.611414 -386.281172) (xy 173.667148 -386.279135) (xy 173.722585 -386.285235) (xy 173.776542 -386.299341)
			(xy 173.827871 -386.321153) (xy 173.875477 -386.350207) (xy 173.918345 -386.385882) (xy 173.955562 -386.427419)
			(xy 173.986335 -386.473932) (xy 174.010007 -386.524429) (xy 174.026075 -386.577836) (xy 174.034195 -386.633012)
			(xy 174.034704 -386.660898) (xy 174.034195 -386.688784) (xy 174.026075 -386.74396) (xy 174.010007 -386.797367)
			(xy 173.986335 -386.847864) (xy 173.955562 -386.894377) (xy 173.918345 -386.935914) (xy 173.875477 -386.971589)
			(xy 173.827871 -387.000643) (xy 173.776542 -387.022455) (xy 173.722585 -387.036561) (xy 173.667148 -387.042661)
			(xy 173.611414 -387.040624) (xy 173.556571 -387.030494) (xy 173.503787 -387.012487) (xy 173.454187 -386.986986)
			(xy 173.408829 -386.954535) (xy 173.36868 -386.915826) (xy 173.334594 -386.871683) (xy 173.307298 -386.823048)
			(xy 173.287375 -386.770957) (xy 173.275249 -386.71652) (xy 173.271178 -386.660898) (xy 171.228782 -386.660898)
			(xy 171.234998 -386.682064) (xy 171.24276 -386.736009) (xy 171.243244 -386.76326) (xy 171.242916 -386.784656)
			(xy 171.238081 -386.827174) (xy 171.233592 -386.848096) (xy 171.231306 -386.858002) (xy 171.234354 -386.877052)
			(xy 171.28109 -386.954522) (xy 171.296584 -386.966206) (xy 171.306236 -386.969) (xy 171.331882 -386.976518)
			(xy 171.380294 -386.999144) (xy 171.424078 -387.02978) (xy 171.443396 -387.048248) (xy 171.857162 -387.462014)
			(xy 171.873952 -387.479438) (xy 171.902394 -387.518582) (xy 171.924362 -387.561693) (xy 171.939316 -387.60771)
			(xy 171.946887 -387.655499) (xy 171.947332 -387.679692) (xy 171.947332 -387.737604) (xy 173.18939 -387.737604)
			(xy 173.193461 -387.681982) (xy 173.205587 -387.627545) (xy 173.22551 -387.575454) (xy 173.252806 -387.526819)
			(xy 173.286892 -387.482676) (xy 173.327041 -387.443967) (xy 173.372399 -387.411516) (xy 173.421999 -387.386015)
			(xy 173.474783 -387.368008) (xy 173.529626 -387.357878) (xy 173.58536 -387.355841) (xy 173.640797 -387.361941)
			(xy 173.694754 -387.376047) (xy 173.746083 -387.397859) (xy 173.793689 -387.426913) (xy 173.836557 -387.462588)
			(xy 173.873774 -387.504125) (xy 173.904547 -387.550638) (xy 173.928219 -387.601135) (xy 173.944287 -387.654542)
			(xy 173.952407 -387.709718) (xy 173.952916 -387.737604) (xy 173.952407 -387.76549) (xy 173.944287 -387.820666)
			(xy 173.928219 -387.874073) (xy 173.904547 -387.92457) (xy 173.873774 -387.971083) (xy 173.836557 -388.01262)
			(xy 173.793689 -388.048295) (xy 173.746083 -388.077349) (xy 173.694754 -388.099161) (xy 173.640797 -388.113267)
			(xy 173.58536 -388.119367) (xy 173.529626 -388.11733) (xy 173.474783 -388.1072) (xy 173.421999 -388.089193)
			(xy 173.372399 -388.063692) (xy 173.327041 -388.031241) (xy 173.286892 -387.992532) (xy 173.252806 -387.948389)
			(xy 173.22551 -387.899754) (xy 173.205587 -387.847663) (xy 173.193461 -387.793226) (xy 173.18939 -387.737604)
			(xy 171.947332 -387.737604) (xy 171.947332 -388.358888) (xy 171.947777 -388.368917) (xy 171.955364 -388.38748)
			(xy 171.962064 -388.394956) (xy 172.632116 -389.065008) (xy 172.639542 -389.071782) (xy 172.658139 -389.079369)
			(xy 172.668184 -389.07974) (xy 173.143672 -389.07974) (xy 173.152368 -389.079379) (xy 173.168753 -389.073548)
			(xy 173.182251 -389.062581) (xy 173.187106 -389.055356) (xy 173.239176 -388.969504) (xy 173.239938 -388.942834)
			(xy 173.233588 -388.93115) (xy 173.2198 -388.903611) (xy 173.200312 -388.84519) (xy 173.190464 -388.784397)
			(xy 173.1899 -388.753604) (xy 173.190386 -388.726353) (xy 173.198142 -388.672405) (xy 173.213497 -388.62011)
			(xy 173.236139 -388.570533) (xy 173.265605 -388.524683) (xy 173.301296 -388.483492) (xy 173.342487 -388.447801)
			(xy 173.388337 -388.418335) (xy 173.437914 -388.395693) (xy 173.490209 -388.380338) (xy 173.544157 -388.372582)
			(xy 173.598659 -388.372582) (xy 173.652607 -388.380338) (xy 173.704902 -388.395693) (xy 173.754479 -388.418335)
			(xy 173.800329 -388.447801) (xy 173.84152 -388.483492) (xy 173.877211 -388.524683) (xy 173.906677 -388.570533)
			(xy 173.929319 -388.62011) (xy 173.944674 -388.672405) (xy 173.95243 -388.726353) (xy 173.952916 -388.753604)
			(xy 173.952344 -388.784396) (xy 173.942486 -388.845184) (xy 173.922996 -388.903601) (xy 173.909228 -388.93115)
			(xy 173.902878 -388.942834) (xy 173.90364 -388.969504) (xy 173.95571 -389.055356) (xy 173.960536 -389.0626)
			(xy 173.974043 -389.07356) (xy 173.990446 -389.079351) (xy 173.999144 -389.07974) (xy 174.3202 -389.07974)
			(xy 174.330227 -389.079292) (xy 174.348785 -389.071699) (xy 174.356268 -389.065008) (xy 174.5869 -388.834122)
			(xy 174.60434 -388.817351) (xy 174.643481 -388.788911) (xy 174.686588 -388.766943) (xy 174.732601 -388.751989)
			(xy 174.780387 -388.744417) (xy 174.804578 -388.743952) (xy 179.065936 -388.743952) (xy 179.078347 -388.743325)
			(xy 179.100295 -388.731727) (xy 179.107846 -388.721854) (xy 179.128324 -388.692838) (xy 179.17522 -388.639501)
			(xy 179.228229 -388.592235) (xy 179.28657 -388.551734) (xy 179.349385 -388.518594) (xy 179.415751 -388.493303)
			(xy 179.48469 -388.476233) (xy 179.555189 -388.467634) (xy 179.5907 -388.467092) (xy 179.626036 -388.467625)
			(xy 179.696193 -388.476144) (xy 179.764811 -388.493057) (xy 179.830891 -388.518117) (xy 179.893468 -388.55096)
			(xy 179.95163 -388.591107) (xy 180.004529 -388.637971) (xy 180.051393 -388.69087) (xy 180.09154 -388.749032)
			(xy 180.124383 -388.811609) (xy 180.149443 -388.877689) (xy 180.166356 -388.946307) (xy 180.174875 -389.016464)
			(xy 180.175408 -389.0518) (xy 180.174138 -389.08863) (xy 180.17363 -389.099044) (xy 180.180742 -389.118856)
			(xy 180.238654 -389.180578) (xy 180.246154 -389.187842) (xy 180.265307 -389.196097) (xy 180.275738 -389.19658)
		)
		(stroke
			(width 0)
			(type solid)
		)
		(fill yes)
		(layer "B.Cu")
		(net "P1V8_CPU1_RT_1D")
	)
	(gr_poly
		(pts
			(xy 352.088958 -263.71931) (xy 352.098797 -263.718777) (xy 352.116962 -263.711194) (xy 352.124264 -263.704578)
			(xy 352.6028 -263.226042) (xy 352.609523 -263.218808) (xy 352.617139 -263.200603) (xy 352.617532 -263.190736)
			(xy 352.617532 -261.072884) (xy 352.618059 -261.063043) (xy 352.625636 -261.044871) (xy 352.632264 -261.037578)
			(xy 352.9838 -260.686042) (xy 352.99104 -260.679332) (xy 353.009244 -260.671741) (xy 353.019106 -260.67131)
			(xy 353.078796 -260.67131) (xy 353.09033 -260.670661) (xy 353.110961 -260.660323) (xy 353.11842 -260.651498)
			(xy 353.147376 -260.60908) (xy 353.166426 -260.58114) (xy 353.169797 -260.575958) (xy 353.174162 -260.564396)
			(xy 353.175062 -260.55828) (xy 353.176332 -260.54685) (xy 353.17176 -260.534912) (xy 353.17049 -260.531356)
			(xy 353.170236 -260.530848) (xy 353.169982 -260.529578) (xy 353.168458 -260.526022) (xy 353.159822 -260.51129)
			(xy 353.158044 -260.509004) (xy 353.157028 -260.507988) (xy 353.14155 -260.488699) (xy 353.115504 -260.446658)
			(xy 353.095518 -260.401422) (xy 353.081974 -260.353857) (xy 353.075133 -260.304878) (xy 353.074732 -260.28015)
			(xy 353.074732 -260.272022) (xy 353.075875 -260.244458) (xy 353.085618 -260.190159) (xy 353.103619 -260.138013)
			(xy 353.129447 -260.089266) (xy 353.162484 -260.045087) (xy 353.20194 -260.006532) (xy 353.24687 -259.974523)
			(xy 353.2962 -259.949827) (xy 353.348748 -259.933034) (xy 353.403257 -259.924547) (xy 353.43084 -259.924042)
			(xy 353.456338 -259.9244) (xy 353.506829 -259.931534) (xy 353.531424 -259.938266) (xy 353.538282 -259.940552)
			(xy 353.596194 -259.940552) (xy 353.62515 -259.969508) (xy 353.62515 -259.969762) (xy 353.654868 -259.998718)
			(xy 353.667822 -260.000496) (xy 354.100384 -260.000496) (xy 354.104529 -260.000397) (xy 354.112697 -259.998985)
			(xy 354.11664 -259.997702) (xy 354.137214 -259.990844) (xy 354.143056 -259.98678) (xy 354.159312 -259.976366)
			(xy 354.169472 -259.970524) (xy 354.180394 -259.962142) (xy 354.186998 -259.955538) (xy 354.194395 -259.948687)
			(xy 354.212993 -259.940946) (xy 354.223066 -259.940552) (xy 354.238306 -259.940552) (xy 354.245164 -259.938266)
			(xy 354.269645 -259.931608) (xy 354.319873 -259.924474) (xy 354.34524 -259.924042) (xy 354.348796 -259.924042)
			(xy 354.37318 -259.925058) (xy 354.373688 -259.925058) (xy 354.388845 -259.926464) (xy 354.41886 -259.931547)
			(xy 354.433632 -259.935218) (xy 354.43414 -259.935218) (xy 354.45065 -259.93979) (xy 354.450904 -259.940044)
			(xy 354.452174 -259.940298) (xy 354.452936 -259.940552) (xy 354.459286 -259.94233) (xy 354.462588 -259.942838)
			(xy 354.484117 -259.946723) (xy 354.525076 -259.962077) (xy 354.562068 -259.98542) (xy 354.578158 -260.000242)
			(xy 354.588419 -260.010376) (xy 354.606387 -260.032934) (xy 354.613972 -260.0452) (xy 354.618544 -260.051804)
			(xy 354.619052 -260.052312) (xy 354.619814 -260.053328) (xy 354.638418 -260.076822) (xy 354.668308 -260.128759)
			(xy 354.689089 -260.184965) (xy 354.700173 -260.243854) (xy 354.701348 -260.2738) (xy 354.701348 -260.280658)
			(xy 354.700917 -260.304899) (xy 354.694303 -260.352927) (xy 354.681245 -260.399618) (xy 354.661985 -260.44411)
			(xy 354.649786 -260.465062) (xy 354.648262 -260.467602) (xy 354.641658 -260.485636) (xy 354.640896 -260.490716)
			(xy 354.637848 -260.505702) (xy 354.637848 -260.50621) (xy 354.637594 -260.506972) (xy 354.637594 -260.507226)
			(xy 354.63607 -260.512814) (xy 354.63607 -260.51383) (xy 354.628958 -260.534404) (xy 354.626418 -260.541262)
			(xy 354.624894 -260.552692) (xy 354.625402 -260.55828) (xy 354.626327 -260.56439) (xy 354.630687 -260.575948)
			(xy 354.634038 -260.58114) (xy 354.653088 -260.60908) (xy 354.682044 -260.651498) (xy 354.689478 -260.660347)
			(xy 354.710128 -260.670669) (xy 354.721668 -260.67131) (xy 365.014256 -260.67131) (xy 365.025437 -260.67071)
			(xy 365.045618 -260.661082) (xy 365.053118 -260.652768) (xy 365.102902 -260.579362) (xy 365.105858 -260.574463)
			(xy 365.109704 -260.563689) (xy 365.110522 -260.558026) (xy 365.111792 -260.546342) (xy 365.106712 -260.533642)
			(xy 365.102648 -260.522466) (xy 365.100616 -260.515608) (xy 365.09833 -260.506972) (xy 365.09833 -260.506464)
			(xy 365.097568 -260.503162) (xy 365.097568 -260.502908) (xy 365.097314 -260.5024) (xy 365.089948 -260.485636)
			(xy 365.087154 -260.481826) (xy 365.072408 -260.459471) (xy 365.04907 -260.411272) (xy 365.033202 -260.360125)
			(xy 365.025163 -260.30718) (xy 365.02467 -260.280404) (xy 365.02467 -260.273038) (xy 365.024924 -260.268212)
			(xy 365.02645 -260.239429) (xy 365.037642 -260.182891) (xy 365.057795 -260.128893) (xy 365.086381 -260.078846)
			(xy 365.122654 -260.034056) (xy 365.143796 -260.014466) (xy 365.147606 -260.010656) (xy 365.148368 -260.00964)
			(xy 365.162084 -259.995924) (xy 365.171693 -259.98748) (xy 365.19258 -259.972712) (xy 365.20374 -259.96646)
			(xy 365.215958 -259.960006) (xy 365.241693 -259.949943) (xy 365.255048 -259.946394) (xy 365.256572 -259.94614)
			(xy 365.260128 -259.945124) (xy 365.261144 -259.944616) (xy 365.290106 -259.934973) (xy 365.350259 -259.924623)
			(xy 365.380778 -259.924042) (xy 365.414052 -259.925566) (xy 365.43112 -259.927304) (xy 365.464834 -259.933667)
			(xy 365.481362 -259.938266) (xy 365.48822 -259.940552) (xy 365.531654 -259.940552) (xy 365.56061 -259.969508)
			(xy 365.56061 -259.971794) (xy 365.583216 -259.987034) (xy 365.595154 -259.99313) (xy 365.609378 -259.997702)
			(xy 365.613325 -259.998964) (xy 365.621492 -260.000365) (xy 365.625634 -260.000496) (xy 365.774732 -260.000496)
			(xy 365.784736 -260.00099) (xy 365.803217 -260.008655) (xy 365.817361 -260.022806) (xy 365.825016 -260.041292)
			(xy 365.825532 -260.051296) (xy 365.825532 -260.558788) (xy 365.825047 -260.5688) (xy 365.81739 -260.587301)
			(xy 365.803238 -260.601466) (xy 365.784743 -260.609138) (xy 365.774732 -260.609588) (xy 365.63046 -260.609588)
			(xy 365.618737 -260.61027) (xy 365.597808 -260.620857) (xy 365.590328 -260.629908) (xy 365.584232 -260.644894)
			(xy 365.581982 -260.65151) (xy 365.580809 -260.665431) (xy 365.581946 -260.672326) (xy 365.584232 -260.68401)
			(xy 365.8108 -260.910578) (xy 365.81752 -260.917814) (xy 365.825128 -260.936019) (xy 365.825532 -260.945884)
			(xy 365.825532 -261.12597) (xy 369.566698 -261.12597) (xy 369.566698 -261.125716) (xy 369.567193 -261.100007)
			(xy 369.575476 -261.049259) (xy 369.591814 -261.000505) (xy 369.615781 -260.955013) (xy 369.646752 -260.913968)
			(xy 369.664996 -260.895846) (xy 369.664996 -260.895592) (xy 369.665546 -260.874631) (xy 369.673725 -260.833514)
			(xy 369.689767 -260.794783) (xy 369.713056 -260.759925) (xy 369.742697 -260.730279) (xy 369.777551 -260.706984)
			(xy 369.81628 -260.690936) (xy 369.857395 -260.68275) (xy 369.878356 -260.682232) (xy 370.133372 -260.682232)
			(xy 370.133372 -260.691376) (xy 370.133907 -260.701379) (xy 370.141553 -260.719865) (xy 370.155692 -260.734017)
			(xy 370.17417 -260.741683) (xy 370.184172 -260.742176) (xy 370.34724 -260.742176) (xy 370.357247 -260.742655)
			(xy 370.375735 -260.750323) (xy 370.389886 -260.764478) (xy 370.397548 -260.782969) (xy 370.39804 -260.792976)
			(xy 370.39804 -261.12597) (xy 371.446806 -261.12597) (xy 371.447349 -261.098635) (xy 371.456685 -261.04477)
			(xy 371.475095 -260.993294) (xy 371.502037 -260.945725) (xy 371.536716 -260.903463) (xy 371.557042 -260.885178)
			(xy 371.563271 -260.879325) (xy 371.571819 -260.864536) (xy 371.573806 -260.856222) (xy 371.578227 -260.835569)
			(xy 371.594044 -260.796414) (xy 371.617239 -260.761124) (xy 371.646908 -260.731074) (xy 371.681898 -260.70743)
			(xy 371.720848 -260.691114) (xy 371.762242 -260.682759) (xy 371.783356 -260.682232) (xy 372.038372 -260.682232)
			(xy 372.038372 -260.691376) (xy 372.038907 -260.701379) (xy 372.046553 -260.719865) (xy 372.060692 -260.734017)
			(xy 372.07917 -260.741683) (xy 372.089172 -260.742176) (xy 372.25224 -260.742176) (xy 372.262247 -260.742655)
			(xy 372.280735 -260.750323) (xy 372.294886 -260.764478) (xy 372.302548 -260.782969) (xy 372.30304 -260.792976)
			(xy 372.30304 -261.150959) (xy 373.327404 -261.150959) (xy 373.327404 -261.100981) (xy 373.335223 -261.051618)
			(xy 373.350667 -261.004086) (xy 373.373357 -260.959554) (xy 373.402733 -260.919121) (xy 373.438073 -260.883781)
			(xy 373.478506 -260.854405) (xy 373.523038 -260.831715) (xy 373.57057 -260.816271) (xy 373.619933 -260.808452)
			(xy 373.669911 -260.808452) (xy 373.719274 -260.816271) (xy 373.766806 -260.831715) (xy 373.811338 -260.854405)
			(xy 373.851771 -260.883781) (xy 373.887111 -260.919121) (xy 373.916487 -260.959554) (xy 373.939177 -261.004086)
			(xy 373.954621 -261.051618) (xy 373.96244 -261.100981) (xy 373.96293 -261.12597) (xy 373.96244 -261.150959)
			(xy 375.207258 -261.150959) (xy 375.207258 -261.100981) (xy 375.215077 -261.051618) (xy 375.230521 -261.004086)
			(xy 375.253211 -260.959554) (xy 375.282587 -260.919121) (xy 375.317927 -260.883781) (xy 375.35836 -260.854405)
			(xy 375.402892 -260.831715) (xy 375.450424 -260.816271) (xy 375.499787 -260.808452) (xy 375.549765 -260.808452)
			(xy 375.599128 -260.816271) (xy 375.64666 -260.831715) (xy 375.691192 -260.854405) (xy 375.731625 -260.883781)
			(xy 375.766965 -260.919121) (xy 375.796341 -260.959554) (xy 375.819031 -261.004086) (xy 375.834475 -261.051618)
			(xy 375.842294 -261.100981) (xy 375.842784 -261.12597) (xy 375.842294 -261.150959) (xy 376.147312 -261.150959)
			(xy 376.147312 -261.100981) (xy 376.155131 -261.051618) (xy 376.170575 -261.004086) (xy 376.193265 -260.959554)
			(xy 376.222641 -260.919121) (xy 376.257981 -260.883781) (xy 376.298414 -260.854405) (xy 376.342946 -260.831715)
			(xy 376.390478 -260.816271) (xy 376.439841 -260.808452) (xy 376.489819 -260.808452) (xy 376.539182 -260.816271)
			(xy 376.586714 -260.831715) (xy 376.631246 -260.854405) (xy 376.671679 -260.883781) (xy 376.707019 -260.919121)
			(xy 376.736395 -260.959554) (xy 376.759085 -261.004086) (xy 376.774529 -261.051618) (xy 376.782348 -261.100981)
			(xy 376.782838 -261.12597) (xy 376.782348 -261.150959) (xy 377.087366 -261.150959) (xy 377.087366 -261.100981)
			(xy 377.095185 -261.051618) (xy 377.110629 -261.004086) (xy 377.133319 -260.959554) (xy 377.162695 -260.919121)
			(xy 377.198035 -260.883781) (xy 377.238468 -260.854405) (xy 377.283 -260.831715) (xy 377.330532 -260.816271)
			(xy 377.379895 -260.808452) (xy 377.429873 -260.808452) (xy 377.479236 -260.816271) (xy 377.526768 -260.831715)
			(xy 377.5713 -260.854405) (xy 377.611733 -260.883781) (xy 377.647073 -260.919121) (xy 377.676449 -260.959554)
			(xy 377.699139 -261.004086) (xy 377.714583 -261.051618) (xy 377.722402 -261.100981) (xy 377.722892 -261.12597)
			(xy 377.722402 -261.150959) (xy 378.02742 -261.150959) (xy 378.02742 -261.100981) (xy 378.035239 -261.051618)
			(xy 378.050683 -261.004086) (xy 378.073373 -260.959554) (xy 378.102749 -260.919121) (xy 378.138089 -260.883781)
			(xy 378.178522 -260.854405) (xy 378.223054 -260.831715) (xy 378.270586 -260.816271) (xy 378.319949 -260.808452)
			(xy 378.369927 -260.808452) (xy 378.41929 -260.816271) (xy 378.466822 -260.831715) (xy 378.511354 -260.854405)
			(xy 378.551787 -260.883781) (xy 378.587127 -260.919121) (xy 378.616503 -260.959554) (xy 378.639193 -261.004086)
			(xy 378.654637 -261.051618) (xy 378.662456 -261.100981) (xy 378.662946 -261.12597) (xy 378.662456 -261.150959)
			(xy 378.96722 -261.150959) (xy 378.96722 -261.100981) (xy 378.975039 -261.051618) (xy 378.990483 -261.004086)
			(xy 379.013173 -260.959554) (xy 379.042549 -260.919121) (xy 379.077889 -260.883781) (xy 379.118322 -260.854405)
			(xy 379.162854 -260.831715) (xy 379.210386 -260.816271) (xy 379.259749 -260.808452) (xy 379.309727 -260.808452)
			(xy 379.35909 -260.816271) (xy 379.406622 -260.831715) (xy 379.451154 -260.854405) (xy 379.491587 -260.883781)
			(xy 379.526927 -260.919121) (xy 379.556303 -260.959554) (xy 379.578993 -261.004086) (xy 379.594437 -261.051618)
			(xy 379.602256 -261.100981) (xy 379.602746 -261.12597) (xy 379.602256 -261.150959) (xy 379.907274 -261.150959)
			(xy 379.907274 -261.100981) (xy 379.915093 -261.051618) (xy 379.930537 -261.004086) (xy 379.953227 -260.959554)
			(xy 379.982603 -260.919121) (xy 380.017943 -260.883781) (xy 380.058376 -260.854405) (xy 380.102908 -260.831715)
			(xy 380.15044 -260.816271) (xy 380.199803 -260.808452) (xy 380.249781 -260.808452) (xy 380.299144 -260.816271)
			(xy 380.346676 -260.831715) (xy 380.391208 -260.854405) (xy 380.431641 -260.883781) (xy 380.466981 -260.919121)
			(xy 380.496357 -260.959554) (xy 380.519047 -261.004086) (xy 380.534491 -261.051618) (xy 380.54231 -261.100981)
			(xy 380.5428 -261.12597) (xy 380.54231 -261.150959) (xy 380.534491 -261.200322) (xy 380.519047 -261.247854)
			(xy 380.496357 -261.292386) (xy 380.466981 -261.332819) (xy 380.431641 -261.368159) (xy 380.391208 -261.397535)
			(xy 380.346676 -261.420225) (xy 380.299144 -261.435669) (xy 380.249781 -261.443488) (xy 380.199803 -261.443488)
			(xy 380.15044 -261.435669) (xy 380.102908 -261.420225) (xy 380.058376 -261.397535) (xy 380.017943 -261.368159)
			(xy 379.982603 -261.332819) (xy 379.953227 -261.292386) (xy 379.930537 -261.247854) (xy 379.915093 -261.200322)
			(xy 379.907274 -261.150959) (xy 379.602256 -261.150959) (xy 379.594437 -261.200322) (xy 379.578993 -261.247854)
			(xy 379.556303 -261.292386) (xy 379.526927 -261.332819) (xy 379.491587 -261.368159) (xy 379.451154 -261.397535)
			(xy 379.406622 -261.420225) (xy 379.35909 -261.435669) (xy 379.309727 -261.443488) (xy 379.259749 -261.443488)
			(xy 379.210386 -261.435669) (xy 379.162854 -261.420225) (xy 379.118322 -261.397535) (xy 379.077889 -261.368159)
			(xy 379.042549 -261.332819) (xy 379.013173 -261.292386) (xy 378.990483 -261.247854) (xy 378.975039 -261.200322)
			(xy 378.96722 -261.150959) (xy 378.662456 -261.150959) (xy 378.654637 -261.200322) (xy 378.639193 -261.247854)
			(xy 378.616503 -261.292386) (xy 378.587127 -261.332819) (xy 378.551787 -261.368159) (xy 378.511354 -261.397535)
			(xy 378.466822 -261.420225) (xy 378.41929 -261.435669) (xy 378.369927 -261.443488) (xy 378.319949 -261.443488)
			(xy 378.270586 -261.435669) (xy 378.223054 -261.420225) (xy 378.178522 -261.397535) (xy 378.138089 -261.368159)
			(xy 378.102749 -261.332819) (xy 378.073373 -261.292386) (xy 378.050683 -261.247854) (xy 378.035239 -261.200322)
			(xy 378.02742 -261.150959) (xy 377.722402 -261.150959) (xy 377.714583 -261.200322) (xy 377.699139 -261.247854)
			(xy 377.676449 -261.292386) (xy 377.647073 -261.332819) (xy 377.611733 -261.368159) (xy 377.5713 -261.397535)
			(xy 377.526768 -261.420225) (xy 377.479236 -261.435669) (xy 377.429873 -261.443488) (xy 377.379895 -261.443488)
			(xy 377.330532 -261.435669) (xy 377.283 -261.420225) (xy 377.238468 -261.397535) (xy 377.198035 -261.368159)
			(xy 377.162695 -261.332819) (xy 377.133319 -261.292386) (xy 377.110629 -261.247854) (xy 377.095185 -261.200322)
			(xy 377.087366 -261.150959) (xy 376.782348 -261.150959) (xy 376.774529 -261.200322) (xy 376.759085 -261.247854)
			(xy 376.736395 -261.292386) (xy 376.707019 -261.332819) (xy 376.671679 -261.368159) (xy 376.631246 -261.397535)
			(xy 376.586714 -261.420225) (xy 376.539182 -261.435669) (xy 376.489819 -261.443488) (xy 376.439841 -261.443488)
			(xy 376.390478 -261.435669) (xy 376.342946 -261.420225) (xy 376.298414 -261.397535) (xy 376.257981 -261.368159)
			(xy 376.222641 -261.332819) (xy 376.193265 -261.292386) (xy 376.170575 -261.247854) (xy 376.155131 -261.200322)
			(xy 376.147312 -261.150959) (xy 375.842294 -261.150959) (xy 375.834475 -261.200322) (xy 375.819031 -261.247854)
			(xy 375.796341 -261.292386) (xy 375.766965 -261.332819) (xy 375.731625 -261.368159) (xy 375.691192 -261.397535)
			(xy 375.64666 -261.420225) (xy 375.599128 -261.435669) (xy 375.549765 -261.443488) (xy 375.499787 -261.443488)
			(xy 375.450424 -261.435669) (xy 375.402892 -261.420225) (xy 375.35836 -261.397535) (xy 375.317927 -261.368159)
			(xy 375.282587 -261.332819) (xy 375.253211 -261.292386) (xy 375.230521 -261.247854) (xy 375.215077 -261.200322)
			(xy 375.207258 -261.150959) (xy 373.96244 -261.150959) (xy 373.954621 -261.200322) (xy 373.939177 -261.247854)
			(xy 373.916487 -261.292386) (xy 373.887111 -261.332819) (xy 373.851771 -261.368159) (xy 373.811338 -261.397535)
			(xy 373.766806 -261.420225) (xy 373.719274 -261.435669) (xy 373.669911 -261.443488) (xy 373.619933 -261.443488)
			(xy 373.57057 -261.435669) (xy 373.523038 -261.420225) (xy 373.478506 -261.397535) (xy 373.438073 -261.368159)
			(xy 373.402733 -261.332819) (xy 373.373357 -261.292386) (xy 373.350667 -261.247854) (xy 373.335223 -261.200322)
			(xy 373.327404 -261.150959) (xy 372.30304 -261.150959) (xy 372.30304 -261.300976) (xy 372.302493 -261.310977)
			(xy 372.294849 -261.329461) (xy 372.280715 -261.343613) (xy 372.262241 -261.351281) (xy 372.25224 -261.351776)
			(xy 372.038372 -261.351776) (xy 372.038372 -261.36092) (xy 372.037996 -261.370946) (xy 372.030314 -261.389469)
			(xy 372.016128 -261.403641) (xy 371.997598 -261.411305) (xy 371.987572 -261.41172) (xy 371.905022 -261.41172)
			(xy 371.895116 -261.416038) (xy 371.87454 -261.424867) (xy 371.831531 -261.43731) (xy 371.787201 -261.443595)
			(xy 371.764814 -261.443978) (xy 371.739822 -261.443531) (xy 371.690452 -261.435713) (xy 371.642914 -261.420267)
			(xy 371.598377 -261.397575) (xy 371.557939 -261.368194) (xy 371.522595 -261.332849) (xy 371.493217 -261.292409)
			(xy 371.470526 -261.247871) (xy 371.455084 -261.200332) (xy 371.447268 -261.150962) (xy 371.446806 -261.12597)
			(xy 370.39804 -261.12597) (xy 370.39804 -261.300976) (xy 370.397493 -261.310977) (xy 370.389849 -261.329461)
			(xy 370.375715 -261.343613) (xy 370.357241 -261.351281) (xy 370.34724 -261.351776) (xy 370.133372 -261.351776)
			(xy 370.133372 -261.36092) (xy 370.132996 -261.370946) (xy 370.125314 -261.389469) (xy 370.111128 -261.403641)
			(xy 370.092598 -261.411305) (xy 370.082572 -261.41172) (xy 370.024914 -261.41172) (xy 370.015008 -261.416038)
			(xy 369.994433 -261.42487) (xy 369.951423 -261.437312) (xy 369.907093 -261.443595) (xy 369.884706 -261.443978)
			(xy 369.859713 -261.443538) (xy 369.810344 -261.435719) (xy 369.762805 -261.420272) (xy 369.718268 -261.397579)
			(xy 369.67783 -261.368197) (xy 369.642487 -261.332851) (xy 369.613108 -261.292411) (xy 369.590418 -261.247873)
			(xy 369.574975 -261.200333) (xy 369.56716 -261.150963) (xy 369.566698 -261.12597) (xy 365.825532 -261.12597)
			(xy 365.825532 -261.412736) (xy 365.826042 -261.422489) (xy 365.83348 -261.440527) (xy 365.84001 -261.447788)
			(xy 366.205262 -261.81304) (xy 366.209468 -261.817069) (xy 366.219352 -261.823225) (xy 366.22482 -261.825232)
			(xy 366.235488 -261.828788) (xy 366.247426 -261.827264) (xy 366.259306 -261.825742) (xy 366.283202 -261.824087)
			(xy 366.295178 -261.823962) (xy 366.300258 -261.823962) (xy 366.313272 -261.824276) (xy 366.339206 -261.826564)
			(xy 366.352074 -261.828534) (xy 366.370857 -261.831815) (xy 366.407638 -261.841874) (xy 366.42548 -261.8486)
			(xy 366.425988 -261.848854) (xy 366.428782 -261.84987) (xy 366.429544 -261.850124) (xy 366.429798 -261.850124)
			(xy 366.45023 -261.857142) (xy 366.487979 -261.878134) (xy 366.504728 -261.89178) (xy 366.505236 -261.892288)
			(xy 366.507776 -261.89432) (xy 366.509808 -261.895844) (xy 366.531414 -261.912779) (xy 366.569647 -261.952169)
			(xy 366.601386 -261.996957) (xy 366.625882 -262.046083) (xy 366.642554 -262.098384) (xy 366.651007 -262.152623)
			(xy 366.65154 -262.18007) (xy 366.649762 -262.215122) (xy 366.648492 -262.22452) (xy 366.648238 -262.226552)
			(xy 366.647984 -262.227822) (xy 366.64646 -262.23976) (xy 366.650016 -262.250428) (xy 366.651815 -262.255398)
			(xy 366.657191 -262.264496) (xy 366.660684 -262.268462) (xy 366.702594 -262.310372) (xy 366.708589 -262.315133)
			(xy 366.722687 -262.321078) (xy 366.73028 -262.322056) (xy 369.359688 -262.322056) (xy 369.364768 -262.32231)
			(xy 369.988846 -262.32231) (xy 370.001337 -262.321633) (xy 370.023324 -262.309768) (xy 370.030756 -262.299704)
			(xy 370.039392 -262.285988) (xy 370.077746 -262.225028) (xy 370.080402 -262.220003) (xy 370.083616 -262.209102)
			(xy 370.084096 -262.203438) (xy 370.084858 -262.191246) (xy 370.079016 -262.179054) (xy 370.068991 -262.156417)
			(xy 370.058469 -262.108052) (xy 370.058188 -262.083296) (xy 370.058188 -262.051038) (xy 370.057172 -262.04799)
			(xy 370.05514 -262.042656) (xy 370.046553 -262.016828) (xy 370.037352 -261.963189) (xy 370.036852 -261.935976)
			(xy 370.037393 -261.908767) (xy 370.046593 -261.855133) (xy 370.05514 -261.829296) (xy 370.057172 -261.823962)
			(xy 370.058188 -261.820914) (xy 370.058188 -261.79145) (xy 370.058188 -261.79018) (xy 370.058182 -261.768865)
			(xy 370.0656 -261.726898) (xy 370.081174 -261.687229) (xy 370.10429 -261.651425) (xy 370.134032 -261.620902)
			(xy 370.169226 -261.596868) (xy 370.208479 -261.580273) (xy 370.25024 -261.571772) (xy 370.271548 -261.571232)
			(xy 370.475764 -261.571232) (xy 370.485788 -261.571646) (xy 370.504311 -261.579311) (xy 370.518487 -261.593485)
			(xy 370.526153 -261.612008) (xy 370.526564 -261.622032) (xy 370.526564 -261.631176) (xy 370.761514 -261.631176)
			(xy 370.791232 -261.660894) (xy 370.791232 -261.676388) (xy 370.791486 -261.67842) (xy 370.791486 -262.272272)
			(xy 370.791956 -262.2821) (xy 370.799449 -262.300271) (xy 370.813312 -262.314206) (xy 370.831444 -262.321793)
			(xy 370.84127 -262.32231) (xy 371.8687 -262.32231) (xy 371.881185 -262.321622) (xy 371.903151 -262.309743)
			(xy 371.91061 -262.299704) (xy 371.919246 -262.285988) (xy 371.9576 -262.225028) (xy 371.960254 -262.220002)
			(xy 371.963464 -262.209101) (xy 371.96395 -262.203438) (xy 371.964712 -262.191246) (xy 371.95887 -262.179054)
			(xy 371.949055 -262.157019) (xy 371.938544 -262.109953) (xy 371.938042 -262.085836) (xy 371.938042 -262.051292)
			(xy 371.934994 -262.04291) (xy 371.926396 -262.01702) (xy 371.917204 -261.963252) (xy 371.916706 -261.935976)
			(xy 371.917227 -261.908703) (xy 371.926421 -261.854938) (xy 371.934994 -261.829042) (xy 371.938042 -261.82066)
			(xy 371.938042 -261.786116) (xy 371.938042 -261.785862) (xy 371.938405 -261.764814) (xy 371.946403 -261.723489)
			(xy 371.962338 -261.68453) (xy 371.985594 -261.649446) (xy 372.015269 -261.619595) (xy 372.050215 -261.596133)
			(xy 372.089079 -261.579968) (xy 372.130356 -261.571726) (xy 372.151402 -261.571232) (xy 372.376446 -261.571232)
			(xy 372.406164 -261.60095) (xy 372.406164 -261.616444) (xy 372.406418 -261.621524) (xy 372.406418 -261.631176)
			(xy 372.62054 -261.631176) (xy 372.630544 -261.63167) (xy 372.649026 -261.639336) (xy 372.663173 -261.653487)
			(xy 372.670833 -261.671972) (xy 372.67134 -261.681976) (xy 372.67134 -261.960965) (xy 373.797304 -261.960965)
			(xy 373.797304 -261.910987) (xy 373.805123 -261.861624) (xy 373.820567 -261.814092) (xy 373.843257 -261.76956)
			(xy 373.872633 -261.729127) (xy 373.907973 -261.693787) (xy 373.948406 -261.664411) (xy 373.992938 -261.641721)
			(xy 374.04047 -261.626277) (xy 374.089833 -261.618458) (xy 374.139811 -261.618458) (xy 374.189174 -261.626277)
			(xy 374.236706 -261.641721) (xy 374.281238 -261.664411) (xy 374.321671 -261.693787) (xy 374.357011 -261.729127)
			(xy 374.386387 -261.76956) (xy 374.409077 -261.814092) (xy 374.424521 -261.861624) (xy 374.43234 -261.910987)
			(xy 374.43283 -261.935976) (xy 375.678695 -261.935976) (xy 375.68279 -261.885248) (xy 375.694969 -261.835834)
			(xy 375.714917 -261.789014) (xy 375.742118 -261.746) (xy 375.775866 -261.707906) (xy 375.815288 -261.675719)
			(xy 375.859362 -261.650273) (xy 375.906948 -261.632226) (xy 375.956812 -261.622046) (xy 376.007664 -261.619997)
			(xy 376.058185 -261.626131) (xy 376.107069 -261.640291) (xy 376.153048 -261.662108) (xy 376.194932 -261.691018)
			(xy 376.231636 -261.726273) (xy 376.262209 -261.766959) (xy 376.28586 -261.812022) (xy 376.301976 -261.860296)
			(xy 376.31014 -261.91053) (xy 376.310652 -261.935976) (xy 376.310149 -261.960965) (xy 376.617212 -261.960965)
			(xy 376.617212 -261.910987) (xy 376.625031 -261.861624) (xy 376.640475 -261.814092) (xy 376.663165 -261.76956)
			(xy 376.692541 -261.729127) (xy 376.727881 -261.693787) (xy 376.768314 -261.664411) (xy 376.812846 -261.641721)
			(xy 376.860378 -261.626277) (xy 376.909741 -261.618458) (xy 376.959719 -261.618458) (xy 377.009082 -261.626277)
			(xy 377.056614 -261.641721) (xy 377.101146 -261.664411) (xy 377.141579 -261.693787) (xy 377.176919 -261.729127)
			(xy 377.206295 -261.76956) (xy 377.228985 -261.814092) (xy 377.244429 -261.861624) (xy 377.252248 -261.910987)
			(xy 377.252738 -261.935976) (xy 377.252248 -261.960965) (xy 377.557266 -261.960965) (xy 377.557266 -261.910987)
			(xy 377.565085 -261.861624) (xy 377.580529 -261.814092) (xy 377.603219 -261.76956) (xy 377.632595 -261.729127)
			(xy 377.667935 -261.693787) (xy 377.708368 -261.664411) (xy 377.7529 -261.641721) (xy 377.800432 -261.626277)
			(xy 377.849795 -261.618458) (xy 377.899773 -261.618458) (xy 377.949136 -261.626277) (xy 377.996668 -261.641721)
			(xy 378.0412 -261.664411) (xy 378.081633 -261.693787) (xy 378.116973 -261.729127) (xy 378.146349 -261.76956)
			(xy 378.169039 -261.814092) (xy 378.184483 -261.861624) (xy 378.192302 -261.910987) (xy 378.192792 -261.935976)
			(xy 378.192302 -261.960965) (xy 378.49732 -261.960965) (xy 378.49732 -261.910987) (xy 378.505139 -261.861624)
			(xy 378.520583 -261.814092) (xy 378.543273 -261.76956) (xy 378.572649 -261.729127) (xy 378.607989 -261.693787)
			(xy 378.648422 -261.664411) (xy 378.692954 -261.641721) (xy 378.740486 -261.626277) (xy 378.789849 -261.618458)
			(xy 378.839827 -261.618458) (xy 378.88919 -261.626277) (xy 378.936722 -261.641721) (xy 378.981254 -261.664411)
			(xy 379.021687 -261.693787) (xy 379.057027 -261.729127) (xy 379.086403 -261.76956) (xy 379.109093 -261.814092)
			(xy 379.124537 -261.861624) (xy 379.132356 -261.910987) (xy 379.132846 -261.935976) (xy 379.438657 -261.935976)
			(xy 379.442752 -261.885248) (xy 379.454931 -261.835834) (xy 379.474879 -261.789014) (xy 379.50208 -261.746)
			(xy 379.535828 -261.707906) (xy 379.57525 -261.675719) (xy 379.619324 -261.650273) (xy 379.66691 -261.632226)
			(xy 379.716774 -261.622046) (xy 379.767626 -261.619997) (xy 379.818147 -261.626131) (xy 379.867031 -261.640291)
			(xy 379.91301 -261.662108) (xy 379.954894 -261.691018) (xy 379.991598 -261.726273) (xy 380.022171 -261.766959)
			(xy 380.045822 -261.812022) (xy 380.061938 -261.860296) (xy 380.070102 -261.91053) (xy 380.070614 -261.935976)
			(xy 380.070111 -261.960965) (xy 380.377174 -261.960965) (xy 380.377174 -261.910987) (xy 380.384993 -261.861624)
			(xy 380.400437 -261.814092) (xy 380.423127 -261.76956) (xy 380.452503 -261.729127) (xy 380.487843 -261.693787)
			(xy 380.528276 -261.664411) (xy 380.572808 -261.641721) (xy 380.62034 -261.626277) (xy 380.669703 -261.618458)
			(xy 380.719681 -261.618458) (xy 380.769044 -261.626277) (xy 380.816576 -261.641721) (xy 380.861108 -261.664411)
			(xy 380.901541 -261.693787) (xy 380.936881 -261.729127) (xy 380.966257 -261.76956) (xy 380.988947 -261.814092)
			(xy 381.004391 -261.861624) (xy 381.01221 -261.910987) (xy 381.0127 -261.935976) (xy 381.01221 -261.960965)
			(xy 381.004391 -262.010328) (xy 380.988947 -262.05786) (xy 380.966257 -262.102392) (xy 380.936881 -262.142825)
			(xy 380.901541 -262.178165) (xy 380.861108 -262.207541) (xy 380.816576 -262.230231) (xy 380.769044 -262.245675)
			(xy 380.719681 -262.253494) (xy 380.669703 -262.253494) (xy 380.62034 -262.245675) (xy 380.572808 -262.230231)
			(xy 380.528276 -262.207541) (xy 380.487843 -262.178165) (xy 380.452503 -262.142825) (xy 380.423127 -262.102392)
			(xy 380.400437 -262.05786) (xy 380.384993 -262.010328) (xy 380.377174 -261.960965) (xy 380.070111 -261.960965)
			(xy 380.070102 -261.961422) (xy 380.061938 -262.011656) (xy 380.045822 -262.05993) (xy 380.022171 -262.104993)
			(xy 379.991598 -262.145679) (xy 379.954894 -262.180934) (xy 379.91301 -262.209844) (xy 379.867031 -262.231661)
			(xy 379.818147 -262.245821) (xy 379.767626 -262.251955) (xy 379.716774 -262.249906) (xy 379.66691 -262.239726)
			(xy 379.619324 -262.221679) (xy 379.57525 -262.196233) (xy 379.535828 -262.164046) (xy 379.50208 -262.125952)
			(xy 379.474879 -262.082938) (xy 379.454931 -262.036118) (xy 379.442752 -261.986704) (xy 379.438657 -261.935976)
			(xy 379.132846 -261.935976) (xy 379.132356 -261.960965) (xy 379.124537 -262.010328) (xy 379.109093 -262.05786)
			(xy 379.086403 -262.102392) (xy 379.057027 -262.142825) (xy 379.021687 -262.178165) (xy 378.981254 -262.207541)
			(xy 378.936722 -262.230231) (xy 378.88919 -262.245675) (xy 378.839827 -262.253494) (xy 378.789849 -262.253494)
			(xy 378.740486 -262.245675) (xy 378.692954 -262.230231) (xy 378.648422 -262.207541) (xy 378.607989 -262.178165)
			(xy 378.572649 -262.142825) (xy 378.543273 -262.102392) (xy 378.520583 -262.05786) (xy 378.505139 -262.010328)
			(xy 378.49732 -261.960965) (xy 378.192302 -261.960965) (xy 378.184483 -262.010328) (xy 378.169039 -262.05786)
			(xy 378.146349 -262.102392) (xy 378.116973 -262.142825) (xy 378.081633 -262.178165) (xy 378.0412 -262.207541)
			(xy 377.996668 -262.230231) (xy 377.949136 -262.245675) (xy 377.899773 -262.253494) (xy 377.849795 -262.253494)
			(xy 377.800432 -262.245675) (xy 377.7529 -262.230231) (xy 377.708368 -262.207541) (xy 377.667935 -262.178165)
			(xy 377.632595 -262.142825) (xy 377.603219 -262.102392) (xy 377.580529 -262.05786) (xy 377.565085 -262.010328)
			(xy 377.557266 -261.960965) (xy 377.252248 -261.960965) (xy 377.244429 -262.010328) (xy 377.228985 -262.05786)
			(xy 377.206295 -262.102392) (xy 377.176919 -262.142825) (xy 377.141579 -262.178165) (xy 377.101146 -262.207541)
			(xy 377.056614 -262.230231) (xy 377.009082 -262.245675) (xy 376.959719 -262.253494) (xy 376.909741 -262.253494)
			(xy 376.860378 -262.245675) (xy 376.812846 -262.230231) (xy 376.768314 -262.207541) (xy 376.727881 -262.178165)
			(xy 376.692541 -262.142825) (xy 376.663165 -262.102392) (xy 376.640475 -262.05786) (xy 376.625031 -262.010328)
			(xy 376.617212 -261.960965) (xy 376.310149 -261.960965) (xy 376.31014 -261.961422) (xy 376.301976 -262.011656)
			(xy 376.28586 -262.05993) (xy 376.262209 -262.104993) (xy 376.231636 -262.145679) (xy 376.194932 -262.180934)
			(xy 376.153048 -262.209844) (xy 376.107069 -262.231661) (xy 376.058185 -262.245821) (xy 376.007664 -262.251955)
			(xy 375.956812 -262.249906) (xy 375.906948 -262.239726) (xy 375.859362 -262.221679) (xy 375.815288 -262.196233)
			(xy 375.775866 -262.164046) (xy 375.742118 -262.125952) (xy 375.714917 -262.082938) (xy 375.694969 -262.036118)
			(xy 375.68279 -261.986704) (xy 375.678695 -261.935976) (xy 374.43283 -261.935976) (xy 374.43234 -261.960965)
			(xy 374.424521 -262.010328) (xy 374.409077 -262.05786) (xy 374.386387 -262.102392) (xy 374.357011 -262.142825)
			(xy 374.321671 -262.178165) (xy 374.281238 -262.207541) (xy 374.236706 -262.230231) (xy 374.189174 -262.245675)
			(xy 374.139811 -262.253494) (xy 374.089833 -262.253494) (xy 374.04047 -262.245675) (xy 373.992938 -262.230231)
			(xy 373.948406 -262.207541) (xy 373.907973 -262.178165) (xy 373.872633 -262.142825) (xy 373.843257 -262.102392)
			(xy 373.820567 -262.05786) (xy 373.805123 -262.010328) (xy 373.797304 -261.960965) (xy 372.67134 -261.960965)
			(xy 372.67134 -262.189976) (xy 372.670857 -262.19999) (xy 372.663203 -262.218497) (xy 372.64905 -262.232667)
			(xy 372.630553 -262.240344) (xy 372.62054 -262.240776) (xy 372.456202 -262.240776) (xy 372.446417 -262.241302)
			(xy 372.428355 -262.248853) (xy 372.41452 -262.262703) (xy 372.40699 -262.280774) (xy 372.406418 -262.29056)
			(xy 372.406418 -262.30072) (xy 372.147338 -262.30072) (xy 372.143732 -262.30078) (xy 372.136591 -262.301793)
			(xy 372.133114 -262.302752) (xy 372.128542 -262.304276) (xy 372.119398 -262.308086) (xy 372.112286 -262.315198)
			(xy 372.107206 -262.321294) (xy 372.102888 -262.331454) (xy 372.10238 -262.33247) (xy 372.098062 -262.343392)
			(xy 372.097003 -262.354998) (xy 372.10428 -262.377109) (xy 372.112032 -262.38581) (xy 372.23192 -262.505698)
			(xy 372.239168 -262.512255) (xy 372.25721 -262.519717) (xy 372.266972 -262.520176) (xy 372.27383 -262.520176)
			(xy 372.303294 -262.54964) (xy 372.303294 -262.770971) (xy 373.327404 -262.770971) (xy 373.327404 -262.720993)
			(xy 373.335223 -262.67163) (xy 373.350667 -262.624098) (xy 373.373357 -262.579566) (xy 373.402733 -262.539133)
			(xy 373.438073 -262.503793) (xy 373.478506 -262.474417) (xy 373.523038 -262.451727) (xy 373.57057 -262.436283)
			(xy 373.619933 -262.428464) (xy 373.669911 -262.428464) (xy 373.719274 -262.436283) (xy 373.766806 -262.451727)
			(xy 373.811338 -262.474417) (xy 373.851771 -262.503793) (xy 373.887111 -262.539133) (xy 373.916487 -262.579566)
			(xy 373.939177 -262.624098) (xy 373.954621 -262.67163) (xy 373.96244 -262.720993) (xy 373.96293 -262.745982)
			(xy 373.96244 -262.770971) (xy 375.207258 -262.770971) (xy 375.207258 -262.720993) (xy 375.215077 -262.67163)
			(xy 375.230521 -262.624098) (xy 375.253211 -262.579566) (xy 375.282587 -262.539133) (xy 375.317927 -262.503793)
			(xy 375.35836 -262.474417) (xy 375.402892 -262.451727) (xy 375.450424 -262.436283) (xy 375.499787 -262.428464)
			(xy 375.549765 -262.428464) (xy 375.599128 -262.436283) (xy 375.64666 -262.451727) (xy 375.691192 -262.474417)
			(xy 375.731625 -262.503793) (xy 375.766965 -262.539133) (xy 375.796341 -262.579566) (xy 375.819031 -262.624098)
			(xy 375.834475 -262.67163) (xy 375.842294 -262.720993) (xy 375.842784 -262.745982) (xy 376.148595 -262.745982)
			(xy 376.15269 -262.695254) (xy 376.164869 -262.64584) (xy 376.184817 -262.59902) (xy 376.212018 -262.556006)
			(xy 376.245766 -262.517912) (xy 376.285188 -262.485725) (xy 376.329262 -262.460279) (xy 376.376848 -262.442232)
			(xy 376.426712 -262.432052) (xy 376.477564 -262.430003) (xy 376.528085 -262.436137) (xy 376.576969 -262.450297)
			(xy 376.622948 -262.472114) (xy 376.664832 -262.501024) (xy 376.701536 -262.536279) (xy 376.732109 -262.576965)
			(xy 376.75576 -262.622028) (xy 376.771876 -262.670302) (xy 376.78004 -262.720536) (xy 376.780552 -262.745982)
			(xy 377.088649 -262.745982) (xy 377.092744 -262.695254) (xy 377.104923 -262.64584) (xy 377.124871 -262.59902)
			(xy 377.152072 -262.556006) (xy 377.18582 -262.517912) (xy 377.225242 -262.485725) (xy 377.269316 -262.460279)
			(xy 377.316902 -262.442232) (xy 377.366766 -262.432052) (xy 377.417618 -262.430003) (xy 377.468139 -262.436137)
			(xy 377.517023 -262.450297) (xy 377.563002 -262.472114) (xy 377.604886 -262.501024) (xy 377.64159 -262.536279)
			(xy 377.672163 -262.576965) (xy 377.695814 -262.622028) (xy 377.71193 -262.670302) (xy 377.720094 -262.720536)
			(xy 377.720606 -262.745982) (xy 377.720103 -262.770971) (xy 378.02742 -262.770971) (xy 378.02742 -262.720993)
			(xy 378.035239 -262.67163) (xy 378.050683 -262.624098) (xy 378.073373 -262.579566) (xy 378.102749 -262.539133)
			(xy 378.138089 -262.503793) (xy 378.178522 -262.474417) (xy 378.223054 -262.451727) (xy 378.270586 -262.436283)
			(xy 378.319949 -262.428464) (xy 378.369927 -262.428464) (xy 378.41929 -262.436283) (xy 378.466822 -262.451727)
			(xy 378.511354 -262.474417) (xy 378.551787 -262.503793) (xy 378.587127 -262.539133) (xy 378.616503 -262.579566)
			(xy 378.639193 -262.624098) (xy 378.654637 -262.67163) (xy 378.662456 -262.720993) (xy 378.662946 -262.745982)
			(xy 378.968503 -262.745982) (xy 378.972598 -262.695254) (xy 378.984777 -262.64584) (xy 379.004725 -262.59902)
			(xy 379.031926 -262.556006) (xy 379.065674 -262.517912) (xy 379.105096 -262.485725) (xy 379.14917 -262.460279)
			(xy 379.196756 -262.442232) (xy 379.24662 -262.432052) (xy 379.297472 -262.430003) (xy 379.347993 -262.436137)
			(xy 379.396877 -262.450297) (xy 379.442856 -262.472114) (xy 379.48474 -262.501024) (xy 379.521444 -262.536279)
			(xy 379.552017 -262.576965) (xy 379.575668 -262.622028) (xy 379.591784 -262.670302) (xy 379.599948 -262.720536)
			(xy 379.60046 -262.745982) (xy 379.599957 -262.770971) (xy 379.907274 -262.770971) (xy 379.907274 -262.720993)
			(xy 379.915093 -262.67163) (xy 379.930537 -262.624098) (xy 379.953227 -262.579566) (xy 379.982603 -262.539133)
			(xy 380.017943 -262.503793) (xy 380.058376 -262.474417) (xy 380.102908 -262.451727) (xy 380.15044 -262.436283)
			(xy 380.199803 -262.428464) (xy 380.249781 -262.428464) (xy 380.299144 -262.436283) (xy 380.346676 -262.451727)
			(xy 380.391208 -262.474417) (xy 380.431641 -262.503793) (xy 380.466981 -262.539133) (xy 380.496357 -262.579566)
			(xy 380.519047 -262.624098) (xy 380.534491 -262.67163) (xy 380.54231 -262.720993) (xy 380.5428 -262.745982)
			(xy 380.54231 -262.770971) (xy 380.534491 -262.820334) (xy 380.519047 -262.867866) (xy 380.496357 -262.912398)
			(xy 380.466981 -262.952831) (xy 380.431641 -262.988171) (xy 380.391208 -263.017547) (xy 380.346676 -263.040237)
			(xy 380.299144 -263.055681) (xy 380.249781 -263.0635) (xy 380.199803 -263.0635) (xy 380.15044 -263.055681)
			(xy 380.102908 -263.040237) (xy 380.058376 -263.017547) (xy 380.017943 -262.988171) (xy 379.982603 -262.952831)
			(xy 379.953227 -262.912398) (xy 379.930537 -262.867866) (xy 379.915093 -262.820334) (xy 379.907274 -262.770971)
			(xy 379.599957 -262.770971) (xy 379.599948 -262.771428) (xy 379.591784 -262.821662) (xy 379.575668 -262.869936)
			(xy 379.552017 -262.914999) (xy 379.521444 -262.955685) (xy 379.48474 -262.99094) (xy 379.442856 -263.01985)
			(xy 379.396877 -263.041667) (xy 379.347993 -263.055827) (xy 379.297472 -263.061961) (xy 379.24662 -263.059912)
			(xy 379.196756 -263.049732) (xy 379.14917 -263.031685) (xy 379.105096 -263.006239) (xy 379.065674 -262.974052)
			(xy 379.031926 -262.935958) (xy 379.004725 -262.892944) (xy 378.984777 -262.846124) (xy 378.972598 -262.79671)
			(xy 378.968503 -262.745982) (xy 378.662946 -262.745982) (xy 378.662456 -262.770971) (xy 378.654637 -262.820334)
			(xy 378.639193 -262.867866) (xy 378.616503 -262.912398) (xy 378.587127 -262.952831) (xy 378.551787 -262.988171)
			(xy 378.511354 -263.017547) (xy 378.466822 -263.040237) (xy 378.41929 -263.055681) (xy 378.369927 -263.0635)
			(xy 378.319949 -263.0635) (xy 378.270586 -263.055681) (xy 378.223054 -263.040237) (xy 378.178522 -263.017547)
			(xy 378.138089 -262.988171) (xy 378.102749 -262.952831) (xy 378.073373 -262.912398) (xy 378.050683 -262.867866)
			(xy 378.035239 -262.820334) (xy 378.02742 -262.770971) (xy 377.720103 -262.770971) (xy 377.720094 -262.771428)
			(xy 377.71193 -262.821662) (xy 377.695814 -262.869936) (xy 377.672163 -262.914999) (xy 377.64159 -262.955685)
			(xy 377.604886 -262.99094) (xy 377.563002 -263.01985) (xy 377.517023 -263.041667) (xy 377.468139 -263.055827)
			(xy 377.417618 -263.061961) (xy 377.366766 -263.059912) (xy 377.316902 -263.049732) (xy 377.269316 -263.031685)
			(xy 377.225242 -263.006239) (xy 377.18582 -262.974052) (xy 377.152072 -262.935958) (xy 377.124871 -262.892944)
			(xy 377.104923 -262.846124) (xy 377.092744 -262.79671) (xy 377.088649 -262.745982) (xy 376.780552 -262.745982)
			(xy 376.78004 -262.771428) (xy 376.771876 -262.821662) (xy 376.75576 -262.869936) (xy 376.732109 -262.914999)
			(xy 376.701536 -262.955685) (xy 376.664832 -262.99094) (xy 376.622948 -263.01985) (xy 376.576969 -263.041667)
			(xy 376.528085 -263.055827) (xy 376.477564 -263.061961) (xy 376.426712 -263.059912) (xy 376.376848 -263.049732)
			(xy 376.329262 -263.031685) (xy 376.285188 -263.006239) (xy 376.245766 -262.974052) (xy 376.212018 -262.935958)
			(xy 376.184817 -262.892944) (xy 376.164869 -262.846124) (xy 376.15269 -262.79671) (xy 376.148595 -262.745982)
			(xy 375.842784 -262.745982) (xy 375.842294 -262.770971) (xy 375.834475 -262.820334) (xy 375.819031 -262.867866)
			(xy 375.796341 -262.912398) (xy 375.766965 -262.952831) (xy 375.731625 -262.988171) (xy 375.691192 -263.017547)
			(xy 375.64666 -263.040237) (xy 375.599128 -263.055681) (xy 375.549765 -263.0635) (xy 375.499787 -263.0635)
			(xy 375.450424 -263.055681) (xy 375.402892 -263.040237) (xy 375.35836 -263.017547) (xy 375.317927 -262.988171)
			(xy 375.282587 -262.952831) (xy 375.253211 -262.912398) (xy 375.230521 -262.867866) (xy 375.215077 -262.820334)
			(xy 375.207258 -262.770971) (xy 373.96244 -262.770971) (xy 373.954621 -262.820334) (xy 373.939177 -262.867866)
			(xy 373.916487 -262.912398) (xy 373.887111 -262.952831) (xy 373.851771 -262.988171) (xy 373.811338 -263.017547)
			(xy 373.766806 -263.040237) (xy 373.719274 -263.055681) (xy 373.669911 -263.0635) (xy 373.619933 -263.0635)
			(xy 373.57057 -263.055681) (xy 373.523038 -263.040237) (xy 373.478506 -263.017547) (xy 373.438073 -262.988171)
			(xy 373.402733 -262.952831) (xy 373.373357 -262.912398) (xy 373.350667 -262.867866) (xy 373.335223 -262.820334)
			(xy 373.327404 -262.770971) (xy 372.303294 -262.770971) (xy 372.303294 -262.937498) (xy 372.303817 -262.947244)
			(xy 372.311278 -262.965261) (xy 372.317772 -262.97255) (xy 372.542054 -263.196832) (xy 372.5493 -263.203391)
			(xy 372.567344 -263.21085) (xy 372.577106 -263.21131) (xy 381.171958 -263.21131) (xy 381.181797 -263.210777)
			(xy 381.199962 -263.203194) (xy 381.207264 -263.196578) (xy 381.259334 -263.144508) (xy 381.266677 -263.136331)
			(xy 381.274087 -263.115669) (xy 381.272008 -263.093818) (xy 381.266954 -263.084056) (xy 381.255524 -263.072626)
			(xy 381.25019 -263.068054) (xy 381.246683 -263.065547) (xy 381.239025 -263.061589) (xy 381.23495 -263.06018)
			(xy 381.228346 -263.058148) (xy 381.221996 -263.05891) (xy 381.216916 -263.059672) (xy 381.2159 -263.059926)
			(xy 381.203414 -263.061824) (xy 381.178237 -263.063856) (xy 381.165608 -263.06399) (xy 381.164846 -263.06399)
			(xy 381.139854 -263.063529) (xy 381.090484 -263.055716) (xy 381.042945 -263.040275) (xy 380.998406 -263.017588)
			(xy 380.957966 -262.988211) (xy 380.922619 -262.95287) (xy 380.893237 -262.912433) (xy 380.870542 -262.867898)
			(xy 380.855095 -262.820361) (xy 380.847275 -262.770992) (xy 380.847275 -262.721008) (xy 380.855095 -262.671639)
			(xy 380.870542 -262.624102) (xy 380.893237 -262.579567) (xy 380.922619 -262.53913) (xy 380.957966 -262.503789)
			(xy 380.998406 -262.474412) (xy 381.042945 -262.451725) (xy 381.090484 -262.436284) (xy 381.139854 -262.428471)
			(xy 381.164846 -262.427974) (xy 381.191259 -262.428498) (xy 381.24336 -262.43723) (xy 381.293303 -262.454444)
			(xy 381.339718 -262.47967) (xy 381.38133 -262.512214) (xy 381.399542 -262.531352) (xy 381.400558 -262.532368)
			(xy 381.404876 -262.537194) (xy 381.41783 -262.544814) (xy 381.424434 -262.546338) (xy 381.431254 -262.547775)
			(xy 381.445176 -262.547272) (xy 381.451866 -262.545322) (xy 381.4953 -262.528558) (xy 381.495808 -262.528558)
			(xy 381.541528 -262.510524) (xy 381.550739 -262.5065) (xy 381.565194 -262.492556) (xy 381.573073 -262.474083)
			(xy 381.573532 -262.464042) (xy 381.573532 -262.286496) (xy 381.573532 -262.283448) (xy 381.572826 -262.276277)
			(xy 381.56794 -262.262729) (xy 381.56388 -262.256778) (xy 381.559308 -262.250936) (xy 381.546862 -262.241792)
			(xy 381.538226 -262.238998) (xy 381.514446 -262.230929) (xy 381.469587 -262.208364) (xy 381.428833 -262.179028)
			(xy 381.393195 -262.143653) (xy 381.363561 -262.103115) (xy 381.340665 -262.058424) (xy 381.325079 -262.01069)
			(xy 381.317188 -261.9611) (xy 381.317189 -261.910886) (xy 381.325082 -261.861295) (xy 381.340671 -261.813562)
			(xy 381.363568 -261.768872) (xy 381.393205 -261.728336) (xy 381.428844 -261.692962) (xy 381.4696 -261.663629)
			(xy 381.51446 -261.641066) (xy 381.538226 -261.632954) (xy 381.541274 -261.631938) (xy 381.548092 -261.629124)
			(xy 381.559842 -261.620219) (xy 381.564388 -261.614412) (xy 381.568706 -261.60857) (xy 381.571246 -261.600696)
			(xy 381.572312 -261.596976) (xy 381.573455 -261.589325) (xy 381.573532 -261.585456) (xy 381.573532 -261.40791)
			(xy 381.573034 -261.397876) (xy 381.565151 -261.379416) (xy 381.550732 -261.365451) (xy 381.541528 -261.361428)
			(xy 381.495808 -261.343394) (xy 381.4953 -261.343394) (xy 381.451866 -261.32663) (xy 381.445166 -261.324727)
			(xy 381.431254 -261.324202) (xy 381.424434 -261.325614) (xy 381.41783 -261.327138) (xy 381.404876 -261.334758)
			(xy 381.400558 -261.339584) (xy 381.399542 -261.3406) (xy 381.381331 -261.359738) (xy 381.339725 -261.39229)
			(xy 381.29331 -261.417514) (xy 381.243363 -261.434718) (xy 381.191259 -261.443427) (xy 381.164846 -261.443978)
			(xy 381.139855 -261.443517) (xy 381.090487 -261.435704) (xy 381.042949 -261.420264) (xy 380.998412 -261.397577)
			(xy 380.957973 -261.368202) (xy 380.922628 -261.332862) (xy 380.893247 -261.292427) (xy 380.870553 -261.247893)
			(xy 380.855107 -261.200358) (xy 380.847287 -261.150991) (xy 380.847287 -261.101009) (xy 380.855107 -261.051642)
			(xy 380.870553 -261.004107) (xy 380.893247 -260.959573) (xy 380.922628 -260.919138) (xy 380.957973 -260.883798)
			(xy 380.998412 -260.854423) (xy 381.042949 -260.831736) (xy 381.090487 -260.816296) (xy 381.139855 -260.808483)
			(xy 381.164846 -260.807962) (xy 381.191259 -260.808487) (xy 381.243357 -260.81722) (xy 381.293297 -260.834438)
			(xy 381.339707 -260.859669) (xy 381.381313 -260.892219) (xy 381.399542 -260.91134) (xy 381.400558 -260.912356)
			(xy 381.404876 -260.917182) (xy 381.41783 -260.924802) (xy 381.424434 -260.926326) (xy 381.431253 -260.927763)
			(xy 381.445176 -260.92726) (xy 381.451866 -260.92531) (xy 381.4953 -260.908546) (xy 381.495808 -260.908546)
			(xy 381.541528 -260.890512) (xy 381.550738 -260.886487) (xy 381.56519 -260.872543) (xy 381.573064 -260.85407)
			(xy 381.573532 -260.84403) (xy 381.573532 -256.880106) (xy 381.573449 -256.875694) (xy 381.571924 -256.867005)
			(xy 381.570484 -256.862834) (xy 381.562102 -256.83972) (xy 381.556768 -256.833116) (xy 381.542161 -256.814209)
			(xy 381.518191 -256.772883) (xy 381.500672 -256.728435) (xy 381.489999 -256.681867) (xy 381.486411 -256.634227)
			(xy 381.489991 -256.586585) (xy 381.500656 -256.540016) (xy 381.518168 -256.495565) (xy 381.542131 -256.454234)
			(xy 381.556768 -256.435352) (xy 381.562102 -256.428748) (xy 381.570484 -256.405634) (xy 381.571893 -256.401455)
			(xy 381.573424 -256.392771) (xy 381.573532 -256.388362) (xy 381.573532 -256.218436) (xy 381.572944 -256.206827)
			(xy 381.562624 -256.186028) (xy 381.55372 -256.178558) (xy 381.545338 -256.172716) (xy 381.485902 -256.130552)
			(xy 381.480847 -256.127167) (xy 381.46955 -256.122666) (xy 381.46355 -256.121662) (xy 381.451866 -256.120138)
			(xy 381.440182 -256.124202) (xy 381.414643 -256.132605) (xy 381.361652 -256.14167) (xy 381.334772 -256.142236)
			(xy 381.309782 -256.141743) (xy 381.260418 -256.133921) (xy 381.212885 -256.118473) (xy 381.168354 -256.09578)
			(xy 381.127921 -256.0664) (xy 381.092582 -256.031057) (xy 381.063206 -255.990622) (xy 381.040516 -255.946089)
			(xy 381.025072 -255.898555) (xy 381.017254 -255.84919) (xy 381.017254 -255.79921) (xy 381.025072 -255.749845)
			(xy 381.040516 -255.702311) (xy 381.063206 -255.657778) (xy 381.092582 -255.617343) (xy 381.127921 -255.582)
			(xy 381.168354 -255.55262) (xy 381.212885 -255.529927) (xy 381.260418 -255.514479) (xy 381.309782 -255.506657)
			(xy 381.334772 -255.50622) (xy 381.36165 -255.506806) (xy 381.414637 -255.515873) (xy 381.440182 -255.524254)
			(xy 381.440436 -255.524254) (xy 381.446161 -255.526039) (xy 381.458095 -255.527183) (xy 381.464058 -255.52654)
			(xy 381.475742 -255.525016) (xy 381.545338 -255.47574) (xy 381.55372 -255.469898) (xy 381.562614 -255.462415)
			(xy 381.572951 -255.441628) (xy 381.573532 -255.43002) (xy 381.573532 -255.260094) (xy 381.573448 -255.255683)
			(xy 381.571921 -255.246993) (xy 381.570484 -255.242822) (xy 381.562102 -255.219708) (xy 381.556768 -255.213104)
			(xy 381.542162 -255.194197) (xy 381.518194 -255.152871) (xy 381.500676 -255.108424) (xy 381.490005 -255.061857)
			(xy 381.486419 -255.014217) (xy 381.49 -254.966577) (xy 381.500666 -254.920009) (xy 381.518179 -254.87556)
			(xy 381.542143 -254.834231) (xy 381.556768 -254.81534) (xy 381.562102 -254.808736) (xy 381.570484 -254.785622)
			(xy 381.571892 -254.781443) (xy 381.573421 -254.772759) (xy 381.573532 -254.76835) (xy 381.573532 -254.598424)
			(xy 381.572942 -254.586816) (xy 381.562619 -254.566022) (xy 381.55372 -254.558546) (xy 381.545338 -254.552704)
			(xy 381.485902 -254.51054) (xy 381.480847 -254.507156) (xy 381.469549 -254.502656) (xy 381.46355 -254.50165)
			(xy 381.451866 -254.500126) (xy 381.440182 -254.50419) (xy 381.414643 -254.512593) (xy 381.361652 -254.521659)
			(xy 381.334772 -254.522224) (xy 381.309783 -254.521732) (xy 381.260421 -254.513909) (xy 381.21289 -254.498462)
			(xy 381.168361 -254.47577) (xy 381.127929 -254.446391) (xy 381.092591 -254.41105) (xy 381.063216 -254.370616)
			(xy 381.040527 -254.326084) (xy 381.025084 -254.278552) (xy 381.017266 -254.229189) (xy 381.017266 -254.179211)
			(xy 381.025084 -254.129848) (xy 381.040527 -254.082316) (xy 381.063216 -254.037784) (xy 381.092591 -253.99735)
			(xy 381.127929 -253.962009) (xy 381.168361 -253.93263) (xy 381.21289 -253.909938) (xy 381.260421 -253.894491)
			(xy 381.309783 -253.886668) (xy 381.334772 -253.886208) (xy 381.36165 -253.886794) (xy 381.414636 -253.895864)
			(xy 381.440182 -253.904242) (xy 381.440436 -253.904242) (xy 381.446161 -253.906027) (xy 381.458095 -253.907172)
			(xy 381.464058 -253.906528) (xy 381.475742 -253.905004) (xy 381.545338 -253.855728) (xy 381.55372 -253.849886)
			(xy 381.562612 -253.842402) (xy 381.572945 -253.821615) (xy 381.573532 -253.810008) (xy 381.573532 -253.640082)
			(xy 381.573447 -253.635671) (xy 381.571918 -253.626982) (xy 381.570484 -253.62281) (xy 381.562102 -253.599696)
			(xy 381.556768 -253.593092) (xy 381.542163 -253.574186) (xy 381.518196 -253.532859) (xy 381.500681 -253.488413)
			(xy 381.490011 -253.441846) (xy 381.486426 -253.394208) (xy 381.490008 -253.346569) (xy 381.500676 -253.300002)
			(xy 381.518189 -253.255555) (xy 381.542154 -253.214227) (xy 381.556768 -253.195328) (xy 381.562102 -253.188724)
			(xy 381.570484 -253.16561) (xy 381.571891 -253.161431) (xy 381.573418 -253.152746) (xy 381.573532 -253.148338)
			(xy 381.573532 -252.978412) (xy 381.572939 -252.966805) (xy 381.562614 -252.946015) (xy 381.55372 -252.938534)
			(xy 381.545338 -252.932692) (xy 381.485902 -252.890528) (xy 381.480847 -252.887144) (xy 381.469549 -252.882645)
			(xy 381.46355 -252.881638) (xy 381.451866 -252.880114) (xy 381.440182 -252.884178) (xy 381.414643 -252.892582)
			(xy 381.361652 -252.901648) (xy 381.334772 -252.902212) (xy 381.309784 -252.90172) (xy 381.260424 -252.893898)
			(xy 381.212895 -252.878451) (xy 381.168367 -252.855759) (xy 381.127937 -252.826382) (xy 381.0926 -252.791042)
			(xy 381.063226 -252.750609) (xy 381.040538 -252.70608) (xy 381.025096 -252.658549) (xy 381.017278 -252.609188)
			(xy 381.017278 -252.559212) (xy 381.025096 -252.509851) (xy 381.040538 -252.46232) (xy 381.063226 -252.417791)
			(xy 381.0926 -252.377358) (xy 381.127937 -252.342018) (xy 381.168367 -252.312641) (xy 381.212895 -252.289949)
			(xy 381.260424 -252.274502) (xy 381.309784 -252.26668) (xy 381.334772 -252.266196) (xy 381.36165 -252.266782)
			(xy 381.414636 -252.275852) (xy 381.440182 -252.28423) (xy 381.440436 -252.28423) (xy 381.446161 -252.286013)
			(xy 381.458095 -252.287156) (xy 381.464058 -252.286516) (xy 381.475742 -252.284992) (xy 381.545338 -252.235716)
			(xy 381.55372 -252.229874) (xy 381.56261 -252.222389) (xy 381.572937 -252.201602) (xy 381.573532 -252.189996)
			(xy 381.573532 -252.02007) (xy 381.573446 -252.015659) (xy 381.571915 -252.006971) (xy 381.570484 -252.002798)
			(xy 381.562102 -251.979684) (xy 381.556768 -251.97308) (xy 381.542164 -251.954174) (xy 381.518199 -251.912847)
			(xy 381.500685 -251.868402) (xy 381.490017 -251.821836) (xy 381.486434 -251.774198) (xy 381.490017 -251.726561)
			(xy 381.500686 -251.679995) (xy 381.5182 -251.63555) (xy 381.542166 -251.594224) (xy 381.556768 -251.575316)
			(xy 381.562102 -251.568712) (xy 381.570484 -251.545598) (xy 381.571899 -251.54142) (xy 381.573441 -251.532736)
			(xy 381.573532 -251.528326) (xy 381.573532 -251.3584) (xy 381.572937 -251.346795) (xy 381.562608 -251.326008)
			(xy 381.55372 -251.318522) (xy 381.545338 -251.31268) (xy 381.485902 -251.270516) (xy 381.480847 -251.267133)
			(xy 381.469549 -251.262635) (xy 381.46355 -251.261626) (xy 381.451866 -251.260102) (xy 381.440182 -251.264166)
			(xy 381.414642 -251.272568) (xy 381.361652 -251.281631) (xy 381.334772 -251.2822) (xy 381.309785 -251.281708)
			(xy 381.260426 -251.273886) (xy 381.212899 -251.25844) (xy 381.168373 -251.235749) (xy 381.127945 -251.206373)
			(xy 381.092609 -251.171034) (xy 381.063236 -251.130603) (xy 381.04055 -251.086075) (xy 381.025107 -251.038546)
			(xy 381.01729 -250.989187) (xy 381.01729 -250.939213) (xy 381.025107 -250.889854) (xy 381.04055 -250.842325)
			(xy 381.063236 -250.797797) (xy 381.092609 -250.757366) (xy 381.127945 -250.722027) (xy 381.168373 -250.692651)
			(xy 381.212899 -250.66996) (xy 381.260426 -250.654514) (xy 381.309785 -250.646692) (xy 381.334772 -250.646184)
			(xy 381.36165 -250.64677) (xy 381.414636 -250.655839) (xy 381.440182 -250.664218) (xy 381.440436 -250.664218)
			(xy 381.446161 -250.666002) (xy 381.458095 -250.667144) (xy 381.464058 -250.666504) (xy 381.475742 -250.66498)
			(xy 381.545338 -250.615704) (xy 381.55372 -250.609862) (xy 381.562608 -250.602377) (xy 381.57293 -250.581589)
			(xy 381.573532 -250.569984) (xy 381.573532 -250.400058) (xy 381.573445 -250.395647) (xy 381.571912 -250.38696)
			(xy 381.570484 -250.382786) (xy 381.562102 -250.359672) (xy 381.556768 -250.353068) (xy 381.542165 -250.334162)
			(xy 381.518202 -250.292836) (xy 381.50069 -250.24839) (xy 381.490023 -250.201826) (xy 381.486441 -250.154189)
			(xy 381.490026 -250.106553) (xy 381.500696 -250.059989) (xy 381.518211 -250.015545) (xy 381.542177 -249.97422)
			(xy 381.556768 -249.955304) (xy 381.562102 -249.9487) (xy 381.570484 -249.925586) (xy 381.571898 -249.921408)
			(xy 381.573438 -249.912724) (xy 381.573532 -249.908314) (xy 381.573532 -249.738388) (xy 381.572934 -249.726784)
			(xy 381.562603 -249.706002) (xy 381.55372 -249.69851) (xy 381.545338 -249.692668) (xy 381.485902 -249.650504)
			(xy 381.480846 -249.647121) (xy 381.469548 -249.642625) (xy 381.46355 -249.641614) (xy 381.451866 -249.64009)
			(xy 381.440182 -249.644154) (xy 381.414643 -249.652556) (xy 381.361652 -249.66162) (xy 381.334772 -249.662188)
			(xy 381.309786 -249.661696) (xy 381.260429 -249.653874) (xy 381.212904 -249.638429) (xy 381.168379 -249.615739)
			(xy 381.127952 -249.586364) (xy 381.092618 -249.551026) (xy 381.063246 -249.510597) (xy 381.040561 -249.46607)
			(xy 381.025119 -249.418543) (xy 381.017302 -249.369186) (xy 381.017302 -249.319214) (xy 381.025119 -249.269857)
			(xy 381.040561 -249.22233) (xy 381.063246 -249.177803) (xy 381.092618 -249.137374) (xy 381.127952 -249.102036)
			(xy 381.168379 -249.072661) (xy 381.212904 -249.049971) (xy 381.260429 -249.034526) (xy 381.309786 -249.026704)
			(xy 381.334772 -249.026172) (xy 381.36165 -249.026758) (xy 381.414637 -249.035827) (xy 381.440182 -249.044206)
			(xy 381.440436 -249.044206) (xy 381.446161 -249.045989) (xy 381.458095 -249.047133) (xy 381.464058 -249.046492)
			(xy 381.475742 -249.044968) (xy 381.545338 -248.995692) (xy 381.55372 -248.98985) (xy 381.562606 -248.982364)
			(xy 381.572924 -248.961576) (xy 381.573532 -248.949972) (xy 381.573532 -248.780046) (xy 381.573444 -248.775635)
			(xy 381.571909 -248.766949) (xy 381.570484 -248.762774) (xy 381.562102 -248.73966) (xy 381.556768 -248.733056)
			(xy 381.542166 -248.71415) (xy 381.518204 -248.672824) (xy 381.500694 -248.628379) (xy 381.490029 -248.581815)
			(xy 381.486449 -248.53418) (xy 381.490035 -248.486545) (xy 381.500706 -248.439982) (xy 381.518222 -248.395539)
			(xy 381.542189 -248.354217) (xy 381.556768 -248.335292) (xy 381.562102 -248.328688) (xy 381.570484 -248.305574)
			(xy 381.571897 -248.301396) (xy 381.573435 -248.292711) (xy 381.573532 -248.288302) (xy 381.573532 -248.118376)
			(xy 381.572932 -248.106773) (xy 381.562597 -248.085995) (xy 381.55372 -248.078498) (xy 381.545338 -248.072656)
			(xy 381.485902 -248.030492) (xy 381.480848 -248.027104) (xy 381.469551 -248.0226) (xy 381.46355 -248.021602)
			(xy 381.451866 -248.020078) (xy 381.440182 -248.024142) (xy 381.414643 -248.032544) (xy 381.361652 -248.041608)
			(xy 381.334772 -248.042176) (xy 381.309787 -248.041684) (xy 381.260432 -248.033863) (xy 381.212908 -248.018418)
			(xy 381.168386 -247.995729) (xy 381.12796 -247.966355) (xy 381.092627 -247.931018) (xy 381.063257 -247.89059)
			(xy 381.040572 -247.846066) (xy 381.025131 -247.798541) (xy 381.017314 -247.749185) (xy 381.017314 -247.699215)
			(xy 381.025131 -247.649859) (xy 381.040572 -247.602334) (xy 381.063257 -247.55781) (xy 381.092627 -247.517381)
			(xy 381.12796 -247.482045) (xy 381.168386 -247.452671) (xy 381.212908 -247.429982) (xy 381.260432 -247.414537)
			(xy 381.309787 -247.406716) (xy 381.334772 -247.40616) (xy 381.36165 -247.406746) (xy 381.414637 -247.415815)
			(xy 381.440182 -247.424194) (xy 381.440436 -247.424194) (xy 381.446161 -247.425978) (xy 381.458095 -247.427121)
			(xy 381.464058 -247.42648) (xy 381.475742 -247.424956) (xy 381.545338 -247.37568) (xy 381.55372 -247.369838)
			(xy 381.562604 -247.362351) (xy 381.572916 -247.341563) (xy 381.573532 -247.32996) (xy 381.573532 -247.160034)
			(xy 381.573443 -247.155624) (xy 381.571906 -247.146938) (xy 381.570484 -247.142762) (xy 381.562102 -247.119648)
			(xy 381.556768 -247.113044) (xy 381.542167 -247.094138) (xy 381.518207 -247.052812) (xy 381.500698 -247.008368)
			(xy 381.490035 -246.961805) (xy 381.486456 -246.91417) (xy 381.490044 -246.866536) (xy 381.500716 -246.819975)
			(xy 381.518233 -246.775534) (xy 381.5422 -246.734213) (xy 381.556768 -246.71528) (xy 381.562102 -246.708676)
			(xy 381.570484 -246.685562) (xy 381.571895 -246.681383) (xy 381.573431 -246.672699) (xy 381.573532 -246.66829)
			(xy 381.573532 -246.498364) (xy 381.572929 -246.486763) (xy 381.562592 -246.465989) (xy 381.55372 -246.458486)
			(xy 381.545338 -246.452644) (xy 381.485902 -246.41048) (xy 381.480848 -246.407093) (xy 381.469551 -246.40259)
			(xy 381.46355 -246.40159) (xy 381.451866 -246.400066) (xy 381.440182 -246.40413) (xy 381.414643 -246.412532)
			(xy 381.361652 -246.421597) (xy 381.334772 -246.422164) (xy 381.309788 -246.421672) (xy 381.260435 -246.413851)
			(xy 381.212913 -246.398406) (xy 381.168392 -246.375718) (xy 381.127968 -246.346345) (xy 381.092636 -246.311011)
			(xy 381.063267 -246.270584) (xy 381.040583 -246.226061) (xy 381.025142 -246.178538) (xy 381.017326 -246.129184)
			(xy 381.017326 -246.079216) (xy 381.025142 -246.029862) (xy 381.040583 -245.982339) (xy 381.063267 -245.937816)
			(xy 381.092636 -245.897389) (xy 381.127968 -245.862055) (xy 381.168392 -245.832682) (xy 381.212913 -245.809994)
			(xy 381.260435 -245.794549) (xy 381.309788 -245.786728) (xy 381.334772 -245.786148) (xy 381.36165 -245.786734)
			(xy 381.414637 -245.795802) (xy 381.440182 -245.804182) (xy 381.440436 -245.804182) (xy 381.446161 -245.805966)
			(xy 381.458095 -245.80711) (xy 381.464058 -245.806468) (xy 381.475742 -245.804944) (xy 381.545338 -245.755668)
			(xy 381.55372 -245.749826) (xy 381.562602 -245.742338) (xy 381.57291 -245.72155) (xy 381.573532 -245.709948)
			(xy 381.573532 -245.540022) (xy 381.573441 -245.535612) (xy 381.571903 -245.526927) (xy 381.570484 -245.52275)
			(xy 381.562102 -245.499636) (xy 381.556768 -245.493032) (xy 381.54216 -245.474125) (xy 381.518187 -245.432798)
			(xy 381.500666 -245.38835) (xy 381.489991 -245.341781) (xy 381.486401 -245.294139) (xy 381.489979 -245.246496)
			(xy 381.500643 -245.199925) (xy 381.518153 -245.155472) (xy 381.542116 -245.114139) (xy 381.556768 -245.095268)
			(xy 381.562102 -245.088664) (xy 381.570484 -245.06555) (xy 381.571894 -245.061371) (xy 381.573428 -245.052687)
			(xy 381.573532 -245.048278) (xy 381.573532 -244.878352) (xy 381.572927 -244.866752) (xy 381.562586 -244.845982)
			(xy 381.55372 -244.838474) (xy 381.545338 -244.832632) (xy 381.485902 -244.790468) (xy 381.480848 -244.787082)
			(xy 381.46955 -244.782579) (xy 381.46355 -244.781578) (xy 381.451866 -244.780054) (xy 381.440182 -244.784118)
			(xy 381.414643 -244.792521) (xy 381.361652 -244.801586) (xy 381.334772 -244.802152) (xy 381.309781 -244.801659)
			(xy 381.260414 -244.793837) (xy 381.212879 -244.778388) (xy 381.168346 -244.755693) (xy 381.127911 -244.726312)
			(xy 381.092569 -244.690968) (xy 381.063192 -244.65053) (xy 381.040501 -244.605995) (xy 381.025057 -244.558458)
			(xy 381.017238 -244.509091) (xy 381.017238 -244.459109) (xy 381.025057 -244.409742) (xy 381.040501 -244.362205)
			(xy 381.063192 -244.31767) (xy 381.092569 -244.277232) (xy 381.127911 -244.241888) (xy 381.168346 -244.212507)
			(xy 381.212879 -244.189812) (xy 381.260414 -244.174363) (xy 381.309781 -244.166541) (xy 381.334772 -244.166136)
			(xy 381.36165 -244.166722) (xy 381.414637 -244.17579) (xy 381.440182 -244.18417) (xy 381.440436 -244.18417)
			(xy 381.446161 -244.185955) (xy 381.458095 -244.187098) (xy 381.464058 -244.186456) (xy 381.475742 -244.184932)
			(xy 381.545338 -244.135656) (xy 381.55372 -244.129814) (xy 381.562617 -244.122332) (xy 381.57296 -244.101545)
			(xy 381.573532 -244.089936) (xy 381.573532 -243.92001) (xy 381.57344 -243.9156) (xy 381.5719 -243.906916)
			(xy 381.570484 -243.902738) (xy 381.562102 -243.879624) (xy 381.556768 -243.87302) (xy 381.542161 -243.854113)
			(xy 381.51819 -243.812787) (xy 381.500671 -243.768339) (xy 381.489997 -243.721771) (xy 381.486409 -243.67413)
			(xy 381.489988 -243.626488) (xy 381.500653 -243.579918) (xy 381.518164 -243.535467) (xy 381.542128 -243.494136)
			(xy 381.556768 -243.475256) (xy 381.562102 -243.468652) (xy 381.570484 -243.445538) (xy 381.571893 -243.441359)
			(xy 381.573425 -243.432675) (xy 381.573532 -243.428266) (xy 381.573532 -243.25834) (xy 381.572945 -243.24673)
			(xy 381.562626 -243.22593) (xy 381.55372 -243.218462) (xy 381.545338 -243.21262) (xy 381.485902 -243.170456)
			(xy 381.480848 -243.167071) (xy 381.46955 -243.162569) (xy 381.46355 -243.161566) (xy 381.451866 -243.160042)
			(xy 381.440182 -243.164106) (xy 381.414643 -243.172509) (xy 381.361652 -243.181574) (xy 381.334772 -243.18214)
			(xy 381.309782 -243.181647) (xy 381.260417 -243.173825) (xy 381.212884 -243.158377) (xy 381.168352 -243.135683)
			(xy 381.127919 -243.106303) (xy 381.092579 -243.07096) (xy 381.063202 -243.030524) (xy 381.040513 -242.98599)
			(xy 381.025069 -242.938456) (xy 381.01725 -242.88909) (xy 381.01725 -242.83911) (xy 381.025069 -242.789744)
			(xy 381.040513 -242.74221) (xy 381.063202 -242.697676) (xy 381.092579 -242.65724) (xy 381.127919 -242.621897)
			(xy 381.168352 -242.592517) (xy 381.212884 -242.569823) (xy 381.260417 -242.554375) (xy 381.309782 -242.546553)
			(xy 381.334772 -242.546124) (xy 381.36165 -242.54671) (xy 381.414637 -242.555778) (xy 381.440182 -242.564158)
			(xy 381.440436 -242.564158) (xy 381.446161 -242.565943) (xy 381.458095 -242.567087) (xy 381.464058 -242.566444)
			(xy 381.475742 -242.56492) (xy 381.545338 -242.515644) (xy 381.55372 -242.509802) (xy 381.562615 -242.502319)
			(xy 381.572954 -242.481532) (xy 381.573532 -242.469924) (xy 381.573532 -242.299998) (xy 381.573448 -242.295587)
			(xy 381.571922 -242.286897) (xy 381.570484 -242.282726) (xy 381.562102 -242.259612) (xy 381.556768 -242.253008)
			(xy 381.542162 -242.234101) (xy 381.518193 -242.192775) (xy 381.500675 -242.148328) (xy 381.490003 -242.10176)
			(xy 381.486416 -242.05412) (xy 381.489997 -242.00648) (xy 381.500663 -241.959911) (xy 381.518175 -241.915462)
			(xy 381.542139 -241.874132) (xy 381.556768 -241.855244) (xy 381.562102 -241.84864) (xy 381.570484 -241.825526)
			(xy 381.571892 -241.821347) (xy 381.573422 -241.812663) (xy 381.573532 -241.808254) (xy 381.573532 -241.638328)
			(xy 381.572942 -241.62672) (xy 381.562621 -241.605924) (xy 381.55372 -241.59845) (xy 381.545338 -241.592608)
			(xy 381.485902 -241.550444) (xy 381.480847 -241.547059) (xy 381.469549 -241.542559) (xy 381.46355 -241.541554)
			(xy 381.451866 -241.54003) (xy 381.440182 -241.544094) (xy 381.414643 -241.552497) (xy 381.361652 -241.561563)
			(xy 381.334772 -241.562128) (xy 381.309783 -241.561636) (xy 381.26042 -241.553813) (xy 381.212888 -241.538366)
			(xy 381.168358 -241.515673) (xy 381.127926 -241.486294) (xy 381.092588 -241.450952) (xy 381.063212 -241.410518)
			(xy 381.040524 -241.365986) (xy 381.02508 -241.318453) (xy 381.017262 -241.269089) (xy 381.017262 -241.219111)
			(xy 381.02508 -241.169747) (xy 381.040524 -241.122214) (xy 381.063212 -241.077682) (xy 381.092588 -241.037248)
			(xy 381.127926 -241.001906) (xy 381.168358 -240.972527) (xy 381.212888 -240.949834) (xy 381.26042 -240.934387)
			(xy 381.309783 -240.926564) (xy 381.334772 -240.926112) (xy 381.36165 -240.926698) (xy 381.414637 -240.935765)
			(xy 381.440182 -240.944146) (xy 381.440436 -240.944146) (xy 381.446161 -240.945931) (xy 381.458095 -240.947076)
			(xy 381.464058 -240.946432) (xy 381.475742 -240.944908) (xy 381.545338 -240.895632) (xy 381.55372 -240.88979)
			(xy 381.562613 -240.882307) (xy 381.572947 -240.861519) (xy 381.573532 -240.849912) (xy 381.573532 -240.679986)
			(xy 381.573447 -240.675575) (xy 381.571919 -240.666886) (xy 381.570484 -240.662714) (xy 381.562102 -240.6396)
			(xy 381.556768 -240.632996) (xy 381.542163 -240.61409) (xy 381.518195 -240.572763) (xy 381.500679 -240.528317)
			(xy 381.490009 -240.48175) (xy 381.486424 -240.434111) (xy 381.490006 -240.386472) (xy 381.500673 -240.339904)
			(xy 381.518186 -240.295457) (xy 381.542151 -240.254129) (xy 381.556768 -240.235232) (xy 381.562102 -240.228628)
			(xy 381.570484 -240.205514) (xy 381.571891 -240.201335) (xy 381.573419 -240.192651) (xy 381.573532 -240.188242)
			(xy 381.573532 -240.018316) (xy 381.57294 -240.006709) (xy 381.562615 -239.985917) (xy 381.55372 -239.978438)
			(xy 381.545338 -239.972596) (xy 381.485902 -239.930432) (xy 381.480847 -239.927048) (xy 381.469549 -239.922548)
			(xy 381.46355 -239.921542) (xy 381.451866 -239.920018) (xy 381.440182 -239.924082) (xy 381.414643 -239.932486)
			(xy 381.361652 -239.941552) (xy 381.334772 -239.942116) (xy 381.309784 -239.941624) (xy 381.260423 -239.933802)
			(xy 381.212893 -239.918355) (xy 381.168365 -239.895663) (xy 381.127934 -239.866285) (xy 381.092597 -239.830944)
			(xy 381.063223 -239.790511) (xy 381.040535 -239.745981) (xy 381.025092 -239.69845) (xy 381.017274 -239.649088)
			(xy 381.017274 -239.599112) (xy 381.025092 -239.54975) (xy 381.040535 -239.502219) (xy 381.063223 -239.457689)
			(xy 381.092597 -239.417256) (xy 381.127934 -239.381915) (xy 381.168365 -239.352537) (xy 381.212893 -239.329845)
			(xy 381.260423 -239.314398) (xy 381.309784 -239.306576) (xy 381.334772 -239.3061) (xy 381.36165 -239.306686)
			(xy 381.414636 -239.315756) (xy 381.440182 -239.324134) (xy 381.440436 -239.324134) (xy 381.446161 -239.32592)
			(xy 381.458095 -239.327064) (xy 381.464058 -239.32642) (xy 381.475742 -239.324896) (xy 381.545338 -239.27562)
			(xy 381.55372 -239.269778) (xy 381.56261 -239.262294) (xy 381.572939 -239.241506) (xy 381.573532 -239.2299)
			(xy 381.573532 -239.059974) (xy 381.573446 -239.055563) (xy 381.571916 -239.046875) (xy 381.570484 -239.042702)
			(xy 381.562102 -239.019588) (xy 381.556768 -239.012984) (xy 381.542164 -238.994078) (xy 381.518198 -238.952751)
			(xy 381.500684 -238.908305) (xy 381.490015 -238.861739) (xy 381.486431 -238.814102) (xy 381.490014 -238.766464)
			(xy 381.500683 -238.719898) (xy 381.518197 -238.675451) (xy 381.542162 -238.634125) (xy 381.556768 -238.61522)
			(xy 381.562102 -238.608616) (xy 381.570484 -238.585502) (xy 381.57189 -238.581323) (xy 381.573416 -238.572638)
			(xy 381.573532 -238.56823) (xy 381.573532 -238.398304) (xy 381.572937 -238.386698) (xy 381.56261 -238.365911)
			(xy 381.55372 -238.358426) (xy 381.545338 -238.352584) (xy 381.485902 -238.31042) (xy 381.480847 -238.307036)
			(xy 381.469549 -238.302538) (xy 381.46355 -238.30153) (xy 381.451866 -238.300006) (xy 381.440182 -238.30407)
			(xy 381.414643 -238.312474) (xy 381.361652 -238.32154) (xy 381.334772 -238.322104) (xy 381.309785 -238.321612)
			(xy 381.260426 -238.31379) (xy 381.212898 -238.298343) (xy 381.168371 -238.275653) (xy 381.127942 -238.246276)
			(xy 381.092606 -238.210937) (xy 381.063233 -238.170505) (xy 381.040546 -238.125976) (xy 381.025104 -238.078447)
			(xy 381.017286 -238.029087) (xy 381.017286 -237.979113) (xy 381.025104 -237.929753) (xy 381.040546 -237.882224)
			(xy 381.063233 -237.837695) (xy 381.092606 -237.797263) (xy 381.127942 -237.761924) (xy 381.168371 -237.732547)
			(xy 381.212898 -237.709857) (xy 381.260426 -237.69441) (xy 381.309785 -237.686588) (xy 381.334772 -237.686088)
			(xy 381.36165 -237.686674) (xy 381.414636 -237.695744) (xy 381.440182 -237.704122) (xy 381.440436 -237.704122)
			(xy 381.446161 -237.705905) (xy 381.458095 -237.707048) (xy 381.464058 -237.706408) (xy 381.475742 -237.704884)
			(xy 381.545338 -237.655608) (xy 381.55372 -237.649766) (xy 381.562609 -237.642281) (xy 381.572933 -237.621493)
			(xy 381.573532 -237.609888) (xy 381.573532 -237.439962) (xy 381.573445 -237.435551) (xy 381.571913 -237.426864)
			(xy 381.570484 -237.42269) (xy 381.562102 -237.399576) (xy 381.556768 -237.392972) (xy 381.542165 -237.374066)
			(xy 381.518201 -237.33274) (xy 381.500688 -237.288294) (xy 381.490021 -237.241729) (xy 381.486439 -237.194092)
			(xy 381.490023 -237.146456) (xy 381.500693 -237.099891) (xy 381.518208 -237.055446) (xy 381.542174 -237.014122)
			(xy 381.556768 -236.995208) (xy 381.562102 -236.988604) (xy 381.570484 -236.96549) (xy 381.571898 -236.961312)
			(xy 381.573439 -236.952628) (xy 381.573532 -236.948218) (xy 381.573532 -236.778292) (xy 381.572935 -236.766687)
			(xy 381.562604 -236.745904) (xy 381.55372 -236.738414) (xy 381.545338 -236.732572) (xy 381.485902 -236.690408)
			(xy 381.480847 -236.687025) (xy 381.469548 -236.682528) (xy 381.46355 -236.681518) (xy 381.451866 -236.679994)
			(xy 381.440182 -236.684058) (xy 381.414642 -236.69246) (xy 381.361652 -236.701523) (xy 381.334772 -236.702092)
			(xy 381.309786 -236.7016) (xy 381.260428 -236.693778) (xy 381.212902 -236.678332) (xy 381.168377 -236.655642)
			(xy 381.12795 -236.626267) (xy 381.092615 -236.590929) (xy 381.063243 -236.550499) (xy 381.040557 -236.505972)
			(xy 381.025115 -236.458444) (xy 381.017298 -236.409087) (xy 381.017298 -236.359113) (xy 381.025115 -236.309756)
			(xy 381.040557 -236.262228) (xy 381.063243 -236.217701) (xy 381.092615 -236.177271) (xy 381.12795 -236.141933)
			(xy 381.168377 -236.112558) (xy 381.212902 -236.089868) (xy 381.260428 -236.074422) (xy 381.309786 -236.0666)
			(xy 381.334772 -236.066076) (xy 381.36165 -236.066662) (xy 381.414637 -236.075731) (xy 381.440182 -236.08411)
			(xy 381.440436 -236.08411) (xy 381.446161 -236.085893) (xy 381.458095 -236.087036) (xy 381.464058 -236.086396)
			(xy 381.475742 -236.084872) (xy 381.545338 -236.035596) (xy 381.55372 -236.029754) (xy 381.562607 -236.022268)
			(xy 381.572926 -236.00148) (xy 381.573532 -235.989876) (xy 381.573532 -235.81995) (xy 381.573444 -235.815539)
			(xy 381.57191 -235.806853) (xy 381.570484 -235.802678) (xy 381.562102 -235.779564) (xy 381.556768 -235.77296)
			(xy 381.542166 -235.754054) (xy 381.518203 -235.712728) (xy 381.500692 -235.668283) (xy 381.490027 -235.621719)
			(xy 381.486446 -235.574083) (xy 381.490032 -235.526447) (xy 381.500703 -235.479884) (xy 381.518218 -235.435441)
			(xy 381.542185 -235.394118) (xy 381.556768 -235.375196) (xy 381.562102 -235.368592) (xy 381.570484 -235.345478)
			(xy 381.571897 -235.3413) (xy 381.573436 -235.332615) (xy 381.573532 -235.328206) (xy 381.573532 -235.15828)
			(xy 381.572932 -235.146677) (xy 381.562599 -235.125897) (xy 381.55372 -235.118402) (xy 381.545338 -235.11256)
			(xy 381.485902 -235.070396) (xy 381.480848 -235.067008) (xy 381.469551 -235.062503) (xy 381.46355 -235.061506)
			(xy 381.451866 -235.059982) (xy 381.440182 -235.064046) (xy 381.414643 -235.072448) (xy 381.361652 -235.081512)
			(xy 381.334772 -235.08208) (xy 381.309786 -235.081588) (xy 381.260431 -235.073767) (xy 381.212907 -235.058321)
			(xy 381.168384 -235.035632) (xy 381.127958 -235.006258) (xy 381.092624 -234.970921) (xy 381.063253 -234.930493)
			(xy 381.040568 -234.885967) (xy 381.025127 -234.838442) (xy 381.01731 -234.789086) (xy 381.01731 -234.739114)
			(xy 381.025127 -234.689758) (xy 381.040568 -234.642233) (xy 381.063253 -234.597707) (xy 381.092624 -234.557279)
			(xy 381.127958 -234.521942) (xy 381.168384 -234.492568) (xy 381.212907 -234.469879) (xy 381.260431 -234.454433)
			(xy 381.309786 -234.446612) (xy 381.334772 -234.446064) (xy 381.36165 -234.44665) (xy 381.414637 -234.455719)
			(xy 381.440182 -234.464098) (xy 381.440436 -234.464098) (xy 381.446161 -234.465882) (xy 381.458095 -234.467025)
			(xy 381.464058 -234.466384) (xy 381.475742 -234.46486) (xy 381.545338 -234.415584) (xy 381.55372 -234.409742)
			(xy 381.562605 -234.402255) (xy 381.572919 -234.381468) (xy 381.573532 -234.369864) (xy 381.573532 -234.199938)
			(xy 381.573443 -234.195528) (xy 381.571907 -234.186842) (xy 381.570484 -234.182666) (xy 381.562102 -234.159552)
			(xy 381.556768 -234.152948) (xy 381.542167 -234.134042) (xy 381.518206 -234.092716) (xy 381.500697 -234.048272)
			(xy 381.490033 -234.001708) (xy 381.486454 -233.954073) (xy 381.490041 -233.906439) (xy 381.500713 -233.859877)
			(xy 381.518229 -233.815436) (xy 381.542197 -233.774115) (xy 381.556768 -233.755184) (xy 381.562102 -233.74858)
			(xy 381.570484 -233.725466) (xy 381.571896 -233.721288) (xy 381.573432 -233.712603) (xy 381.573532 -233.708194)
			(xy 381.573532 -233.538268) (xy 381.57293 -233.526666) (xy 381.562594 -233.505891) (xy 381.55372 -233.49839)
			(xy 381.545338 -233.492548) (xy 381.485902 -233.450384) (xy 381.480848 -233.446997) (xy 381.469551 -233.442493)
			(xy 381.46355 -233.441494) (xy 381.451866 -233.43997) (xy 381.440182 -233.444034) (xy 381.414643 -233.452436)
			(xy 381.361652 -233.461501) (xy 381.334772 -233.462068) (xy 381.309787 -233.461576) (xy 381.260434 -233.453755)
			(xy 381.212911 -233.43831) (xy 381.16839 -233.415622) (xy 381.127965 -233.386248) (xy 381.092633 -233.350913)
			(xy 381.063264 -233.310486) (xy 381.040579 -233.265963) (xy 381.025139 -233.218439) (xy 381.017322 -233.169085)
			(xy 381.017322 -233.119115) (xy 381.025139 -233.069761) (xy 381.040579 -233.022237) (xy 381.063264 -232.977714)
			(xy 381.092633 -232.937287) (xy 381.127965 -232.901952) (xy 381.16839 -232.872578) (xy 381.212911 -232.84989)
			(xy 381.260434 -232.834445) (xy 381.309787 -232.826624) (xy 381.334772 -232.826052) (xy 381.36165 -232.826638)
			(xy 381.414637 -232.835706) (xy 381.440182 -232.844086) (xy 381.440436 -232.844086) (xy 381.446161 -232.84587)
			(xy 381.458095 -232.847014) (xy 381.464058 -232.846372) (xy 381.475742 -232.844848) (xy 381.545338 -232.795572)
			(xy 381.55372 -232.78973) (xy 381.562602 -232.782242) (xy 381.572912 -232.761455) (xy 381.573532 -232.749852)
			(xy 381.573532 -232.579926) (xy 381.573442 -232.575516) (xy 381.571904 -232.566831) (xy 381.570484 -232.562654)
			(xy 381.562102 -232.53954) (xy 381.556768 -232.532936) (xy 381.542167 -232.51403) (xy 381.518209 -232.472705)
			(xy 381.500701 -232.428261) (xy 381.490039 -232.381698) (xy 381.486461 -232.334064) (xy 381.49005 -232.286431)
			(xy 381.500723 -232.239871) (xy 381.51824 -232.195431) (xy 381.542208 -232.154111) (xy 381.556768 -232.135172)
			(xy 381.562102 -232.128568) (xy 381.570484 -232.105454) (xy 381.571895 -232.101275) (xy 381.573429 -232.092591)
			(xy 381.573532 -232.088182) (xy 381.573532 -231.918256) (xy 381.572927 -231.906655) (xy 381.562588 -231.885884)
			(xy 381.55372 -231.878378) (xy 381.545338 -231.872536) (xy 381.485902 -231.830372) (xy 381.480848 -231.826986)
			(xy 381.46955 -231.822483) (xy 381.46355 -231.821482) (xy 381.451866 -231.819958) (xy 381.440182 -231.824022)
			(xy 381.414643 -231.832425) (xy 381.361652 -231.841489) (xy 381.334772 -231.842056) (xy 381.30978 -231.841563)
			(xy 381.260413 -231.83374) (xy 381.212878 -231.818291) (xy 381.168344 -231.795597) (xy 381.127908 -231.766215)
			(xy 381.092566 -231.73087) (xy 381.063188 -231.690432) (xy 381.040498 -231.645896) (xy 381.025053 -231.598359)
			(xy 381.017234 -231.548992) (xy 381.017234 -231.499008) (xy 381.025053 -231.449641) (xy 381.040498 -231.402104)
			(xy 381.063188 -231.357568) (xy 381.092566 -231.31713) (xy 381.127908 -231.281785) (xy 381.168344 -231.252403)
			(xy 381.212878 -231.229709) (xy 381.260413 -231.21426) (xy 381.30978 -231.206437) (xy 381.334772 -231.20604)
			(xy 381.36165 -231.206626) (xy 381.414637 -231.215694) (xy 381.440182 -231.224074) (xy 381.440436 -231.224074)
			(xy 381.446161 -231.225858) (xy 381.458095 -231.227002) (xy 381.464058 -231.22636) (xy 381.475742 -231.224836)
			(xy 381.545338 -231.17556) (xy 381.55372 -231.169718) (xy 381.562617 -231.162236) (xy 381.572963 -231.141449)
			(xy 381.573532 -231.12984) (xy 381.573532 -230.960168) (xy 381.573445 -230.955757) (xy 381.571914 -230.947069)
			(xy 381.570484 -230.942896) (xy 381.562102 -230.919782) (xy 381.556768 -230.913178) (xy 381.540394 -230.891859)
			(xy 381.5143 -230.844867) (xy 381.496481 -230.794157) (xy 381.487442 -230.741171) (xy 381.486918 -230.714296)
			(xy 381.486918 -230.714042) (xy 381.48748 -230.687125) (xy 381.496544 -230.634059) (xy 381.514419 -230.583279)
			(xy 381.540595 -230.536237) (xy 381.557022 -230.514906) (xy 381.562356 -230.508556) (xy 381.570484 -230.485696)
			(xy 381.571899 -230.481518) (xy 381.57344 -230.472834) (xy 381.573532 -230.468424) (xy 381.573532 -230.298244)
			(xy 381.572946 -230.286634) (xy 381.562628 -230.265833) (xy 381.55372 -230.258366) (xy 381.545338 -230.252524)
			(xy 381.485902 -230.21036) (xy 381.480848 -230.206974) (xy 381.46955 -230.202473) (xy 381.46355 -230.20147)
			(xy 381.451866 -230.199946) (xy 381.440182 -230.20401) (xy 381.414643 -230.212413) (xy 381.361652 -230.221478)
			(xy 381.334772 -230.222044) (xy 381.309781 -230.221551) (xy 381.260416 -230.213729) (xy 381.212882 -230.19828)
			(xy 381.16835 -230.175587) (xy 381.127916 -230.146206) (xy 381.092576 -230.110863) (xy 381.063199 -230.070426)
			(xy 381.040509 -230.025892) (xy 381.025065 -229.978357) (xy 381.017246 -229.928991) (xy 381.017246 -229.879009)
			(xy 381.025065 -229.829643) (xy 381.040509 -229.782108) (xy 381.063199 -229.737574) (xy 381.092576 -229.697137)
			(xy 381.127916 -229.661794) (xy 381.16835 -229.632413) (xy 381.212882 -229.60972) (xy 381.260416 -229.594271)
			(xy 381.309781 -229.586449) (xy 381.334772 -229.586028) (xy 381.36165 -229.586614) (xy 381.414637 -229.595682)
			(xy 381.440182 -229.604062) (xy 381.440436 -229.604062) (xy 381.446161 -229.605847) (xy 381.458095 -229.606991)
			(xy 381.464058 -229.606348) (xy 381.475742 -229.604824) (xy 381.545338 -229.555548) (xy 381.55372 -229.549706)
			(xy 381.562615 -229.542223) (xy 381.572956 -229.521436) (xy 381.573532 -229.509828) (xy 381.573532 -229.340156)
			(xy 381.573444 -229.335745) (xy 381.571911 -229.327058) (xy 381.570484 -229.322884) (xy 381.562102 -229.29977)
			(xy 381.556768 -229.293166) (xy 381.542165 -229.27426) (xy 381.518202 -229.232934) (xy 381.50069 -229.188489)
			(xy 381.490024 -229.141924) (xy 381.486443 -229.094287) (xy 381.490028 -229.046651) (xy 381.500698 -229.000088)
			(xy 381.518213 -228.955644) (xy 381.542179 -228.91432) (xy 381.556768 -228.895402) (xy 381.562102 -228.888798)
			(xy 381.570484 -228.865684) (xy 381.571898 -228.861506) (xy 381.573437 -228.852822) (xy 381.573532 -228.848412)
			(xy 381.573532 -228.678486) (xy 381.572934 -228.666882) (xy 381.562602 -228.646101) (xy 381.55372 -228.638608)
			(xy 381.545338 -228.632766) (xy 381.485902 -228.590602) (xy 381.480846 -228.587219) (xy 381.469548 -228.582723)
			(xy 381.46355 -228.581712) (xy 381.451866 -228.580188) (xy 381.440182 -228.584252) (xy 381.414643 -228.592654)
			(xy 381.361652 -228.601718) (xy 381.334772 -228.602286) (xy 381.309786 -228.601794) (xy 381.26043 -228.593972)
			(xy 381.212905 -228.578527) (xy 381.16838 -228.555837) (xy 381.127954 -228.526462) (xy 381.09262 -228.491125)
			(xy 381.063248 -228.450696) (xy 381.040562 -228.40617) (xy 381.025121 -228.358643) (xy 381.017304 -228.309286)
			(xy 381.017304 -228.259314) (xy 381.025121 -228.209957) (xy 381.040562 -228.16243) (xy 381.063248 -228.117904)
			(xy 381.09262 -228.077475) (xy 381.127954 -228.042138) (xy 381.16838 -228.012763) (xy 381.212905 -227.990073)
			(xy 381.26043 -227.974628) (xy 381.309786 -227.966806) (xy 381.334772 -227.96627) (xy 381.36165 -227.966856)
			(xy 381.414637 -227.975925) (xy 381.440182 -227.984304) (xy 381.440436 -227.984304) (xy 381.446161 -227.986087)
			(xy 381.458095 -227.987231) (xy 381.464058 -227.98659) (xy 381.475742 -227.985066) (xy 381.545338 -227.93579)
			(xy 381.55372 -227.929948) (xy 381.562606 -227.922462) (xy 381.572922 -227.901674) (xy 381.573532 -227.89007)
			(xy 381.573532 -227.720144) (xy 381.573443 -227.715734) (xy 381.571908 -227.707047) (xy 381.570484 -227.702872)
			(xy 381.562102 -227.679758) (xy 381.556768 -227.673154) (xy 381.543052 -227.654866) (xy 381.543052 -227.654358)
			(xy 381.540258 -227.650548) (xy 381.523494 -227.622608) (xy 381.510032 -227.593652) (xy 381.506222 -227.584)
			(xy 381.352806 -227.430584) (xy 381.345708 -227.42411) (xy 381.328047 -227.416592) (xy 381.308857 -227.416185)
			(xy 381.29972 -227.419154) (xy 381.257048 -227.435156) (xy 381.212852 -227.45192) (xy 381.206673 -227.454737)
			(xy 381.195982 -227.463103) (xy 381.19177 -227.46843) (xy 381.187706 -227.474018) (xy 381.182626 -227.487734)
			(xy 381.182118 -227.495354) (xy 381.179814 -227.521849) (xy 381.1675 -227.573583) (xy 381.146752 -227.622548)
			(xy 381.118149 -227.66738) (xy 381.082487 -227.70683) (xy 381.04076 -227.739798) (xy 380.994131 -227.765366)
			(xy 380.943898 -227.782822) (xy 380.891462 -227.79168) (xy 380.864872 -227.79228) (xy 380.840025 -227.791799)
			(xy 380.790935 -227.784063) (xy 380.743647 -227.768786) (xy 380.699311 -227.746337) (xy 380.659007 -227.717265)
			(xy 380.623716 -227.682277) (xy 380.594298 -227.642225) (xy 380.571469 -227.598084) (xy 380.555785 -227.550929)
			(xy 380.547627 -227.501908) (xy 380.546864 -227.477066) (xy 380.546864 -227.473764) (xy 380.547184 -227.453929)
			(xy 380.552152 -227.414571) (xy 380.55677 -227.395278) (xy 380.557532 -227.392738) (xy 380.559818 -227.383594)
			(xy 380.557532 -227.372926) (xy 380.556194 -227.367284) (xy 380.551324 -227.356763) (xy 380.54788 -227.352098)
			(xy 380.500382 -227.290884) (xy 380.49835 -227.288344) (xy 380.490874 -227.280269) (xy 380.470984 -227.270909)
			(xy 380.459996 -227.27031) (xy 380.329694 -227.27031) (xy 380.318695 -227.270871) (xy 380.29879 -227.280232)
			(xy 380.29134 -227.288344) (xy 380.289308 -227.290884) (xy 380.24181 -227.352098) (xy 380.238371 -227.356767)
			(xy 380.233492 -227.367283) (xy 380.232158 -227.372926) (xy 380.229872 -227.383594) (xy 380.232158 -227.392738)
			(xy 380.23292 -227.395278) (xy 380.236855 -227.41153) (xy 380.241694 -227.444619) (xy 380.242572 -227.461318)
			(xy 380.242826 -227.469192) (xy 380.242826 -227.477066) (xy 380.242128 -227.501911) (xy 380.233965 -227.550938)
			(xy 380.218275 -227.598098) (xy 380.195439 -227.642242) (xy 380.166014 -227.682297) (xy 380.130716 -227.717286)
			(xy 380.090404 -227.746358) (xy 380.046061 -227.768806) (xy 379.998765 -227.784081) (xy 379.949669 -227.791813)
			(xy 379.899967 -227.791813) (xy 379.850871 -227.784081) (xy 379.803575 -227.768806) (xy 379.759232 -227.746358)
			(xy 379.71892 -227.717286) (xy 379.683622 -227.682297) (xy 379.654197 -227.642242) (xy 379.631361 -227.598098)
			(xy 379.615671 -227.550938) (xy 379.607508 -227.501911) (xy 379.60681 -227.477066) (xy 379.60681 -227.473764)
			(xy 379.60713 -227.453929) (xy 379.612097 -227.41457) (xy 379.616716 -227.395278) (xy 379.617478 -227.392738)
			(xy 379.619764 -227.383594) (xy 379.617478 -227.372926) (xy 379.616138 -227.367285) (xy 379.611264 -227.356767)
			(xy 379.607826 -227.352098) (xy 379.560328 -227.290884) (xy 379.558296 -227.288344) (xy 379.550816 -227.280278)
			(xy 379.530926 -227.270939) (xy 379.519942 -227.27031) (xy 379.38964 -227.27031) (xy 379.378636 -227.270861)
			(xy 379.358717 -227.280211) (xy 379.351286 -227.288344) (xy 379.349254 -227.290884) (xy 379.301756 -227.352098)
			(xy 379.298315 -227.356766) (xy 379.293431 -227.367281) (xy 379.292104 -227.372926) (xy 379.289818 -227.383594)
			(xy 379.292104 -227.392738) (xy 379.292866 -227.395278) (xy 379.297283 -227.413574) (xy 379.302248 -227.450885)
			(xy 379.302772 -227.4697) (xy 379.302772 -227.477066) (xy 379.302074 -227.501911) (xy 379.293911 -227.550938)
			(xy 379.278221 -227.598098) (xy 379.255385 -227.642242) (xy 379.22596 -227.682297) (xy 379.190662 -227.717286)
			(xy 379.15035 -227.746358) (xy 379.106007 -227.768806) (xy 379.058711 -227.784081) (xy 379.009615 -227.791813)
			(xy 378.959913 -227.791813) (xy 378.910817 -227.784081) (xy 378.863521 -227.768806) (xy 378.819178 -227.746358)
			(xy 378.778866 -227.717286) (xy 378.743568 -227.682297) (xy 378.714143 -227.642242) (xy 378.691307 -227.598098)
			(xy 378.675617 -227.550938) (xy 378.667454 -227.501911) (xy 378.666756 -227.477066) (xy 378.666756 -227.473764)
			(xy 378.667076 -227.453929) (xy 378.672043 -227.414571) (xy 378.676662 -227.395278) (xy 378.677424 -227.392738)
			(xy 378.67971 -227.383594) (xy 378.677424 -227.372926) (xy 378.676086 -227.367284) (xy 378.671215 -227.356764)
			(xy 378.667772 -227.352098) (xy 378.620274 -227.290884) (xy 378.618242 -227.288344) (xy 378.610765 -227.28027)
			(xy 378.590875 -227.270913) (xy 378.579888 -227.27031) (xy 377.509786 -227.27031) (xy 377.498788 -227.270872)
			(xy 377.478885 -227.280236) (xy 377.471432 -227.288344) (xy 377.4694 -227.290884) (xy 377.421902 -227.352098)
			(xy 377.418464 -227.356767) (xy 377.413585 -227.367284) (xy 377.41225 -227.372926) (xy 377.409964 -227.383594)
			(xy 377.41225 -227.392738) (xy 377.413012 -227.395278) (xy 377.41743 -227.413574) (xy 377.422395 -227.450885)
			(xy 377.422918 -227.4697) (xy 377.422918 -227.477066) (xy 377.42222 -227.501911) (xy 377.414057 -227.550938)
			(xy 377.398367 -227.598098) (xy 377.375531 -227.642242) (xy 377.346106 -227.682297) (xy 377.310808 -227.717286)
			(xy 377.270496 -227.746358) (xy 377.226153 -227.768806) (xy 377.178857 -227.784081) (xy 377.129761 -227.791813)
			(xy 377.080059 -227.791813) (xy 377.030963 -227.784081) (xy 376.983667 -227.768806) (xy 376.939324 -227.746358)
			(xy 376.899012 -227.717286) (xy 376.863714 -227.682297) (xy 376.834289 -227.642242) (xy 376.811453 -227.598098)
			(xy 376.795763 -227.550938) (xy 376.7876 -227.501911) (xy 376.786902 -227.477066) (xy 376.786902 -227.473764)
			(xy 376.787222 -227.453929) (xy 376.792189 -227.41457) (xy 376.796808 -227.395278) (xy 376.79757 -227.392738)
			(xy 376.799856 -227.383594) (xy 376.79757 -227.372926) (xy 376.796233 -227.367283) (xy 376.791365 -227.356761)
			(xy 376.787918 -227.352098) (xy 376.74042 -227.290884) (xy 376.738388 -227.288344) (xy 376.730908 -227.280279)
			(xy 376.711017 -227.270943) (xy 376.700034 -227.27031) (xy 376.569732 -227.27031) (xy 376.558729 -227.270863)
			(xy 376.538812 -227.280215) (xy 376.531378 -227.288344) (xy 376.529346 -227.290884) (xy 376.481848 -227.352098)
			(xy 376.478407 -227.356766) (xy 376.473524 -227.367282) (xy 376.472196 -227.372926) (xy 376.46991 -227.383594)
			(xy 376.472196 -227.392738) (xy 376.472958 -227.395278) (xy 376.477375 -227.413574) (xy 376.48234 -227.450885)
			(xy 376.482864 -227.4697) (xy 376.482864 -227.477066) (xy 376.482168 -227.501912) (xy 376.474008 -227.550939)
			(xy 376.45832 -227.598099) (xy 376.435485 -227.642245) (xy 376.406059 -227.682299) (xy 376.37076 -227.717288)
			(xy 376.330447 -227.746358) (xy 376.286102 -227.768803) (xy 376.238804 -227.784074) (xy 376.189707 -227.7918)
			(xy 376.164856 -227.79228) (xy 376.139111 -227.79178) (xy 376.088294 -227.783479) (xy 376.039478 -227.767101)
			(xy 375.993937 -227.743075) (xy 375.952861 -227.712026) (xy 375.917322 -227.674767) (xy 375.888249 -227.63227)
			(xy 375.866401 -227.585645) (xy 375.852348 -227.53611) (xy 375.84888 -227.510594) (xy 375.84888 -227.51034)
			(xy 375.848118 -227.504498) (xy 375.848118 -227.503736) (xy 375.846848 -227.4951) (xy 375.838466 -227.484432)
			(xy 375.834284 -227.479552) (xy 375.823998 -227.471852) (xy 375.818146 -227.469192) (xy 375.729246 -227.43795)
			(xy 375.720416 -227.43555) (xy 375.702161 -227.436547) (xy 375.685454 -227.443971) (xy 375.6787 -227.450142)
			(xy 375.506234 -227.622608) (xy 375.502678 -227.628958) (xy 375.487804 -227.654369) (xy 375.450199 -227.69967)
			(xy 375.404903 -227.737281) (xy 375.379488 -227.752148) (xy 375.373138 -227.755704) (xy 375.04751 -228.081332)
			(xy 375.042086 -228.087201) (xy 375.034839 -228.101433) (xy 375.033286 -228.109272) (xy 375.030746 -228.12502)
			(xy 375.032778 -228.129084) (xy 375.038366 -228.140006) (xy 375.049332 -228.162586) (xy 375.064784 -228.210344)
			(xy 375.072516 -228.259941) (xy 375.072898 -228.284278) (xy 375.378467 -228.284278) (xy 375.382562 -228.23355)
			(xy 375.394741 -228.184136) (xy 375.414689 -228.137316) (xy 375.44189 -228.094302) (xy 375.475638 -228.056208)
			(xy 375.51506 -228.024021) (xy 375.559134 -227.998575) (xy 375.60672 -227.980528) (xy 375.656584 -227.970348)
			(xy 375.707436 -227.968299) (xy 375.757957 -227.974433) (xy 375.806841 -227.988593) (xy 375.85282 -228.01041)
			(xy 375.894704 -228.03932) (xy 375.931408 -228.074575) (xy 375.961981 -228.115261) (xy 375.985632 -228.160324)
			(xy 376.001748 -228.208598) (xy 376.009912 -228.258832) (xy 376.010424 -228.284278) (xy 376.009921 -228.309267)
			(xy 376.317238 -228.309267) (xy 376.317238 -228.259289) (xy 376.325057 -228.209926) (xy 376.340501 -228.162394)
			(xy 376.363191 -228.117862) (xy 376.392567 -228.077429) (xy 376.427907 -228.042089) (xy 376.46834 -228.012713)
			(xy 376.512872 -227.990023) (xy 376.560404 -227.974579) (xy 376.609767 -227.96676) (xy 376.659745 -227.96676)
			(xy 376.709108 -227.974579) (xy 376.75664 -227.990023) (xy 376.801172 -228.012713) (xy 376.841605 -228.042089)
			(xy 376.876945 -228.077429) (xy 376.906321 -228.117862) (xy 376.929011 -228.162394) (xy 376.944455 -228.209926)
			(xy 376.952274 -228.259289) (xy 376.952764 -228.284278) (xy 377.258575 -228.284278) (xy 377.26267 -228.23355)
			(xy 377.274849 -228.184136) (xy 377.294797 -228.137316) (xy 377.321998 -228.094302) (xy 377.355746 -228.056208)
			(xy 377.395168 -228.024021) (xy 377.439242 -227.998575) (xy 377.486828 -227.980528) (xy 377.536692 -227.970348)
			(xy 377.587544 -227.968299) (xy 377.638065 -227.974433) (xy 377.686949 -227.988593) (xy 377.732928 -228.01041)
			(xy 377.774812 -228.03932) (xy 377.811516 -228.074575) (xy 377.842089 -228.115261) (xy 377.86574 -228.160324)
			(xy 377.881856 -228.208598) (xy 377.89002 -228.258832) (xy 377.890532 -228.284278) (xy 377.890029 -228.309267)
			(xy 378.197346 -228.309267) (xy 378.197346 -228.259289) (xy 378.205165 -228.209926) (xy 378.220609 -228.162394)
			(xy 378.243299 -228.117862) (xy 378.272675 -228.077429) (xy 378.308015 -228.042089) (xy 378.348448 -228.012713)
			(xy 378.39298 -227.990023) (xy 378.440512 -227.974579) (xy 378.489875 -227.96676) (xy 378.539853 -227.96676)
			(xy 378.589216 -227.974579) (xy 378.636748 -227.990023) (xy 378.68128 -228.012713) (xy 378.721713 -228.042089)
			(xy 378.757053 -228.077429) (xy 378.786429 -228.117862) (xy 378.809119 -228.162394) (xy 378.824563 -228.209926)
			(xy 378.832382 -228.259289) (xy 378.832872 -228.284278) (xy 379.138683 -228.284278) (xy 379.142778 -228.23355)
			(xy 379.154957 -228.184136) (xy 379.174905 -228.137316) (xy 379.202106 -228.094302) (xy 379.235854 -228.056208)
			(xy 379.275276 -228.024021) (xy 379.31935 -227.998575) (xy 379.366936 -227.980528) (xy 379.4168 -227.970348)
			(xy 379.467652 -227.968299) (xy 379.518173 -227.974433) (xy 379.567057 -227.988593) (xy 379.613036 -228.01041)
			(xy 379.65492 -228.03932) (xy 379.691624 -228.074575) (xy 379.722197 -228.115261) (xy 379.745848 -228.160324)
			(xy 379.761964 -228.208598) (xy 379.770128 -228.258832) (xy 379.77064 -228.284278) (xy 380.078483 -228.284278)
			(xy 380.082578 -228.23355) (xy 380.094757 -228.184136) (xy 380.114705 -228.137316) (xy 380.141906 -228.094302)
			(xy 380.175654 -228.056208) (xy 380.215076 -228.024021) (xy 380.25915 -227.998575) (xy 380.306736 -227.980528)
			(xy 380.3566 -227.970348) (xy 380.407452 -227.968299) (xy 380.457973 -227.974433) (xy 380.506857 -227.988593)
			(xy 380.552836 -228.01041) (xy 380.59472 -228.03932) (xy 380.631424 -228.074575) (xy 380.661997 -228.115261)
			(xy 380.685648 -228.160324) (xy 380.701764 -228.208598) (xy 380.709928 -228.258832) (xy 380.71044 -228.284278)
			(xy 380.709928 -228.309724) (xy 380.701764 -228.359958) (xy 380.685648 -228.408232) (xy 380.661997 -228.453295)
			(xy 380.631424 -228.493981) (xy 380.59472 -228.529236) (xy 380.552836 -228.558146) (xy 380.506857 -228.579963)
			(xy 380.457973 -228.594123) (xy 380.407452 -228.600257) (xy 380.3566 -228.598208) (xy 380.306736 -228.588028)
			(xy 380.25915 -228.569981) (xy 380.215076 -228.544535) (xy 380.175654 -228.512348) (xy 380.141906 -228.474254)
			(xy 380.114705 -228.43124) (xy 380.094757 -228.38442) (xy 380.082578 -228.335006) (xy 380.078483 -228.284278)
			(xy 379.77064 -228.284278) (xy 379.770128 -228.309724) (xy 379.761964 -228.359958) (xy 379.745848 -228.408232)
			(xy 379.722197 -228.453295) (xy 379.691624 -228.493981) (xy 379.65492 -228.529236) (xy 379.613036 -228.558146)
			(xy 379.567057 -228.579963) (xy 379.518173 -228.594123) (xy 379.467652 -228.600257) (xy 379.4168 -228.598208)
			(xy 379.366936 -228.588028) (xy 379.31935 -228.569981) (xy 379.275276 -228.544535) (xy 379.235854 -228.512348)
			(xy 379.202106 -228.474254) (xy 379.174905 -228.43124) (xy 379.154957 -228.38442) (xy 379.142778 -228.335006)
			(xy 379.138683 -228.284278) (xy 378.832872 -228.284278) (xy 378.832382 -228.309267) (xy 378.824563 -228.35863)
			(xy 378.809119 -228.406162) (xy 378.786429 -228.450694) (xy 378.757053 -228.491127) (xy 378.721713 -228.526467)
			(xy 378.68128 -228.555843) (xy 378.636748 -228.578533) (xy 378.589216 -228.593977) (xy 378.539853 -228.601796)
			(xy 378.489875 -228.601796) (xy 378.440512 -228.593977) (xy 378.39298 -228.578533) (xy 378.348448 -228.555843)
			(xy 378.308015 -228.526467) (xy 378.272675 -228.491127) (xy 378.243299 -228.450694) (xy 378.220609 -228.406162)
			(xy 378.205165 -228.35863) (xy 378.197346 -228.309267) (xy 377.890029 -228.309267) (xy 377.89002 -228.309724)
			(xy 377.881856 -228.359958) (xy 377.86574 -228.408232) (xy 377.842089 -228.453295) (xy 377.811516 -228.493981)
			(xy 377.774812 -228.529236) (xy 377.732928 -228.558146) (xy 377.686949 -228.579963) (xy 377.638065 -228.594123)
			(xy 377.587544 -228.600257) (xy 377.536692 -228.598208) (xy 377.486828 -228.588028) (xy 377.439242 -228.569981)
			(xy 377.395168 -228.544535) (xy 377.355746 -228.512348) (xy 377.321998 -228.474254) (xy 377.294797 -228.43124)
			(xy 377.274849 -228.38442) (xy 377.26267 -228.335006) (xy 377.258575 -228.284278) (xy 376.952764 -228.284278)
			(xy 376.952274 -228.309267) (xy 376.944455 -228.35863) (xy 376.929011 -228.406162) (xy 376.906321 -228.450694)
			(xy 376.876945 -228.491127) (xy 376.841605 -228.526467) (xy 376.801172 -228.555843) (xy 376.75664 -228.578533)
			(xy 376.709108 -228.593977) (xy 376.659745 -228.601796) (xy 376.609767 -228.601796) (xy 376.560404 -228.593977)
			(xy 376.512872 -228.578533) (xy 376.46834 -228.555843) (xy 376.427907 -228.526467) (xy 376.392567 -228.491127)
			(xy 376.363191 -228.450694) (xy 376.340501 -228.406162) (xy 376.325057 -228.35863) (xy 376.317238 -228.309267)
			(xy 376.009921 -228.309267) (xy 376.009912 -228.309724) (xy 376.001748 -228.359958) (xy 375.985632 -228.408232)
			(xy 375.961981 -228.453295) (xy 375.931408 -228.493981) (xy 375.894704 -228.529236) (xy 375.85282 -228.558146)
			(xy 375.806841 -228.579963) (xy 375.757957 -228.594123) (xy 375.707436 -228.600257) (xy 375.656584 -228.598208)
			(xy 375.60672 -228.588028) (xy 375.559134 -228.569981) (xy 375.51506 -228.544535) (xy 375.475638 -228.512348)
			(xy 375.44189 -228.474254) (xy 375.414689 -228.43124) (xy 375.394741 -228.38442) (xy 375.382562 -228.335006)
			(xy 375.378467 -228.284278) (xy 375.072898 -228.284278) (xy 375.07291 -228.28504) (xy 375.07291 -228.289104)
			(xy 375.071991 -228.315181) (xy 375.062695 -228.366521) (xy 375.045142 -228.415655) (xy 375.019803 -228.461264)
			(xy 374.987357 -228.502123) (xy 374.948675 -228.537137) (xy 374.904796 -228.565366) (xy 374.856896 -228.586051)
			(xy 374.806263 -228.598639) (xy 374.780302 -228.60127) (xy 374.771666 -228.602032) (xy 374.74779 -228.6127)
			(xy 374.743668 -228.614637) (xy 374.736132 -228.61975) (xy 374.732804 -228.62286) (xy 374.715278 -228.640386)
			(xy 374.710434 -228.646423) (xy 374.704366 -228.660653) (xy 374.70334 -228.668326) (xy 374.70334 -228.676454)
			(xy 374.703086 -228.677724) (xy 374.703086 -229.094284) (xy 375.848621 -229.094284) (xy 375.852716 -229.043556)
			(xy 375.864895 -228.994142) (xy 375.884843 -228.947322) (xy 375.912044 -228.904308) (xy 375.945792 -228.866214)
			(xy 375.985214 -228.834027) (xy 376.029288 -228.808581) (xy 376.076874 -228.790534) (xy 376.126738 -228.780354)
			(xy 376.17759 -228.778305) (xy 376.228111 -228.784439) (xy 376.276995 -228.798599) (xy 376.322974 -228.820416)
			(xy 376.364858 -228.849326) (xy 376.401562 -228.884581) (xy 376.432135 -228.925267) (xy 376.455786 -228.97033)
			(xy 376.471902 -229.018604) (xy 376.480066 -229.068838) (xy 376.480578 -229.094284) (xy 376.788675 -229.094284)
			(xy 376.79277 -229.043556) (xy 376.804949 -228.994142) (xy 376.824897 -228.947322) (xy 376.852098 -228.904308)
			(xy 376.885846 -228.866214) (xy 376.925268 -228.834027) (xy 376.969342 -228.808581) (xy 377.016928 -228.790534)
			(xy 377.066792 -228.780354) (xy 377.117644 -228.778305) (xy 377.168165 -228.784439) (xy 377.217049 -228.798599)
			(xy 377.263028 -228.820416) (xy 377.304912 -228.849326) (xy 377.341616 -228.884581) (xy 377.372189 -228.925267)
			(xy 377.39584 -228.97033) (xy 377.411956 -229.018604) (xy 377.42012 -229.068838) (xy 377.420632 -229.094284)
			(xy 377.420129 -229.119273) (xy 377.727192 -229.119273) (xy 377.727192 -229.069295) (xy 377.735011 -229.019932)
			(xy 377.750455 -228.9724) (xy 377.773145 -228.927868) (xy 377.802521 -228.887435) (xy 377.837861 -228.852095)
			(xy 377.878294 -228.822719) (xy 377.922826 -228.800029) (xy 377.970358 -228.784585) (xy 378.019721 -228.776766)
			(xy 378.069699 -228.776766) (xy 378.119062 -228.784585) (xy 378.166594 -228.800029) (xy 378.211126 -228.822719)
			(xy 378.251559 -228.852095) (xy 378.286899 -228.887435) (xy 378.316275 -228.927868) (xy 378.338965 -228.9724)
			(xy 378.354409 -229.019932) (xy 378.362228 -229.069295) (xy 378.362718 -229.094284) (xy 378.668529 -229.094284)
			(xy 378.672624 -229.043556) (xy 378.684803 -228.994142) (xy 378.704751 -228.947322) (xy 378.731952 -228.904308)
			(xy 378.7657 -228.866214) (xy 378.805122 -228.834027) (xy 378.849196 -228.808581) (xy 378.896782 -228.790534)
			(xy 378.946646 -228.780354) (xy 378.997498 -228.778305) (xy 379.048019 -228.784439) (xy 379.096903 -228.798599)
			(xy 379.142882 -228.820416) (xy 379.184766 -228.849326) (xy 379.22147 -228.884581) (xy 379.252043 -228.925267)
			(xy 379.275694 -228.97033) (xy 379.29181 -229.018604) (xy 379.299974 -229.068838) (xy 379.300486 -229.094284)
			(xy 379.299983 -229.119273) (xy 379.6073 -229.119273) (xy 379.6073 -229.069295) (xy 379.615119 -229.019932)
			(xy 379.630563 -228.9724) (xy 379.653253 -228.927868) (xy 379.682629 -228.887435) (xy 379.717969 -228.852095)
			(xy 379.758402 -228.822719) (xy 379.802934 -228.800029) (xy 379.850466 -228.784585) (xy 379.899829 -228.776766)
			(xy 379.949807 -228.776766) (xy 379.99917 -228.784585) (xy 380.046702 -228.800029) (xy 380.091234 -228.822719)
			(xy 380.131667 -228.852095) (xy 380.167007 -228.887435) (xy 380.196383 -228.927868) (xy 380.219073 -228.9724)
			(xy 380.234517 -229.019932) (xy 380.242336 -229.069295) (xy 380.242826 -229.094284) (xy 380.548637 -229.094284)
			(xy 380.552732 -229.043556) (xy 380.564911 -228.994142) (xy 380.584859 -228.947322) (xy 380.61206 -228.904308)
			(xy 380.645808 -228.866214) (xy 380.68523 -228.834027) (xy 380.729304 -228.808581) (xy 380.77689 -228.790534)
			(xy 380.826754 -228.780354) (xy 380.877606 -228.778305) (xy 380.928127 -228.784439) (xy 380.977011 -228.798599)
			(xy 381.02299 -228.820416) (xy 381.064874 -228.849326) (xy 381.101578 -228.884581) (xy 381.132151 -228.925267)
			(xy 381.155802 -228.97033) (xy 381.171918 -229.018604) (xy 381.180082 -229.068838) (xy 381.180594 -229.094284)
			(xy 381.180082 -229.11973) (xy 381.171918 -229.169964) (xy 381.155802 -229.218238) (xy 381.132151 -229.263301)
			(xy 381.101578 -229.303987) (xy 381.064874 -229.339242) (xy 381.02299 -229.368152) (xy 380.977011 -229.389969)
			(xy 380.928127 -229.404129) (xy 380.877606 -229.410263) (xy 380.826754 -229.408214) (xy 380.77689 -229.398034)
			(xy 380.729304 -229.379987) (xy 380.68523 -229.354541) (xy 380.645808 -229.322354) (xy 380.61206 -229.28426)
			(xy 380.584859 -229.241246) (xy 380.564911 -229.194426) (xy 380.552732 -229.145012) (xy 380.548637 -229.094284)
			(xy 380.242826 -229.094284) (xy 380.242336 -229.119273) (xy 380.234517 -229.168636) (xy 380.219073 -229.216168)
			(xy 380.196383 -229.2607) (xy 380.167007 -229.301133) (xy 380.131667 -229.336473) (xy 380.091234 -229.365849)
			(xy 380.046702 -229.388539) (xy 379.99917 -229.403983) (xy 379.949807 -229.411802) (xy 379.899829 -229.411802)
			(xy 379.850466 -229.403983) (xy 379.802934 -229.388539) (xy 379.758402 -229.365849) (xy 379.717969 -229.336473)
			(xy 379.682629 -229.301133) (xy 379.653253 -229.2607) (xy 379.630563 -229.216168) (xy 379.615119 -229.168636)
			(xy 379.6073 -229.119273) (xy 379.299983 -229.119273) (xy 379.299974 -229.11973) (xy 379.29181 -229.169964)
			(xy 379.275694 -229.218238) (xy 379.252043 -229.263301) (xy 379.22147 -229.303987) (xy 379.184766 -229.339242)
			(xy 379.142882 -229.368152) (xy 379.096903 -229.389969) (xy 379.048019 -229.404129) (xy 378.997498 -229.410263)
			(xy 378.946646 -229.408214) (xy 378.896782 -229.398034) (xy 378.849196 -229.379987) (xy 378.805122 -229.354541)
			(xy 378.7657 -229.322354) (xy 378.731952 -229.28426) (xy 378.704751 -229.241246) (xy 378.684803 -229.194426)
			(xy 378.672624 -229.145012) (xy 378.668529 -229.094284) (xy 378.362718 -229.094284) (xy 378.362228 -229.119273)
			(xy 378.354409 -229.168636) (xy 378.338965 -229.216168) (xy 378.316275 -229.2607) (xy 378.286899 -229.301133)
			(xy 378.251559 -229.336473) (xy 378.211126 -229.365849) (xy 378.166594 -229.388539) (xy 378.119062 -229.403983)
			(xy 378.069699 -229.411802) (xy 378.019721 -229.411802) (xy 377.970358 -229.403983) (xy 377.922826 -229.388539)
			(xy 377.878294 -229.365849) (xy 377.837861 -229.336473) (xy 377.802521 -229.301133) (xy 377.773145 -229.2607)
			(xy 377.750455 -229.216168) (xy 377.735011 -229.168636) (xy 377.727192 -229.119273) (xy 377.420129 -229.119273)
			(xy 377.42012 -229.11973) (xy 377.411956 -229.169964) (xy 377.39584 -229.218238) (xy 377.372189 -229.263301)
			(xy 377.341616 -229.303987) (xy 377.304912 -229.339242) (xy 377.263028 -229.368152) (xy 377.217049 -229.389969)
			(xy 377.168165 -229.404129) (xy 377.117644 -229.410263) (xy 377.066792 -229.408214) (xy 377.016928 -229.398034)
			(xy 376.969342 -229.379987) (xy 376.925268 -229.354541) (xy 376.885846 -229.322354) (xy 376.852098 -229.28426)
			(xy 376.824897 -229.241246) (xy 376.804949 -229.194426) (xy 376.79277 -229.145012) (xy 376.788675 -229.094284)
			(xy 376.480578 -229.094284) (xy 376.480066 -229.11973) (xy 376.471902 -229.169964) (xy 376.455786 -229.218238)
			(xy 376.432135 -229.263301) (xy 376.401562 -229.303987) (xy 376.364858 -229.339242) (xy 376.322974 -229.368152)
			(xy 376.276995 -229.389969) (xy 376.228111 -229.404129) (xy 376.17759 -229.410263) (xy 376.126738 -229.408214)
			(xy 376.076874 -229.398034) (xy 376.029288 -229.379987) (xy 375.985214 -229.354541) (xy 375.945792 -229.322354)
			(xy 375.912044 -229.28426) (xy 375.884843 -229.241246) (xy 375.864895 -229.194426) (xy 375.852716 -229.145012)
			(xy 375.848621 -229.094284) (xy 374.703086 -229.094284) (xy 374.703086 -229.51059) (xy 374.70334 -229.51186)
			(xy 374.70334 -229.519988) (xy 374.704365 -229.527661) (xy 374.710428 -229.541896) (xy 374.715278 -229.547928)
			(xy 374.732804 -229.565454) (xy 374.736128 -229.568568) (xy 374.743666 -229.57368) (xy 374.74779 -229.575614)
			(xy 374.771666 -229.586282) (xy 374.780302 -229.587044) (xy 374.805146 -229.589525) (xy 374.853677 -229.601242)
			(xy 374.89978 -229.6204) (xy 374.942322 -229.646528) (xy 374.980259 -229.678983) (xy 375.012656 -229.716969)
			(xy 375.03872 -229.759551) (xy 375.057807 -229.805683) (xy 375.069451 -229.854231) (xy 375.073364 -229.904003)
			(xy 375.073361 -229.904036) (xy 375.378467 -229.904036) (xy 375.382562 -229.853308) (xy 375.394741 -229.803894)
			(xy 375.414689 -229.757074) (xy 375.44189 -229.71406) (xy 375.475638 -229.675966) (xy 375.51506 -229.643779)
			(xy 375.559134 -229.618333) (xy 375.60672 -229.600286) (xy 375.656584 -229.590106) (xy 375.707436 -229.588057)
			(xy 375.757957 -229.594191) (xy 375.806841 -229.608351) (xy 375.85282 -229.630168) (xy 375.894704 -229.659078)
			(xy 375.931408 -229.694333) (xy 375.961981 -229.735019) (xy 375.985632 -229.780082) (xy 376.001748 -229.828356)
			(xy 376.009912 -229.87859) (xy 376.010424 -229.904036) (xy 376.009921 -229.929025) (xy 376.317238 -229.929025)
			(xy 376.317238 -229.879047) (xy 376.325057 -229.829684) (xy 376.340501 -229.782152) (xy 376.363191 -229.73762)
			(xy 376.392567 -229.697187) (xy 376.427907 -229.661847) (xy 376.46834 -229.632471) (xy 376.512872 -229.609781)
			(xy 376.560404 -229.594337) (xy 376.609767 -229.586518) (xy 376.659745 -229.586518) (xy 376.709108 -229.594337)
			(xy 376.75664 -229.609781) (xy 376.801172 -229.632471) (xy 376.841605 -229.661847) (xy 376.876945 -229.697187)
			(xy 376.906321 -229.73762) (xy 376.929011 -229.782152) (xy 376.944455 -229.829684) (xy 376.952274 -229.879047)
			(xy 376.952764 -229.904036) (xy 377.258575 -229.904036) (xy 377.26267 -229.853308) (xy 377.274849 -229.803894)
			(xy 377.294797 -229.757074) (xy 377.321998 -229.71406) (xy 377.355746 -229.675966) (xy 377.395168 -229.643779)
			(xy 377.439242 -229.618333) (xy 377.486828 -229.600286) (xy 377.536692 -229.590106) (xy 377.587544 -229.588057)
			(xy 377.638065 -229.594191) (xy 377.686949 -229.608351) (xy 377.732928 -229.630168) (xy 377.774812 -229.659078)
			(xy 377.811516 -229.694333) (xy 377.842089 -229.735019) (xy 377.86574 -229.780082) (xy 377.881856 -229.828356)
			(xy 377.89002 -229.87859) (xy 377.890532 -229.904036) (xy 379.138683 -229.904036) (xy 379.142778 -229.853308)
			(xy 379.154957 -229.803894) (xy 379.174905 -229.757074) (xy 379.202106 -229.71406) (xy 379.235854 -229.675966)
			(xy 379.275276 -229.643779) (xy 379.31935 -229.618333) (xy 379.366936 -229.600286) (xy 379.4168 -229.590106)
			(xy 379.467652 -229.588057) (xy 379.518173 -229.594191) (xy 379.567057 -229.608351) (xy 379.613036 -229.630168)
			(xy 379.65492 -229.659078) (xy 379.691624 -229.694333) (xy 379.722197 -229.735019) (xy 379.745848 -229.780082)
			(xy 379.761964 -229.828356) (xy 379.770128 -229.87859) (xy 379.77064 -229.904036) (xy 380.078483 -229.904036)
			(xy 380.082578 -229.853308) (xy 380.094757 -229.803894) (xy 380.114705 -229.757074) (xy 380.141906 -229.71406)
			(xy 380.175654 -229.675966) (xy 380.215076 -229.643779) (xy 380.25915 -229.618333) (xy 380.306736 -229.600286)
			(xy 380.3566 -229.590106) (xy 380.407452 -229.588057) (xy 380.457973 -229.594191) (xy 380.506857 -229.608351)
			(xy 380.552836 -229.630168) (xy 380.59472 -229.659078) (xy 380.631424 -229.694333) (xy 380.661997 -229.735019)
			(xy 380.685648 -229.780082) (xy 380.701764 -229.828356) (xy 380.709928 -229.87859) (xy 380.71044 -229.904036)
			(xy 380.709928 -229.929482) (xy 380.701764 -229.979716) (xy 380.685648 -230.02799) (xy 380.661997 -230.073053)
			(xy 380.631424 -230.113739) (xy 380.59472 -230.148994) (xy 380.552836 -230.177904) (xy 380.506857 -230.199721)
			(xy 380.457973 -230.213881) (xy 380.407452 -230.220015) (xy 380.3566 -230.217966) (xy 380.306736 -230.207786)
			(xy 380.25915 -230.189739) (xy 380.215076 -230.164293) (xy 380.175654 -230.132106) (xy 380.141906 -230.094012)
			(xy 380.114705 -230.050998) (xy 380.094757 -230.004178) (xy 380.082578 -229.954764) (xy 380.078483 -229.904036)
			(xy 379.77064 -229.904036) (xy 379.770128 -229.929482) (xy 379.761964 -229.979716) (xy 379.745848 -230.02799)
			(xy 379.722197 -230.073053) (xy 379.691624 -230.113739) (xy 379.65492 -230.148994) (xy 379.613036 -230.177904)
			(xy 379.567057 -230.199721) (xy 379.518173 -230.213881) (xy 379.467652 -230.220015) (xy 379.4168 -230.217966)
			(xy 379.366936 -230.207786) (xy 379.31935 -230.189739) (xy 379.275276 -230.164293) (xy 379.235854 -230.132106)
			(xy 379.202106 -230.094012) (xy 379.174905 -230.050998) (xy 379.154957 -230.004178) (xy 379.142778 -229.954764)
			(xy 379.138683 -229.904036) (xy 377.890532 -229.904036) (xy 377.89002 -229.929482) (xy 377.881856 -229.979716)
			(xy 377.86574 -230.02799) (xy 377.842089 -230.073053) (xy 377.811516 -230.113739) (xy 377.774812 -230.148994)
			(xy 377.732928 -230.177904) (xy 377.686949 -230.199721) (xy 377.638065 -230.213881) (xy 377.587544 -230.220015)
			(xy 377.536692 -230.217966) (xy 377.486828 -230.207786) (xy 377.439242 -230.189739) (xy 377.395168 -230.164293)
			(xy 377.355746 -230.132106) (xy 377.321998 -230.094012) (xy 377.294797 -230.050998) (xy 377.274849 -230.004178)
			(xy 377.26267 -229.954764) (xy 377.258575 -229.904036) (xy 376.952764 -229.904036) (xy 376.952274 -229.929025)
			(xy 376.944455 -229.978388) (xy 376.929011 -230.02592) (xy 376.906321 -230.070452) (xy 376.876945 -230.110885)
			(xy 376.841605 -230.146225) (xy 376.801172 -230.175601) (xy 376.75664 -230.198291) (xy 376.709108 -230.213735)
			(xy 376.659745 -230.221554) (xy 376.609767 -230.221554) (xy 376.560404 -230.213735) (xy 376.512872 -230.198291)
			(xy 376.46834 -230.175601) (xy 376.427907 -230.146225) (xy 376.392567 -230.110885) (xy 376.363191 -230.070452)
			(xy 376.340501 -230.02592) (xy 376.325057 -229.978388) (xy 376.317238 -229.929025) (xy 376.009921 -229.929025)
			(xy 376.009912 -229.929482) (xy 376.001748 -229.979716) (xy 375.985632 -230.02799) (xy 375.961981 -230.073053)
			(xy 375.931408 -230.113739) (xy 375.894704 -230.148994) (xy 375.85282 -230.177904) (xy 375.806841 -230.199721)
			(xy 375.757957 -230.213881) (xy 375.707436 -230.220015) (xy 375.656584 -230.217966) (xy 375.60672 -230.207786)
			(xy 375.559134 -230.189739) (xy 375.51506 -230.164293) (xy 375.475638 -230.132106) (xy 375.44189 -230.094012)
			(xy 375.414689 -230.050998) (xy 375.394741 -230.004178) (xy 375.382562 -229.954764) (xy 375.378467 -229.904036)
			(xy 375.073361 -229.904036) (xy 375.06945 -229.953774) (xy 375.057806 -230.002323) (xy 375.038717 -230.048454)
			(xy 375.012653 -230.091036) (xy 374.980255 -230.129021) (xy 374.942318 -230.161476) (xy 374.899775 -230.187603)
			(xy 374.853671 -230.20676) (xy 374.80514 -230.218476) (xy 374.780302 -230.221028) (xy 374.771666 -230.22179)
			(xy 374.74779 -230.232458) (xy 374.74367 -230.234398) (xy 374.736138 -230.239515) (xy 374.732804 -230.242618)
			(xy 374.715278 -230.260144) (xy 374.710429 -230.26618) (xy 374.704349 -230.280408) (xy 374.70334 -230.288084)
			(xy 374.70334 -230.296212) (xy 374.703086 -230.297482) (xy 374.703086 -230.739285) (xy 374.907284 -230.739285)
			(xy 374.907284 -230.689307) (xy 374.915103 -230.639944) (xy 374.930547 -230.592412) (xy 374.953237 -230.54788)
			(xy 374.982613 -230.507447) (xy 375.017953 -230.472107) (xy 375.058386 -230.442731) (xy 375.102918 -230.420041)
			(xy 375.15045 -230.404597) (xy 375.199813 -230.396778) (xy 375.249791 -230.396778) (xy 375.299154 -230.404597)
			(xy 375.346686 -230.420041) (xy 375.391218 -230.442731) (xy 375.431651 -230.472107) (xy 375.466991 -230.507447)
			(xy 375.496367 -230.54788) (xy 375.519057 -230.592412) (xy 375.534501 -230.639944) (xy 375.54232 -230.689307)
			(xy 375.54281 -230.714296) (xy 375.848621 -230.714296) (xy 375.852716 -230.663568) (xy 375.864895 -230.614154)
			(xy 375.884843 -230.567334) (xy 375.912044 -230.52432) (xy 375.945792 -230.486226) (xy 375.985214 -230.454039)
			(xy 376.029288 -230.428593) (xy 376.076874 -230.410546) (xy 376.126738 -230.400366) (xy 376.17759 -230.398317)
			(xy 376.228111 -230.404451) (xy 376.276995 -230.418611) (xy 376.322974 -230.440428) (xy 376.364858 -230.469338)
			(xy 376.401562 -230.504593) (xy 376.432135 -230.545279) (xy 376.455786 -230.590342) (xy 376.471902 -230.638616)
			(xy 376.480066 -230.68885) (xy 376.480578 -230.714296) (xy 376.788675 -230.714296) (xy 376.79277 -230.663568)
			(xy 376.804949 -230.614154) (xy 376.824897 -230.567334) (xy 376.852098 -230.52432) (xy 376.885846 -230.486226)
			(xy 376.925268 -230.454039) (xy 376.969342 -230.428593) (xy 377.016928 -230.410546) (xy 377.066792 -230.400366)
			(xy 377.117644 -230.398317) (xy 377.168165 -230.404451) (xy 377.217049 -230.418611) (xy 377.263028 -230.440428)
			(xy 377.304912 -230.469338) (xy 377.341616 -230.504593) (xy 377.372189 -230.545279) (xy 377.39584 -230.590342)
			(xy 377.411956 -230.638616) (xy 377.42012 -230.68885) (xy 377.420632 -230.714296) (xy 377.420129 -230.739285)
			(xy 377.727192 -230.739285) (xy 377.727192 -230.689307) (xy 377.735011 -230.639944) (xy 377.750455 -230.592412)
			(xy 377.773145 -230.54788) (xy 377.802521 -230.507447) (xy 377.837861 -230.472107) (xy 377.878294 -230.442731)
			(xy 377.922826 -230.420041) (xy 377.970358 -230.404597) (xy 378.019721 -230.396778) (xy 378.069699 -230.396778)
			(xy 378.119062 -230.404597) (xy 378.166594 -230.420041) (xy 378.211126 -230.442731) (xy 378.251559 -230.472107)
			(xy 378.286899 -230.507447) (xy 378.316275 -230.54788) (xy 378.338965 -230.592412) (xy 378.354409 -230.639944)
			(xy 378.362228 -230.689307) (xy 378.362718 -230.714296) (xy 378.668529 -230.714296) (xy 378.672624 -230.663568)
			(xy 378.684803 -230.614154) (xy 378.704751 -230.567334) (xy 378.731952 -230.52432) (xy 378.7657 -230.486226)
			(xy 378.805122 -230.454039) (xy 378.849196 -230.428593) (xy 378.896782 -230.410546) (xy 378.946646 -230.400366)
			(xy 378.997498 -230.398317) (xy 379.048019 -230.404451) (xy 379.096903 -230.418611) (xy 379.142882 -230.440428)
			(xy 379.184766 -230.469338) (xy 379.22147 -230.504593) (xy 379.252043 -230.545279) (xy 379.275694 -230.590342)
			(xy 379.29181 -230.638616) (xy 379.299974 -230.68885) (xy 379.300486 -230.714296) (xy 379.299983 -230.739285)
			(xy 379.6073 -230.739285) (xy 379.6073 -230.689307) (xy 379.615119 -230.639944) (xy 379.630563 -230.592412)
			(xy 379.653253 -230.54788) (xy 379.682629 -230.507447) (xy 379.717969 -230.472107) (xy 379.758402 -230.442731)
			(xy 379.802934 -230.420041) (xy 379.850466 -230.404597) (xy 379.899829 -230.396778) (xy 379.949807 -230.396778)
			(xy 379.99917 -230.404597) (xy 380.046702 -230.420041) (xy 380.091234 -230.442731) (xy 380.131667 -230.472107)
			(xy 380.167007 -230.507447) (xy 380.196383 -230.54788) (xy 380.219073 -230.592412) (xy 380.234517 -230.639944)
			(xy 380.242336 -230.689307) (xy 380.242826 -230.714296) (xy 380.548637 -230.714296) (xy 380.552732 -230.663568)
			(xy 380.564911 -230.614154) (xy 380.584859 -230.567334) (xy 380.61206 -230.52432) (xy 380.645808 -230.486226)
			(xy 380.68523 -230.454039) (xy 380.729304 -230.428593) (xy 380.77689 -230.410546) (xy 380.826754 -230.400366)
			(xy 380.877606 -230.398317) (xy 380.928127 -230.404451) (xy 380.977011 -230.418611) (xy 381.02299 -230.440428)
			(xy 381.064874 -230.469338) (xy 381.101578 -230.504593) (xy 381.132151 -230.545279) (xy 381.155802 -230.590342)
			(xy 381.171918 -230.638616) (xy 381.180082 -230.68885) (xy 381.180594 -230.714296) (xy 381.180082 -230.739742)
			(xy 381.171918 -230.789976) (xy 381.155802 -230.83825) (xy 381.132151 -230.883313) (xy 381.101578 -230.923999)
			(xy 381.064874 -230.959254) (xy 381.02299 -230.988164) (xy 380.977011 -231.009981) (xy 380.928127 -231.024141)
			(xy 380.877606 -231.030275) (xy 380.826754 -231.028226) (xy 380.77689 -231.018046) (xy 380.729304 -230.999999)
			(xy 380.68523 -230.974553) (xy 380.645808 -230.942366) (xy 380.61206 -230.904272) (xy 380.584859 -230.861258)
			(xy 380.564911 -230.814438) (xy 380.552732 -230.765024) (xy 380.548637 -230.714296) (xy 380.242826 -230.714296)
			(xy 380.242336 -230.739285) (xy 380.234517 -230.788648) (xy 380.219073 -230.83618) (xy 380.196383 -230.880712)
			(xy 380.167007 -230.921145) (xy 380.131667 -230.956485) (xy 380.091234 -230.985861) (xy 380.046702 -231.008551)
			(xy 379.99917 -231.023995) (xy 379.949807 -231.031814) (xy 379.899829 -231.031814) (xy 379.850466 -231.023995)
			(xy 379.802934 -231.008551) (xy 379.758402 -230.985861) (xy 379.717969 -230.956485) (xy 379.682629 -230.921145)
			(xy 379.653253 -230.880712) (xy 379.630563 -230.83618) (xy 379.615119 -230.788648) (xy 379.6073 -230.739285)
			(xy 379.299983 -230.739285) (xy 379.299974 -230.739742) (xy 379.29181 -230.789976) (xy 379.275694 -230.83825)
			(xy 379.252043 -230.883313) (xy 379.22147 -230.923999) (xy 379.184766 -230.959254) (xy 379.142882 -230.988164)
			(xy 379.096903 -231.009981) (xy 379.048019 -231.024141) (xy 378.997498 -231.030275) (xy 378.946646 -231.028226)
			(xy 378.896782 -231.018046) (xy 378.849196 -230.999999) (xy 378.805122 -230.974553) (xy 378.7657 -230.942366)
			(xy 378.731952 -230.904272) (xy 378.704751 -230.861258) (xy 378.684803 -230.814438) (xy 378.672624 -230.765024)
			(xy 378.668529 -230.714296) (xy 378.362718 -230.714296) (xy 378.362228 -230.739285) (xy 378.354409 -230.788648)
			(xy 378.338965 -230.83618) (xy 378.316275 -230.880712) (xy 378.286899 -230.921145) (xy 378.251559 -230.956485)
			(xy 378.211126 -230.985861) (xy 378.166594 -231.008551) (xy 378.119062 -231.023995) (xy 378.069699 -231.031814)
			(xy 378.019721 -231.031814) (xy 377.970358 -231.023995) (xy 377.922826 -231.008551) (xy 377.878294 -230.985861)
			(xy 377.837861 -230.956485) (xy 377.802521 -230.921145) (xy 377.773145 -230.880712) (xy 377.750455 -230.83618)
			(xy 377.735011 -230.788648) (xy 377.727192 -230.739285) (xy 377.420129 -230.739285) (xy 377.42012 -230.739742)
			(xy 377.411956 -230.789976) (xy 377.39584 -230.83825) (xy 377.372189 -230.883313) (xy 377.341616 -230.923999)
			(xy 377.304912 -230.959254) (xy 377.263028 -230.988164) (xy 377.217049 -231.009981) (xy 377.168165 -231.024141)
			(xy 377.117644 -231.030275) (xy 377.066792 -231.028226) (xy 377.016928 -231.018046) (xy 376.969342 -230.999999)
			(xy 376.925268 -230.974553) (xy 376.885846 -230.942366) (xy 376.852098 -230.904272) (xy 376.824897 -230.861258)
			(xy 376.804949 -230.814438) (xy 376.79277 -230.765024) (xy 376.788675 -230.714296) (xy 376.480578 -230.714296)
			(xy 376.480066 -230.739742) (xy 376.471902 -230.789976) (xy 376.455786 -230.83825) (xy 376.432135 -230.883313)
			(xy 376.401562 -230.923999) (xy 376.364858 -230.959254) (xy 376.322974 -230.988164) (xy 376.276995 -231.009981)
			(xy 376.228111 -231.024141) (xy 376.17759 -231.030275) (xy 376.126738 -231.028226) (xy 376.076874 -231.018046)
			(xy 376.029288 -230.999999) (xy 375.985214 -230.974553) (xy 375.945792 -230.942366) (xy 375.912044 -230.904272)
			(xy 375.884843 -230.861258) (xy 375.864895 -230.814438) (xy 375.852716 -230.765024) (xy 375.848621 -230.714296)
			(xy 375.54281 -230.714296) (xy 375.54232 -230.739285) (xy 375.534501 -230.788648) (xy 375.519057 -230.83618)
			(xy 375.496367 -230.880712) (xy 375.466991 -230.921145) (xy 375.431651 -230.956485) (xy 375.391218 -230.985861)
			(xy 375.346686 -231.008551) (xy 375.299154 -231.023995) (xy 375.249791 -231.031814) (xy 375.199813 -231.031814)
			(xy 375.15045 -231.023995) (xy 375.102918 -231.008551) (xy 375.058386 -230.985861) (xy 375.017953 -230.956485)
			(xy 374.982613 -230.921145) (xy 374.953237 -230.880712) (xy 374.930547 -230.83618) (xy 374.915103 -230.788648)
			(xy 374.907284 -230.739285) (xy 374.703086 -230.739285) (xy 374.703086 -231.130602) (xy 374.70334 -231.131872)
			(xy 374.70334 -231.14) (xy 374.704367 -231.147672) (xy 374.710432 -231.161905) (xy 374.715278 -231.16794)
			(xy 374.732804 -231.185466) (xy 374.736129 -231.188579) (xy 374.743667 -231.193691) (xy 374.74779 -231.195626)
			(xy 374.771666 -231.206294) (xy 374.780302 -231.207056) (xy 374.805145 -231.209537) (xy 374.853674 -231.221254)
			(xy 374.899775 -231.240411) (xy 374.942316 -231.266538) (xy 374.980251 -231.298992) (xy 375.012647 -231.336976)
			(xy 375.038709 -231.379557) (xy 375.057796 -231.425687) (xy 375.069439 -231.474234) (xy 375.073352 -231.524004)
			(xy 375.073349 -231.524048) (xy 375.378467 -231.524048) (xy 375.382562 -231.47332) (xy 375.394741 -231.423906)
			(xy 375.414689 -231.377086) (xy 375.44189 -231.334072) (xy 375.475638 -231.295978) (xy 375.51506 -231.263791)
			(xy 375.559134 -231.238345) (xy 375.60672 -231.220298) (xy 375.656584 -231.210118) (xy 375.707436 -231.208069)
			(xy 375.757957 -231.214203) (xy 375.806841 -231.228363) (xy 375.85282 -231.25018) (xy 375.894704 -231.27909)
			(xy 375.931408 -231.314345) (xy 375.961981 -231.355031) (xy 375.985632 -231.400094) (xy 376.001748 -231.448368)
			(xy 376.009912 -231.498602) (xy 376.010424 -231.524048) (xy 376.009921 -231.549037) (xy 376.317238 -231.549037)
			(xy 376.317238 -231.499059) (xy 376.325057 -231.449696) (xy 376.340501 -231.402164) (xy 376.363191 -231.357632)
			(xy 376.392567 -231.317199) (xy 376.427907 -231.281859) (xy 376.46834 -231.252483) (xy 376.512872 -231.229793)
			(xy 376.560404 -231.214349) (xy 376.609767 -231.20653) (xy 376.659745 -231.20653) (xy 376.709108 -231.214349)
			(xy 376.75664 -231.229793) (xy 376.801172 -231.252483) (xy 376.841605 -231.281859) (xy 376.876945 -231.317199)
			(xy 376.906321 -231.357632) (xy 376.929011 -231.402164) (xy 376.944455 -231.449696) (xy 376.952274 -231.499059)
			(xy 376.952764 -231.524048) (xy 377.258575 -231.524048) (xy 377.26267 -231.47332) (xy 377.274849 -231.423906)
			(xy 377.294797 -231.377086) (xy 377.321998 -231.334072) (xy 377.355746 -231.295978) (xy 377.395168 -231.263791)
			(xy 377.439242 -231.238345) (xy 377.486828 -231.220298) (xy 377.536692 -231.210118) (xy 377.587544 -231.208069)
			(xy 377.638065 -231.214203) (xy 377.686949 -231.228363) (xy 377.732928 -231.25018) (xy 377.774812 -231.27909)
			(xy 377.811516 -231.314345) (xy 377.842089 -231.355031) (xy 377.86574 -231.400094) (xy 377.881856 -231.448368)
			(xy 377.89002 -231.498602) (xy 377.890532 -231.524048) (xy 377.890029 -231.549037) (xy 378.197346 -231.549037)
			(xy 378.197346 -231.499059) (xy 378.205165 -231.449696) (xy 378.220609 -231.402164) (xy 378.243299 -231.357632)
			(xy 378.272675 -231.317199) (xy 378.308015 -231.281859) (xy 378.348448 -231.252483) (xy 378.39298 -231.229793)
			(xy 378.440512 -231.214349) (xy 378.489875 -231.20653) (xy 378.539853 -231.20653) (xy 378.589216 -231.214349)
			(xy 378.636748 -231.229793) (xy 378.68128 -231.252483) (xy 378.721713 -231.281859) (xy 378.757053 -231.317199)
			(xy 378.786429 -231.357632) (xy 378.809119 -231.402164) (xy 378.824563 -231.449696) (xy 378.832382 -231.499059)
			(xy 378.832872 -231.524048) (xy 379.138683 -231.524048) (xy 379.142778 -231.47332) (xy 379.154957 -231.423906)
			(xy 379.174905 -231.377086) (xy 379.202106 -231.334072) (xy 379.235854 -231.295978) (xy 379.275276 -231.263791)
			(xy 379.31935 -231.238345) (xy 379.366936 -231.220298) (xy 379.4168 -231.210118) (xy 379.467652 -231.208069)
			(xy 379.518173 -231.214203) (xy 379.567057 -231.228363) (xy 379.613036 -231.25018) (xy 379.65492 -231.27909)
			(xy 379.691624 -231.314345) (xy 379.722197 -231.355031) (xy 379.745848 -231.400094) (xy 379.761964 -231.448368)
			(xy 379.770128 -231.498602) (xy 379.77064 -231.524048) (xy 380.078483 -231.524048) (xy 380.082578 -231.47332)
			(xy 380.094757 -231.423906) (xy 380.114705 -231.377086) (xy 380.141906 -231.334072) (xy 380.175654 -231.295978)
			(xy 380.215076 -231.263791) (xy 380.25915 -231.238345) (xy 380.306736 -231.220298) (xy 380.3566 -231.210118)
			(xy 380.407452 -231.208069) (xy 380.457973 -231.214203) (xy 380.506857 -231.228363) (xy 380.552836 -231.25018)
			(xy 380.59472 -231.27909) (xy 380.631424 -231.314345) (xy 380.661997 -231.355031) (xy 380.685648 -231.400094)
			(xy 380.701764 -231.448368) (xy 380.709928 -231.498602) (xy 380.71044 -231.524048) (xy 380.709928 -231.549494)
			(xy 380.701764 -231.599728) (xy 380.685648 -231.648002) (xy 380.661997 -231.693065) (xy 380.631424 -231.733751)
			(xy 380.59472 -231.769006) (xy 380.552836 -231.797916) (xy 380.506857 -231.819733) (xy 380.457973 -231.833893)
			(xy 380.407452 -231.840027) (xy 380.3566 -231.837978) (xy 380.306736 -231.827798) (xy 380.25915 -231.809751)
			(xy 380.215076 -231.784305) (xy 380.175654 -231.752118) (xy 380.141906 -231.714024) (xy 380.114705 -231.67101)
			(xy 380.094757 -231.62419) (xy 380.082578 -231.574776) (xy 380.078483 -231.524048) (xy 379.77064 -231.524048)
			(xy 379.770128 -231.549494) (xy 379.761964 -231.599728) (xy 379.745848 -231.648002) (xy 379.722197 -231.693065)
			(xy 379.691624 -231.733751) (xy 379.65492 -231.769006) (xy 379.613036 -231.797916) (xy 379.567057 -231.819733)
			(xy 379.518173 -231.833893) (xy 379.467652 -231.840027) (xy 379.4168 -231.837978) (xy 379.366936 -231.827798)
			(xy 379.31935 -231.809751) (xy 379.275276 -231.784305) (xy 379.235854 -231.752118) (xy 379.202106 -231.714024)
			(xy 379.174905 -231.67101) (xy 379.154957 -231.62419) (xy 379.142778 -231.574776) (xy 379.138683 -231.524048)
			(xy 378.832872 -231.524048) (xy 378.832382 -231.549037) (xy 378.824563 -231.5984) (xy 378.809119 -231.645932)
			(xy 378.786429 -231.690464) (xy 378.757053 -231.730897) (xy 378.721713 -231.766237) (xy 378.68128 -231.795613)
			(xy 378.636748 -231.818303) (xy 378.589216 -231.833747) (xy 378.539853 -231.841566) (xy 378.489875 -231.841566)
			(xy 378.440512 -231.833747) (xy 378.39298 -231.818303) (xy 378.348448 -231.795613) (xy 378.308015 -231.766237)
			(xy 378.272675 -231.730897) (xy 378.243299 -231.690464) (xy 378.220609 -231.645932) (xy 378.205165 -231.5984)
			(xy 378.197346 -231.549037) (xy 377.890029 -231.549037) (xy 377.89002 -231.549494) (xy 377.881856 -231.599728)
			(xy 377.86574 -231.648002) (xy 377.842089 -231.693065) (xy 377.811516 -231.733751) (xy 377.774812 -231.769006)
			(xy 377.732928 -231.797916) (xy 377.686949 -231.819733) (xy 377.638065 -231.833893) (xy 377.587544 -231.840027)
			(xy 377.536692 -231.837978) (xy 377.486828 -231.827798) (xy 377.439242 -231.809751) (xy 377.395168 -231.784305)
			(xy 377.355746 -231.752118) (xy 377.321998 -231.714024) (xy 377.294797 -231.67101) (xy 377.274849 -231.62419)
			(xy 377.26267 -231.574776) (xy 377.258575 -231.524048) (xy 376.952764 -231.524048) (xy 376.952274 -231.549037)
			(xy 376.944455 -231.5984) (xy 376.929011 -231.645932) (xy 376.906321 -231.690464) (xy 376.876945 -231.730897)
			(xy 376.841605 -231.766237) (xy 376.801172 -231.795613) (xy 376.75664 -231.818303) (xy 376.709108 -231.833747)
			(xy 376.659745 -231.841566) (xy 376.609767 -231.841566) (xy 376.560404 -231.833747) (xy 376.512872 -231.818303)
			(xy 376.46834 -231.795613) (xy 376.427907 -231.766237) (xy 376.392567 -231.730897) (xy 376.363191 -231.690464)
			(xy 376.340501 -231.645932) (xy 376.325057 -231.5984) (xy 376.317238 -231.549037) (xy 376.009921 -231.549037)
			(xy 376.009912 -231.549494) (xy 376.001748 -231.599728) (xy 375.985632 -231.648002) (xy 375.961981 -231.693065)
			(xy 375.931408 -231.733751) (xy 375.894704 -231.769006) (xy 375.85282 -231.797916) (xy 375.806841 -231.819733)
			(xy 375.757957 -231.833893) (xy 375.707436 -231.840027) (xy 375.656584 -231.837978) (xy 375.60672 -231.827798)
			(xy 375.559134 -231.809751) (xy 375.51506 -231.784305) (xy 375.475638 -231.752118) (xy 375.44189 -231.714024)
			(xy 375.414689 -231.67101) (xy 375.394741 -231.62419) (xy 375.382562 -231.574776) (xy 375.378467 -231.524048)
			(xy 375.073349 -231.524048) (xy 375.069438 -231.573773) (xy 375.057794 -231.62232) (xy 375.038706 -231.66845)
			(xy 375.012643 -231.71103) (xy 374.980245 -231.749013) (xy 374.94231 -231.781467) (xy 374.899768 -231.807593)
			(xy 374.853666 -231.826749) (xy 374.805137 -231.838464) (xy 374.780302 -231.84104) (xy 374.771666 -231.841802)
			(xy 374.74779 -231.85247) (xy 374.74367 -231.85441) (xy 374.736139 -231.859528) (xy 374.732804 -231.86263)
			(xy 374.715278 -231.880156) (xy 374.71043 -231.886192) (xy 374.704353 -231.900421) (xy 374.70334 -231.908096)
			(xy 374.70334 -231.916224) (xy 374.703086 -231.917494) (xy 374.703086 -232.334054) (xy 375.848621 -232.334054)
			(xy 375.852716 -232.283326) (xy 375.864895 -232.233912) (xy 375.884843 -232.187092) (xy 375.912044 -232.144078)
			(xy 375.945792 -232.105984) (xy 375.985214 -232.073797) (xy 376.029288 -232.048351) (xy 376.076874 -232.030304)
			(xy 376.126738 -232.020124) (xy 376.17759 -232.018075) (xy 376.228111 -232.024209) (xy 376.276995 -232.038369)
			(xy 376.322974 -232.060186) (xy 376.364858 -232.089096) (xy 376.401562 -232.124351) (xy 376.432135 -232.165037)
			(xy 376.455786 -232.2101) (xy 376.471902 -232.258374) (xy 376.480066 -232.308608) (xy 376.480578 -232.334054)
			(xy 376.788675 -232.334054) (xy 376.79277 -232.283326) (xy 376.804949 -232.233912) (xy 376.824897 -232.187092)
			(xy 376.852098 -232.144078) (xy 376.885846 -232.105984) (xy 376.925268 -232.073797) (xy 376.969342 -232.048351)
			(xy 377.016928 -232.030304) (xy 377.066792 -232.020124) (xy 377.117644 -232.018075) (xy 377.168165 -232.024209)
			(xy 377.217049 -232.038369) (xy 377.263028 -232.060186) (xy 377.304912 -232.089096) (xy 377.341616 -232.124351)
			(xy 377.372189 -232.165037) (xy 377.39584 -232.2101) (xy 377.411956 -232.258374) (xy 377.42012 -232.308608)
			(xy 377.420632 -232.334054) (xy 378.668529 -232.334054) (xy 378.672624 -232.283326) (xy 378.684803 -232.233912)
			(xy 378.704751 -232.187092) (xy 378.731952 -232.144078) (xy 378.7657 -232.105984) (xy 378.805122 -232.073797)
			(xy 378.849196 -232.048351) (xy 378.896782 -232.030304) (xy 378.946646 -232.020124) (xy 378.997498 -232.018075)
			(xy 379.048019 -232.024209) (xy 379.096903 -232.038369) (xy 379.142882 -232.060186) (xy 379.184766 -232.089096)
			(xy 379.22147 -232.124351) (xy 379.252043 -232.165037) (xy 379.275694 -232.2101) (xy 379.29181 -232.258374)
			(xy 379.299974 -232.308608) (xy 379.300486 -232.334054) (xy 379.299983 -232.359043) (xy 379.6073 -232.359043)
			(xy 379.6073 -232.309065) (xy 379.615119 -232.259702) (xy 379.630563 -232.21217) (xy 379.653253 -232.167638)
			(xy 379.682629 -232.127205) (xy 379.717969 -232.091865) (xy 379.758402 -232.062489) (xy 379.802934 -232.039799)
			(xy 379.850466 -232.024355) (xy 379.899829 -232.016536) (xy 379.949807 -232.016536) (xy 379.99917 -232.024355)
			(xy 380.046702 -232.039799) (xy 380.091234 -232.062489) (xy 380.131667 -232.091865) (xy 380.167007 -232.127205)
			(xy 380.196383 -232.167638) (xy 380.219073 -232.21217) (xy 380.234517 -232.259702) (xy 380.242336 -232.309065)
			(xy 380.242826 -232.334054) (xy 380.548637 -232.334054) (xy 380.552732 -232.283326) (xy 380.564911 -232.233912)
			(xy 380.584859 -232.187092) (xy 380.61206 -232.144078) (xy 380.645808 -232.105984) (xy 380.68523 -232.073797)
			(xy 380.729304 -232.048351) (xy 380.77689 -232.030304) (xy 380.826754 -232.020124) (xy 380.877606 -232.018075)
			(xy 380.928127 -232.024209) (xy 380.977011 -232.038369) (xy 381.02299 -232.060186) (xy 381.064874 -232.089096)
			(xy 381.101578 -232.124351) (xy 381.132151 -232.165037) (xy 381.155802 -232.2101) (xy 381.171918 -232.258374)
			(xy 381.180082 -232.308608) (xy 381.180594 -232.334054) (xy 381.180082 -232.3595) (xy 381.171918 -232.409734)
			(xy 381.155802 -232.458008) (xy 381.132151 -232.503071) (xy 381.101578 -232.543757) (xy 381.064874 -232.579012)
			(xy 381.02299 -232.607922) (xy 380.977011 -232.629739) (xy 380.928127 -232.643899) (xy 380.877606 -232.650033)
			(xy 380.826754 -232.647984) (xy 380.77689 -232.637804) (xy 380.729304 -232.619757) (xy 380.68523 -232.594311)
			(xy 380.645808 -232.562124) (xy 380.61206 -232.52403) (xy 380.584859 -232.481016) (xy 380.564911 -232.434196)
			(xy 380.552732 -232.384782) (xy 380.548637 -232.334054) (xy 380.242826 -232.334054) (xy 380.242336 -232.359043)
			(xy 380.234517 -232.408406) (xy 380.219073 -232.455938) (xy 380.196383 -232.50047) (xy 380.167007 -232.540903)
			(xy 380.131667 -232.576243) (xy 380.091234 -232.605619) (xy 380.046702 -232.628309) (xy 379.99917 -232.643753)
			(xy 379.949807 -232.651572) (xy 379.899829 -232.651572) (xy 379.850466 -232.643753) (xy 379.802934 -232.628309)
			(xy 379.758402 -232.605619) (xy 379.717969 -232.576243) (xy 379.682629 -232.540903) (xy 379.653253 -232.50047)
			(xy 379.630563 -232.455938) (xy 379.615119 -232.408406) (xy 379.6073 -232.359043) (xy 379.299983 -232.359043)
			(xy 379.299974 -232.3595) (xy 379.29181 -232.409734) (xy 379.275694 -232.458008) (xy 379.252043 -232.503071)
			(xy 379.22147 -232.543757) (xy 379.184766 -232.579012) (xy 379.142882 -232.607922) (xy 379.096903 -232.629739)
			(xy 379.048019 -232.643899) (xy 378.997498 -232.650033) (xy 378.946646 -232.647984) (xy 378.896782 -232.637804)
			(xy 378.849196 -232.619757) (xy 378.805122 -232.594311) (xy 378.7657 -232.562124) (xy 378.731952 -232.52403)
			(xy 378.704751 -232.481016) (xy 378.684803 -232.434196) (xy 378.672624 -232.384782) (xy 378.668529 -232.334054)
			(xy 377.420632 -232.334054) (xy 377.42012 -232.3595) (xy 377.411956 -232.409734) (xy 377.39584 -232.458008)
			(xy 377.372189 -232.503071) (xy 377.341616 -232.543757) (xy 377.304912 -232.579012) (xy 377.263028 -232.607922)
			(xy 377.217049 -232.629739) (xy 377.168165 -232.643899) (xy 377.117644 -232.650033) (xy 377.066792 -232.647984)
			(xy 377.016928 -232.637804) (xy 376.969342 -232.619757) (xy 376.925268 -232.594311) (xy 376.885846 -232.562124)
			(xy 376.852098 -232.52403) (xy 376.824897 -232.481016) (xy 376.804949 -232.434196) (xy 376.79277 -232.384782)
			(xy 376.788675 -232.334054) (xy 376.480578 -232.334054) (xy 376.480066 -232.3595) (xy 376.471902 -232.409734)
			(xy 376.455786 -232.458008) (xy 376.432135 -232.503071) (xy 376.401562 -232.543757) (xy 376.364858 -232.579012)
			(xy 376.322974 -232.607922) (xy 376.276995 -232.629739) (xy 376.228111 -232.643899) (xy 376.17759 -232.650033)
			(xy 376.126738 -232.647984) (xy 376.076874 -232.637804) (xy 376.029288 -232.619757) (xy 375.985214 -232.594311)
			(xy 375.945792 -232.562124) (xy 375.912044 -232.52403) (xy 375.884843 -232.481016) (xy 375.864895 -232.434196)
			(xy 375.852716 -232.384782) (xy 375.848621 -232.334054) (xy 374.703086 -232.334054) (xy 374.703086 -232.750614)
			(xy 374.70334 -232.751884) (xy 374.70334 -232.760012) (xy 374.704369 -232.767683) (xy 374.710437 -232.781914)
			(xy 374.715278 -232.787952) (xy 374.732804 -232.805478) (xy 374.736129 -232.808591) (xy 374.743668 -232.813701)
			(xy 374.74779 -232.815638) (xy 374.771666 -232.826306) (xy 374.780302 -232.827068) (xy 374.805152 -232.829549)
			(xy 374.853694 -232.841268) (xy 374.899809 -232.86043) (xy 374.942362 -232.886563) (xy 374.980308 -232.919025)
			(xy 375.012714 -232.957019) (xy 375.038784 -232.999611) (xy 375.057878 -233.045754) (xy 375.069525 -233.094313)
			(xy 375.073437 -233.14406) (xy 375.378467 -233.14406) (xy 375.382562 -233.093332) (xy 375.394741 -233.043918)
			(xy 375.414689 -232.997098) (xy 375.44189 -232.954084) (xy 375.475638 -232.91599) (xy 375.51506 -232.883803)
			(xy 375.559134 -232.858357) (xy 375.60672 -232.84031) (xy 375.656584 -232.83013) (xy 375.707436 -232.828081)
			(xy 375.757957 -232.834215) (xy 375.806841 -232.848375) (xy 375.85282 -232.870192) (xy 375.894704 -232.899102)
			(xy 375.931408 -232.934357) (xy 375.961981 -232.975043) (xy 375.985632 -233.020106) (xy 376.001748 -233.06838)
			(xy 376.009912 -233.118614) (xy 376.010424 -233.14406) (xy 376.009921 -233.169049) (xy 376.317238 -233.169049)
			(xy 376.317238 -233.119071) (xy 376.325057 -233.069708) (xy 376.340501 -233.022176) (xy 376.363191 -232.977644)
			(xy 376.392567 -232.937211) (xy 376.427907 -232.901871) (xy 376.46834 -232.872495) (xy 376.512872 -232.849805)
			(xy 376.560404 -232.834361) (xy 376.609767 -232.826542) (xy 376.659745 -232.826542) (xy 376.709108 -232.834361)
			(xy 376.75664 -232.849805) (xy 376.801172 -232.872495) (xy 376.841605 -232.901871) (xy 376.876945 -232.937211)
			(xy 376.906321 -232.977644) (xy 376.929011 -233.022176) (xy 376.944455 -233.069708) (xy 376.952274 -233.119071)
			(xy 376.952764 -233.14406) (xy 377.258575 -233.14406) (xy 377.26267 -233.093332) (xy 377.274849 -233.043918)
			(xy 377.294797 -232.997098) (xy 377.321998 -232.954084) (xy 377.355746 -232.91599) (xy 377.395168 -232.883803)
			(xy 377.439242 -232.858357) (xy 377.486828 -232.84031) (xy 377.536692 -232.83013) (xy 377.587544 -232.828081)
			(xy 377.638065 -232.834215) (xy 377.686949 -232.848375) (xy 377.732928 -232.870192) (xy 377.774812 -232.899102)
			(xy 377.811516 -232.934357) (xy 377.842089 -232.975043) (xy 377.86574 -233.020106) (xy 377.881856 -233.06838)
			(xy 377.89002 -233.118614) (xy 377.890532 -233.14406) (xy 377.890029 -233.169049) (xy 378.197346 -233.169049)
			(xy 378.197346 -233.119071) (xy 378.205165 -233.069708) (xy 378.220609 -233.022176) (xy 378.243299 -232.977644)
			(xy 378.272675 -232.937211) (xy 378.308015 -232.901871) (xy 378.348448 -232.872495) (xy 378.39298 -232.849805)
			(xy 378.440512 -232.834361) (xy 378.489875 -232.826542) (xy 378.539853 -232.826542) (xy 378.589216 -232.834361)
			(xy 378.636748 -232.849805) (xy 378.68128 -232.872495) (xy 378.721713 -232.901871) (xy 378.757053 -232.937211)
			(xy 378.786429 -232.977644) (xy 378.809119 -233.022176) (xy 378.824563 -233.069708) (xy 378.832382 -233.119071)
			(xy 378.832872 -233.14406) (xy 379.138683 -233.14406) (xy 379.142778 -233.093332) (xy 379.154957 -233.043918)
			(xy 379.174905 -232.997098) (xy 379.202106 -232.954084) (xy 379.235854 -232.91599) (xy 379.275276 -232.883803)
			(xy 379.31935 -232.858357) (xy 379.366936 -232.84031) (xy 379.4168 -232.83013) (xy 379.467652 -232.828081)
			(xy 379.518173 -232.834215) (xy 379.567057 -232.848375) (xy 379.613036 -232.870192) (xy 379.65492 -232.899102)
			(xy 379.691624 -232.934357) (xy 379.722197 -232.975043) (xy 379.745848 -233.020106) (xy 379.761964 -233.06838)
			(xy 379.770128 -233.118614) (xy 379.77064 -233.14406) (xy 380.078483 -233.14406) (xy 380.082578 -233.093332)
			(xy 380.094757 -233.043918) (xy 380.114705 -232.997098) (xy 380.141906 -232.954084) (xy 380.175654 -232.91599)
			(xy 380.215076 -232.883803) (xy 380.25915 -232.858357) (xy 380.306736 -232.84031) (xy 380.3566 -232.83013)
			(xy 380.407452 -232.828081) (xy 380.457973 -232.834215) (xy 380.506857 -232.848375) (xy 380.552836 -232.870192)
			(xy 380.59472 -232.899102) (xy 380.631424 -232.934357) (xy 380.661997 -232.975043) (xy 380.685648 -233.020106)
			(xy 380.701764 -233.06838) (xy 380.709928 -233.118614) (xy 380.71044 -233.14406) (xy 380.709928 -233.169506)
			(xy 380.701764 -233.21974) (xy 380.685648 -233.268014) (xy 380.661997 -233.313077) (xy 380.631424 -233.353763)
			(xy 380.59472 -233.389018) (xy 380.552836 -233.417928) (xy 380.506857 -233.439745) (xy 380.457973 -233.453905)
			(xy 380.407452 -233.460039) (xy 380.3566 -233.45799) (xy 380.306736 -233.44781) (xy 380.25915 -233.429763)
			(xy 380.215076 -233.404317) (xy 380.175654 -233.37213) (xy 380.141906 -233.334036) (xy 380.114705 -233.291022)
			(xy 380.094757 -233.244202) (xy 380.082578 -233.194788) (xy 380.078483 -233.14406) (xy 379.77064 -233.14406)
			(xy 379.770128 -233.169506) (xy 379.761964 -233.21974) (xy 379.745848 -233.268014) (xy 379.722197 -233.313077)
			(xy 379.691624 -233.353763) (xy 379.65492 -233.389018) (xy 379.613036 -233.417928) (xy 379.567057 -233.439745)
			(xy 379.518173 -233.453905) (xy 379.467652 -233.460039) (xy 379.4168 -233.45799) (xy 379.366936 -233.44781)
			(xy 379.31935 -233.429763) (xy 379.275276 -233.404317) (xy 379.235854 -233.37213) (xy 379.202106 -233.334036)
			(xy 379.174905 -233.291022) (xy 379.154957 -233.244202) (xy 379.142778 -233.194788) (xy 379.138683 -233.14406)
			(xy 378.832872 -233.14406) (xy 378.832382 -233.169049) (xy 378.824563 -233.218412) (xy 378.809119 -233.265944)
			(xy 378.786429 -233.310476) (xy 378.757053 -233.350909) (xy 378.721713 -233.386249) (xy 378.68128 -233.415625)
			(xy 378.636748 -233.438315) (xy 378.589216 -233.453759) (xy 378.539853 -233.461578) (xy 378.489875 -233.461578)
			(xy 378.440512 -233.453759) (xy 378.39298 -233.438315) (xy 378.348448 -233.415625) (xy 378.308015 -233.386249)
			(xy 378.272675 -233.350909) (xy 378.243299 -233.310476) (xy 378.220609 -233.265944) (xy 378.205165 -233.218412)
			(xy 378.197346 -233.169049) (xy 377.890029 -233.169049) (xy 377.89002 -233.169506) (xy 377.881856 -233.21974)
			(xy 377.86574 -233.268014) (xy 377.842089 -233.313077) (xy 377.811516 -233.353763) (xy 377.774812 -233.389018)
			(xy 377.732928 -233.417928) (xy 377.686949 -233.439745) (xy 377.638065 -233.453905) (xy 377.587544 -233.460039)
			(xy 377.536692 -233.45799) (xy 377.486828 -233.44781) (xy 377.439242 -233.429763) (xy 377.395168 -233.404317)
			(xy 377.355746 -233.37213) (xy 377.321998 -233.334036) (xy 377.294797 -233.291022) (xy 377.274849 -233.244202)
			(xy 377.26267 -233.194788) (xy 377.258575 -233.14406) (xy 376.952764 -233.14406) (xy 376.952274 -233.169049)
			(xy 376.944455 -233.218412) (xy 376.929011 -233.265944) (xy 376.906321 -233.310476) (xy 376.876945 -233.350909)
			(xy 376.841605 -233.386249) (xy 376.801172 -233.415625) (xy 376.75664 -233.438315) (xy 376.709108 -233.453759)
			(xy 376.659745 -233.461578) (xy 376.609767 -233.461578) (xy 376.560404 -233.453759) (xy 376.512872 -233.438315)
			(xy 376.46834 -233.415625) (xy 376.427907 -233.386249) (xy 376.392567 -233.350909) (xy 376.363191 -233.310476)
			(xy 376.340501 -233.265944) (xy 376.325057 -233.218412) (xy 376.317238 -233.169049) (xy 376.009921 -233.169049)
			(xy 376.009912 -233.169506) (xy 376.001748 -233.21974) (xy 375.985632 -233.268014) (xy 375.961981 -233.313077)
			(xy 375.931408 -233.353763) (xy 375.894704 -233.389018) (xy 375.85282 -233.417928) (xy 375.806841 -233.439745)
			(xy 375.757957 -233.453905) (xy 375.707436 -233.460039) (xy 375.656584 -233.45799) (xy 375.60672 -233.44781)
			(xy 375.559134 -233.429763) (xy 375.51506 -233.404317) (xy 375.475638 -233.37213) (xy 375.44189 -233.334036)
			(xy 375.414689 -233.291022) (xy 375.394741 -233.244202) (xy 375.382562 -233.194788) (xy 375.378467 -233.14406)
			(xy 375.073437 -233.14406) (xy 375.07344 -233.144097) (xy 375.069526 -233.19388) (xy 375.05788 -233.24244)
			(xy 375.038787 -233.288583) (xy 375.012718 -233.331176) (xy 374.980312 -233.36917) (xy 374.942367 -233.401634)
			(xy 374.899814 -233.427767) (xy 374.8537 -233.44693) (xy 374.805158 -233.45865) (xy 374.780302 -233.461052)
			(xy 374.771666 -233.461814) (xy 374.74779 -233.472482) (xy 374.74367 -233.474422) (xy 374.73614 -233.479541)
			(xy 374.732804 -233.482642) (xy 374.715278 -233.500168) (xy 374.710432 -233.506205) (xy 374.704358 -233.520434)
			(xy 374.70334 -233.528108) (xy 374.70334 -233.536236) (xy 374.703086 -233.537506) (xy 374.703086 -233.979055)
			(xy 374.907284 -233.979055) (xy 374.907284 -233.929077) (xy 374.915103 -233.879714) (xy 374.930547 -233.832182)
			(xy 374.953237 -233.78765) (xy 374.982613 -233.747217) (xy 375.017953 -233.711877) (xy 375.058386 -233.682501)
			(xy 375.102918 -233.659811) (xy 375.15045 -233.644367) (xy 375.199813 -233.636548) (xy 375.249791 -233.636548)
			(xy 375.299154 -233.644367) (xy 375.346686 -233.659811) (xy 375.391218 -233.682501) (xy 375.431651 -233.711877)
			(xy 375.466991 -233.747217) (xy 375.496367 -233.78765) (xy 375.519057 -233.832182) (xy 375.534501 -233.879714)
			(xy 375.54232 -233.929077) (xy 375.54281 -233.954066) (xy 375.848621 -233.954066) (xy 375.852716 -233.903338)
			(xy 375.864895 -233.853924) (xy 375.884843 -233.807104) (xy 375.912044 -233.76409) (xy 375.945792 -233.725996)
			(xy 375.985214 -233.693809) (xy 376.029288 -233.668363) (xy 376.076874 -233.650316) (xy 376.126738 -233.640136)
			(xy 376.17759 -233.638087) (xy 376.228111 -233.644221) (xy 376.276995 -233.658381) (xy 376.322974 -233.680198)
			(xy 376.364858 -233.709108) (xy 376.401562 -233.744363) (xy 376.432135 -233.785049) (xy 376.455786 -233.830112)
			(xy 376.471902 -233.878386) (xy 376.480066 -233.92862) (xy 376.480578 -233.954066) (xy 376.788675 -233.954066)
			(xy 376.79277 -233.903338) (xy 376.804949 -233.853924) (xy 376.824897 -233.807104) (xy 376.852098 -233.76409)
			(xy 376.885846 -233.725996) (xy 376.925268 -233.693809) (xy 376.969342 -233.668363) (xy 377.016928 -233.650316)
			(xy 377.066792 -233.640136) (xy 377.117644 -233.638087) (xy 377.168165 -233.644221) (xy 377.217049 -233.658381)
			(xy 377.263028 -233.680198) (xy 377.304912 -233.709108) (xy 377.341616 -233.744363) (xy 377.372189 -233.785049)
			(xy 377.39584 -233.830112) (xy 377.411956 -233.878386) (xy 377.42012 -233.92862) (xy 377.420632 -233.954066)
			(xy 377.420129 -233.979055) (xy 377.727192 -233.979055) (xy 377.727192 -233.929077) (xy 377.735011 -233.879714)
			(xy 377.750455 -233.832182) (xy 377.773145 -233.78765) (xy 377.802521 -233.747217) (xy 377.837861 -233.711877)
			(xy 377.878294 -233.682501) (xy 377.922826 -233.659811) (xy 377.970358 -233.644367) (xy 378.019721 -233.636548)
			(xy 378.069699 -233.636548) (xy 378.119062 -233.644367) (xy 378.166594 -233.659811) (xy 378.211126 -233.682501)
			(xy 378.251559 -233.711877) (xy 378.286899 -233.747217) (xy 378.316275 -233.78765) (xy 378.338965 -233.832182)
			(xy 378.354409 -233.879714) (xy 378.362228 -233.929077) (xy 378.362718 -233.954066) (xy 378.668529 -233.954066)
			(xy 378.672624 -233.903338) (xy 378.684803 -233.853924) (xy 378.704751 -233.807104) (xy 378.731952 -233.76409)
			(xy 378.7657 -233.725996) (xy 378.805122 -233.693809) (xy 378.849196 -233.668363) (xy 378.896782 -233.650316)
			(xy 378.946646 -233.640136) (xy 378.997498 -233.638087) (xy 379.048019 -233.644221) (xy 379.096903 -233.658381)
			(xy 379.142882 -233.680198) (xy 379.184766 -233.709108) (xy 379.22147 -233.744363) (xy 379.252043 -233.785049)
			(xy 379.275694 -233.830112) (xy 379.29181 -233.878386) (xy 379.299974 -233.92862) (xy 379.300486 -233.954066)
			(xy 379.299983 -233.979055) (xy 379.6073 -233.979055) (xy 379.6073 -233.929077) (xy 379.615119 -233.879714)
			(xy 379.630563 -233.832182) (xy 379.653253 -233.78765) (xy 379.682629 -233.747217) (xy 379.717969 -233.711877)
			(xy 379.758402 -233.682501) (xy 379.802934 -233.659811) (xy 379.850466 -233.644367) (xy 379.899829 -233.636548)
			(xy 379.949807 -233.636548) (xy 379.99917 -233.644367) (xy 380.046702 -233.659811) (xy 380.091234 -233.682501)
			(xy 380.131667 -233.711877) (xy 380.167007 -233.747217) (xy 380.196383 -233.78765) (xy 380.219073 -233.832182)
			(xy 380.234517 -233.879714) (xy 380.242336 -233.929077) (xy 380.242826 -233.954066) (xy 380.548637 -233.954066)
			(xy 380.552732 -233.903338) (xy 380.564911 -233.853924) (xy 380.584859 -233.807104) (xy 380.61206 -233.76409)
			(xy 380.645808 -233.725996) (xy 380.68523 -233.693809) (xy 380.729304 -233.668363) (xy 380.77689 -233.650316)
			(xy 380.826754 -233.640136) (xy 380.877606 -233.638087) (xy 380.928127 -233.644221) (xy 380.977011 -233.658381)
			(xy 381.02299 -233.680198) (xy 381.064874 -233.709108) (xy 381.101578 -233.744363) (xy 381.132151 -233.785049)
			(xy 381.155802 -233.830112) (xy 381.171918 -233.878386) (xy 381.180082 -233.92862) (xy 381.180594 -233.954066)
			(xy 381.180082 -233.979512) (xy 381.171918 -234.029746) (xy 381.155802 -234.07802) (xy 381.132151 -234.123083)
			(xy 381.101578 -234.163769) (xy 381.064874 -234.199024) (xy 381.02299 -234.227934) (xy 380.977011 -234.249751)
			(xy 380.928127 -234.263911) (xy 380.877606 -234.270045) (xy 380.826754 -234.267996) (xy 380.77689 -234.257816)
			(xy 380.729304 -234.239769) (xy 380.68523 -234.214323) (xy 380.645808 -234.182136) (xy 380.61206 -234.144042)
			(xy 380.584859 -234.101028) (xy 380.564911 -234.054208) (xy 380.552732 -234.004794) (xy 380.548637 -233.954066)
			(xy 380.242826 -233.954066) (xy 380.242336 -233.979055) (xy 380.234517 -234.028418) (xy 380.219073 -234.07595)
			(xy 380.196383 -234.120482) (xy 380.167007 -234.160915) (xy 380.131667 -234.196255) (xy 380.091234 -234.225631)
			(xy 380.046702 -234.248321) (xy 379.99917 -234.263765) (xy 379.949807 -234.271584) (xy 379.899829 -234.271584)
			(xy 379.850466 -234.263765) (xy 379.802934 -234.248321) (xy 379.758402 -234.225631) (xy 379.717969 -234.196255)
			(xy 379.682629 -234.160915) (xy 379.653253 -234.120482) (xy 379.630563 -234.07595) (xy 379.615119 -234.028418)
			(xy 379.6073 -233.979055) (xy 379.299983 -233.979055) (xy 379.299974 -233.979512) (xy 379.29181 -234.029746)
			(xy 379.275694 -234.07802) (xy 379.252043 -234.123083) (xy 379.22147 -234.163769) (xy 379.184766 -234.199024)
			(xy 379.142882 -234.227934) (xy 379.096903 -234.249751) (xy 379.048019 -234.263911) (xy 378.997498 -234.270045)
			(xy 378.946646 -234.267996) (xy 378.896782 -234.257816) (xy 378.849196 -234.239769) (xy 378.805122 -234.214323)
			(xy 378.7657 -234.182136) (xy 378.731952 -234.144042) (xy 378.704751 -234.101028) (xy 378.684803 -234.054208)
			(xy 378.672624 -234.004794) (xy 378.668529 -233.954066) (xy 378.362718 -233.954066) (xy 378.362228 -233.979055)
			(xy 378.354409 -234.028418) (xy 378.338965 -234.07595) (xy 378.316275 -234.120482) (xy 378.286899 -234.160915)
			(xy 378.251559 -234.196255) (xy 378.211126 -234.225631) (xy 378.166594 -234.248321) (xy 378.119062 -234.263765)
			(xy 378.069699 -234.271584) (xy 378.019721 -234.271584) (xy 377.970358 -234.263765) (xy 377.922826 -234.248321)
			(xy 377.878294 -234.225631) (xy 377.837861 -234.196255) (xy 377.802521 -234.160915) (xy 377.773145 -234.120482)
			(xy 377.750455 -234.07595) (xy 377.735011 -234.028418) (xy 377.727192 -233.979055) (xy 377.420129 -233.979055)
			(xy 377.42012 -233.979512) (xy 377.411956 -234.029746) (xy 377.39584 -234.07802) (xy 377.372189 -234.123083)
			(xy 377.341616 -234.163769) (xy 377.304912 -234.199024) (xy 377.263028 -234.227934) (xy 377.217049 -234.249751)
			(xy 377.168165 -234.263911) (xy 377.117644 -234.270045) (xy 377.066792 -234.267996) (xy 377.016928 -234.257816)
			(xy 376.969342 -234.239769) (xy 376.925268 -234.214323) (xy 376.885846 -234.182136) (xy 376.852098 -234.144042)
			(xy 376.824897 -234.101028) (xy 376.804949 -234.054208) (xy 376.79277 -234.004794) (xy 376.788675 -233.954066)
			(xy 376.480578 -233.954066) (xy 376.480066 -233.979512) (xy 376.471902 -234.029746) (xy 376.455786 -234.07802)
			(xy 376.432135 -234.123083) (xy 376.401562 -234.163769) (xy 376.364858 -234.199024) (xy 376.322974 -234.227934)
			(xy 376.276995 -234.249751) (xy 376.228111 -234.263911) (xy 376.17759 -234.270045) (xy 376.126738 -234.267996)
			(xy 376.076874 -234.257816) (xy 376.029288 -234.239769) (xy 375.985214 -234.214323) (xy 375.945792 -234.182136)
			(xy 375.912044 -234.144042) (xy 375.884843 -234.101028) (xy 375.864895 -234.054208) (xy 375.852716 -234.004794)
			(xy 375.848621 -233.954066) (xy 375.54281 -233.954066) (xy 375.54232 -233.979055) (xy 375.534501 -234.028418)
			(xy 375.519057 -234.07595) (xy 375.496367 -234.120482) (xy 375.466991 -234.160915) (xy 375.431651 -234.196255)
			(xy 375.391218 -234.225631) (xy 375.346686 -234.248321) (xy 375.299154 -234.263765) (xy 375.249791 -234.271584)
			(xy 375.199813 -234.271584) (xy 375.15045 -234.263765) (xy 375.102918 -234.248321) (xy 375.058386 -234.225631)
			(xy 375.017953 -234.196255) (xy 374.982613 -234.160915) (xy 374.953237 -234.120482) (xy 374.930547 -234.07595)
			(xy 374.915103 -234.028418) (xy 374.907284 -233.979055) (xy 374.703086 -233.979055) (xy 374.703086 -234.370626)
			(xy 374.70334 -234.371896) (xy 374.70334 -234.380024) (xy 374.70437 -234.387695) (xy 374.710441 -234.401923)
			(xy 374.715278 -234.407964) (xy 374.732804 -234.42549) (xy 374.73613 -234.428602) (xy 374.743669 -234.433711)
			(xy 374.74779 -234.43565) (xy 374.771666 -234.446318) (xy 374.780302 -234.44708) (xy 374.805151 -234.449561)
			(xy 374.853691 -234.46128) (xy 374.899804 -234.480441) (xy 374.942356 -234.506573) (xy 374.9803 -234.539034)
			(xy 375.012705 -234.577027) (xy 375.038774 -234.619617) (xy 375.057867 -234.665758) (xy 375.069513 -234.714316)
			(xy 375.073426 -234.764072) (xy 375.378467 -234.764072) (xy 375.382562 -234.713344) (xy 375.394741 -234.66393)
			(xy 375.414689 -234.61711) (xy 375.44189 -234.574096) (xy 375.475638 -234.536002) (xy 375.51506 -234.503815)
			(xy 375.559134 -234.478369) (xy 375.60672 -234.460322) (xy 375.656584 -234.450142) (xy 375.707436 -234.448093)
			(xy 375.757957 -234.454227) (xy 375.806841 -234.468387) (xy 375.85282 -234.490204) (xy 375.894704 -234.519114)
			(xy 375.931408 -234.554369) (xy 375.961981 -234.595055) (xy 375.985632 -234.640118) (xy 376.001748 -234.688392)
			(xy 376.009912 -234.738626) (xy 376.010424 -234.764072) (xy 376.009921 -234.789061) (xy 376.317238 -234.789061)
			(xy 376.317238 -234.739083) (xy 376.325057 -234.68972) (xy 376.340501 -234.642188) (xy 376.363191 -234.597656)
			(xy 376.392567 -234.557223) (xy 376.427907 -234.521883) (xy 376.46834 -234.492507) (xy 376.512872 -234.469817)
			(xy 376.560404 -234.454373) (xy 376.609767 -234.446554) (xy 376.659745 -234.446554) (xy 376.709108 -234.454373)
			(xy 376.75664 -234.469817) (xy 376.801172 -234.492507) (xy 376.841605 -234.521883) (xy 376.876945 -234.557223)
			(xy 376.906321 -234.597656) (xy 376.929011 -234.642188) (xy 376.944455 -234.68972) (xy 376.952274 -234.739083)
			(xy 376.952764 -234.764072) (xy 377.258575 -234.764072) (xy 377.26267 -234.713344) (xy 377.274849 -234.66393)
			(xy 377.294797 -234.61711) (xy 377.321998 -234.574096) (xy 377.355746 -234.536002) (xy 377.395168 -234.503815)
			(xy 377.439242 -234.478369) (xy 377.486828 -234.460322) (xy 377.536692 -234.450142) (xy 377.587544 -234.448093)
			(xy 377.638065 -234.454227) (xy 377.686949 -234.468387) (xy 377.732928 -234.490204) (xy 377.774812 -234.519114)
			(xy 377.811516 -234.554369) (xy 377.842089 -234.595055) (xy 377.86574 -234.640118) (xy 377.881856 -234.688392)
			(xy 377.89002 -234.738626) (xy 377.890532 -234.764072) (xy 379.138683 -234.764072) (xy 379.142778 -234.713344)
			(xy 379.154957 -234.66393) (xy 379.174905 -234.61711) (xy 379.202106 -234.574096) (xy 379.235854 -234.536002)
			(xy 379.275276 -234.503815) (xy 379.31935 -234.478369) (xy 379.366936 -234.460322) (xy 379.4168 -234.450142)
			(xy 379.467652 -234.448093) (xy 379.518173 -234.454227) (xy 379.567057 -234.468387) (xy 379.613036 -234.490204)
			(xy 379.65492 -234.519114) (xy 379.691624 -234.554369) (xy 379.722197 -234.595055) (xy 379.745848 -234.640118)
			(xy 379.761964 -234.688392) (xy 379.770128 -234.738626) (xy 379.77064 -234.764072) (xy 380.078483 -234.764072)
			(xy 380.082578 -234.713344) (xy 380.094757 -234.66393) (xy 380.114705 -234.61711) (xy 380.141906 -234.574096)
			(xy 380.175654 -234.536002) (xy 380.215076 -234.503815) (xy 380.25915 -234.478369) (xy 380.306736 -234.460322)
			(xy 380.3566 -234.450142) (xy 380.407452 -234.448093) (xy 380.457973 -234.454227) (xy 380.506857 -234.468387)
			(xy 380.552836 -234.490204) (xy 380.59472 -234.519114) (xy 380.631424 -234.554369) (xy 380.661997 -234.595055)
			(xy 380.685648 -234.640118) (xy 380.701764 -234.688392) (xy 380.709928 -234.738626) (xy 380.71044 -234.764072)
			(xy 380.709928 -234.789518) (xy 380.701764 -234.839752) (xy 380.685648 -234.888026) (xy 380.661997 -234.933089)
			(xy 380.631424 -234.973775) (xy 380.59472 -235.00903) (xy 380.552836 -235.03794) (xy 380.506857 -235.059757)
			(xy 380.457973 -235.073917) (xy 380.407452 -235.080051) (xy 380.3566 -235.078002) (xy 380.306736 -235.067822)
			(xy 380.25915 -235.049775) (xy 380.215076 -235.024329) (xy 380.175654 -234.992142) (xy 380.141906 -234.954048)
			(xy 380.114705 -234.911034) (xy 380.094757 -234.864214) (xy 380.082578 -234.8148) (xy 380.078483 -234.764072)
			(xy 379.77064 -234.764072) (xy 379.770128 -234.789518) (xy 379.761964 -234.839752) (xy 379.745848 -234.888026)
			(xy 379.722197 -234.933089) (xy 379.691624 -234.973775) (xy 379.65492 -235.00903) (xy 379.613036 -235.03794)
			(xy 379.567057 -235.059757) (xy 379.518173 -235.073917) (xy 379.467652 -235.080051) (xy 379.4168 -235.078002)
			(xy 379.366936 -235.067822) (xy 379.31935 -235.049775) (xy 379.275276 -235.024329) (xy 379.235854 -234.992142)
			(xy 379.202106 -234.954048) (xy 379.174905 -234.911034) (xy 379.154957 -234.864214) (xy 379.142778 -234.8148)
			(xy 379.138683 -234.764072) (xy 377.890532 -234.764072) (xy 377.89002 -234.789518) (xy 377.881856 -234.839752)
			(xy 377.86574 -234.888026) (xy 377.842089 -234.933089) (xy 377.811516 -234.973775) (xy 377.774812 -235.00903)
			(xy 377.732928 -235.03794) (xy 377.686949 -235.059757) (xy 377.638065 -235.073917) (xy 377.587544 -235.080051)
			(xy 377.536692 -235.078002) (xy 377.486828 -235.067822) (xy 377.439242 -235.049775) (xy 377.395168 -235.024329)
			(xy 377.355746 -234.992142) (xy 377.321998 -234.954048) (xy 377.294797 -234.911034) (xy 377.274849 -234.864214)
			(xy 377.26267 -234.8148) (xy 377.258575 -234.764072) (xy 376.952764 -234.764072) (xy 376.952274 -234.789061)
			(xy 376.944455 -234.838424) (xy 376.929011 -234.885956) (xy 376.906321 -234.930488) (xy 376.876945 -234.970921)
			(xy 376.841605 -235.006261) (xy 376.801172 -235.035637) (xy 376.75664 -235.058327) (xy 376.709108 -235.073771)
			(xy 376.659745 -235.08159) (xy 376.609767 -235.08159) (xy 376.560404 -235.073771) (xy 376.512872 -235.058327)
			(xy 376.46834 -235.035637) (xy 376.427907 -235.006261) (xy 376.392567 -234.970921) (xy 376.363191 -234.930488)
			(xy 376.340501 -234.885956) (xy 376.325057 -234.838424) (xy 376.317238 -234.789061) (xy 376.009921 -234.789061)
			(xy 376.009912 -234.789518) (xy 376.001748 -234.839752) (xy 375.985632 -234.888026) (xy 375.961981 -234.933089)
			(xy 375.931408 -234.973775) (xy 375.894704 -235.00903) (xy 375.85282 -235.03794) (xy 375.806841 -235.059757)
			(xy 375.757957 -235.073917) (xy 375.707436 -235.080051) (xy 375.656584 -235.078002) (xy 375.60672 -235.067822)
			(xy 375.559134 -235.049775) (xy 375.51506 -235.024329) (xy 375.475638 -234.992142) (xy 375.44189 -234.954048)
			(xy 375.414689 -234.911034) (xy 375.394741 -234.864214) (xy 375.382562 -234.8148) (xy 375.378467 -234.764072)
			(xy 375.073426 -234.764072) (xy 375.073428 -234.764098) (xy 375.069514 -234.813879) (xy 375.057868 -234.862437)
			(xy 375.038776 -234.908579) (xy 375.012708 -234.951169) (xy 374.980303 -234.989163) (xy 374.942359 -235.021624)
			(xy 374.899808 -235.047757) (xy 374.853696 -235.066919) (xy 374.805155 -235.078638) (xy 374.780302 -235.081064)
			(xy 374.771666 -235.081826) (xy 374.74779 -235.092494) (xy 374.743668 -235.094431) (xy 374.736131 -235.099544)
			(xy 374.732804 -235.102654) (xy 374.715278 -235.12018) (xy 374.710433 -235.126217) (xy 374.704363 -235.140447)
			(xy 374.70334 -235.14812) (xy 374.70334 -235.156248) (xy 374.703086 -235.157518) (xy 374.703086 -235.574078)
			(xy 375.848621 -235.574078) (xy 375.852716 -235.52335) (xy 375.864895 -235.473936) (xy 375.884843 -235.427116)
			(xy 375.912044 -235.384102) (xy 375.945792 -235.346008) (xy 375.985214 -235.313821) (xy 376.029288 -235.288375)
			(xy 376.076874 -235.270328) (xy 376.126738 -235.260148) (xy 376.17759 -235.258099) (xy 376.228111 -235.264233)
			(xy 376.276995 -235.278393) (xy 376.322974 -235.30021) (xy 376.364858 -235.32912) (xy 376.401562 -235.364375)
			(xy 376.432135 -235.405061) (xy 376.455786 -235.450124) (xy 376.471902 -235.498398) (xy 376.480066 -235.548632)
			(xy 376.480578 -235.574078) (xy 376.788675 -235.574078) (xy 376.79277 -235.52335) (xy 376.804949 -235.473936)
			(xy 376.824897 -235.427116) (xy 376.852098 -235.384102) (xy 376.885846 -235.346008) (xy 376.925268 -235.313821)
			(xy 376.969342 -235.288375) (xy 377.016928 -235.270328) (xy 377.066792 -235.260148) (xy 377.117644 -235.258099)
			(xy 377.168165 -235.264233) (xy 377.217049 -235.278393) (xy 377.263028 -235.30021) (xy 377.304912 -235.32912)
			(xy 377.341616 -235.364375) (xy 377.372189 -235.405061) (xy 377.39584 -235.450124) (xy 377.411956 -235.498398)
			(xy 377.42012 -235.548632) (xy 377.420632 -235.574078) (xy 377.420129 -235.599067) (xy 377.727192 -235.599067)
			(xy 377.727192 -235.549089) (xy 377.735011 -235.499726) (xy 377.750455 -235.452194) (xy 377.773145 -235.407662)
			(xy 377.802521 -235.367229) (xy 377.837861 -235.331889) (xy 377.878294 -235.302513) (xy 377.922826 -235.279823)
			(xy 377.970358 -235.264379) (xy 378.019721 -235.25656) (xy 378.069699 -235.25656) (xy 378.119062 -235.264379)
			(xy 378.166594 -235.279823) (xy 378.211126 -235.302513) (xy 378.251559 -235.331889) (xy 378.286899 -235.367229)
			(xy 378.316275 -235.407662) (xy 378.338965 -235.452194) (xy 378.354409 -235.499726) (xy 378.362228 -235.549089)
			(xy 378.362718 -235.574078) (xy 378.668529 -235.574078) (xy 378.672624 -235.52335) (xy 378.684803 -235.473936)
			(xy 378.704751 -235.427116) (xy 378.731952 -235.384102) (xy 378.7657 -235.346008) (xy 378.805122 -235.313821)
			(xy 378.849196 -235.288375) (xy 378.896782 -235.270328) (xy 378.946646 -235.260148) (xy 378.997498 -235.258099)
			(xy 379.048019 -235.264233) (xy 379.096903 -235.278393) (xy 379.142882 -235.30021) (xy 379.184766 -235.32912)
			(xy 379.22147 -235.364375) (xy 379.252043 -235.405061) (xy 379.275694 -235.450124) (xy 379.29181 -235.498398)
			(xy 379.299974 -235.548632) (xy 379.300486 -235.574078) (xy 379.299983 -235.599067) (xy 379.6073 -235.599067)
			(xy 379.6073 -235.549089) (xy 379.615119 -235.499726) (xy 379.630563 -235.452194) (xy 379.653253 -235.407662)
			(xy 379.682629 -235.367229) (xy 379.717969 -235.331889) (xy 379.758402 -235.302513) (xy 379.802934 -235.279823)
			(xy 379.850466 -235.264379) (xy 379.899829 -235.25656) (xy 379.949807 -235.25656) (xy 379.99917 -235.264379)
			(xy 380.046702 -235.279823) (xy 380.091234 -235.302513) (xy 380.131667 -235.331889) (xy 380.167007 -235.367229)
			(xy 380.196383 -235.407662) (xy 380.219073 -235.452194) (xy 380.234517 -235.499726) (xy 380.242336 -235.549089)
			(xy 380.242826 -235.574078) (xy 380.548637 -235.574078) (xy 380.552732 -235.52335) (xy 380.564911 -235.473936)
			(xy 380.584859 -235.427116) (xy 380.61206 -235.384102) (xy 380.645808 -235.346008) (xy 380.68523 -235.313821)
			(xy 380.729304 -235.288375) (xy 380.77689 -235.270328) (xy 380.826754 -235.260148) (xy 380.877606 -235.258099)
			(xy 380.928127 -235.264233) (xy 380.977011 -235.278393) (xy 381.02299 -235.30021) (xy 381.064874 -235.32912)
			(xy 381.101578 -235.364375) (xy 381.132151 -235.405061) (xy 381.155802 -235.450124) (xy 381.171918 -235.498398)
			(xy 381.180082 -235.548632) (xy 381.180594 -235.574078) (xy 381.180082 -235.599524) (xy 381.171918 -235.649758)
			(xy 381.155802 -235.698032) (xy 381.132151 -235.743095) (xy 381.101578 -235.783781) (xy 381.064874 -235.819036)
			(xy 381.02299 -235.847946) (xy 380.977011 -235.869763) (xy 380.928127 -235.883923) (xy 380.877606 -235.890057)
			(xy 380.826754 -235.888008) (xy 380.77689 -235.877828) (xy 380.729304 -235.859781) (xy 380.68523 -235.834335)
			(xy 380.645808 -235.802148) (xy 380.61206 -235.764054) (xy 380.584859 -235.72104) (xy 380.564911 -235.67422)
			(xy 380.552732 -235.624806) (xy 380.548637 -235.574078) (xy 380.242826 -235.574078) (xy 380.242336 -235.599067)
			(xy 380.234517 -235.64843) (xy 380.219073 -235.695962) (xy 380.196383 -235.740494) (xy 380.167007 -235.780927)
			(xy 380.131667 -235.816267) (xy 380.091234 -235.845643) (xy 380.046702 -235.868333) (xy 379.99917 -235.883777)
			(xy 379.949807 -235.891596) (xy 379.899829 -235.891596) (xy 379.850466 -235.883777) (xy 379.802934 -235.868333)
			(xy 379.758402 -235.845643) (xy 379.717969 -235.816267) (xy 379.682629 -235.780927) (xy 379.653253 -235.740494)
			(xy 379.630563 -235.695962) (xy 379.615119 -235.64843) (xy 379.6073 -235.599067) (xy 379.299983 -235.599067)
			(xy 379.299974 -235.599524) (xy 379.29181 -235.649758) (xy 379.275694 -235.698032) (xy 379.252043 -235.743095)
			(xy 379.22147 -235.783781) (xy 379.184766 -235.819036) (xy 379.142882 -235.847946) (xy 379.096903 -235.869763)
			(xy 379.048019 -235.883923) (xy 378.997498 -235.890057) (xy 378.946646 -235.888008) (xy 378.896782 -235.877828)
			(xy 378.849196 -235.859781) (xy 378.805122 -235.834335) (xy 378.7657 -235.802148) (xy 378.731952 -235.764054)
			(xy 378.704751 -235.72104) (xy 378.684803 -235.67422) (xy 378.672624 -235.624806) (xy 378.668529 -235.574078)
			(xy 378.362718 -235.574078) (xy 378.362228 -235.599067) (xy 378.354409 -235.64843) (xy 378.338965 -235.695962)
			(xy 378.316275 -235.740494) (xy 378.286899 -235.780927) (xy 378.251559 -235.816267) (xy 378.211126 -235.845643)
			(xy 378.166594 -235.868333) (xy 378.119062 -235.883777) (xy 378.069699 -235.891596) (xy 378.019721 -235.891596)
			(xy 377.970358 -235.883777) (xy 377.922826 -235.868333) (xy 377.878294 -235.845643) (xy 377.837861 -235.816267)
			(xy 377.802521 -235.780927) (xy 377.773145 -235.740494) (xy 377.750455 -235.695962) (xy 377.735011 -235.64843)
			(xy 377.727192 -235.599067) (xy 377.420129 -235.599067) (xy 377.42012 -235.599524) (xy 377.411956 -235.649758)
			(xy 377.39584 -235.698032) (xy 377.372189 -235.743095) (xy 377.341616 -235.783781) (xy 377.304912 -235.819036)
			(xy 377.263028 -235.847946) (xy 377.217049 -235.869763) (xy 377.168165 -235.883923) (xy 377.117644 -235.890057)
			(xy 377.066792 -235.888008) (xy 377.016928 -235.877828) (xy 376.969342 -235.859781) (xy 376.925268 -235.834335)
			(xy 376.885846 -235.802148) (xy 376.852098 -235.764054) (xy 376.824897 -235.72104) (xy 376.804949 -235.67422)
			(xy 376.79277 -235.624806) (xy 376.788675 -235.574078) (xy 376.480578 -235.574078) (xy 376.480066 -235.599524)
			(xy 376.471902 -235.649758) (xy 376.455786 -235.698032) (xy 376.432135 -235.743095) (xy 376.401562 -235.783781)
			(xy 376.364858 -235.819036) (xy 376.322974 -235.847946) (xy 376.276995 -235.869763) (xy 376.228111 -235.883923)
			(xy 376.17759 -235.890057) (xy 376.126738 -235.888008) (xy 376.076874 -235.877828) (xy 376.029288 -235.859781)
			(xy 375.985214 -235.834335) (xy 375.945792 -235.802148) (xy 375.912044 -235.764054) (xy 375.884843 -235.72104)
			(xy 375.864895 -235.67422) (xy 375.852716 -235.624806) (xy 375.848621 -235.574078) (xy 374.703086 -235.574078)
			(xy 374.703086 -235.990638) (xy 374.70334 -235.991908) (xy 374.70334 -236.000036) (xy 374.704372 -236.007706)
			(xy 374.710445 -236.021932) (xy 374.715278 -236.027976) (xy 374.732804 -236.045502) (xy 374.736127 -236.048619)
			(xy 374.743662 -236.053736) (xy 374.74779 -236.055662) (xy 374.771666 -236.06633) (xy 374.780302 -236.067092)
			(xy 374.80515 -236.069573) (xy 374.853689 -236.081291) (xy 374.8998 -236.100452) (xy 374.942349 -236.126583)
			(xy 374.980292 -236.159043) (xy 375.012696 -236.197035) (xy 375.038764 -236.239623) (xy 375.057855 -236.285763)
			(xy 375.069501 -236.334319) (xy 375.073415 -236.384084) (xy 375.378467 -236.384084) (xy 375.382562 -236.333356)
			(xy 375.394741 -236.283942) (xy 375.414689 -236.237122) (xy 375.44189 -236.194108) (xy 375.475638 -236.156014)
			(xy 375.51506 -236.123827) (xy 375.559134 -236.098381) (xy 375.60672 -236.080334) (xy 375.656584 -236.070154)
			(xy 375.707436 -236.068105) (xy 375.757957 -236.074239) (xy 375.806841 -236.088399) (xy 375.85282 -236.110216)
			(xy 375.894704 -236.139126) (xy 375.931408 -236.174381) (xy 375.961981 -236.215067) (xy 375.985632 -236.26013)
			(xy 376.001748 -236.308404) (xy 376.009912 -236.358638) (xy 376.010424 -236.384084) (xy 376.009921 -236.409073)
			(xy 376.317238 -236.409073) (xy 376.317238 -236.359095) (xy 376.325057 -236.309732) (xy 376.340501 -236.2622)
			(xy 376.363191 -236.217668) (xy 376.392567 -236.177235) (xy 376.427907 -236.141895) (xy 376.46834 -236.112519)
			(xy 376.512872 -236.089829) (xy 376.560404 -236.074385) (xy 376.609767 -236.066566) (xy 376.659745 -236.066566)
			(xy 376.709108 -236.074385) (xy 376.75664 -236.089829) (xy 376.801172 -236.112519) (xy 376.841605 -236.141895)
			(xy 376.876945 -236.177235) (xy 376.906321 -236.217668) (xy 376.929011 -236.2622) (xy 376.944455 -236.309732)
			(xy 376.952274 -236.359095) (xy 376.952764 -236.384084) (xy 377.258575 -236.384084) (xy 377.26267 -236.333356)
			(xy 377.274849 -236.283942) (xy 377.294797 -236.237122) (xy 377.321998 -236.194108) (xy 377.355746 -236.156014)
			(xy 377.395168 -236.123827) (xy 377.439242 -236.098381) (xy 377.486828 -236.080334) (xy 377.536692 -236.070154)
			(xy 377.587544 -236.068105) (xy 377.638065 -236.074239) (xy 377.686949 -236.088399) (xy 377.732928 -236.110216)
			(xy 377.774812 -236.139126) (xy 377.811516 -236.174381) (xy 377.842089 -236.215067) (xy 377.86574 -236.26013)
			(xy 377.881856 -236.308404) (xy 377.89002 -236.358638) (xy 377.890532 -236.384084) (xy 377.890029 -236.409073)
			(xy 378.197346 -236.409073) (xy 378.197346 -236.359095) (xy 378.205165 -236.309732) (xy 378.220609 -236.2622)
			(xy 378.243299 -236.217668) (xy 378.272675 -236.177235) (xy 378.308015 -236.141895) (xy 378.348448 -236.112519)
			(xy 378.39298 -236.089829) (xy 378.440512 -236.074385) (xy 378.489875 -236.066566) (xy 378.539853 -236.066566)
			(xy 378.589216 -236.074385) (xy 378.636748 -236.089829) (xy 378.68128 -236.112519) (xy 378.721713 -236.141895)
			(xy 378.757053 -236.177235) (xy 378.786429 -236.217668) (xy 378.809119 -236.2622) (xy 378.824563 -236.309732)
			(xy 378.832382 -236.359095) (xy 378.832872 -236.384084) (xy 379.138683 -236.384084) (xy 379.142778 -236.333356)
			(xy 379.154957 -236.283942) (xy 379.174905 -236.237122) (xy 379.202106 -236.194108) (xy 379.235854 -236.156014)
			(xy 379.275276 -236.123827) (xy 379.31935 -236.098381) (xy 379.366936 -236.080334) (xy 379.4168 -236.070154)
			(xy 379.467652 -236.068105) (xy 379.518173 -236.074239) (xy 379.567057 -236.088399) (xy 379.613036 -236.110216)
			(xy 379.65492 -236.139126) (xy 379.691624 -236.174381) (xy 379.722197 -236.215067) (xy 379.745848 -236.26013)
			(xy 379.761964 -236.308404) (xy 379.770128 -236.358638) (xy 379.77064 -236.384084) (xy 380.078483 -236.384084)
			(xy 380.082578 -236.333356) (xy 380.094757 -236.283942) (xy 380.114705 -236.237122) (xy 380.141906 -236.194108)
			(xy 380.175654 -236.156014) (xy 380.215076 -236.123827) (xy 380.25915 -236.098381) (xy 380.306736 -236.080334)
			(xy 380.3566 -236.070154) (xy 380.407452 -236.068105) (xy 380.457973 -236.074239) (xy 380.506857 -236.088399)
			(xy 380.552836 -236.110216) (xy 380.59472 -236.139126) (xy 380.631424 -236.174381) (xy 380.661997 -236.215067)
			(xy 380.685648 -236.26013) (xy 380.701764 -236.308404) (xy 380.709928 -236.358638) (xy 380.71044 -236.384084)
			(xy 380.709928 -236.40953) (xy 380.701764 -236.459764) (xy 380.685648 -236.508038) (xy 380.661997 -236.553101)
			(xy 380.631424 -236.593787) (xy 380.59472 -236.629042) (xy 380.552836 -236.657952) (xy 380.506857 -236.679769)
			(xy 380.457973 -236.693929) (xy 380.407452 -236.700063) (xy 380.3566 -236.698014) (xy 380.306736 -236.687834)
			(xy 380.25915 -236.669787) (xy 380.215076 -236.644341) (xy 380.175654 -236.612154) (xy 380.141906 -236.57406)
			(xy 380.114705 -236.531046) (xy 380.094757 -236.484226) (xy 380.082578 -236.434812) (xy 380.078483 -236.384084)
			(xy 379.77064 -236.384084) (xy 379.770128 -236.40953) (xy 379.761964 -236.459764) (xy 379.745848 -236.508038)
			(xy 379.722197 -236.553101) (xy 379.691624 -236.593787) (xy 379.65492 -236.629042) (xy 379.613036 -236.657952)
			(xy 379.567057 -236.679769) (xy 379.518173 -236.693929) (xy 379.467652 -236.700063) (xy 379.4168 -236.698014)
			(xy 379.366936 -236.687834) (xy 379.31935 -236.669787) (xy 379.275276 -236.644341) (xy 379.235854 -236.612154)
			(xy 379.202106 -236.57406) (xy 379.174905 -236.531046) (xy 379.154957 -236.484226) (xy 379.142778 -236.434812)
			(xy 379.138683 -236.384084) (xy 378.832872 -236.384084) (xy 378.832382 -236.409073) (xy 378.824563 -236.458436)
			(xy 378.809119 -236.505968) (xy 378.786429 -236.5505) (xy 378.757053 -236.590933) (xy 378.721713 -236.626273)
			(xy 378.68128 -236.655649) (xy 378.636748 -236.678339) (xy 378.589216 -236.693783) (xy 378.539853 -236.701602)
			(xy 378.489875 -236.701602) (xy 378.440512 -236.693783) (xy 378.39298 -236.678339) (xy 378.348448 -236.655649)
			(xy 378.308015 -236.626273) (xy 378.272675 -236.590933) (xy 378.243299 -236.5505) (xy 378.220609 -236.505968)
			(xy 378.205165 -236.458436) (xy 378.197346 -236.409073) (xy 377.890029 -236.409073) (xy 377.89002 -236.40953)
			(xy 377.881856 -236.459764) (xy 377.86574 -236.508038) (xy 377.842089 -236.553101) (xy 377.811516 -236.593787)
			(xy 377.774812 -236.629042) (xy 377.732928 -236.657952) (xy 377.686949 -236.679769) (xy 377.638065 -236.693929)
			(xy 377.587544 -236.700063) (xy 377.536692 -236.698014) (xy 377.486828 -236.687834) (xy 377.439242 -236.669787)
			(xy 377.395168 -236.644341) (xy 377.355746 -236.612154) (xy 377.321998 -236.57406) (xy 377.294797 -236.531046)
			(xy 377.274849 -236.484226) (xy 377.26267 -236.434812) (xy 377.258575 -236.384084) (xy 376.952764 -236.384084)
			(xy 376.952274 -236.409073) (xy 376.944455 -236.458436) (xy 376.929011 -236.505968) (xy 376.906321 -236.5505)
			(xy 376.876945 -236.590933) (xy 376.841605 -236.626273) (xy 376.801172 -236.655649) (xy 376.75664 -236.678339)
			(xy 376.709108 -236.693783) (xy 376.659745 -236.701602) (xy 376.609767 -236.701602) (xy 376.560404 -236.693783)
			(xy 376.512872 -236.678339) (xy 376.46834 -236.655649) (xy 376.427907 -236.626273) (xy 376.392567 -236.590933)
			(xy 376.363191 -236.5505) (xy 376.340501 -236.505968) (xy 376.325057 -236.458436) (xy 376.317238 -236.409073)
			(xy 376.009921 -236.409073) (xy 376.009912 -236.40953) (xy 376.001748 -236.459764) (xy 375.985632 -236.508038)
			(xy 375.961981 -236.553101) (xy 375.931408 -236.593787) (xy 375.894704 -236.629042) (xy 375.85282 -236.657952)
			(xy 375.806841 -236.679769) (xy 375.757957 -236.693929) (xy 375.707436 -236.700063) (xy 375.656584 -236.698014)
			(xy 375.60672 -236.687834) (xy 375.559134 -236.669787) (xy 375.51506 -236.644341) (xy 375.475638 -236.612154)
			(xy 375.44189 -236.57406) (xy 375.414689 -236.531046) (xy 375.394741 -236.484226) (xy 375.382562 -236.434812)
			(xy 375.378467 -236.384084) (xy 375.073415 -236.384084) (xy 375.073416 -236.384099) (xy 375.069502 -236.433878)
			(xy 375.057856 -236.482435) (xy 375.038765 -236.528574) (xy 375.012697 -236.571163) (xy 374.980294 -236.609155)
			(xy 374.942351 -236.641615) (xy 374.899802 -236.667747) (xy 374.853691 -236.686908) (xy 374.805152 -236.698626)
			(xy 374.780302 -236.701076) (xy 374.771666 -236.701838) (xy 374.74779 -236.712506) (xy 374.743668 -236.714443)
			(xy 374.736132 -236.719557) (xy 374.732804 -236.722666) (xy 374.715278 -236.740192) (xy 374.710435 -236.74623)
			(xy 374.704368 -236.760459) (xy 374.70334 -236.768132) (xy 374.70334 -236.77626) (xy 374.703086 -236.77753)
			(xy 374.703086 -237.219079) (xy 374.907284 -237.219079) (xy 374.907284 -237.169101) (xy 374.915103 -237.119738)
			(xy 374.930547 -237.072206) (xy 374.953237 -237.027674) (xy 374.982613 -236.987241) (xy 375.017953 -236.951901)
			(xy 375.058386 -236.922525) (xy 375.102918 -236.899835) (xy 375.15045 -236.884391) (xy 375.199813 -236.876572)
			(xy 375.249791 -236.876572) (xy 375.299154 -236.884391) (xy 375.346686 -236.899835) (xy 375.391218 -236.922525)
			(xy 375.431651 -236.951901) (xy 375.466991 -236.987241) (xy 375.496367 -237.027674) (xy 375.519057 -237.072206)
			(xy 375.534501 -237.119738) (xy 375.54232 -237.169101) (xy 375.54281 -237.19409) (xy 375.848621 -237.19409)
			(xy 375.852716 -237.143362) (xy 375.864895 -237.093948) (xy 375.884843 -237.047128) (xy 375.912044 -237.004114)
			(xy 375.945792 -236.96602) (xy 375.985214 -236.933833) (xy 376.029288 -236.908387) (xy 376.076874 -236.89034)
			(xy 376.126738 -236.88016) (xy 376.17759 -236.878111) (xy 376.228111 -236.884245) (xy 376.276995 -236.898405)
			(xy 376.322974 -236.920222) (xy 376.364858 -236.949132) (xy 376.401562 -236.984387) (xy 376.432135 -237.025073)
			(xy 376.455786 -237.070136) (xy 376.471902 -237.11841) (xy 376.480066 -237.168644) (xy 376.480578 -237.19409)
			(xy 376.788675 -237.19409) (xy 376.79277 -237.143362) (xy 376.804949 -237.093948) (xy 376.824897 -237.047128)
			(xy 376.852098 -237.004114) (xy 376.885846 -236.96602) (xy 376.925268 -236.933833) (xy 376.969342 -236.908387)
			(xy 377.016928 -236.89034) (xy 377.066792 -236.88016) (xy 377.117644 -236.878111) (xy 377.168165 -236.884245)
			(xy 377.217049 -236.898405) (xy 377.263028 -236.920222) (xy 377.304912 -236.949132) (xy 377.341616 -236.984387)
			(xy 377.372189 -237.025073) (xy 377.39584 -237.070136) (xy 377.411956 -237.11841) (xy 377.42012 -237.168644)
			(xy 377.420632 -237.19409) (xy 378.668529 -237.19409) (xy 378.672624 -237.143362) (xy 378.684803 -237.093948)
			(xy 378.704751 -237.047128) (xy 378.731952 -237.004114) (xy 378.7657 -236.96602) (xy 378.805122 -236.933833)
			(xy 378.849196 -236.908387) (xy 378.896782 -236.89034) (xy 378.946646 -236.88016) (xy 378.997498 -236.878111)
			(xy 379.048019 -236.884245) (xy 379.096903 -236.898405) (xy 379.142882 -236.920222) (xy 379.184766 -236.949132)
			(xy 379.22147 -236.984387) (xy 379.252043 -237.025073) (xy 379.275694 -237.070136) (xy 379.29181 -237.11841)
			(xy 379.299974 -237.168644) (xy 379.300486 -237.19409) (xy 379.299983 -237.219079) (xy 379.6073 -237.219079)
			(xy 379.6073 -237.169101) (xy 379.615119 -237.119738) (xy 379.630563 -237.072206) (xy 379.653253 -237.027674)
			(xy 379.682629 -236.987241) (xy 379.717969 -236.951901) (xy 379.758402 -236.922525) (xy 379.802934 -236.899835)
			(xy 379.850466 -236.884391) (xy 379.899829 -236.876572) (xy 379.949807 -236.876572) (xy 379.99917 -236.884391)
			(xy 380.046702 -236.899835) (xy 380.091234 -236.922525) (xy 380.131667 -236.951901) (xy 380.167007 -236.987241)
			(xy 380.196383 -237.027674) (xy 380.219073 -237.072206) (xy 380.234517 -237.119738) (xy 380.242336 -237.169101)
			(xy 380.242826 -237.19409) (xy 380.548637 -237.19409) (xy 380.552732 -237.143362) (xy 380.564911 -237.093948)
			(xy 380.584859 -237.047128) (xy 380.61206 -237.004114) (xy 380.645808 -236.96602) (xy 380.68523 -236.933833)
			(xy 380.729304 -236.908387) (xy 380.77689 -236.89034) (xy 380.826754 -236.88016) (xy 380.877606 -236.878111)
			(xy 380.928127 -236.884245) (xy 380.977011 -236.898405) (xy 381.02299 -236.920222) (xy 381.064874 -236.949132)
			(xy 381.101578 -236.984387) (xy 381.132151 -237.025073) (xy 381.155802 -237.070136) (xy 381.171918 -237.11841)
			(xy 381.180082 -237.168644) (xy 381.180594 -237.19409) (xy 381.180082 -237.219536) (xy 381.171918 -237.26977)
			(xy 381.155802 -237.318044) (xy 381.132151 -237.363107) (xy 381.101578 -237.403793) (xy 381.064874 -237.439048)
			(xy 381.02299 -237.467958) (xy 380.977011 -237.489775) (xy 380.928127 -237.503935) (xy 380.877606 -237.510069)
			(xy 380.826754 -237.50802) (xy 380.77689 -237.49784) (xy 380.729304 -237.479793) (xy 380.68523 -237.454347)
			(xy 380.645808 -237.42216) (xy 380.61206 -237.384066) (xy 380.584859 -237.341052) (xy 380.564911 -237.294232)
			(xy 380.552732 -237.244818) (xy 380.548637 -237.19409) (xy 380.242826 -237.19409) (xy 380.242336 -237.219079)
			(xy 380.234517 -237.268442) (xy 380.219073 -237.315974) (xy 380.196383 -237.360506) (xy 380.167007 -237.400939)
			(xy 380.131667 -237.436279) (xy 380.091234 -237.465655) (xy 380.046702 -237.488345) (xy 379.99917 -237.503789)
			(xy 379.949807 -237.511608) (xy 379.899829 -237.511608) (xy 379.850466 -237.503789) (xy 379.802934 -237.488345)
			(xy 379.758402 -237.465655) (xy 379.717969 -237.436279) (xy 379.682629 -237.400939) (xy 379.653253 -237.360506)
			(xy 379.630563 -237.315974) (xy 379.615119 -237.268442) (xy 379.6073 -237.219079) (xy 379.299983 -237.219079)
			(xy 379.299974 -237.219536) (xy 379.29181 -237.26977) (xy 379.275694 -237.318044) (xy 379.252043 -237.363107)
			(xy 379.22147 -237.403793) (xy 379.184766 -237.439048) (xy 379.142882 -237.467958) (xy 379.096903 -237.489775)
			(xy 379.048019 -237.503935) (xy 378.997498 -237.510069) (xy 378.946646 -237.50802) (xy 378.896782 -237.49784)
			(xy 378.849196 -237.479793) (xy 378.805122 -237.454347) (xy 378.7657 -237.42216) (xy 378.731952 -237.384066)
			(xy 378.704751 -237.341052) (xy 378.684803 -237.294232) (xy 378.672624 -237.244818) (xy 378.668529 -237.19409)
			(xy 377.420632 -237.19409) (xy 377.42012 -237.219536) (xy 377.411956 -237.26977) (xy 377.39584 -237.318044)
			(xy 377.372189 -237.363107) (xy 377.341616 -237.403793) (xy 377.304912 -237.439048) (xy 377.263028 -237.467958)
			(xy 377.217049 -237.489775) (xy 377.168165 -237.503935) (xy 377.117644 -237.510069) (xy 377.066792 -237.50802)
			(xy 377.016928 -237.49784) (xy 376.969342 -237.479793) (xy 376.925268 -237.454347) (xy 376.885846 -237.42216)
			(xy 376.852098 -237.384066) (xy 376.824897 -237.341052) (xy 376.804949 -237.294232) (xy 376.79277 -237.244818)
			(xy 376.788675 -237.19409) (xy 376.480578 -237.19409) (xy 376.480066 -237.219536) (xy 376.471902 -237.26977)
			(xy 376.455786 -237.318044) (xy 376.432135 -237.363107) (xy 376.401562 -237.403793) (xy 376.364858 -237.439048)
			(xy 376.322974 -237.467958) (xy 376.276995 -237.489775) (xy 376.228111 -237.503935) (xy 376.17759 -237.510069)
			(xy 376.126738 -237.50802) (xy 376.076874 -237.49784) (xy 376.029288 -237.479793) (xy 375.985214 -237.454347)
			(xy 375.945792 -237.42216) (xy 375.912044 -237.384066) (xy 375.884843 -237.341052) (xy 375.864895 -237.294232)
			(xy 375.852716 -237.244818) (xy 375.848621 -237.19409) (xy 375.54281 -237.19409) (xy 375.54232 -237.219079)
			(xy 375.534501 -237.268442) (xy 375.519057 -237.315974) (xy 375.496367 -237.360506) (xy 375.466991 -237.400939)
			(xy 375.431651 -237.436279) (xy 375.391218 -237.465655) (xy 375.346686 -237.488345) (xy 375.299154 -237.503789)
			(xy 375.249791 -237.511608) (xy 375.199813 -237.511608) (xy 375.15045 -237.503789) (xy 375.102918 -237.488345)
			(xy 375.058386 -237.465655) (xy 375.017953 -237.436279) (xy 374.982613 -237.400939) (xy 374.953237 -237.360506)
			(xy 374.930547 -237.315974) (xy 374.915103 -237.268442) (xy 374.907284 -237.219079) (xy 374.703086 -237.219079)
			(xy 374.703086 -238.004096) (xy 375.378467 -238.004096) (xy 375.382562 -237.953368) (xy 375.394741 -237.903954)
			(xy 375.414689 -237.857134) (xy 375.44189 -237.81412) (xy 375.475638 -237.776026) (xy 375.51506 -237.743839)
			(xy 375.559134 -237.718393) (xy 375.60672 -237.700346) (xy 375.656584 -237.690166) (xy 375.707436 -237.688117)
			(xy 375.757957 -237.694251) (xy 375.806841 -237.708411) (xy 375.85282 -237.730228) (xy 375.894704 -237.759138)
			(xy 375.931408 -237.794393) (xy 375.961981 -237.835079) (xy 375.985632 -237.880142) (xy 376.001748 -237.928416)
			(xy 376.009912 -237.97865) (xy 376.010424 -238.004096) (xy 376.009921 -238.029085) (xy 376.317238 -238.029085)
			(xy 376.317238 -237.979107) (xy 376.325057 -237.929744) (xy 376.340501 -237.882212) (xy 376.363191 -237.83768)
			(xy 376.392567 -237.797247) (xy 376.427907 -237.761907) (xy 376.46834 -237.732531) (xy 376.512872 -237.709841)
			(xy 376.560404 -237.694397) (xy 376.609767 -237.686578) (xy 376.659745 -237.686578) (xy 376.709108 -237.694397)
			(xy 376.75664 -237.709841) (xy 376.801172 -237.732531) (xy 376.841605 -237.761907) (xy 376.876945 -237.797247)
			(xy 376.906321 -237.83768) (xy 376.929011 -237.882212) (xy 376.944455 -237.929744) (xy 376.952274 -237.979107)
			(xy 376.952764 -238.004096) (xy 377.258575 -238.004096) (xy 377.26267 -237.953368) (xy 377.274849 -237.903954)
			(xy 377.294797 -237.857134) (xy 377.321998 -237.81412) (xy 377.355746 -237.776026) (xy 377.395168 -237.743839)
			(xy 377.439242 -237.718393) (xy 377.486828 -237.700346) (xy 377.536692 -237.690166) (xy 377.587544 -237.688117)
			(xy 377.638065 -237.694251) (xy 377.686949 -237.708411) (xy 377.732928 -237.730228) (xy 377.774812 -237.759138)
			(xy 377.811516 -237.794393) (xy 377.842089 -237.835079) (xy 377.86574 -237.880142) (xy 377.881856 -237.928416)
			(xy 377.89002 -237.97865) (xy 377.890532 -238.004096) (xy 377.890029 -238.029085) (xy 378.197346 -238.029085)
			(xy 378.197346 -237.979107) (xy 378.205165 -237.929744) (xy 378.220609 -237.882212) (xy 378.243299 -237.83768)
			(xy 378.272675 -237.797247) (xy 378.308015 -237.761907) (xy 378.348448 -237.732531) (xy 378.39298 -237.709841)
			(xy 378.440512 -237.694397) (xy 378.489875 -237.686578) (xy 378.539853 -237.686578) (xy 378.589216 -237.694397)
			(xy 378.636748 -237.709841) (xy 378.68128 -237.732531) (xy 378.721713 -237.761907) (xy 378.757053 -237.797247)
			(xy 378.786429 -237.83768) (xy 378.809119 -237.882212) (xy 378.824563 -237.929744) (xy 378.832382 -237.979107)
			(xy 378.832872 -238.004096) (xy 379.138683 -238.004096) (xy 379.142778 -237.953368) (xy 379.154957 -237.903954)
			(xy 379.174905 -237.857134) (xy 379.202106 -237.81412) (xy 379.235854 -237.776026) (xy 379.275276 -237.743839)
			(xy 379.31935 -237.718393) (xy 379.366936 -237.700346) (xy 379.4168 -237.690166) (xy 379.467652 -237.688117)
			(xy 379.518173 -237.694251) (xy 379.567057 -237.708411) (xy 379.613036 -237.730228) (xy 379.65492 -237.759138)
			(xy 379.691624 -237.794393) (xy 379.722197 -237.835079) (xy 379.745848 -237.880142) (xy 379.761964 -237.928416)
			(xy 379.770128 -237.97865) (xy 379.77064 -238.004096) (xy 380.078483 -238.004096) (xy 380.082578 -237.953368)
			(xy 380.094757 -237.903954) (xy 380.114705 -237.857134) (xy 380.141906 -237.81412) (xy 380.175654 -237.776026)
			(xy 380.215076 -237.743839) (xy 380.25915 -237.718393) (xy 380.306736 -237.700346) (xy 380.3566 -237.690166)
			(xy 380.407452 -237.688117) (xy 380.457973 -237.694251) (xy 380.506857 -237.708411) (xy 380.552836 -237.730228)
			(xy 380.59472 -237.759138) (xy 380.631424 -237.794393) (xy 380.661997 -237.835079) (xy 380.685648 -237.880142)
			(xy 380.701764 -237.928416) (xy 380.709928 -237.97865) (xy 380.71044 -238.004096) (xy 380.709928 -238.029542)
			(xy 380.701764 -238.079776) (xy 380.685648 -238.12805) (xy 380.661997 -238.173113) (xy 380.631424 -238.213799)
			(xy 380.59472 -238.249054) (xy 380.552836 -238.277964) (xy 380.506857 -238.299781) (xy 380.457973 -238.313941)
			(xy 380.407452 -238.320075) (xy 380.3566 -238.318026) (xy 380.306736 -238.307846) (xy 380.25915 -238.289799)
			(xy 380.215076 -238.264353) (xy 380.175654 -238.232166) (xy 380.141906 -238.194072) (xy 380.114705 -238.151058)
			(xy 380.094757 -238.104238) (xy 380.082578 -238.054824) (xy 380.078483 -238.004096) (xy 379.77064 -238.004096)
			(xy 379.770128 -238.029542) (xy 379.761964 -238.079776) (xy 379.745848 -238.12805) (xy 379.722197 -238.173113)
			(xy 379.691624 -238.213799) (xy 379.65492 -238.249054) (xy 379.613036 -238.277964) (xy 379.567057 -238.299781)
			(xy 379.518173 -238.313941) (xy 379.467652 -238.320075) (xy 379.4168 -238.318026) (xy 379.366936 -238.307846)
			(xy 379.31935 -238.289799) (xy 379.275276 -238.264353) (xy 379.235854 -238.232166) (xy 379.202106 -238.194072)
			(xy 379.174905 -238.151058) (xy 379.154957 -238.104238) (xy 379.142778 -238.054824) (xy 379.138683 -238.004096)
			(xy 378.832872 -238.004096) (xy 378.832382 -238.029085) (xy 378.824563 -238.078448) (xy 378.809119 -238.12598)
			(xy 378.786429 -238.170512) (xy 378.757053 -238.210945) (xy 378.721713 -238.246285) (xy 378.68128 -238.275661)
			(xy 378.636748 -238.298351) (xy 378.589216 -238.313795) (xy 378.539853 -238.321614) (xy 378.489875 -238.321614)
			(xy 378.440512 -238.313795) (xy 378.39298 -238.298351) (xy 378.348448 -238.275661) (xy 378.308015 -238.246285)
			(xy 378.272675 -238.210945) (xy 378.243299 -238.170512) (xy 378.220609 -238.12598) (xy 378.205165 -238.078448)
			(xy 378.197346 -238.029085) (xy 377.890029 -238.029085) (xy 377.89002 -238.029542) (xy 377.881856 -238.079776)
			(xy 377.86574 -238.12805) (xy 377.842089 -238.173113) (xy 377.811516 -238.213799) (xy 377.774812 -238.249054)
			(xy 377.732928 -238.277964) (xy 377.686949 -238.299781) (xy 377.638065 -238.313941) (xy 377.587544 -238.320075)
			(xy 377.536692 -238.318026) (xy 377.486828 -238.307846) (xy 377.439242 -238.289799) (xy 377.395168 -238.264353)
			(xy 377.355746 -238.232166) (xy 377.321998 -238.194072) (xy 377.294797 -238.151058) (xy 377.274849 -238.104238)
			(xy 377.26267 -238.054824) (xy 377.258575 -238.004096) (xy 376.952764 -238.004096) (xy 376.952274 -238.029085)
			(xy 376.944455 -238.078448) (xy 376.929011 -238.12598) (xy 376.906321 -238.170512) (xy 376.876945 -238.210945)
			(xy 376.841605 -238.246285) (xy 376.801172 -238.275661) (xy 376.75664 -238.298351) (xy 376.709108 -238.313795)
			(xy 376.659745 -238.321614) (xy 376.609767 -238.321614) (xy 376.560404 -238.313795) (xy 376.512872 -238.298351)
			(xy 376.46834 -238.275661) (xy 376.427907 -238.246285) (xy 376.392567 -238.210945) (xy 376.363191 -238.170512)
			(xy 376.340501 -238.12598) (xy 376.325057 -238.078448) (xy 376.317238 -238.029085) (xy 376.009921 -238.029085)
			(xy 376.009912 -238.029542) (xy 376.001748 -238.079776) (xy 375.985632 -238.12805) (xy 375.961981 -238.173113)
			(xy 375.931408 -238.213799) (xy 375.894704 -238.249054) (xy 375.85282 -238.277964) (xy 375.806841 -238.299781)
			(xy 375.757957 -238.313941) (xy 375.707436 -238.320075) (xy 375.656584 -238.318026) (xy 375.60672 -238.307846)
			(xy 375.559134 -238.289799) (xy 375.51506 -238.264353) (xy 375.475638 -238.232166) (xy 375.44189 -238.194072)
			(xy 375.414689 -238.151058) (xy 375.394741 -238.104238) (xy 375.382562 -238.054824) (xy 375.378467 -238.004096)
			(xy 374.703086 -238.004096) (xy 374.703086 -238.839091) (xy 374.907284 -238.839091) (xy 374.907284 -238.789113)
			(xy 374.915103 -238.73975) (xy 374.930547 -238.692218) (xy 374.953237 -238.647686) (xy 374.982613 -238.607253)
			(xy 375.017953 -238.571913) (xy 375.058386 -238.542537) (xy 375.102918 -238.519847) (xy 375.15045 -238.504403)
			(xy 375.199813 -238.496584) (xy 375.249791 -238.496584) (xy 375.299154 -238.504403) (xy 375.346686 -238.519847)
			(xy 375.391218 -238.542537) (xy 375.431651 -238.571913) (xy 375.466991 -238.607253) (xy 375.496367 -238.647686)
			(xy 375.519057 -238.692218) (xy 375.534501 -238.73975) (xy 375.54232 -238.789113) (xy 375.54281 -238.814102)
			(xy 375.848621 -238.814102) (xy 375.852716 -238.763374) (xy 375.864895 -238.71396) (xy 375.884843 -238.66714)
			(xy 375.912044 -238.624126) (xy 375.945792 -238.586032) (xy 375.985214 -238.553845) (xy 376.029288 -238.528399)
			(xy 376.076874 -238.510352) (xy 376.126738 -238.500172) (xy 376.17759 -238.498123) (xy 376.228111 -238.504257)
			(xy 376.276995 -238.518417) (xy 376.322974 -238.540234) (xy 376.364858 -238.569144) (xy 376.401562 -238.604399)
			(xy 376.432135 -238.645085) (xy 376.455786 -238.690148) (xy 376.471902 -238.738422) (xy 376.480066 -238.788656)
			(xy 376.480578 -238.814102) (xy 376.788675 -238.814102) (xy 376.79277 -238.763374) (xy 376.804949 -238.71396)
			(xy 376.824897 -238.66714) (xy 376.852098 -238.624126) (xy 376.885846 -238.586032) (xy 376.925268 -238.553845)
			(xy 376.969342 -238.528399) (xy 377.016928 -238.510352) (xy 377.066792 -238.500172) (xy 377.117644 -238.498123)
			(xy 377.168165 -238.504257) (xy 377.217049 -238.518417) (xy 377.263028 -238.540234) (xy 377.304912 -238.569144)
			(xy 377.341616 -238.604399) (xy 377.372189 -238.645085) (xy 377.39584 -238.690148) (xy 377.411956 -238.738422)
			(xy 377.42012 -238.788656) (xy 377.420632 -238.814102) (xy 377.420129 -238.839091) (xy 377.727192 -238.839091)
			(xy 377.727192 -238.789113) (xy 377.735011 -238.73975) (xy 377.750455 -238.692218) (xy 377.773145 -238.647686)
			(xy 377.802521 -238.607253) (xy 377.837861 -238.571913) (xy 377.878294 -238.542537) (xy 377.922826 -238.519847)
			(xy 377.970358 -238.504403) (xy 378.019721 -238.496584) (xy 378.069699 -238.496584) (xy 378.119062 -238.504403)
			(xy 378.166594 -238.519847) (xy 378.211126 -238.542537) (xy 378.251559 -238.571913) (xy 378.286899 -238.607253)
			(xy 378.316275 -238.647686) (xy 378.338965 -238.692218) (xy 378.354409 -238.73975) (xy 378.362228 -238.789113)
			(xy 378.362718 -238.814102) (xy 378.668529 -238.814102) (xy 378.672624 -238.763374) (xy 378.684803 -238.71396)
			(xy 378.704751 -238.66714) (xy 378.731952 -238.624126) (xy 378.7657 -238.586032) (xy 378.805122 -238.553845)
			(xy 378.849196 -238.528399) (xy 378.896782 -238.510352) (xy 378.946646 -238.500172) (xy 378.997498 -238.498123)
			(xy 379.048019 -238.504257) (xy 379.096903 -238.518417) (xy 379.142882 -238.540234) (xy 379.184766 -238.569144)
			(xy 379.22147 -238.604399) (xy 379.252043 -238.645085) (xy 379.275694 -238.690148) (xy 379.29181 -238.738422)
			(xy 379.299974 -238.788656) (xy 379.300486 -238.814102) (xy 379.299983 -238.839091) (xy 379.6073 -238.839091)
			(xy 379.6073 -238.789113) (xy 379.615119 -238.73975) (xy 379.630563 -238.692218) (xy 379.653253 -238.647686)
			(xy 379.682629 -238.607253) (xy 379.717969 -238.571913) (xy 379.758402 -238.542537) (xy 379.802934 -238.519847)
			(xy 379.850466 -238.504403) (xy 379.899829 -238.496584) (xy 379.949807 -238.496584) (xy 379.99917 -238.504403)
			(xy 380.046702 -238.519847) (xy 380.091234 -238.542537) (xy 380.131667 -238.571913) (xy 380.167007 -238.607253)
			(xy 380.196383 -238.647686) (xy 380.219073 -238.692218) (xy 380.234517 -238.73975) (xy 380.242336 -238.789113)
			(xy 380.242826 -238.814102) (xy 380.548637 -238.814102) (xy 380.552732 -238.763374) (xy 380.564911 -238.71396)
			(xy 380.584859 -238.66714) (xy 380.61206 -238.624126) (xy 380.645808 -238.586032) (xy 380.68523 -238.553845)
			(xy 380.729304 -238.528399) (xy 380.77689 -238.510352) (xy 380.826754 -238.500172) (xy 380.877606 -238.498123)
			(xy 380.928127 -238.504257) (xy 380.977011 -238.518417) (xy 381.02299 -238.540234) (xy 381.064874 -238.569144)
			(xy 381.101578 -238.604399) (xy 381.132151 -238.645085) (xy 381.155802 -238.690148) (xy 381.171918 -238.738422)
			(xy 381.180082 -238.788656) (xy 381.180594 -238.814102) (xy 381.180082 -238.839548) (xy 381.171918 -238.889782)
			(xy 381.155802 -238.938056) (xy 381.132151 -238.983119) (xy 381.101578 -239.023805) (xy 381.064874 -239.05906)
			(xy 381.02299 -239.08797) (xy 380.977011 -239.109787) (xy 380.928127 -239.123947) (xy 380.877606 -239.130081)
			(xy 380.826754 -239.128032) (xy 380.77689 -239.117852) (xy 380.729304 -239.099805) (xy 380.68523 -239.074359)
			(xy 380.645808 -239.042172) (xy 380.61206 -239.004078) (xy 380.584859 -238.961064) (xy 380.564911 -238.914244)
			(xy 380.552732 -238.86483) (xy 380.548637 -238.814102) (xy 380.242826 -238.814102) (xy 380.242336 -238.839091)
			(xy 380.234517 -238.888454) (xy 380.219073 -238.935986) (xy 380.196383 -238.980518) (xy 380.167007 -239.020951)
			(xy 380.131667 -239.056291) (xy 380.091234 -239.085667) (xy 380.046702 -239.108357) (xy 379.99917 -239.123801)
			(xy 379.949807 -239.13162) (xy 379.899829 -239.13162) (xy 379.850466 -239.123801) (xy 379.802934 -239.108357)
			(xy 379.758402 -239.085667) (xy 379.717969 -239.056291) (xy 379.682629 -239.020951) (xy 379.653253 -238.980518)
			(xy 379.630563 -238.935986) (xy 379.615119 -238.888454) (xy 379.6073 -238.839091) (xy 379.299983 -238.839091)
			(xy 379.299974 -238.839548) (xy 379.29181 -238.889782) (xy 379.275694 -238.938056) (xy 379.252043 -238.983119)
			(xy 379.22147 -239.023805) (xy 379.184766 -239.05906) (xy 379.142882 -239.08797) (xy 379.096903 -239.109787)
			(xy 379.048019 -239.123947) (xy 378.997498 -239.130081) (xy 378.946646 -239.128032) (xy 378.896782 -239.117852)
			(xy 378.849196 -239.099805) (xy 378.805122 -239.074359) (xy 378.7657 -239.042172) (xy 378.731952 -239.004078)
			(xy 378.704751 -238.961064) (xy 378.684803 -238.914244) (xy 378.672624 -238.86483) (xy 378.668529 -238.814102)
			(xy 378.362718 -238.814102) (xy 378.362228 -238.839091) (xy 378.354409 -238.888454) (xy 378.338965 -238.935986)
			(xy 378.316275 -238.980518) (xy 378.286899 -239.020951) (xy 378.251559 -239.056291) (xy 378.211126 -239.085667)
			(xy 378.166594 -239.108357) (xy 378.119062 -239.123801) (xy 378.069699 -239.13162) (xy 378.019721 -239.13162)
			(xy 377.970358 -239.123801) (xy 377.922826 -239.108357) (xy 377.878294 -239.085667) (xy 377.837861 -239.056291)
			(xy 377.802521 -239.020951) (xy 377.773145 -238.980518) (xy 377.750455 -238.935986) (xy 377.735011 -238.888454)
			(xy 377.727192 -238.839091) (xy 377.420129 -238.839091) (xy 377.42012 -238.839548) (xy 377.411956 -238.889782)
			(xy 377.39584 -238.938056) (xy 377.372189 -238.983119) (xy 377.341616 -239.023805) (xy 377.304912 -239.05906)
			(xy 377.263028 -239.08797) (xy 377.217049 -239.109787) (xy 377.168165 -239.123947) (xy 377.117644 -239.130081)
			(xy 377.066792 -239.128032) (xy 377.016928 -239.117852) (xy 376.969342 -239.099805) (xy 376.925268 -239.074359)
			(xy 376.885846 -239.042172) (xy 376.852098 -239.004078) (xy 376.824897 -238.961064) (xy 376.804949 -238.914244)
			(xy 376.79277 -238.86483) (xy 376.788675 -238.814102) (xy 376.480578 -238.814102) (xy 376.480066 -238.839548)
			(xy 376.471902 -238.889782) (xy 376.455786 -238.938056) (xy 376.432135 -238.983119) (xy 376.401562 -239.023805)
			(xy 376.364858 -239.05906) (xy 376.322974 -239.08797) (xy 376.276995 -239.109787) (xy 376.228111 -239.123947)
			(xy 376.17759 -239.130081) (xy 376.126738 -239.128032) (xy 376.076874 -239.117852) (xy 376.029288 -239.099805)
			(xy 375.985214 -239.074359) (xy 375.945792 -239.042172) (xy 375.912044 -239.004078) (xy 375.884843 -238.961064)
			(xy 375.864895 -238.914244) (xy 375.852716 -238.86483) (xy 375.848621 -238.814102) (xy 375.54281 -238.814102)
			(xy 375.54232 -238.839091) (xy 375.534501 -238.888454) (xy 375.519057 -238.935986) (xy 375.496367 -238.980518)
			(xy 375.466991 -239.020951) (xy 375.431651 -239.056291) (xy 375.391218 -239.085667) (xy 375.346686 -239.108357)
			(xy 375.299154 -239.123801) (xy 375.249791 -239.13162) (xy 375.199813 -239.13162) (xy 375.15045 -239.123801)
			(xy 375.102918 -239.108357) (xy 375.058386 -239.085667) (xy 375.017953 -239.056291) (xy 374.982613 -239.020951)
			(xy 374.953237 -238.980518) (xy 374.930547 -238.935986) (xy 374.915103 -238.888454) (xy 374.907284 -238.839091)
			(xy 374.703086 -238.839091) (xy 374.703086 -239.230662) (xy 374.70334 -239.231932) (xy 374.70334 -239.24006)
			(xy 374.704375 -239.247729) (xy 374.710453 -239.26195) (xy 374.715278 -239.268) (xy 374.732804 -239.285526)
			(xy 374.736127 -239.288641) (xy 374.743664 -239.293756) (xy 374.74779 -239.295686) (xy 374.771666 -239.306354)
			(xy 374.780302 -239.307116) (xy 374.805148 -239.309597) (xy 374.853683 -239.321315) (xy 374.89979 -239.340474)
			(xy 374.942337 -239.366604) (xy 374.980277 -239.399062) (xy 375.012678 -239.43705) (xy 375.038743 -239.479636)
			(xy 375.057833 -239.525772) (xy 375.069478 -239.574325) (xy 375.073392 -239.624101) (xy 375.073391 -239.624108)
			(xy 375.378467 -239.624108) (xy 375.382562 -239.57338) (xy 375.394741 -239.523966) (xy 375.414689 -239.477146)
			(xy 375.44189 -239.434132) (xy 375.475638 -239.396038) (xy 375.51506 -239.363851) (xy 375.559134 -239.338405)
			(xy 375.60672 -239.320358) (xy 375.656584 -239.310178) (xy 375.707436 -239.308129) (xy 375.757957 -239.314263)
			(xy 375.806841 -239.328423) (xy 375.85282 -239.35024) (xy 375.894704 -239.37915) (xy 375.931408 -239.414405)
			(xy 375.961981 -239.455091) (xy 375.985632 -239.500154) (xy 376.001748 -239.548428) (xy 376.009912 -239.598662)
			(xy 376.010424 -239.624108) (xy 376.009921 -239.649097) (xy 376.317238 -239.649097) (xy 376.317238 -239.599119)
			(xy 376.325057 -239.549756) (xy 376.340501 -239.502224) (xy 376.363191 -239.457692) (xy 376.392567 -239.417259)
			(xy 376.427907 -239.381919) (xy 376.46834 -239.352543) (xy 376.512872 -239.329853) (xy 376.560404 -239.314409)
			(xy 376.609767 -239.30659) (xy 376.659745 -239.30659) (xy 376.709108 -239.314409) (xy 376.75664 -239.329853)
			(xy 376.801172 -239.352543) (xy 376.841605 -239.381919) (xy 376.876945 -239.417259) (xy 376.906321 -239.457692)
			(xy 376.929011 -239.502224) (xy 376.944455 -239.549756) (xy 376.952274 -239.599119) (xy 376.952764 -239.624108)
			(xy 377.258575 -239.624108) (xy 377.26267 -239.57338) (xy 377.274849 -239.523966) (xy 377.294797 -239.477146)
			(xy 377.321998 -239.434132) (xy 377.355746 -239.396038) (xy 377.395168 -239.363851) (xy 377.439242 -239.338405)
			(xy 377.486828 -239.320358) (xy 377.536692 -239.310178) (xy 377.587544 -239.308129) (xy 377.638065 -239.314263)
			(xy 377.686949 -239.328423) (xy 377.732928 -239.35024) (xy 377.774812 -239.37915) (xy 377.811516 -239.414405)
			(xy 377.842089 -239.455091) (xy 377.86574 -239.500154) (xy 377.881856 -239.548428) (xy 377.89002 -239.598662)
			(xy 377.890532 -239.624108) (xy 379.138683 -239.624108) (xy 379.142778 -239.57338) (xy 379.154957 -239.523966)
			(xy 379.174905 -239.477146) (xy 379.202106 -239.434132) (xy 379.235854 -239.396038) (xy 379.275276 -239.363851)
			(xy 379.31935 -239.338405) (xy 379.366936 -239.320358) (xy 379.4168 -239.310178) (xy 379.467652 -239.308129)
			(xy 379.518173 -239.314263) (xy 379.567057 -239.328423) (xy 379.613036 -239.35024) (xy 379.65492 -239.37915)
			(xy 379.691624 -239.414405) (xy 379.722197 -239.455091) (xy 379.745848 -239.500154) (xy 379.761964 -239.548428)
			(xy 379.770128 -239.598662) (xy 379.77064 -239.624108) (xy 380.078483 -239.624108) (xy 380.082578 -239.57338)
			(xy 380.094757 -239.523966) (xy 380.114705 -239.477146) (xy 380.141906 -239.434132) (xy 380.175654 -239.396038)
			(xy 380.215076 -239.363851) (xy 380.25915 -239.338405) (xy 380.306736 -239.320358) (xy 380.3566 -239.310178)
			(xy 380.407452 -239.308129) (xy 380.457973 -239.314263) (xy 380.506857 -239.328423) (xy 380.552836 -239.35024)
			(xy 380.59472 -239.37915) (xy 380.631424 -239.414405) (xy 380.661997 -239.455091) (xy 380.685648 -239.500154)
			(xy 380.701764 -239.548428) (xy 380.709928 -239.598662) (xy 380.71044 -239.624108) (xy 380.709928 -239.649554)
			(xy 380.701764 -239.699788) (xy 380.685648 -239.748062) (xy 380.661997 -239.793125) (xy 380.631424 -239.833811)
			(xy 380.59472 -239.869066) (xy 380.552836 -239.897976) (xy 380.506857 -239.919793) (xy 380.457973 -239.933953)
			(xy 380.407452 -239.940087) (xy 380.3566 -239.938038) (xy 380.306736 -239.927858) (xy 380.25915 -239.909811)
			(xy 380.215076 -239.884365) (xy 380.175654 -239.852178) (xy 380.141906 -239.814084) (xy 380.114705 -239.77107)
			(xy 380.094757 -239.72425) (xy 380.082578 -239.674836) (xy 380.078483 -239.624108) (xy 379.77064 -239.624108)
			(xy 379.770128 -239.649554) (xy 379.761964 -239.699788) (xy 379.745848 -239.748062) (xy 379.722197 -239.793125)
			(xy 379.691624 -239.833811) (xy 379.65492 -239.869066) (xy 379.613036 -239.897976) (xy 379.567057 -239.919793)
			(xy 379.518173 -239.933953) (xy 379.467652 -239.940087) (xy 379.4168 -239.938038) (xy 379.366936 -239.927858)
			(xy 379.31935 -239.909811) (xy 379.275276 -239.884365) (xy 379.235854 -239.852178) (xy 379.202106 -239.814084)
			(xy 379.174905 -239.77107) (xy 379.154957 -239.72425) (xy 379.142778 -239.674836) (xy 379.138683 -239.624108)
			(xy 377.890532 -239.624108) (xy 377.89002 -239.649554) (xy 377.881856 -239.699788) (xy 377.86574 -239.748062)
			(xy 377.842089 -239.793125) (xy 377.811516 -239.833811) (xy 377.774812 -239.869066) (xy 377.732928 -239.897976)
			(xy 377.686949 -239.919793) (xy 377.638065 -239.933953) (xy 377.587544 -239.940087) (xy 377.536692 -239.938038)
			(xy 377.486828 -239.927858) (xy 377.439242 -239.909811) (xy 377.395168 -239.884365) (xy 377.355746 -239.852178)
			(xy 377.321998 -239.814084) (xy 377.294797 -239.77107) (xy 377.274849 -239.72425) (xy 377.26267 -239.674836)
			(xy 377.258575 -239.624108) (xy 376.952764 -239.624108) (xy 376.952274 -239.649097) (xy 376.944455 -239.69846)
			(xy 376.929011 -239.745992) (xy 376.906321 -239.790524) (xy 376.876945 -239.830957) (xy 376.841605 -239.866297)
			(xy 376.801172 -239.895673) (xy 376.75664 -239.918363) (xy 376.709108 -239.933807) (xy 376.659745 -239.941626)
			(xy 376.609767 -239.941626) (xy 376.560404 -239.933807) (xy 376.512872 -239.918363) (xy 376.46834 -239.895673)
			(xy 376.427907 -239.866297) (xy 376.392567 -239.830957) (xy 376.363191 -239.790524) (xy 376.340501 -239.745992)
			(xy 376.325057 -239.69846) (xy 376.317238 -239.649097) (xy 376.009921 -239.649097) (xy 376.009912 -239.649554)
			(xy 376.001748 -239.699788) (xy 375.985632 -239.748062) (xy 375.961981 -239.793125) (xy 375.931408 -239.833811)
			(xy 375.894704 -239.869066) (xy 375.85282 -239.897976) (xy 375.806841 -239.919793) (xy 375.757957 -239.933953)
			(xy 375.707436 -239.940087) (xy 375.656584 -239.938038) (xy 375.60672 -239.927858) (xy 375.559134 -239.909811)
			(xy 375.51506 -239.884365) (xy 375.475638 -239.852178) (xy 375.44189 -239.814084) (xy 375.414689 -239.77107)
			(xy 375.394741 -239.72425) (xy 375.382562 -239.674836) (xy 375.378467 -239.624108) (xy 375.073391 -239.624108)
			(xy 375.069478 -239.673877) (xy 375.057833 -239.722429) (xy 375.038743 -239.768565) (xy 375.012677 -239.811151)
			(xy 374.980276 -239.849139) (xy 374.942336 -239.881597) (xy 374.899789 -239.907727) (xy 374.853682 -239.926886)
			(xy 374.805147 -239.938603) (xy 374.780302 -239.9411) (xy 374.771666 -239.941862) (xy 374.74779 -239.95253)
			(xy 374.743669 -239.954469) (xy 374.736135 -239.959584) (xy 374.732804 -239.96269) (xy 374.715278 -239.980216)
			(xy 374.710438 -239.986255) (xy 374.704378 -240.000485) (xy 374.70334 -240.008156) (xy 374.70334 -240.016284)
			(xy 374.703086 -240.017554) (xy 374.703086 -240.434114) (xy 375.848621 -240.434114) (xy 375.852716 -240.383386)
			(xy 375.864895 -240.333972) (xy 375.884843 -240.287152) (xy 375.912044 -240.244138) (xy 375.945792 -240.206044)
			(xy 375.985214 -240.173857) (xy 376.029288 -240.148411) (xy 376.076874 -240.130364) (xy 376.126738 -240.120184)
			(xy 376.17759 -240.118135) (xy 376.228111 -240.124269) (xy 376.276995 -240.138429) (xy 376.322974 -240.160246)
			(xy 376.364858 -240.189156) (xy 376.401562 -240.224411) (xy 376.432135 -240.265097) (xy 376.455786 -240.31016)
			(xy 376.471902 -240.358434) (xy 376.480066 -240.408668) (xy 376.480578 -240.434114) (xy 376.788675 -240.434114)
			(xy 376.79277 -240.383386) (xy 376.804949 -240.333972) (xy 376.824897 -240.287152) (xy 376.852098 -240.244138)
			(xy 376.885846 -240.206044) (xy 376.925268 -240.173857) (xy 376.969342 -240.148411) (xy 377.016928 -240.130364)
			(xy 377.066792 -240.120184) (xy 377.117644 -240.118135) (xy 377.168165 -240.124269) (xy 377.217049 -240.138429)
			(xy 377.263028 -240.160246) (xy 377.304912 -240.189156) (xy 377.341616 -240.224411) (xy 377.372189 -240.265097)
			(xy 377.39584 -240.31016) (xy 377.411956 -240.358434) (xy 377.42012 -240.408668) (xy 377.420632 -240.434114)
			(xy 377.420129 -240.459103) (xy 377.727192 -240.459103) (xy 377.727192 -240.409125) (xy 377.735011 -240.359762)
			(xy 377.750455 -240.31223) (xy 377.773145 -240.267698) (xy 377.802521 -240.227265) (xy 377.837861 -240.191925)
			(xy 377.878294 -240.162549) (xy 377.922826 -240.139859) (xy 377.970358 -240.124415) (xy 378.019721 -240.116596)
			(xy 378.069699 -240.116596) (xy 378.119062 -240.124415) (xy 378.166594 -240.139859) (xy 378.211126 -240.162549)
			(xy 378.251559 -240.191925) (xy 378.286899 -240.227265) (xy 378.316275 -240.267698) (xy 378.338965 -240.31223)
			(xy 378.354409 -240.359762) (xy 378.362228 -240.409125) (xy 378.362718 -240.434114) (xy 378.668529 -240.434114)
			(xy 378.672624 -240.383386) (xy 378.684803 -240.333972) (xy 378.704751 -240.287152) (xy 378.731952 -240.244138)
			(xy 378.7657 -240.206044) (xy 378.805122 -240.173857) (xy 378.849196 -240.148411) (xy 378.896782 -240.130364)
			(xy 378.946646 -240.120184) (xy 378.997498 -240.118135) (xy 379.048019 -240.124269) (xy 379.096903 -240.138429)
			(xy 379.142882 -240.160246) (xy 379.184766 -240.189156) (xy 379.22147 -240.224411) (xy 379.252043 -240.265097)
			(xy 379.275694 -240.31016) (xy 379.29181 -240.358434) (xy 379.299974 -240.408668) (xy 379.300486 -240.434114)
			(xy 379.299983 -240.459103) (xy 379.6073 -240.459103) (xy 379.6073 -240.409125) (xy 379.615119 -240.359762)
			(xy 379.630563 -240.31223) (xy 379.653253 -240.267698) (xy 379.682629 -240.227265) (xy 379.717969 -240.191925)
			(xy 379.758402 -240.162549) (xy 379.802934 -240.139859) (xy 379.850466 -240.124415) (xy 379.899829 -240.116596)
			(xy 379.949807 -240.116596) (xy 379.99917 -240.124415) (xy 380.046702 -240.139859) (xy 380.091234 -240.162549)
			(xy 380.131667 -240.191925) (xy 380.167007 -240.227265) (xy 380.196383 -240.267698) (xy 380.219073 -240.31223)
			(xy 380.234517 -240.359762) (xy 380.242336 -240.409125) (xy 380.242826 -240.434114) (xy 380.548637 -240.434114)
			(xy 380.552732 -240.383386) (xy 380.564911 -240.333972) (xy 380.584859 -240.287152) (xy 380.61206 -240.244138)
			(xy 380.645808 -240.206044) (xy 380.68523 -240.173857) (xy 380.729304 -240.148411) (xy 380.77689 -240.130364)
			(xy 380.826754 -240.120184) (xy 380.877606 -240.118135) (xy 380.928127 -240.124269) (xy 380.977011 -240.138429)
			(xy 381.02299 -240.160246) (xy 381.064874 -240.189156) (xy 381.101578 -240.224411) (xy 381.132151 -240.265097)
			(xy 381.155802 -240.31016) (xy 381.171918 -240.358434) (xy 381.180082 -240.408668) (xy 381.180594 -240.434114)
			(xy 381.180082 -240.45956) (xy 381.171918 -240.509794) (xy 381.155802 -240.558068) (xy 381.132151 -240.603131)
			(xy 381.101578 -240.643817) (xy 381.064874 -240.679072) (xy 381.02299 -240.707982) (xy 380.977011 -240.729799)
			(xy 380.928127 -240.743959) (xy 380.877606 -240.750093) (xy 380.826754 -240.748044) (xy 380.77689 -240.737864)
			(xy 380.729304 -240.719817) (xy 380.68523 -240.694371) (xy 380.645808 -240.662184) (xy 380.61206 -240.62409)
			(xy 380.584859 -240.581076) (xy 380.564911 -240.534256) (xy 380.552732 -240.484842) (xy 380.548637 -240.434114)
			(xy 380.242826 -240.434114) (xy 380.242336 -240.459103) (xy 380.234517 -240.508466) (xy 380.219073 -240.555998)
			(xy 380.196383 -240.60053) (xy 380.167007 -240.640963) (xy 380.131667 -240.676303) (xy 380.091234 -240.705679)
			(xy 380.046702 -240.728369) (xy 379.99917 -240.743813) (xy 379.949807 -240.751632) (xy 379.899829 -240.751632)
			(xy 379.850466 -240.743813) (xy 379.802934 -240.728369) (xy 379.758402 -240.705679) (xy 379.717969 -240.676303)
			(xy 379.682629 -240.640963) (xy 379.653253 -240.60053) (xy 379.630563 -240.555998) (xy 379.615119 -240.508466)
			(xy 379.6073 -240.459103) (xy 379.299983 -240.459103) (xy 379.299974 -240.45956) (xy 379.29181 -240.509794)
			(xy 379.275694 -240.558068) (xy 379.252043 -240.603131) (xy 379.22147 -240.643817) (xy 379.184766 -240.679072)
			(xy 379.142882 -240.707982) (xy 379.096903 -240.729799) (xy 379.048019 -240.743959) (xy 378.997498 -240.750093)
			(xy 378.946646 -240.748044) (xy 378.896782 -240.737864) (xy 378.849196 -240.719817) (xy 378.805122 -240.694371)
			(xy 378.7657 -240.662184) (xy 378.731952 -240.62409) (xy 378.704751 -240.581076) (xy 378.684803 -240.534256)
			(xy 378.672624 -240.484842) (xy 378.668529 -240.434114) (xy 378.362718 -240.434114) (xy 378.362228 -240.459103)
			(xy 378.354409 -240.508466) (xy 378.338965 -240.555998) (xy 378.316275 -240.60053) (xy 378.286899 -240.640963)
			(xy 378.251559 -240.676303) (xy 378.211126 -240.705679) (xy 378.166594 -240.728369) (xy 378.119062 -240.743813)
			(xy 378.069699 -240.751632) (xy 378.019721 -240.751632) (xy 377.970358 -240.743813) (xy 377.922826 -240.728369)
			(xy 377.878294 -240.705679) (xy 377.837861 -240.676303) (xy 377.802521 -240.640963) (xy 377.773145 -240.60053)
			(xy 377.750455 -240.555998) (xy 377.735011 -240.508466) (xy 377.727192 -240.459103) (xy 377.420129 -240.459103)
			(xy 377.42012 -240.45956) (xy 377.411956 -240.509794) (xy 377.39584 -240.558068) (xy 377.372189 -240.603131)
			(xy 377.341616 -240.643817) (xy 377.304912 -240.679072) (xy 377.263028 -240.707982) (xy 377.217049 -240.729799)
			(xy 377.168165 -240.743959) (xy 377.117644 -240.750093) (xy 377.066792 -240.748044) (xy 377.016928 -240.737864)
			(xy 376.969342 -240.719817) (xy 376.925268 -240.694371) (xy 376.885846 -240.662184) (xy 376.852098 -240.62409)
			(xy 376.824897 -240.581076) (xy 376.804949 -240.534256) (xy 376.79277 -240.484842) (xy 376.788675 -240.434114)
			(xy 376.480578 -240.434114) (xy 376.480066 -240.45956) (xy 376.471902 -240.509794) (xy 376.455786 -240.558068)
			(xy 376.432135 -240.603131) (xy 376.401562 -240.643817) (xy 376.364858 -240.679072) (xy 376.322974 -240.707982)
			(xy 376.276995 -240.729799) (xy 376.228111 -240.743959) (xy 376.17759 -240.750093) (xy 376.126738 -240.748044)
			(xy 376.076874 -240.737864) (xy 376.029288 -240.719817) (xy 375.985214 -240.694371) (xy 375.945792 -240.662184)
			(xy 375.912044 -240.62409) (xy 375.884843 -240.581076) (xy 375.864895 -240.534256) (xy 375.852716 -240.484842)
			(xy 375.848621 -240.434114) (xy 374.703086 -240.434114) (xy 374.703086 -240.850674) (xy 374.70334 -240.851944)
			(xy 374.70334 -240.860072) (xy 374.704377 -240.86774) (xy 374.710457 -240.881959) (xy 374.715278 -240.888012)
			(xy 374.732804 -240.905538) (xy 374.736128 -240.908653) (xy 374.743665 -240.913767) (xy 374.74779 -240.915698)
			(xy 374.771666 -240.926366) (xy 374.780302 -240.927128) (xy 374.805147 -240.929609) (xy 374.85368 -240.941326)
			(xy 374.899786 -240.960485) (xy 374.942331 -240.986614) (xy 374.980269 -241.019071) (xy 375.012669 -241.057058)
			(xy 375.038733 -241.099642) (xy 375.057822 -241.145777) (xy 375.069466 -241.194328) (xy 375.07338 -241.244102)
			(xy 375.073379 -241.24412) (xy 375.378467 -241.24412) (xy 375.382562 -241.193392) (xy 375.394741 -241.143978)
			(xy 375.414689 -241.097158) (xy 375.44189 -241.054144) (xy 375.475638 -241.01605) (xy 375.51506 -240.983863)
			(xy 375.559134 -240.958417) (xy 375.60672 -240.94037) (xy 375.656584 -240.93019) (xy 375.707436 -240.928141)
			(xy 375.757957 -240.934275) (xy 375.806841 -240.948435) (xy 375.85282 -240.970252) (xy 375.894704 -240.999162)
			(xy 375.931408 -241.034417) (xy 375.961981 -241.075103) (xy 375.985632 -241.120166) (xy 376.001748 -241.16844)
			(xy 376.009912 -241.218674) (xy 376.010424 -241.24412) (xy 376.009921 -241.269109) (xy 376.317238 -241.269109)
			(xy 376.317238 -241.219131) (xy 376.325057 -241.169768) (xy 376.340501 -241.122236) (xy 376.363191 -241.077704)
			(xy 376.392567 -241.037271) (xy 376.427907 -241.001931) (xy 376.46834 -240.972555) (xy 376.512872 -240.949865)
			(xy 376.560404 -240.934421) (xy 376.609767 -240.926602) (xy 376.659745 -240.926602) (xy 376.709108 -240.934421)
			(xy 376.75664 -240.949865) (xy 376.801172 -240.972555) (xy 376.841605 -241.001931) (xy 376.876945 -241.037271)
			(xy 376.906321 -241.077704) (xy 376.929011 -241.122236) (xy 376.944455 -241.169768) (xy 376.952274 -241.219131)
			(xy 376.952764 -241.24412) (xy 377.258575 -241.24412) (xy 377.26267 -241.193392) (xy 377.274849 -241.143978)
			(xy 377.294797 -241.097158) (xy 377.321998 -241.054144) (xy 377.355746 -241.01605) (xy 377.395168 -240.983863)
			(xy 377.439242 -240.958417) (xy 377.486828 -240.94037) (xy 377.536692 -240.93019) (xy 377.587544 -240.928141)
			(xy 377.638065 -240.934275) (xy 377.686949 -240.948435) (xy 377.732928 -240.970252) (xy 377.774812 -240.999162)
			(xy 377.811516 -241.034417) (xy 377.842089 -241.075103) (xy 377.86574 -241.120166) (xy 377.881856 -241.16844)
			(xy 377.89002 -241.218674) (xy 377.890532 -241.24412) (xy 377.890029 -241.269109) (xy 378.197346 -241.269109)
			(xy 378.197346 -241.219131) (xy 378.205165 -241.169768) (xy 378.220609 -241.122236) (xy 378.243299 -241.077704)
			(xy 378.272675 -241.037271) (xy 378.308015 -241.001931) (xy 378.348448 -240.972555) (xy 378.39298 -240.949865)
			(xy 378.440512 -240.934421) (xy 378.489875 -240.926602) (xy 378.539853 -240.926602) (xy 378.589216 -240.934421)
			(xy 378.636748 -240.949865) (xy 378.68128 -240.972555) (xy 378.721713 -241.001931) (xy 378.757053 -241.037271)
			(xy 378.786429 -241.077704) (xy 378.809119 -241.122236) (xy 378.824563 -241.169768) (xy 378.832382 -241.219131)
			(xy 378.832872 -241.24412) (xy 379.138683 -241.24412) (xy 379.142778 -241.193392) (xy 379.154957 -241.143978)
			(xy 379.174905 -241.097158) (xy 379.202106 -241.054144) (xy 379.235854 -241.01605) (xy 379.275276 -240.983863)
			(xy 379.31935 -240.958417) (xy 379.366936 -240.94037) (xy 379.4168 -240.93019) (xy 379.467652 -240.928141)
			(xy 379.518173 -240.934275) (xy 379.567057 -240.948435) (xy 379.613036 -240.970252) (xy 379.65492 -240.999162)
			(xy 379.691624 -241.034417) (xy 379.722197 -241.075103) (xy 379.745848 -241.120166) (xy 379.761964 -241.16844)
			(xy 379.770128 -241.218674) (xy 379.77064 -241.24412) (xy 380.078483 -241.24412) (xy 380.082578 -241.193392)
			(xy 380.094757 -241.143978) (xy 380.114705 -241.097158) (xy 380.141906 -241.054144) (xy 380.175654 -241.01605)
			(xy 380.215076 -240.983863) (xy 380.25915 -240.958417) (xy 380.306736 -240.94037) (xy 380.3566 -240.93019)
			(xy 380.407452 -240.928141) (xy 380.457973 -240.934275) (xy 380.506857 -240.948435) (xy 380.552836 -240.970252)
			(xy 380.59472 -240.999162) (xy 380.631424 -241.034417) (xy 380.661997 -241.075103) (xy 380.685648 -241.120166)
			(xy 380.701764 -241.16844) (xy 380.709928 -241.218674) (xy 380.71044 -241.24412) (xy 380.709928 -241.269566)
			(xy 380.701764 -241.3198) (xy 380.685648 -241.368074) (xy 380.661997 -241.413137) (xy 380.631424 -241.453823)
			(xy 380.59472 -241.489078) (xy 380.552836 -241.517988) (xy 380.506857 -241.539805) (xy 380.457973 -241.553965)
			(xy 380.407452 -241.560099) (xy 380.3566 -241.55805) (xy 380.306736 -241.54787) (xy 380.25915 -241.529823)
			(xy 380.215076 -241.504377) (xy 380.175654 -241.47219) (xy 380.141906 -241.434096) (xy 380.114705 -241.391082)
			(xy 380.094757 -241.344262) (xy 380.082578 -241.294848) (xy 380.078483 -241.24412) (xy 379.77064 -241.24412)
			(xy 379.770128 -241.269566) (xy 379.761964 -241.3198) (xy 379.745848 -241.368074) (xy 379.722197 -241.413137)
			(xy 379.691624 -241.453823) (xy 379.65492 -241.489078) (xy 379.613036 -241.517988) (xy 379.567057 -241.539805)
			(xy 379.518173 -241.553965) (xy 379.467652 -241.560099) (xy 379.4168 -241.55805) (xy 379.366936 -241.54787)
			(xy 379.31935 -241.529823) (xy 379.275276 -241.504377) (xy 379.235854 -241.47219) (xy 379.202106 -241.434096)
			(xy 379.174905 -241.391082) (xy 379.154957 -241.344262) (xy 379.142778 -241.294848) (xy 379.138683 -241.24412)
			(xy 378.832872 -241.24412) (xy 378.832382 -241.269109) (xy 378.824563 -241.318472) (xy 378.809119 -241.366004)
			(xy 378.786429 -241.410536) (xy 378.757053 -241.450969) (xy 378.721713 -241.486309) (xy 378.68128 -241.515685)
			(xy 378.636748 -241.538375) (xy 378.589216 -241.553819) (xy 378.539853 -241.561638) (xy 378.489875 -241.561638)
			(xy 378.440512 -241.553819) (xy 378.39298 -241.538375) (xy 378.348448 -241.515685) (xy 378.308015 -241.486309)
			(xy 378.272675 -241.450969) (xy 378.243299 -241.410536) (xy 378.220609 -241.366004) (xy 378.205165 -241.318472)
			(xy 378.197346 -241.269109) (xy 377.890029 -241.269109) (xy 377.89002 -241.269566) (xy 377.881856 -241.3198)
			(xy 377.86574 -241.368074) (xy 377.842089 -241.413137) (xy 377.811516 -241.453823) (xy 377.774812 -241.489078)
			(xy 377.732928 -241.517988) (xy 377.686949 -241.539805) (xy 377.638065 -241.553965) (xy 377.587544 -241.560099)
			(xy 377.536692 -241.55805) (xy 377.486828 -241.54787) (xy 377.439242 -241.529823) (xy 377.395168 -241.504377)
			(xy 377.355746 -241.47219) (xy 377.321998 -241.434096) (xy 377.294797 -241.391082) (xy 377.274849 -241.344262)
			(xy 377.26267 -241.294848) (xy 377.258575 -241.24412) (xy 376.952764 -241.24412) (xy 376.952274 -241.269109)
			(xy 376.944455 -241.318472) (xy 376.929011 -241.366004) (xy 376.906321 -241.410536) (xy 376.876945 -241.450969)
			(xy 376.841605 -241.486309) (xy 376.801172 -241.515685) (xy 376.75664 -241.538375) (xy 376.709108 -241.553819)
			(xy 376.659745 -241.561638) (xy 376.609767 -241.561638) (xy 376.560404 -241.553819) (xy 376.512872 -241.538375)
			(xy 376.46834 -241.515685) (xy 376.427907 -241.486309) (xy 376.392567 -241.450969) (xy 376.363191 -241.410536)
			(xy 376.340501 -241.366004) (xy 376.325057 -241.318472) (xy 376.317238 -241.269109) (xy 376.009921 -241.269109)
			(xy 376.009912 -241.269566) (xy 376.001748 -241.3198) (xy 375.985632 -241.368074) (xy 375.961981 -241.413137)
			(xy 375.931408 -241.453823) (xy 375.894704 -241.489078) (xy 375.85282 -241.517988) (xy 375.806841 -241.539805)
			(xy 375.757957 -241.553965) (xy 375.707436 -241.560099) (xy 375.656584 -241.55805) (xy 375.60672 -241.54787)
			(xy 375.559134 -241.529823) (xy 375.51506 -241.504377) (xy 375.475638 -241.47219) (xy 375.44189 -241.434096)
			(xy 375.414689 -241.391082) (xy 375.394741 -241.344262) (xy 375.382562 -241.294848) (xy 375.378467 -241.24412)
			(xy 375.073379 -241.24412) (xy 375.069466 -241.293876) (xy 375.057821 -241.342426) (xy 375.038732 -241.388561)
			(xy 375.012667 -241.431144) (xy 374.980267 -241.469131) (xy 374.942328 -241.501588) (xy 374.899783 -241.527716)
			(xy 374.853677 -241.546874) (xy 374.805144 -241.558591) (xy 374.780302 -241.561112) (xy 374.771666 -241.561874)
			(xy 374.74779 -241.572542) (xy 374.743669 -241.574481) (xy 374.736136 -241.579597) (xy 374.732804 -241.582702)
			(xy 374.715278 -241.600228) (xy 374.710427 -241.606263) (xy 374.704342 -241.620491) (xy 374.70334 -241.628168)
			(xy 374.70334 -241.636296) (xy 374.703086 -241.637566) (xy 374.703086 -242.079115) (xy 374.907284 -242.079115)
			(xy 374.907284 -242.029137) (xy 374.915103 -241.979774) (xy 374.930547 -241.932242) (xy 374.953237 -241.88771)
			(xy 374.982613 -241.847277) (xy 375.017953 -241.811937) (xy 375.058386 -241.782561) (xy 375.102918 -241.759871)
			(xy 375.15045 -241.744427) (xy 375.199813 -241.736608) (xy 375.249791 -241.736608) (xy 375.299154 -241.744427)
			(xy 375.346686 -241.759871) (xy 375.391218 -241.782561) (xy 375.431651 -241.811937) (xy 375.466991 -241.847277)
			(xy 375.496367 -241.88771) (xy 375.519057 -241.932242) (xy 375.534501 -241.979774) (xy 375.54232 -242.029137)
			(xy 375.54281 -242.054126) (xy 375.848621 -242.054126) (xy 375.852716 -242.003398) (xy 375.864895 -241.953984)
			(xy 375.884843 -241.907164) (xy 375.912044 -241.86415) (xy 375.945792 -241.826056) (xy 375.985214 -241.793869)
			(xy 376.029288 -241.768423) (xy 376.076874 -241.750376) (xy 376.126738 -241.740196) (xy 376.17759 -241.738147)
			(xy 376.228111 -241.744281) (xy 376.276995 -241.758441) (xy 376.322974 -241.780258) (xy 376.364858 -241.809168)
			(xy 376.401562 -241.844423) (xy 376.432135 -241.885109) (xy 376.455786 -241.930172) (xy 376.471902 -241.978446)
			(xy 376.480066 -242.02868) (xy 376.480578 -242.054126) (xy 376.788675 -242.054126) (xy 376.79277 -242.003398)
			(xy 376.804949 -241.953984) (xy 376.824897 -241.907164) (xy 376.852098 -241.86415) (xy 376.885846 -241.826056)
			(xy 376.925268 -241.793869) (xy 376.969342 -241.768423) (xy 377.016928 -241.750376) (xy 377.066792 -241.740196)
			(xy 377.117644 -241.738147) (xy 377.168165 -241.744281) (xy 377.217049 -241.758441) (xy 377.263028 -241.780258)
			(xy 377.304912 -241.809168) (xy 377.341616 -241.844423) (xy 377.372189 -241.885109) (xy 377.39584 -241.930172)
			(xy 377.411956 -241.978446) (xy 377.42012 -242.02868) (xy 377.420632 -242.054126) (xy 378.668529 -242.054126)
			(xy 378.672624 -242.003398) (xy 378.684803 -241.953984) (xy 378.704751 -241.907164) (xy 378.731952 -241.86415)
			(xy 378.7657 -241.826056) (xy 378.805122 -241.793869) (xy 378.849196 -241.768423) (xy 378.896782 -241.750376)
			(xy 378.946646 -241.740196) (xy 378.997498 -241.738147) (xy 379.048019 -241.744281) (xy 379.096903 -241.758441)
			(xy 379.142882 -241.780258) (xy 379.184766 -241.809168) (xy 379.22147 -241.844423) (xy 379.252043 -241.885109)
			(xy 379.275694 -241.930172) (xy 379.29181 -241.978446) (xy 379.299974 -242.02868) (xy 379.300486 -242.054126)
			(xy 379.299983 -242.079115) (xy 379.6073 -242.079115) (xy 379.6073 -242.029137) (xy 379.615119 -241.979774)
			(xy 379.630563 -241.932242) (xy 379.653253 -241.88771) (xy 379.682629 -241.847277) (xy 379.717969 -241.811937)
			(xy 379.758402 -241.782561) (xy 379.802934 -241.759871) (xy 379.850466 -241.744427) (xy 379.899829 -241.736608)
			(xy 379.949807 -241.736608) (xy 379.99917 -241.744427) (xy 380.046702 -241.759871) (xy 380.091234 -241.782561)
			(xy 380.131667 -241.811937) (xy 380.167007 -241.847277) (xy 380.196383 -241.88771) (xy 380.219073 -241.932242)
			(xy 380.234517 -241.979774) (xy 380.242336 -242.029137) (xy 380.242826 -242.054126) (xy 380.548637 -242.054126)
			(xy 380.552732 -242.003398) (xy 380.564911 -241.953984) (xy 380.584859 -241.907164) (xy 380.61206 -241.86415)
			(xy 380.645808 -241.826056) (xy 380.68523 -241.793869) (xy 380.729304 -241.768423) (xy 380.77689 -241.750376)
			(xy 380.826754 -241.740196) (xy 380.877606 -241.738147) (xy 380.928127 -241.744281) (xy 380.977011 -241.758441)
			(xy 381.02299 -241.780258) (xy 381.064874 -241.809168) (xy 381.101578 -241.844423) (xy 381.132151 -241.885109)
			(xy 381.155802 -241.930172) (xy 381.171918 -241.978446) (xy 381.180082 -242.02868) (xy 381.180594 -242.054126)
			(xy 381.180082 -242.079572) (xy 381.171918 -242.129806) (xy 381.155802 -242.17808) (xy 381.132151 -242.223143)
			(xy 381.101578 -242.263829) (xy 381.064874 -242.299084) (xy 381.02299 -242.327994) (xy 380.977011 -242.349811)
			(xy 380.928127 -242.363971) (xy 380.877606 -242.370105) (xy 380.826754 -242.368056) (xy 380.77689 -242.357876)
			(xy 380.729304 -242.339829) (xy 380.68523 -242.314383) (xy 380.645808 -242.282196) (xy 380.61206 -242.244102)
			(xy 380.584859 -242.201088) (xy 380.564911 -242.154268) (xy 380.552732 -242.104854) (xy 380.548637 -242.054126)
			(xy 380.242826 -242.054126) (xy 380.242336 -242.079115) (xy 380.234517 -242.128478) (xy 380.219073 -242.17601)
			(xy 380.196383 -242.220542) (xy 380.167007 -242.260975) (xy 380.131667 -242.296315) (xy 380.091234 -242.325691)
			(xy 380.046702 -242.348381) (xy 379.99917 -242.363825) (xy 379.949807 -242.371644) (xy 379.899829 -242.371644)
			(xy 379.850466 -242.363825) (xy 379.802934 -242.348381) (xy 379.758402 -242.325691) (xy 379.717969 -242.296315)
			(xy 379.682629 -242.260975) (xy 379.653253 -242.220542) (xy 379.630563 -242.17601) (xy 379.615119 -242.128478)
			(xy 379.6073 -242.079115) (xy 379.299983 -242.079115) (xy 379.299974 -242.079572) (xy 379.29181 -242.129806)
			(xy 379.275694 -242.17808) (xy 379.252043 -242.223143) (xy 379.22147 -242.263829) (xy 379.184766 -242.299084)
			(xy 379.142882 -242.327994) (xy 379.096903 -242.349811) (xy 379.048019 -242.363971) (xy 378.997498 -242.370105)
			(xy 378.946646 -242.368056) (xy 378.896782 -242.357876) (xy 378.849196 -242.339829) (xy 378.805122 -242.314383)
			(xy 378.7657 -242.282196) (xy 378.731952 -242.244102) (xy 378.704751 -242.201088) (xy 378.684803 -242.154268)
			(xy 378.672624 -242.104854) (xy 378.668529 -242.054126) (xy 377.420632 -242.054126) (xy 377.42012 -242.079572)
			(xy 377.411956 -242.129806) (xy 377.39584 -242.17808) (xy 377.372189 -242.223143) (xy 377.341616 -242.263829)
			(xy 377.304912 -242.299084) (xy 377.263028 -242.327994) (xy 377.217049 -242.349811) (xy 377.168165 -242.363971)
			(xy 377.117644 -242.370105) (xy 377.066792 -242.368056) (xy 377.016928 -242.357876) (xy 376.969342 -242.339829)
			(xy 376.925268 -242.314383) (xy 376.885846 -242.282196) (xy 376.852098 -242.244102) (xy 376.824897 -242.201088)
			(xy 376.804949 -242.154268) (xy 376.79277 -242.104854) (xy 376.788675 -242.054126) (xy 376.480578 -242.054126)
			(xy 376.480066 -242.079572) (xy 376.471902 -242.129806) (xy 376.455786 -242.17808) (xy 376.432135 -242.223143)
			(xy 376.401562 -242.263829) (xy 376.364858 -242.299084) (xy 376.322974 -242.327994) (xy 376.276995 -242.349811)
			(xy 376.228111 -242.363971) (xy 376.17759 -242.370105) (xy 376.126738 -242.368056) (xy 376.076874 -242.357876)
			(xy 376.029288 -242.339829) (xy 375.985214 -242.314383) (xy 375.945792 -242.282196) (xy 375.912044 -242.244102)
			(xy 375.884843 -242.201088) (xy 375.864895 -242.154268) (xy 375.852716 -242.104854) (xy 375.848621 -242.054126)
			(xy 375.54281 -242.054126) (xy 375.54232 -242.079115) (xy 375.534501 -242.128478) (xy 375.519057 -242.17601)
			(xy 375.496367 -242.220542) (xy 375.466991 -242.260975) (xy 375.431651 -242.296315) (xy 375.391218 -242.325691)
			(xy 375.346686 -242.348381) (xy 375.299154 -242.363825) (xy 375.249791 -242.371644) (xy 375.199813 -242.371644)
			(xy 375.15045 -242.363825) (xy 375.102918 -242.348381) (xy 375.058386 -242.325691) (xy 375.017953 -242.296315)
			(xy 374.982613 -242.260975) (xy 374.953237 -242.220542) (xy 374.930547 -242.17601) (xy 374.915103 -242.128478)
			(xy 374.907284 -242.079115) (xy 374.703086 -242.079115) (xy 374.703086 -242.470686) (xy 374.70334 -242.471956)
			(xy 374.70334 -242.480084) (xy 374.704378 -242.487751) (xy 374.710462 -242.501968) (xy 374.715278 -242.508024)
			(xy 374.732804 -242.52555) (xy 374.736128 -242.528664) (xy 374.743666 -242.533777) (xy 374.74779 -242.53571)
			(xy 374.771666 -242.546378) (xy 374.780302 -242.54714) (xy 374.805146 -242.549621) (xy 374.853677 -242.561338)
			(xy 374.899781 -242.580496) (xy 374.942324 -242.606624) (xy 374.980261 -242.63908) (xy 375.01266 -242.677066)
			(xy 375.038723 -242.719649) (xy 375.057811 -242.765781) (xy 375.069455 -242.81433) (xy 375.073368 -242.864103)
			(xy 375.073366 -242.864132) (xy 375.378467 -242.864132) (xy 375.382562 -242.813404) (xy 375.394741 -242.76399)
			(xy 375.414689 -242.71717) (xy 375.44189 -242.674156) (xy 375.475638 -242.636062) (xy 375.51506 -242.603875)
			(xy 375.559134 -242.578429) (xy 375.60672 -242.560382) (xy 375.656584 -242.550202) (xy 375.707436 -242.548153)
			(xy 375.757957 -242.554287) (xy 375.806841 -242.568447) (xy 375.85282 -242.590264) (xy 375.894704 -242.619174)
			(xy 375.931408 -242.654429) (xy 375.961981 -242.695115) (xy 375.985632 -242.740178) (xy 376.001748 -242.788452)
			(xy 376.009912 -242.838686) (xy 376.010424 -242.864132) (xy 376.009921 -242.889121) (xy 376.317238 -242.889121)
			(xy 376.317238 -242.839143) (xy 376.325057 -242.78978) (xy 376.340501 -242.742248) (xy 376.363191 -242.697716)
			(xy 376.392567 -242.657283) (xy 376.427907 -242.621943) (xy 376.46834 -242.592567) (xy 376.512872 -242.569877)
			(xy 376.560404 -242.554433) (xy 376.609767 -242.546614) (xy 376.659745 -242.546614) (xy 376.709108 -242.554433)
			(xy 376.75664 -242.569877) (xy 376.801172 -242.592567) (xy 376.841605 -242.621943) (xy 376.876945 -242.657283)
			(xy 376.906321 -242.697716) (xy 376.929011 -242.742248) (xy 376.944455 -242.78978) (xy 376.952274 -242.839143)
			(xy 376.952764 -242.864132) (xy 377.258575 -242.864132) (xy 377.26267 -242.813404) (xy 377.274849 -242.76399)
			(xy 377.294797 -242.71717) (xy 377.321998 -242.674156) (xy 377.355746 -242.636062) (xy 377.395168 -242.603875)
			(xy 377.439242 -242.578429) (xy 377.486828 -242.560382) (xy 377.536692 -242.550202) (xy 377.587544 -242.548153)
			(xy 377.638065 -242.554287) (xy 377.686949 -242.568447) (xy 377.732928 -242.590264) (xy 377.774812 -242.619174)
			(xy 377.811516 -242.654429) (xy 377.842089 -242.695115) (xy 377.86574 -242.740178) (xy 377.881856 -242.788452)
			(xy 377.89002 -242.838686) (xy 377.890532 -242.864132) (xy 377.890029 -242.889121) (xy 378.197346 -242.889121)
			(xy 378.197346 -242.839143) (xy 378.205165 -242.78978) (xy 378.220609 -242.742248) (xy 378.243299 -242.697716)
			(xy 378.272675 -242.657283) (xy 378.308015 -242.621943) (xy 378.348448 -242.592567) (xy 378.39298 -242.569877)
			(xy 378.440512 -242.554433) (xy 378.489875 -242.546614) (xy 378.539853 -242.546614) (xy 378.589216 -242.554433)
			(xy 378.636748 -242.569877) (xy 378.68128 -242.592567) (xy 378.721713 -242.621943) (xy 378.757053 -242.657283)
			(xy 378.786429 -242.697716) (xy 378.809119 -242.742248) (xy 378.824563 -242.78978) (xy 378.832382 -242.839143)
			(xy 378.832872 -242.864132) (xy 379.138683 -242.864132) (xy 379.142778 -242.813404) (xy 379.154957 -242.76399)
			(xy 379.174905 -242.71717) (xy 379.202106 -242.674156) (xy 379.235854 -242.636062) (xy 379.275276 -242.603875)
			(xy 379.31935 -242.578429) (xy 379.366936 -242.560382) (xy 379.4168 -242.550202) (xy 379.467652 -242.548153)
			(xy 379.518173 -242.554287) (xy 379.567057 -242.568447) (xy 379.613036 -242.590264) (xy 379.65492 -242.619174)
			(xy 379.691624 -242.654429) (xy 379.722197 -242.695115) (xy 379.745848 -242.740178) (xy 379.761964 -242.788452)
			(xy 379.770128 -242.838686) (xy 379.77064 -242.864132) (xy 380.078483 -242.864132) (xy 380.082578 -242.813404)
			(xy 380.094757 -242.76399) (xy 380.114705 -242.71717) (xy 380.141906 -242.674156) (xy 380.175654 -242.636062)
			(xy 380.215076 -242.603875) (xy 380.25915 -242.578429) (xy 380.306736 -242.560382) (xy 380.3566 -242.550202)
			(xy 380.407452 -242.548153) (xy 380.457973 -242.554287) (xy 380.506857 -242.568447) (xy 380.552836 -242.590264)
			(xy 380.59472 -242.619174) (xy 380.631424 -242.654429) (xy 380.661997 -242.695115) (xy 380.685648 -242.740178)
			(xy 380.701764 -242.788452) (xy 380.709928 -242.838686) (xy 380.71044 -242.864132) (xy 380.709928 -242.889578)
			(xy 380.701764 -242.939812) (xy 380.685648 -242.988086) (xy 380.661997 -243.033149) (xy 380.631424 -243.073835)
			(xy 380.59472 -243.10909) (xy 380.552836 -243.138) (xy 380.506857 -243.159817) (xy 380.457973 -243.173977)
			(xy 380.407452 -243.180111) (xy 380.3566 -243.178062) (xy 380.306736 -243.167882) (xy 380.25915 -243.149835)
			(xy 380.215076 -243.124389) (xy 380.175654 -243.092202) (xy 380.141906 -243.054108) (xy 380.114705 -243.011094)
			(xy 380.094757 -242.964274) (xy 380.082578 -242.91486) (xy 380.078483 -242.864132) (xy 379.77064 -242.864132)
			(xy 379.770128 -242.889578) (xy 379.761964 -242.939812) (xy 379.745848 -242.988086) (xy 379.722197 -243.033149)
			(xy 379.691624 -243.073835) (xy 379.65492 -243.10909) (xy 379.613036 -243.138) (xy 379.567057 -243.159817)
			(xy 379.518173 -243.173977) (xy 379.467652 -243.180111) (xy 379.4168 -243.178062) (xy 379.366936 -243.167882)
			(xy 379.31935 -243.149835) (xy 379.275276 -243.124389) (xy 379.235854 -243.092202) (xy 379.202106 -243.054108)
			(xy 379.174905 -243.011094) (xy 379.154957 -242.964274) (xy 379.142778 -242.91486) (xy 379.138683 -242.864132)
			(xy 378.832872 -242.864132) (xy 378.832382 -242.889121) (xy 378.824563 -242.938484) (xy 378.809119 -242.986016)
			(xy 378.786429 -243.030548) (xy 378.757053 -243.070981) (xy 378.721713 -243.106321) (xy 378.68128 -243.135697)
			(xy 378.636748 -243.158387) (xy 378.589216 -243.173831) (xy 378.539853 -243.18165) (xy 378.489875 -243.18165)
			(xy 378.440512 -243.173831) (xy 378.39298 -243.158387) (xy 378.348448 -243.135697) (xy 378.308015 -243.106321)
			(xy 378.272675 -243.070981) (xy 378.243299 -243.030548) (xy 378.220609 -242.986016) (xy 378.205165 -242.938484)
			(xy 378.197346 -242.889121) (xy 377.890029 -242.889121) (xy 377.89002 -242.889578) (xy 377.881856 -242.939812)
			(xy 377.86574 -242.988086) (xy 377.842089 -243.033149) (xy 377.811516 -243.073835) (xy 377.774812 -243.10909)
			(xy 377.732928 -243.138) (xy 377.686949 -243.159817) (xy 377.638065 -243.173977) (xy 377.587544 -243.180111)
			(xy 377.536692 -243.178062) (xy 377.486828 -243.167882) (xy 377.439242 -243.149835) (xy 377.395168 -243.124389)
			(xy 377.355746 -243.092202) (xy 377.321998 -243.054108) (xy 377.294797 -243.011094) (xy 377.274849 -242.964274)
			(xy 377.26267 -242.91486) (xy 377.258575 -242.864132) (xy 376.952764 -242.864132) (xy 376.952274 -242.889121)
			(xy 376.944455 -242.938484) (xy 376.929011 -242.986016) (xy 376.906321 -243.030548) (xy 376.876945 -243.070981)
			(xy 376.841605 -243.106321) (xy 376.801172 -243.135697) (xy 376.75664 -243.158387) (xy 376.709108 -243.173831)
			(xy 376.659745 -243.18165) (xy 376.609767 -243.18165) (xy 376.560404 -243.173831) (xy 376.512872 -243.158387)
			(xy 376.46834 -243.135697) (xy 376.427907 -243.106321) (xy 376.392567 -243.070981) (xy 376.363191 -243.030548)
			(xy 376.340501 -242.986016) (xy 376.325057 -242.938484) (xy 376.317238 -242.889121) (xy 376.009921 -242.889121)
			(xy 376.009912 -242.889578) (xy 376.001748 -242.939812) (xy 375.985632 -242.988086) (xy 375.961981 -243.033149)
			(xy 375.931408 -243.073835) (xy 375.894704 -243.10909) (xy 375.85282 -243.138) (xy 375.806841 -243.159817)
			(xy 375.757957 -243.173977) (xy 375.707436 -243.180111) (xy 375.656584 -243.178062) (xy 375.60672 -243.167882)
			(xy 375.559134 -243.149835) (xy 375.51506 -243.124389) (xy 375.475638 -243.092202) (xy 375.44189 -243.054108)
			(xy 375.414689 -243.011094) (xy 375.394741 -242.964274) (xy 375.382562 -242.91486) (xy 375.378467 -242.864132)
			(xy 375.073366 -242.864132) (xy 375.069454 -242.913875) (xy 375.05781 -242.962424) (xy 375.038721 -243.008556)
			(xy 375.012657 -243.051138) (xy 374.980258 -243.089124) (xy 374.94232 -243.121579) (xy 374.899777 -243.147706)
			(xy 374.853673 -243.166863) (xy 374.805141 -243.17858) (xy 374.780302 -243.181124) (xy 374.771666 -243.181886)
			(xy 374.74779 -243.192554) (xy 374.74367 -243.194493) (xy 374.736137 -243.19961) (xy 374.732804 -243.202714)
			(xy 374.715278 -243.22024) (xy 374.710428 -243.226275) (xy 374.704347 -243.240504) (xy 374.70334 -243.24818)
			(xy 374.70334 -243.256308) (xy 374.703086 -243.257578) (xy 374.703086 -243.674138) (xy 375.848621 -243.674138)
			(xy 375.852716 -243.62341) (xy 375.864895 -243.573996) (xy 375.884843 -243.527176) (xy 375.912044 -243.484162)
			(xy 375.945792 -243.446068) (xy 375.985214 -243.413881) (xy 376.029288 -243.388435) (xy 376.076874 -243.370388)
			(xy 376.126738 -243.360208) (xy 376.17759 -243.358159) (xy 376.228111 -243.364293) (xy 376.276995 -243.378453)
			(xy 376.322974 -243.40027) (xy 376.364858 -243.42918) (xy 376.401562 -243.464435) (xy 376.432135 -243.505121)
			(xy 376.455786 -243.550184) (xy 376.471902 -243.598458) (xy 376.480066 -243.648692) (xy 376.480578 -243.674138)
			(xy 376.788675 -243.674138) (xy 376.79277 -243.62341) (xy 376.804949 -243.573996) (xy 376.824897 -243.527176)
			(xy 376.852098 -243.484162) (xy 376.885846 -243.446068) (xy 376.925268 -243.413881) (xy 376.969342 -243.388435)
			(xy 377.016928 -243.370388) (xy 377.066792 -243.360208) (xy 377.117644 -243.358159) (xy 377.168165 -243.364293)
			(xy 377.217049 -243.378453) (xy 377.263028 -243.40027) (xy 377.304912 -243.42918) (xy 377.341616 -243.464435)
			(xy 377.372189 -243.505121) (xy 377.39584 -243.550184) (xy 377.411956 -243.598458) (xy 377.42012 -243.648692)
			(xy 377.420632 -243.674138) (xy 377.420129 -243.699127) (xy 377.727192 -243.699127) (xy 377.727192 -243.649149)
			(xy 377.735011 -243.599786) (xy 377.750455 -243.552254) (xy 377.773145 -243.507722) (xy 377.802521 -243.467289)
			(xy 377.837861 -243.431949) (xy 377.878294 -243.402573) (xy 377.922826 -243.379883) (xy 377.970358 -243.364439)
			(xy 378.019721 -243.35662) (xy 378.069699 -243.35662) (xy 378.119062 -243.364439) (xy 378.166594 -243.379883)
			(xy 378.211126 -243.402573) (xy 378.251559 -243.431949) (xy 378.286899 -243.467289) (xy 378.316275 -243.507722)
			(xy 378.338965 -243.552254) (xy 378.354409 -243.599786) (xy 378.362228 -243.649149) (xy 378.362718 -243.674138)
			(xy 378.668529 -243.674138) (xy 378.672624 -243.62341) (xy 378.684803 -243.573996) (xy 378.704751 -243.527176)
			(xy 378.731952 -243.484162) (xy 378.7657 -243.446068) (xy 378.805122 -243.413881) (xy 378.849196 -243.388435)
			(xy 378.896782 -243.370388) (xy 378.946646 -243.360208) (xy 378.997498 -243.358159) (xy 379.048019 -243.364293)
			(xy 379.096903 -243.378453) (xy 379.142882 -243.40027) (xy 379.184766 -243.42918) (xy 379.22147 -243.464435)
			(xy 379.252043 -243.505121) (xy 379.275694 -243.550184) (xy 379.29181 -243.598458) (xy 379.299974 -243.648692)
			(xy 379.300486 -243.674138) (xy 379.299983 -243.699127) (xy 379.6073 -243.699127) (xy 379.6073 -243.649149)
			(xy 379.615119 -243.599786) (xy 379.630563 -243.552254) (xy 379.653253 -243.507722) (xy 379.682629 -243.467289)
			(xy 379.717969 -243.431949) (xy 379.758402 -243.402573) (xy 379.802934 -243.379883) (xy 379.850466 -243.364439)
			(xy 379.899829 -243.35662) (xy 379.949807 -243.35662) (xy 379.99917 -243.364439) (xy 380.046702 -243.379883)
			(xy 380.091234 -243.402573) (xy 380.131667 -243.431949) (xy 380.167007 -243.467289) (xy 380.196383 -243.507722)
			(xy 380.219073 -243.552254) (xy 380.234517 -243.599786) (xy 380.242336 -243.649149) (xy 380.242826 -243.674138)
			(xy 380.548637 -243.674138) (xy 380.552732 -243.62341) (xy 380.564911 -243.573996) (xy 380.584859 -243.527176)
			(xy 380.61206 -243.484162) (xy 380.645808 -243.446068) (xy 380.68523 -243.413881) (xy 380.729304 -243.388435)
			(xy 380.77689 -243.370388) (xy 380.826754 -243.360208) (xy 380.877606 -243.358159) (xy 380.928127 -243.364293)
			(xy 380.977011 -243.378453) (xy 381.02299 -243.40027) (xy 381.064874 -243.42918) (xy 381.101578 -243.464435)
			(xy 381.132151 -243.505121) (xy 381.155802 -243.550184) (xy 381.171918 -243.598458) (xy 381.180082 -243.648692)
			(xy 381.180594 -243.674138) (xy 381.180082 -243.699584) (xy 381.171918 -243.749818) (xy 381.155802 -243.798092)
			(xy 381.132151 -243.843155) (xy 381.101578 -243.883841) (xy 381.064874 -243.919096) (xy 381.02299 -243.948006)
			(xy 380.977011 -243.969823) (xy 380.928127 -243.983983) (xy 380.877606 -243.990117) (xy 380.826754 -243.988068)
			(xy 380.77689 -243.977888) (xy 380.729304 -243.959841) (xy 380.68523 -243.934395) (xy 380.645808 -243.902208)
			(xy 380.61206 -243.864114) (xy 380.584859 -243.8211) (xy 380.564911 -243.77428) (xy 380.552732 -243.724866)
			(xy 380.548637 -243.674138) (xy 380.242826 -243.674138) (xy 380.242336 -243.699127) (xy 380.234517 -243.74849)
			(xy 380.219073 -243.796022) (xy 380.196383 -243.840554) (xy 380.167007 -243.880987) (xy 380.131667 -243.916327)
			(xy 380.091234 -243.945703) (xy 380.046702 -243.968393) (xy 379.99917 -243.983837) (xy 379.949807 -243.991656)
			(xy 379.899829 -243.991656) (xy 379.850466 -243.983837) (xy 379.802934 -243.968393) (xy 379.758402 -243.945703)
			(xy 379.717969 -243.916327) (xy 379.682629 -243.880987) (xy 379.653253 -243.840554) (xy 379.630563 -243.796022)
			(xy 379.615119 -243.74849) (xy 379.6073 -243.699127) (xy 379.299983 -243.699127) (xy 379.299974 -243.699584)
			(xy 379.29181 -243.749818) (xy 379.275694 -243.798092) (xy 379.252043 -243.843155) (xy 379.22147 -243.883841)
			(xy 379.184766 -243.919096) (xy 379.142882 -243.948006) (xy 379.096903 -243.969823) (xy 379.048019 -243.983983)
			(xy 378.997498 -243.990117) (xy 378.946646 -243.988068) (xy 378.896782 -243.977888) (xy 378.849196 -243.959841)
			(xy 378.805122 -243.934395) (xy 378.7657 -243.902208) (xy 378.731952 -243.864114) (xy 378.704751 -243.8211)
			(xy 378.684803 -243.77428) (xy 378.672624 -243.724866) (xy 378.668529 -243.674138) (xy 378.362718 -243.674138)
			(xy 378.362228 -243.699127) (xy 378.354409 -243.74849) (xy 378.338965 -243.796022) (xy 378.316275 -243.840554)
			(xy 378.286899 -243.880987) (xy 378.251559 -243.916327) (xy 378.211126 -243.945703) (xy 378.166594 -243.968393)
			(xy 378.119062 -243.983837) (xy 378.069699 -243.991656) (xy 378.019721 -243.991656) (xy 377.970358 -243.983837)
			(xy 377.922826 -243.968393) (xy 377.878294 -243.945703) (xy 377.837861 -243.916327) (xy 377.802521 -243.880987)
			(xy 377.773145 -243.840554) (xy 377.750455 -243.796022) (xy 377.735011 -243.74849) (xy 377.727192 -243.699127)
			(xy 377.420129 -243.699127) (xy 377.42012 -243.699584) (xy 377.411956 -243.749818) (xy 377.39584 -243.798092)
			(xy 377.372189 -243.843155) (xy 377.341616 -243.883841) (xy 377.304912 -243.919096) (xy 377.263028 -243.948006)
			(xy 377.217049 -243.969823) (xy 377.168165 -243.983983) (xy 377.117644 -243.990117) (xy 377.066792 -243.988068)
			(xy 377.016928 -243.977888) (xy 376.969342 -243.959841) (xy 376.925268 -243.934395) (xy 376.885846 -243.902208)
			(xy 376.852098 -243.864114) (xy 376.824897 -243.8211) (xy 376.804949 -243.77428) (xy 376.79277 -243.724866)
			(xy 376.788675 -243.674138) (xy 376.480578 -243.674138) (xy 376.480066 -243.699584) (xy 376.471902 -243.749818)
			(xy 376.455786 -243.798092) (xy 376.432135 -243.843155) (xy 376.401562 -243.883841) (xy 376.364858 -243.919096)
			(xy 376.322974 -243.948006) (xy 376.276995 -243.969823) (xy 376.228111 -243.983983) (xy 376.17759 -243.990117)
			(xy 376.126738 -243.988068) (xy 376.076874 -243.977888) (xy 376.029288 -243.959841) (xy 375.985214 -243.934395)
			(xy 375.945792 -243.902208) (xy 375.912044 -243.864114) (xy 375.884843 -243.8211) (xy 375.864895 -243.77428)
			(xy 375.852716 -243.724866) (xy 375.848621 -243.674138) (xy 374.703086 -243.674138) (xy 374.703086 -244.090698)
			(xy 374.70334 -244.091968) (xy 374.70334 -244.100096) (xy 374.704367 -244.107768) (xy 374.710431 -244.122002)
			(xy 374.715278 -244.128036) (xy 374.732804 -244.145562) (xy 374.736129 -244.148676) (xy 374.743666 -244.153787)
			(xy 374.74779 -244.155722) (xy 374.771666 -244.16639) (xy 374.780302 -244.167152) (xy 374.805145 -244.169633)
			(xy 374.853675 -244.18135) (xy 374.899777 -244.200507) (xy 374.942318 -244.226634) (xy 374.980253 -244.259089)
			(xy 375.01265 -244.297074) (xy 375.038713 -244.339655) (xy 375.0578 -244.385786) (xy 375.069443 -244.434333)
			(xy 375.073356 -244.484104) (xy 375.073353 -244.484144) (xy 375.378467 -244.484144) (xy 375.382562 -244.433416)
			(xy 375.394741 -244.384002) (xy 375.414689 -244.337182) (xy 375.44189 -244.294168) (xy 375.475638 -244.256074)
			(xy 375.51506 -244.223887) (xy 375.559134 -244.198441) (xy 375.60672 -244.180394) (xy 375.656584 -244.170214)
			(xy 375.707436 -244.168165) (xy 375.757957 -244.174299) (xy 375.806841 -244.188459) (xy 375.85282 -244.210276)
			(xy 375.894704 -244.239186) (xy 375.931408 -244.274441) (xy 375.961981 -244.315127) (xy 375.985632 -244.36019)
			(xy 376.001748 -244.408464) (xy 376.009912 -244.458698) (xy 376.010424 -244.484144) (xy 376.009921 -244.509133)
			(xy 376.317238 -244.509133) (xy 376.317238 -244.459155) (xy 376.325057 -244.409792) (xy 376.340501 -244.36226)
			(xy 376.363191 -244.317728) (xy 376.392567 -244.277295) (xy 376.427907 -244.241955) (xy 376.46834 -244.212579)
			(xy 376.512872 -244.189889) (xy 376.560404 -244.174445) (xy 376.609767 -244.166626) (xy 376.659745 -244.166626)
			(xy 376.709108 -244.174445) (xy 376.75664 -244.189889) (xy 376.801172 -244.212579) (xy 376.841605 -244.241955)
			(xy 376.876945 -244.277295) (xy 376.906321 -244.317728) (xy 376.929011 -244.36226) (xy 376.944455 -244.409792)
			(xy 376.952274 -244.459155) (xy 376.952764 -244.484144) (xy 377.258575 -244.484144) (xy 377.26267 -244.433416)
			(xy 377.274849 -244.384002) (xy 377.294797 -244.337182) (xy 377.321998 -244.294168) (xy 377.355746 -244.256074)
			(xy 377.395168 -244.223887) (xy 377.439242 -244.198441) (xy 377.486828 -244.180394) (xy 377.536692 -244.170214)
			(xy 377.587544 -244.168165) (xy 377.638065 -244.174299) (xy 377.686949 -244.188459) (xy 377.732928 -244.210276)
			(xy 377.774812 -244.239186) (xy 377.811516 -244.274441) (xy 377.842089 -244.315127) (xy 377.86574 -244.36019)
			(xy 377.881856 -244.408464) (xy 377.89002 -244.458698) (xy 377.890532 -244.484144) (xy 379.138683 -244.484144)
			(xy 379.142778 -244.433416) (xy 379.154957 -244.384002) (xy 379.174905 -244.337182) (xy 379.202106 -244.294168)
			(xy 379.235854 -244.256074) (xy 379.275276 -244.223887) (xy 379.31935 -244.198441) (xy 379.366936 -244.180394)
			(xy 379.4168 -244.170214) (xy 379.467652 -244.168165) (xy 379.518173 -244.174299) (xy 379.567057 -244.188459)
			(xy 379.613036 -244.210276) (xy 379.65492 -244.239186) (xy 379.691624 -244.274441) (xy 379.722197 -244.315127)
			(xy 379.745848 -244.36019) (xy 379.761964 -244.408464) (xy 379.770128 -244.458698) (xy 379.77064 -244.484144)
			(xy 380.078483 -244.484144) (xy 380.082578 -244.433416) (xy 380.094757 -244.384002) (xy 380.114705 -244.337182)
			(xy 380.141906 -244.294168) (xy 380.175654 -244.256074) (xy 380.215076 -244.223887) (xy 380.25915 -244.198441)
			(xy 380.306736 -244.180394) (xy 380.3566 -244.170214) (xy 380.407452 -244.168165) (xy 380.457973 -244.174299)
			(xy 380.506857 -244.188459) (xy 380.552836 -244.210276) (xy 380.59472 -244.239186) (xy 380.631424 -244.274441)
			(xy 380.661997 -244.315127) (xy 380.685648 -244.36019) (xy 380.701764 -244.408464) (xy 380.709928 -244.458698)
			(xy 380.71044 -244.484144) (xy 380.709928 -244.50959) (xy 380.701764 -244.559824) (xy 380.685648 -244.608098)
			(xy 380.661997 -244.653161) (xy 380.631424 -244.693847) (xy 380.59472 -244.729102) (xy 380.552836 -244.758012)
			(xy 380.506857 -244.779829) (xy 380.457973 -244.793989) (xy 380.407452 -244.800123) (xy 380.3566 -244.798074)
			(xy 380.306736 -244.787894) (xy 380.25915 -244.769847) (xy 380.215076 -244.744401) (xy 380.175654 -244.712214)
			(xy 380.141906 -244.67412) (xy 380.114705 -244.631106) (xy 380.094757 -244.584286) (xy 380.082578 -244.534872)
			(xy 380.078483 -244.484144) (xy 379.77064 -244.484144) (xy 379.770128 -244.50959) (xy 379.761964 -244.559824)
			(xy 379.745848 -244.608098) (xy 379.722197 -244.653161) (xy 379.691624 -244.693847) (xy 379.65492 -244.729102)
			(xy 379.613036 -244.758012) (xy 379.567057 -244.779829) (xy 379.518173 -244.793989) (xy 379.467652 -244.800123)
			(xy 379.4168 -244.798074) (xy 379.366936 -244.787894) (xy 379.31935 -244.769847) (xy 379.275276 -244.744401)
			(xy 379.235854 -244.712214) (xy 379.202106 -244.67412) (xy 379.174905 -244.631106) (xy 379.154957 -244.584286)
			(xy 379.142778 -244.534872) (xy 379.138683 -244.484144) (xy 377.890532 -244.484144) (xy 377.89002 -244.50959)
			(xy 377.881856 -244.559824) (xy 377.86574 -244.608098) (xy 377.842089 -244.653161) (xy 377.811516 -244.693847)
			(xy 377.774812 -244.729102) (xy 377.732928 -244.758012) (xy 377.686949 -244.779829) (xy 377.638065 -244.793989)
			(xy 377.587544 -244.800123) (xy 377.536692 -244.798074) (xy 377.486828 -244.787894) (xy 377.439242 -244.769847)
			(xy 377.395168 -244.744401) (xy 377.355746 -244.712214) (xy 377.321998 -244.67412) (xy 377.294797 -244.631106)
			(xy 377.274849 -244.584286) (xy 377.26267 -244.534872) (xy 377.258575 -244.484144) (xy 376.952764 -244.484144)
			(xy 376.952274 -244.509133) (xy 376.944455 -244.558496) (xy 376.929011 -244.606028) (xy 376.906321 -244.65056)
			(xy 376.876945 -244.690993) (xy 376.841605 -244.726333) (xy 376.801172 -244.755709) (xy 376.75664 -244.778399)
			(xy 376.709108 -244.793843) (xy 376.659745 -244.801662) (xy 376.609767 -244.801662) (xy 376.560404 -244.793843)
			(xy 376.512872 -244.778399) (xy 376.46834 -244.755709) (xy 376.427907 -244.726333) (xy 376.392567 -244.690993)
			(xy 376.363191 -244.65056) (xy 376.340501 -244.606028) (xy 376.325057 -244.558496) (xy 376.317238 -244.509133)
			(xy 376.009921 -244.509133) (xy 376.009912 -244.50959) (xy 376.001748 -244.559824) (xy 375.985632 -244.608098)
			(xy 375.961981 -244.653161) (xy 375.931408 -244.693847) (xy 375.894704 -244.729102) (xy 375.85282 -244.758012)
			(xy 375.806841 -244.779829) (xy 375.757957 -244.793989) (xy 375.707436 -244.800123) (xy 375.656584 -244.798074)
			(xy 375.60672 -244.787894) (xy 375.559134 -244.769847) (xy 375.51506 -244.744401) (xy 375.475638 -244.712214)
			(xy 375.44189 -244.67412) (xy 375.414689 -244.631106) (xy 375.394741 -244.584286) (xy 375.382562 -244.534872)
			(xy 375.378467 -244.484144) (xy 375.073353 -244.484144) (xy 375.069442 -244.533874) (xy 375.057798 -244.582421)
			(xy 375.03871 -244.628551) (xy 375.012646 -244.671132) (xy 374.980248 -244.709116) (xy 374.942312 -244.74157)
			(xy 374.89977 -244.767696) (xy 374.853668 -244.786852) (xy 374.805138 -244.798568) (xy 374.780302 -244.801136)
			(xy 374.771666 -244.801898) (xy 374.74779 -244.812566) (xy 374.74367 -244.814506) (xy 374.736138 -244.819624)
			(xy 374.732804 -244.822726) (xy 374.715278 -244.840252) (xy 374.71043 -244.846288) (xy 374.704352 -244.860517)
			(xy 374.70334 -244.868192) (xy 374.70334 -244.87632) (xy 374.703086 -244.87759) (xy 374.703086 -245.319139)
			(xy 374.907284 -245.319139) (xy 374.907284 -245.269161) (xy 374.915103 -245.219798) (xy 374.930547 -245.172266)
			(xy 374.953237 -245.127734) (xy 374.982613 -245.087301) (xy 375.017953 -245.051961) (xy 375.058386 -245.022585)
			(xy 375.102918 -244.999895) (xy 375.15045 -244.984451) (xy 375.199813 -244.976632) (xy 375.249791 -244.976632)
			(xy 375.299154 -244.984451) (xy 375.346686 -244.999895) (xy 375.391218 -245.022585) (xy 375.431651 -245.051961)
			(xy 375.466991 -245.087301) (xy 375.496367 -245.127734) (xy 375.519057 -245.172266) (xy 375.534501 -245.219798)
			(xy 375.54232 -245.269161) (xy 375.54281 -245.29415) (xy 375.848621 -245.29415) (xy 375.852716 -245.243422)
			(xy 375.864895 -245.194008) (xy 375.884843 -245.147188) (xy 375.912044 -245.104174) (xy 375.945792 -245.06608)
			(xy 375.985214 -245.033893) (xy 376.029288 -245.008447) (xy 376.076874 -244.9904) (xy 376.126738 -244.98022)
			(xy 376.17759 -244.978171) (xy 376.228111 -244.984305) (xy 376.276995 -244.998465) (xy 376.322974 -245.020282)
			(xy 376.364858 -245.049192) (xy 376.401562 -245.084447) (xy 376.432135 -245.125133) (xy 376.455786 -245.170196)
			(xy 376.471902 -245.21847) (xy 376.480066 -245.268704) (xy 376.480578 -245.29415) (xy 376.788675 -245.29415)
			(xy 376.79277 -245.243422) (xy 376.804949 -245.194008) (xy 376.824897 -245.147188) (xy 376.852098 -245.104174)
			(xy 376.885846 -245.06608) (xy 376.925268 -245.033893) (xy 376.969342 -245.008447) (xy 377.016928 -244.9904)
			(xy 377.066792 -244.98022) (xy 377.117644 -244.978171) (xy 377.168165 -244.984305) (xy 377.217049 -244.998465)
			(xy 377.263028 -245.020282) (xy 377.304912 -245.049192) (xy 377.341616 -245.084447) (xy 377.372189 -245.125133)
			(xy 377.39584 -245.170196) (xy 377.411956 -245.21847) (xy 377.42012 -245.268704) (xy 377.420632 -245.29415)
			(xy 377.420129 -245.319139) (xy 377.727192 -245.319139) (xy 377.727192 -245.269161) (xy 377.735011 -245.219798)
			(xy 377.750455 -245.172266) (xy 377.773145 -245.127734) (xy 377.802521 -245.087301) (xy 377.837861 -245.051961)
			(xy 377.878294 -245.022585) (xy 377.922826 -244.999895) (xy 377.970358 -244.984451) (xy 378.019721 -244.976632)
			(xy 378.069699 -244.976632) (xy 378.119062 -244.984451) (xy 378.166594 -244.999895) (xy 378.211126 -245.022585)
			(xy 378.251559 -245.051961) (xy 378.286899 -245.087301) (xy 378.316275 -245.127734) (xy 378.338965 -245.172266)
			(xy 378.354409 -245.219798) (xy 378.362228 -245.269161) (xy 378.362718 -245.29415) (xy 378.668529 -245.29415)
			(xy 378.672624 -245.243422) (xy 378.684803 -245.194008) (xy 378.704751 -245.147188) (xy 378.731952 -245.104174)
			(xy 378.7657 -245.06608) (xy 378.805122 -245.033893) (xy 378.849196 -245.008447) (xy 378.896782 -244.9904)
			(xy 378.946646 -244.98022) (xy 378.997498 -244.978171) (xy 379.048019 -244.984305) (xy 379.096903 -244.998465)
			(xy 379.142882 -245.020282) (xy 379.184766 -245.049192) (xy 379.22147 -245.084447) (xy 379.252043 -245.125133)
			(xy 379.275694 -245.170196) (xy 379.29181 -245.21847) (xy 379.299974 -245.268704) (xy 379.300486 -245.29415)
			(xy 379.299983 -245.319139) (xy 379.6073 -245.319139) (xy 379.6073 -245.269161) (xy 379.615119 -245.219798)
			(xy 379.630563 -245.172266) (xy 379.653253 -245.127734) (xy 379.682629 -245.087301) (xy 379.717969 -245.051961)
			(xy 379.758402 -245.022585) (xy 379.802934 -244.999895) (xy 379.850466 -244.984451) (xy 379.899829 -244.976632)
			(xy 379.949807 -244.976632) (xy 379.99917 -244.984451) (xy 380.046702 -244.999895) (xy 380.091234 -245.022585)
			(xy 380.131667 -245.051961) (xy 380.167007 -245.087301) (xy 380.196383 -245.127734) (xy 380.219073 -245.172266)
			(xy 380.234517 -245.219798) (xy 380.242336 -245.269161) (xy 380.242826 -245.29415) (xy 380.548637 -245.29415)
			(xy 380.552732 -245.243422) (xy 380.564911 -245.194008) (xy 380.584859 -245.147188) (xy 380.61206 -245.104174)
			(xy 380.645808 -245.06608) (xy 380.68523 -245.033893) (xy 380.729304 -245.008447) (xy 380.77689 -244.9904)
			(xy 380.826754 -244.98022) (xy 380.877606 -244.978171) (xy 380.928127 -244.984305) (xy 380.977011 -244.998465)
			(xy 381.02299 -245.020282) (xy 381.064874 -245.049192) (xy 381.101578 -245.084447) (xy 381.132151 -245.125133)
			(xy 381.155802 -245.170196) (xy 381.171918 -245.21847) (xy 381.180082 -245.268704) (xy 381.180594 -245.29415)
			(xy 381.180082 -245.319596) (xy 381.171918 -245.36983) (xy 381.155802 -245.418104) (xy 381.132151 -245.463167)
			(xy 381.101578 -245.503853) (xy 381.064874 -245.539108) (xy 381.02299 -245.568018) (xy 380.977011 -245.589835)
			(xy 380.928127 -245.603995) (xy 380.877606 -245.610129) (xy 380.826754 -245.60808) (xy 380.77689 -245.5979)
			(xy 380.729304 -245.579853) (xy 380.68523 -245.554407) (xy 380.645808 -245.52222) (xy 380.61206 -245.484126)
			(xy 380.584859 -245.441112) (xy 380.564911 -245.394292) (xy 380.552732 -245.344878) (xy 380.548637 -245.29415)
			(xy 380.242826 -245.29415) (xy 380.242336 -245.319139) (xy 380.234517 -245.368502) (xy 380.219073 -245.416034)
			(xy 380.196383 -245.460566) (xy 380.167007 -245.500999) (xy 380.131667 -245.536339) (xy 380.091234 -245.565715)
			(xy 380.046702 -245.588405) (xy 379.99917 -245.603849) (xy 379.949807 -245.611668) (xy 379.899829 -245.611668)
			(xy 379.850466 -245.603849) (xy 379.802934 -245.588405) (xy 379.758402 -245.565715) (xy 379.717969 -245.536339)
			(xy 379.682629 -245.500999) (xy 379.653253 -245.460566) (xy 379.630563 -245.416034) (xy 379.615119 -245.368502)
			(xy 379.6073 -245.319139) (xy 379.299983 -245.319139) (xy 379.299974 -245.319596) (xy 379.29181 -245.36983)
			(xy 379.275694 -245.418104) (xy 379.252043 -245.463167) (xy 379.22147 -245.503853) (xy 379.184766 -245.539108)
			(xy 379.142882 -245.568018) (xy 379.096903 -245.589835) (xy 379.048019 -245.603995) (xy 378.997498 -245.610129)
			(xy 378.946646 -245.60808) (xy 378.896782 -245.5979) (xy 378.849196 -245.579853) (xy 378.805122 -245.554407)
			(xy 378.7657 -245.52222) (xy 378.731952 -245.484126) (xy 378.704751 -245.441112) (xy 378.684803 -245.394292)
			(xy 378.672624 -245.344878) (xy 378.668529 -245.29415) (xy 378.362718 -245.29415) (xy 378.362228 -245.319139)
			(xy 378.354409 -245.368502) (xy 378.338965 -245.416034) (xy 378.316275 -245.460566) (xy 378.286899 -245.500999)
			(xy 378.251559 -245.536339) (xy 378.211126 -245.565715) (xy 378.166594 -245.588405) (xy 378.119062 -245.603849)
			(xy 378.069699 -245.611668) (xy 378.019721 -245.611668) (xy 377.970358 -245.603849) (xy 377.922826 -245.588405)
			(xy 377.878294 -245.565715) (xy 377.837861 -245.536339) (xy 377.802521 -245.500999) (xy 377.773145 -245.460566)
			(xy 377.750455 -245.416034) (xy 377.735011 -245.368502) (xy 377.727192 -245.319139) (xy 377.420129 -245.319139)
			(xy 377.42012 -245.319596) (xy 377.411956 -245.36983) (xy 377.39584 -245.418104) (xy 377.372189 -245.463167)
			(xy 377.341616 -245.503853) (xy 377.304912 -245.539108) (xy 377.263028 -245.568018) (xy 377.217049 -245.589835)
			(xy 377.168165 -245.603995) (xy 377.117644 -245.610129) (xy 377.066792 -245.60808) (xy 377.016928 -245.5979)
			(xy 376.969342 -245.579853) (xy 376.925268 -245.554407) (xy 376.885846 -245.52222) (xy 376.852098 -245.484126)
			(xy 376.824897 -245.441112) (xy 376.804949 -245.394292) (xy 376.79277 -245.344878) (xy 376.788675 -245.29415)
			(xy 376.480578 -245.29415) (xy 376.480066 -245.319596) (xy 376.471902 -245.36983) (xy 376.455786 -245.418104)
			(xy 376.432135 -245.463167) (xy 376.401562 -245.503853) (xy 376.364858 -245.539108) (xy 376.322974 -245.568018)
			(xy 376.276995 -245.589835) (xy 376.228111 -245.603995) (xy 376.17759 -245.610129) (xy 376.126738 -245.60808)
			(xy 376.076874 -245.5979) (xy 376.029288 -245.579853) (xy 375.985214 -245.554407) (xy 375.945792 -245.52222)
			(xy 375.912044 -245.484126) (xy 375.884843 -245.441112) (xy 375.864895 -245.394292) (xy 375.852716 -245.344878)
			(xy 375.848621 -245.29415) (xy 375.54281 -245.29415) (xy 375.54232 -245.319139) (xy 375.534501 -245.368502)
			(xy 375.519057 -245.416034) (xy 375.496367 -245.460566) (xy 375.466991 -245.500999) (xy 375.431651 -245.536339)
			(xy 375.391218 -245.565715) (xy 375.346686 -245.588405) (xy 375.299154 -245.603849) (xy 375.249791 -245.611668)
			(xy 375.199813 -245.611668) (xy 375.15045 -245.603849) (xy 375.102918 -245.588405) (xy 375.058386 -245.565715)
			(xy 375.017953 -245.536339) (xy 374.982613 -245.500999) (xy 374.953237 -245.460566) (xy 374.930547 -245.416034)
			(xy 374.915103 -245.368502) (xy 374.907284 -245.319139) (xy 374.703086 -245.319139) (xy 374.703086 -245.71071)
			(xy 374.70334 -245.71198) (xy 374.70334 -245.720108) (xy 374.704368 -245.72778) (xy 374.710435 -245.742011)
			(xy 374.715278 -245.748048) (xy 374.732804 -245.765574) (xy 374.736129 -245.768687) (xy 374.743667 -245.773797)
			(xy 374.74779 -245.775734) (xy 374.771666 -245.786402) (xy 374.780302 -245.787164) (xy 374.805152 -245.789645)
			(xy 374.853695 -245.801364) (xy 374.89981 -245.820526) (xy 374.942364 -245.846659) (xy 374.980311 -245.879122)
			(xy 375.012717 -245.917116) (xy 375.038788 -245.959709) (xy 375.057881 -246.005852) (xy 375.069529 -246.054412)
			(xy 375.073441 -246.104156) (xy 375.378467 -246.104156) (xy 375.382562 -246.053428) (xy 375.394741 -246.004014)
			(xy 375.414689 -245.957194) (xy 375.44189 -245.91418) (xy 375.475638 -245.876086) (xy 375.51506 -245.843899)
			(xy 375.559134 -245.818453) (xy 375.60672 -245.800406) (xy 375.656584 -245.790226) (xy 375.707436 -245.788177)
			(xy 375.757957 -245.794311) (xy 375.806841 -245.808471) (xy 375.85282 -245.830288) (xy 375.894704 -245.859198)
			(xy 375.931408 -245.894453) (xy 375.961981 -245.935139) (xy 375.985632 -245.980202) (xy 376.001748 -246.028476)
			(xy 376.009912 -246.07871) (xy 376.010424 -246.104156) (xy 376.009921 -246.129145) (xy 376.317238 -246.129145)
			(xy 376.317238 -246.079167) (xy 376.325057 -246.029804) (xy 376.340501 -245.982272) (xy 376.363191 -245.93774)
			(xy 376.392567 -245.897307) (xy 376.427907 -245.861967) (xy 376.46834 -245.832591) (xy 376.512872 -245.809901)
			(xy 376.560404 -245.794457) (xy 376.609767 -245.786638) (xy 376.659745 -245.786638) (xy 376.709108 -245.794457)
			(xy 376.75664 -245.809901) (xy 376.801172 -245.832591) (xy 376.841605 -245.861967) (xy 376.876945 -245.897307)
			(xy 376.906321 -245.93774) (xy 376.929011 -245.982272) (xy 376.944455 -246.029804) (xy 376.952274 -246.079167)
			(xy 376.952764 -246.104156) (xy 377.258575 -246.104156) (xy 377.26267 -246.053428) (xy 377.274849 -246.004014)
			(xy 377.294797 -245.957194) (xy 377.321998 -245.91418) (xy 377.355746 -245.876086) (xy 377.395168 -245.843899)
			(xy 377.439242 -245.818453) (xy 377.486828 -245.800406) (xy 377.536692 -245.790226) (xy 377.587544 -245.788177)
			(xy 377.638065 -245.794311) (xy 377.686949 -245.808471) (xy 377.732928 -245.830288) (xy 377.774812 -245.859198)
			(xy 377.811516 -245.894453) (xy 377.842089 -245.935139) (xy 377.86574 -245.980202) (xy 377.881856 -246.028476)
			(xy 377.89002 -246.07871) (xy 377.890532 -246.104156) (xy 377.890029 -246.129145) (xy 378.197346 -246.129145)
			(xy 378.197346 -246.079167) (xy 378.205165 -246.029804) (xy 378.220609 -245.982272) (xy 378.243299 -245.93774)
			(xy 378.272675 -245.897307) (xy 378.308015 -245.861967) (xy 378.348448 -245.832591) (xy 378.39298 -245.809901)
			(xy 378.440512 -245.794457) (xy 378.489875 -245.786638) (xy 378.539853 -245.786638) (xy 378.589216 -245.794457)
			(xy 378.636748 -245.809901) (xy 378.68128 -245.832591) (xy 378.721713 -245.861967) (xy 378.757053 -245.897307)
			(xy 378.786429 -245.93774) (xy 378.809119 -245.982272) (xy 378.824563 -246.029804) (xy 378.832382 -246.079167)
			(xy 378.832872 -246.104156) (xy 379.138683 -246.104156) (xy 379.142778 -246.053428) (xy 379.154957 -246.004014)
			(xy 379.174905 -245.957194) (xy 379.202106 -245.91418) (xy 379.235854 -245.876086) (xy 379.275276 -245.843899)
			(xy 379.31935 -245.818453) (xy 379.366936 -245.800406) (xy 379.4168 -245.790226) (xy 379.467652 -245.788177)
			(xy 379.518173 -245.794311) (xy 379.567057 -245.808471) (xy 379.613036 -245.830288) (xy 379.65492 -245.859198)
			(xy 379.691624 -245.894453) (xy 379.722197 -245.935139) (xy 379.745848 -245.980202) (xy 379.761964 -246.028476)
			(xy 379.770128 -246.07871) (xy 379.77064 -246.104156) (xy 380.078483 -246.104156) (xy 380.082578 -246.053428)
			(xy 380.094757 -246.004014) (xy 380.114705 -245.957194) (xy 380.141906 -245.91418) (xy 380.175654 -245.876086)
			(xy 380.215076 -245.843899) (xy 380.25915 -245.818453) (xy 380.306736 -245.800406) (xy 380.3566 -245.790226)
			(xy 380.407452 -245.788177) (xy 380.457973 -245.794311) (xy 380.506857 -245.808471) (xy 380.552836 -245.830288)
			(xy 380.59472 -245.859198) (xy 380.631424 -245.894453) (xy 380.661997 -245.935139) (xy 380.685648 -245.980202)
			(xy 380.701764 -246.028476) (xy 380.709928 -246.07871) (xy 380.71044 -246.104156) (xy 380.709928 -246.129602)
			(xy 380.701764 -246.179836) (xy 380.685648 -246.22811) (xy 380.661997 -246.273173) (xy 380.631424 -246.313859)
			(xy 380.59472 -246.349114) (xy 380.552836 -246.378024) (xy 380.506857 -246.399841) (xy 380.457973 -246.414001)
			(xy 380.407452 -246.420135) (xy 380.3566 -246.418086) (xy 380.306736 -246.407906) (xy 380.25915 -246.389859)
			(xy 380.215076 -246.364413) (xy 380.175654 -246.332226) (xy 380.141906 -246.294132) (xy 380.114705 -246.251118)
			(xy 380.094757 -246.204298) (xy 380.082578 -246.154884) (xy 380.078483 -246.104156) (xy 379.77064 -246.104156)
			(xy 379.770128 -246.129602) (xy 379.761964 -246.179836) (xy 379.745848 -246.22811) (xy 379.722197 -246.273173)
			(xy 379.691624 -246.313859) (xy 379.65492 -246.349114) (xy 379.613036 -246.378024) (xy 379.567057 -246.399841)
			(xy 379.518173 -246.414001) (xy 379.467652 -246.420135) (xy 379.4168 -246.418086) (xy 379.366936 -246.407906)
			(xy 379.31935 -246.389859) (xy 379.275276 -246.364413) (xy 379.235854 -246.332226) (xy 379.202106 -246.294132)
			(xy 379.174905 -246.251118) (xy 379.154957 -246.204298) (xy 379.142778 -246.154884) (xy 379.138683 -246.104156)
			(xy 378.832872 -246.104156) (xy 378.832382 -246.129145) (xy 378.824563 -246.178508) (xy 378.809119 -246.22604)
			(xy 378.786429 -246.270572) (xy 378.757053 -246.311005) (xy 378.721713 -246.346345) (xy 378.68128 -246.375721)
			(xy 378.636748 -246.398411) (xy 378.589216 -246.413855) (xy 378.539853 -246.421674) (xy 378.489875 -246.421674)
			(xy 378.440512 -246.413855) (xy 378.39298 -246.398411) (xy 378.348448 -246.375721) (xy 378.308015 -246.346345)
			(xy 378.272675 -246.311005) (xy 378.243299 -246.270572) (xy 378.220609 -246.22604) (xy 378.205165 -246.178508)
			(xy 378.197346 -246.129145) (xy 377.890029 -246.129145) (xy 377.89002 -246.129602) (xy 377.881856 -246.179836)
			(xy 377.86574 -246.22811) (xy 377.842089 -246.273173) (xy 377.811516 -246.313859) (xy 377.774812 -246.349114)
			(xy 377.732928 -246.378024) (xy 377.686949 -246.399841) (xy 377.638065 -246.414001) (xy 377.587544 -246.420135)
			(xy 377.536692 -246.418086) (xy 377.486828 -246.407906) (xy 377.439242 -246.389859) (xy 377.395168 -246.364413)
			(xy 377.355746 -246.332226) (xy 377.321998 -246.294132) (xy 377.294797 -246.251118) (xy 377.274849 -246.204298)
			(xy 377.26267 -246.154884) (xy 377.258575 -246.104156) (xy 376.952764 -246.104156) (xy 376.952274 -246.129145)
			(xy 376.944455 -246.178508) (xy 376.929011 -246.22604) (xy 376.906321 -246.270572) (xy 376.876945 -246.311005)
			(xy 376.841605 -246.346345) (xy 376.801172 -246.375721) (xy 376.75664 -246.398411) (xy 376.709108 -246.413855)
			(xy 376.659745 -246.421674) (xy 376.609767 -246.421674) (xy 376.560404 -246.413855) (xy 376.512872 -246.398411)
			(xy 376.46834 -246.375721) (xy 376.427907 -246.346345) (xy 376.392567 -246.311005) (xy 376.363191 -246.270572)
			(xy 376.340501 -246.22604) (xy 376.325057 -246.178508) (xy 376.317238 -246.129145) (xy 376.009921 -246.129145)
			(xy 376.009912 -246.129602) (xy 376.001748 -246.179836) (xy 375.985632 -246.22811) (xy 375.961981 -246.273173)
			(xy 375.931408 -246.313859) (xy 375.894704 -246.349114) (xy 375.85282 -246.378024) (xy 375.806841 -246.399841)
			(xy 375.757957 -246.414001) (xy 375.707436 -246.420135) (xy 375.656584 -246.418086) (xy 375.60672 -246.407906)
			(xy 375.559134 -246.389859) (xy 375.51506 -246.364413) (xy 375.475638 -246.332226) (xy 375.44189 -246.294132)
			(xy 375.414689 -246.251118) (xy 375.394741 -246.204298) (xy 375.382562 -246.154884) (xy 375.378467 -246.104156)
			(xy 375.073441 -246.104156) (xy 375.073444 -246.104196) (xy 375.06953 -246.153981) (xy 375.057883 -246.202541)
			(xy 375.038791 -246.248685) (xy 375.012721 -246.291278) (xy 374.980316 -246.329273) (xy 374.94237 -246.361737)
			(xy 374.899817 -246.387871) (xy 374.853702 -246.407034) (xy 374.805159 -246.418754) (xy 374.780302 -246.421148)
			(xy 374.771666 -246.42191) (xy 374.74779 -246.432578) (xy 374.74367 -246.434518) (xy 374.73614 -246.439637)
			(xy 374.732804 -246.442738) (xy 374.715278 -246.460264) (xy 374.710431 -246.4663) (xy 374.704357 -246.480529)
			(xy 374.70334 -246.488204) (xy 374.70334 -246.496332) (xy 374.703086 -246.497602) (xy 374.703086 -246.914162)
			(xy 375.848621 -246.914162) (xy 375.852716 -246.863434) (xy 375.864895 -246.81402) (xy 375.884843 -246.7672)
			(xy 375.912044 -246.724186) (xy 375.945792 -246.686092) (xy 375.985214 -246.653905) (xy 376.029288 -246.628459)
			(xy 376.076874 -246.610412) (xy 376.126738 -246.600232) (xy 376.17759 -246.598183) (xy 376.228111 -246.604317)
			(xy 376.276995 -246.618477) (xy 376.322974 -246.640294) (xy 376.364858 -246.669204) (xy 376.401562 -246.704459)
			(xy 376.432135 -246.745145) (xy 376.455786 -246.790208) (xy 376.471902 -246.838482) (xy 376.480066 -246.888716)
			(xy 376.480578 -246.914162) (xy 376.788675 -246.914162) (xy 376.79277 -246.863434) (xy 376.804949 -246.81402)
			(xy 376.824897 -246.7672) (xy 376.852098 -246.724186) (xy 376.885846 -246.686092) (xy 376.925268 -246.653905)
			(xy 376.969342 -246.628459) (xy 377.016928 -246.610412) (xy 377.066792 -246.600232) (xy 377.117644 -246.598183)
			(xy 377.168165 -246.604317) (xy 377.217049 -246.618477) (xy 377.263028 -246.640294) (xy 377.304912 -246.669204)
			(xy 377.341616 -246.704459) (xy 377.372189 -246.745145) (xy 377.39584 -246.790208) (xy 377.411956 -246.838482)
			(xy 377.42012 -246.888716) (xy 377.420632 -246.914162) (xy 378.668529 -246.914162) (xy 378.672624 -246.863434)
			(xy 378.684803 -246.81402) (xy 378.704751 -246.7672) (xy 378.731952 -246.724186) (xy 378.7657 -246.686092)
			(xy 378.805122 -246.653905) (xy 378.849196 -246.628459) (xy 378.896782 -246.610412) (xy 378.946646 -246.600232)
			(xy 378.997498 -246.598183) (xy 379.048019 -246.604317) (xy 379.096903 -246.618477) (xy 379.142882 -246.640294)
			(xy 379.184766 -246.669204) (xy 379.22147 -246.704459) (xy 379.252043 -246.745145) (xy 379.275694 -246.790208)
			(xy 379.29181 -246.838482) (xy 379.299974 -246.888716) (xy 379.300486 -246.914162) (xy 379.299983 -246.939151)
			(xy 379.6073 -246.939151) (xy 379.6073 -246.889173) (xy 379.615119 -246.83981) (xy 379.630563 -246.792278)
			(xy 379.653253 -246.747746) (xy 379.682629 -246.707313) (xy 379.717969 -246.671973) (xy 379.758402 -246.642597)
			(xy 379.802934 -246.619907) (xy 379.850466 -246.604463) (xy 379.899829 -246.596644) (xy 379.949807 -246.596644)
			(xy 379.99917 -246.604463) (xy 380.046702 -246.619907) (xy 380.091234 -246.642597) (xy 380.131667 -246.671973)
			(xy 380.167007 -246.707313) (xy 380.196383 -246.747746) (xy 380.219073 -246.792278) (xy 380.234517 -246.83981)
			(xy 380.242336 -246.889173) (xy 380.242826 -246.914162) (xy 380.548637 -246.914162) (xy 380.552732 -246.863434)
			(xy 380.564911 -246.81402) (xy 380.584859 -246.7672) (xy 380.61206 -246.724186) (xy 380.645808 -246.686092)
			(xy 380.68523 -246.653905) (xy 380.729304 -246.628459) (xy 380.77689 -246.610412) (xy 380.826754 -246.600232)
			(xy 380.877606 -246.598183) (xy 380.928127 -246.604317) (xy 380.977011 -246.618477) (xy 381.02299 -246.640294)
			(xy 381.064874 -246.669204) (xy 381.101578 -246.704459) (xy 381.132151 -246.745145) (xy 381.155802 -246.790208)
			(xy 381.171918 -246.838482) (xy 381.180082 -246.888716) (xy 381.180594 -246.914162) (xy 381.180082 -246.939608)
			(xy 381.171918 -246.989842) (xy 381.155802 -247.038116) (xy 381.132151 -247.083179) (xy 381.101578 -247.123865)
			(xy 381.064874 -247.15912) (xy 381.02299 -247.18803) (xy 380.977011 -247.209847) (xy 380.928127 -247.224007)
			(xy 380.877606 -247.230141) (xy 380.826754 -247.228092) (xy 380.77689 -247.217912) (xy 380.729304 -247.199865)
			(xy 380.68523 -247.174419) (xy 380.645808 -247.142232) (xy 380.61206 -247.104138) (xy 380.584859 -247.061124)
			(xy 380.564911 -247.014304) (xy 380.552732 -246.96489) (xy 380.548637 -246.914162) (xy 380.242826 -246.914162)
			(xy 380.242336 -246.939151) (xy 380.234517 -246.988514) (xy 380.219073 -247.036046) (xy 380.196383 -247.080578)
			(xy 380.167007 -247.121011) (xy 380.131667 -247.156351) (xy 380.091234 -247.185727) (xy 380.046702 -247.208417)
			(xy 379.99917 -247.223861) (xy 379.949807 -247.23168) (xy 379.899829 -247.23168) (xy 379.850466 -247.223861)
			(xy 379.802934 -247.208417) (xy 379.758402 -247.185727) (xy 379.717969 -247.156351) (xy 379.682629 -247.121011)
			(xy 379.653253 -247.080578) (xy 379.630563 -247.036046) (xy 379.615119 -246.988514) (xy 379.6073 -246.939151)
			(xy 379.299983 -246.939151) (xy 379.299974 -246.939608) (xy 379.29181 -246.989842) (xy 379.275694 -247.038116)
			(xy 379.252043 -247.083179) (xy 379.22147 -247.123865) (xy 379.184766 -247.15912) (xy 379.142882 -247.18803)
			(xy 379.096903 -247.209847) (xy 379.048019 -247.224007) (xy 378.997498 -247.230141) (xy 378.946646 -247.228092)
			(xy 378.896782 -247.217912) (xy 378.849196 -247.199865) (xy 378.805122 -247.174419) (xy 378.7657 -247.142232)
			(xy 378.731952 -247.104138) (xy 378.704751 -247.061124) (xy 378.684803 -247.014304) (xy 378.672624 -246.96489)
			(xy 378.668529 -246.914162) (xy 377.420632 -246.914162) (xy 377.42012 -246.939608) (xy 377.411956 -246.989842)
			(xy 377.39584 -247.038116) (xy 377.372189 -247.083179) (xy 377.341616 -247.123865) (xy 377.304912 -247.15912)
			(xy 377.263028 -247.18803) (xy 377.217049 -247.209847) (xy 377.168165 -247.224007) (xy 377.117644 -247.230141)
			(xy 377.066792 -247.228092) (xy 377.016928 -247.217912) (xy 376.969342 -247.199865) (xy 376.925268 -247.174419)
			(xy 376.885846 -247.142232) (xy 376.852098 -247.104138) (xy 376.824897 -247.061124) (xy 376.804949 -247.014304)
			(xy 376.79277 -246.96489) (xy 376.788675 -246.914162) (xy 376.480578 -246.914162) (xy 376.480066 -246.939608)
			(xy 376.471902 -246.989842) (xy 376.455786 -247.038116) (xy 376.432135 -247.083179) (xy 376.401562 -247.123865)
			(xy 376.364858 -247.15912) (xy 376.322974 -247.18803) (xy 376.276995 -247.209847) (xy 376.228111 -247.224007)
			(xy 376.17759 -247.230141) (xy 376.126738 -247.228092) (xy 376.076874 -247.217912) (xy 376.029288 -247.199865)
			(xy 375.985214 -247.174419) (xy 375.945792 -247.142232) (xy 375.912044 -247.104138) (xy 375.884843 -247.061124)
			(xy 375.864895 -247.014304) (xy 375.852716 -246.96489) (xy 375.848621 -246.914162) (xy 374.703086 -246.914162)
			(xy 374.703086 -247.330722) (xy 374.70334 -247.331992) (xy 374.70334 -247.34012) (xy 374.70437 -247.347791)
			(xy 374.71044 -247.36202) (xy 374.715278 -247.36806) (xy 374.732804 -247.385586) (xy 374.736129 -247.388698)
			(xy 374.743668 -247.393808) (xy 374.74779 -247.395746) (xy 374.771666 -247.406414) (xy 374.780302 -247.407176)
			(xy 374.805151 -247.409657) (xy 374.853692 -247.421376) (xy 374.899806 -247.440537) (xy 374.942358 -247.46667)
			(xy 374.980303 -247.499131) (xy 375.012708 -247.537124) (xy 375.038778 -247.579715) (xy 375.05787 -247.625857)
			(xy 375.069517 -247.674415) (xy 375.07343 -247.724168) (xy 375.378467 -247.724168) (xy 375.382562 -247.67344)
			(xy 375.394741 -247.624026) (xy 375.414689 -247.577206) (xy 375.44189 -247.534192) (xy 375.475638 -247.496098)
			(xy 375.51506 -247.463911) (xy 375.559134 -247.438465) (xy 375.60672 -247.420418) (xy 375.656584 -247.410238)
			(xy 375.707436 -247.408189) (xy 375.757957 -247.414323) (xy 375.806841 -247.428483) (xy 375.85282 -247.4503)
			(xy 375.894704 -247.47921) (xy 375.931408 -247.514465) (xy 375.961981 -247.555151) (xy 375.985632 -247.600214)
			(xy 376.001748 -247.648488) (xy 376.009912 -247.698722) (xy 376.010424 -247.724168) (xy 376.009921 -247.749157)
			(xy 376.317238 -247.749157) (xy 376.317238 -247.699179) (xy 376.325057 -247.649816) (xy 376.340501 -247.602284)
			(xy 376.363191 -247.557752) (xy 376.392567 -247.517319) (xy 376.427907 -247.481979) (xy 376.46834 -247.452603)
			(xy 376.512872 -247.429913) (xy 376.560404 -247.414469) (xy 376.609767 -247.40665) (xy 376.659745 -247.40665)
			(xy 376.709108 -247.414469) (xy 376.75664 -247.429913) (xy 376.801172 -247.452603) (xy 376.841605 -247.481979)
			(xy 376.876945 -247.517319) (xy 376.906321 -247.557752) (xy 376.929011 -247.602284) (xy 376.944455 -247.649816)
			(xy 376.952274 -247.699179) (xy 376.952764 -247.724168) (xy 377.258575 -247.724168) (xy 377.26267 -247.67344)
			(xy 377.274849 -247.624026) (xy 377.294797 -247.577206) (xy 377.321998 -247.534192) (xy 377.355746 -247.496098)
			(xy 377.395168 -247.463911) (xy 377.439242 -247.438465) (xy 377.486828 -247.420418) (xy 377.536692 -247.410238)
			(xy 377.587544 -247.408189) (xy 377.638065 -247.414323) (xy 377.686949 -247.428483) (xy 377.732928 -247.4503)
			(xy 377.774812 -247.47921) (xy 377.811516 -247.514465) (xy 377.842089 -247.555151) (xy 377.86574 -247.600214)
			(xy 377.881856 -247.648488) (xy 377.89002 -247.698722) (xy 377.890532 -247.724168) (xy 377.890029 -247.749157)
			(xy 378.197346 -247.749157) (xy 378.197346 -247.699179) (xy 378.205165 -247.649816) (xy 378.220609 -247.602284)
			(xy 378.243299 -247.557752) (xy 378.272675 -247.517319) (xy 378.308015 -247.481979) (xy 378.348448 -247.452603)
			(xy 378.39298 -247.429913) (xy 378.440512 -247.414469) (xy 378.489875 -247.40665) (xy 378.539853 -247.40665)
			(xy 378.589216 -247.414469) (xy 378.636748 -247.429913) (xy 378.68128 -247.452603) (xy 378.721713 -247.481979)
			(xy 378.757053 -247.517319) (xy 378.786429 -247.557752) (xy 378.809119 -247.602284) (xy 378.824563 -247.649816)
			(xy 378.832382 -247.699179) (xy 378.832872 -247.724168) (xy 379.138683 -247.724168) (xy 379.142778 -247.67344)
			(xy 379.154957 -247.624026) (xy 379.174905 -247.577206) (xy 379.202106 -247.534192) (xy 379.235854 -247.496098)
			(xy 379.275276 -247.463911) (xy 379.31935 -247.438465) (xy 379.366936 -247.420418) (xy 379.4168 -247.410238)
			(xy 379.467652 -247.408189) (xy 379.518173 -247.414323) (xy 379.567057 -247.428483) (xy 379.613036 -247.4503)
			(xy 379.65492 -247.47921) (xy 379.691624 -247.514465) (xy 379.722197 -247.555151) (xy 379.745848 -247.600214)
			(xy 379.761964 -247.648488) (xy 379.770128 -247.698722) (xy 379.77064 -247.724168) (xy 380.078483 -247.724168)
			(xy 380.082578 -247.67344) (xy 380.094757 -247.624026) (xy 380.114705 -247.577206) (xy 380.141906 -247.534192)
			(xy 380.175654 -247.496098) (xy 380.215076 -247.463911) (xy 380.25915 -247.438465) (xy 380.306736 -247.420418)
			(xy 380.3566 -247.410238) (xy 380.407452 -247.408189) (xy 380.457973 -247.414323) (xy 380.506857 -247.428483)
			(xy 380.552836 -247.4503) (xy 380.59472 -247.47921) (xy 380.631424 -247.514465) (xy 380.661997 -247.555151)
			(xy 380.685648 -247.600214) (xy 380.701764 -247.648488) (xy 380.709928 -247.698722) (xy 380.71044 -247.724168)
			(xy 380.709928 -247.749614) (xy 380.701764 -247.799848) (xy 380.685648 -247.848122) (xy 380.661997 -247.893185)
			(xy 380.631424 -247.933871) (xy 380.59472 -247.969126) (xy 380.552836 -247.998036) (xy 380.506857 -248.019853)
			(xy 380.457973 -248.034013) (xy 380.407452 -248.040147) (xy 380.3566 -248.038098) (xy 380.306736 -248.027918)
			(xy 380.25915 -248.009871) (xy 380.215076 -247.984425) (xy 380.175654 -247.952238) (xy 380.141906 -247.914144)
			(xy 380.114705 -247.87113) (xy 380.094757 -247.82431) (xy 380.082578 -247.774896) (xy 380.078483 -247.724168)
			(xy 379.77064 -247.724168) (xy 379.770128 -247.749614) (xy 379.761964 -247.799848) (xy 379.745848 -247.848122)
			(xy 379.722197 -247.893185) (xy 379.691624 -247.933871) (xy 379.65492 -247.969126) (xy 379.613036 -247.998036)
			(xy 379.567057 -248.019853) (xy 379.518173 -248.034013) (xy 379.467652 -248.040147) (xy 379.4168 -248.038098)
			(xy 379.366936 -248.027918) (xy 379.31935 -248.009871) (xy 379.275276 -247.984425) (xy 379.235854 -247.952238)
			(xy 379.202106 -247.914144) (xy 379.174905 -247.87113) (xy 379.154957 -247.82431) (xy 379.142778 -247.774896)
			(xy 379.138683 -247.724168) (xy 378.832872 -247.724168) (xy 378.832382 -247.749157) (xy 378.824563 -247.79852)
			(xy 378.809119 -247.846052) (xy 378.786429 -247.890584) (xy 378.757053 -247.931017) (xy 378.721713 -247.966357)
			(xy 378.68128 -247.995733) (xy 378.636748 -248.018423) (xy 378.589216 -248.033867) (xy 378.539853 -248.041686)
			(xy 378.489875 -248.041686) (xy 378.440512 -248.033867) (xy 378.39298 -248.018423) (xy 378.348448 -247.995733)
			(xy 378.308015 -247.966357) (xy 378.272675 -247.931017) (xy 378.243299 -247.890584) (xy 378.220609 -247.846052)
			(xy 378.205165 -247.79852) (xy 378.197346 -247.749157) (xy 377.890029 -247.749157) (xy 377.89002 -247.749614)
			(xy 377.881856 -247.799848) (xy 377.86574 -247.848122) (xy 377.842089 -247.893185) (xy 377.811516 -247.933871)
			(xy 377.774812 -247.969126) (xy 377.732928 -247.998036) (xy 377.686949 -248.019853) (xy 377.638065 -248.034013)
			(xy 377.587544 -248.040147) (xy 377.536692 -248.038098) (xy 377.486828 -248.027918) (xy 377.439242 -248.009871)
			(xy 377.395168 -247.984425) (xy 377.355746 -247.952238) (xy 377.321998 -247.914144) (xy 377.294797 -247.87113)
			(xy 377.274849 -247.82431) (xy 377.26267 -247.774896) (xy 377.258575 -247.724168) (xy 376.952764 -247.724168)
			(xy 376.952274 -247.749157) (xy 376.944455 -247.79852) (xy 376.929011 -247.846052) (xy 376.906321 -247.890584)
			(xy 376.876945 -247.931017) (xy 376.841605 -247.966357) (xy 376.801172 -247.995733) (xy 376.75664 -248.018423)
			(xy 376.709108 -248.033867) (xy 376.659745 -248.041686) (xy 376.609767 -248.041686) (xy 376.560404 -248.033867)
			(xy 376.512872 -248.018423) (xy 376.46834 -247.995733) (xy 376.427907 -247.966357) (xy 376.392567 -247.931017)
			(xy 376.363191 -247.890584) (xy 376.340501 -247.846052) (xy 376.325057 -247.79852) (xy 376.317238 -247.749157)
			(xy 376.009921 -247.749157) (xy 376.009912 -247.749614) (xy 376.001748 -247.799848) (xy 375.985632 -247.848122)
			(xy 375.961981 -247.893185) (xy 375.931408 -247.933871) (xy 375.894704 -247.969126) (xy 375.85282 -247.998036)
			(xy 375.806841 -248.019853) (xy 375.757957 -248.034013) (xy 375.707436 -248.040147) (xy 375.656584 -248.038098)
			(xy 375.60672 -248.027918) (xy 375.559134 -248.009871) (xy 375.51506 -247.984425) (xy 375.475638 -247.952238)
			(xy 375.44189 -247.914144) (xy 375.414689 -247.87113) (xy 375.394741 -247.82431) (xy 375.382562 -247.774896)
			(xy 375.378467 -247.724168) (xy 375.07343 -247.724168) (xy 375.073432 -247.724197) (xy 375.069518 -247.77398)
			(xy 375.057872 -247.822538) (xy 375.03878 -247.86868) (xy 375.012711 -247.911272) (xy 374.980306 -247.949265)
			(xy 374.942362 -247.981727) (xy 374.89981 -248.007861) (xy 374.853697 -248.027022) (xy 374.805156 -248.038742)
			(xy 374.780302 -248.04116) (xy 374.771666 -248.041922) (xy 374.74779 -248.05259) (xy 374.743668 -248.054527)
			(xy 374.736131 -248.059639) (xy 374.732804 -248.06275) (xy 374.715278 -248.080276) (xy 374.710433 -248.086313)
			(xy 374.704361 -248.100542) (xy 374.70334 -248.108216) (xy 374.70334 -248.116344) (xy 374.703086 -248.117614)
			(xy 374.703086 -248.559163) (xy 374.907284 -248.559163) (xy 374.907284 -248.509185) (xy 374.915103 -248.459822)
			(xy 374.930547 -248.41229) (xy 374.953237 -248.367758) (xy 374.982613 -248.327325) (xy 375.017953 -248.291985)
			(xy 375.058386 -248.262609) (xy 375.102918 -248.239919) (xy 375.15045 -248.224475) (xy 375.199813 -248.216656)
			(xy 375.249791 -248.216656) (xy 375.299154 -248.224475) (xy 375.346686 -248.239919) (xy 375.391218 -248.262609)
			(xy 375.431651 -248.291985) (xy 375.466991 -248.327325) (xy 375.496367 -248.367758) (xy 375.519057 -248.41229)
			(xy 375.534501 -248.459822) (xy 375.54232 -248.509185) (xy 375.54281 -248.534174) (xy 375.848621 -248.534174)
			(xy 375.852716 -248.483446) (xy 375.864895 -248.434032) (xy 375.884843 -248.387212) (xy 375.912044 -248.344198)
			(xy 375.945792 -248.306104) (xy 375.985214 -248.273917) (xy 376.029288 -248.248471) (xy 376.076874 -248.230424)
			(xy 376.126738 -248.220244) (xy 376.17759 -248.218195) (xy 376.228111 -248.224329) (xy 376.276995 -248.238489)
			(xy 376.322974 -248.260306) (xy 376.364858 -248.289216) (xy 376.401562 -248.324471) (xy 376.432135 -248.365157)
			(xy 376.455786 -248.41022) (xy 376.471902 -248.458494) (xy 376.480066 -248.508728) (xy 376.480578 -248.534174)
			(xy 376.788675 -248.534174) (xy 376.79277 -248.483446) (xy 376.804949 -248.434032) (xy 376.824897 -248.387212)
			(xy 376.852098 -248.344198) (xy 376.885846 -248.306104) (xy 376.925268 -248.273917) (xy 376.969342 -248.248471)
			(xy 377.016928 -248.230424) (xy 377.066792 -248.220244) (xy 377.117644 -248.218195) (xy 377.168165 -248.224329)
			(xy 377.217049 -248.238489) (xy 377.263028 -248.260306) (xy 377.304912 -248.289216) (xy 377.341616 -248.324471)
			(xy 377.372189 -248.365157) (xy 377.39584 -248.41022) (xy 377.411956 -248.458494) (xy 377.42012 -248.508728)
			(xy 377.420632 -248.534174) (xy 377.420129 -248.559163) (xy 377.727192 -248.559163) (xy 377.727192 -248.509185)
			(xy 377.735011 -248.459822) (xy 377.750455 -248.41229) (xy 377.773145 -248.367758) (xy 377.802521 -248.327325)
			(xy 377.837861 -248.291985) (xy 377.878294 -248.262609) (xy 377.922826 -248.239919) (xy 377.970358 -248.224475)
			(xy 378.019721 -248.216656) (xy 378.069699 -248.216656) (xy 378.119062 -248.224475) (xy 378.166594 -248.239919)
			(xy 378.211126 -248.262609) (xy 378.251559 -248.291985) (xy 378.286899 -248.327325) (xy 378.316275 -248.367758)
			(xy 378.338965 -248.41229) (xy 378.354409 -248.459822) (xy 378.362228 -248.509185) (xy 378.362718 -248.534174)
			(xy 378.668529 -248.534174) (xy 378.672624 -248.483446) (xy 378.684803 -248.434032) (xy 378.704751 -248.387212)
			(xy 378.731952 -248.344198) (xy 378.7657 -248.306104) (xy 378.805122 -248.273917) (xy 378.849196 -248.248471)
			(xy 378.896782 -248.230424) (xy 378.946646 -248.220244) (xy 378.997498 -248.218195) (xy 379.048019 -248.224329)
			(xy 379.096903 -248.238489) (xy 379.142882 -248.260306) (xy 379.184766 -248.289216) (xy 379.22147 -248.324471)
			(xy 379.252043 -248.365157) (xy 379.275694 -248.41022) (xy 379.29181 -248.458494) (xy 379.299974 -248.508728)
			(xy 379.300486 -248.534174) (xy 379.299983 -248.559163) (xy 379.6073 -248.559163) (xy 379.6073 -248.509185)
			(xy 379.615119 -248.459822) (xy 379.630563 -248.41229) (xy 379.653253 -248.367758) (xy 379.682629 -248.327325)
			(xy 379.717969 -248.291985) (xy 379.758402 -248.262609) (xy 379.802934 -248.239919) (xy 379.850466 -248.224475)
			(xy 379.899829 -248.216656) (xy 379.949807 -248.216656) (xy 379.99917 -248.224475) (xy 380.046702 -248.239919)
			(xy 380.091234 -248.262609) (xy 380.131667 -248.291985) (xy 380.167007 -248.327325) (xy 380.196383 -248.367758)
			(xy 380.219073 -248.41229) (xy 380.234517 -248.459822) (xy 380.242336 -248.509185) (xy 380.242826 -248.534174)
			(xy 380.548637 -248.534174) (xy 380.552732 -248.483446) (xy 380.564911 -248.434032) (xy 380.584859 -248.387212)
			(xy 380.61206 -248.344198) (xy 380.645808 -248.306104) (xy 380.68523 -248.273917) (xy 380.729304 -248.248471)
			(xy 380.77689 -248.230424) (xy 380.826754 -248.220244) (xy 380.877606 -248.218195) (xy 380.928127 -248.224329)
			(xy 380.977011 -248.238489) (xy 381.02299 -248.260306) (xy 381.064874 -248.289216) (xy 381.101578 -248.324471)
			(xy 381.132151 -248.365157) (xy 381.155802 -248.41022) (xy 381.171918 -248.458494) (xy 381.180082 -248.508728)
			(xy 381.180594 -248.534174) (xy 381.180082 -248.55962) (xy 381.171918 -248.609854) (xy 381.155802 -248.658128)
			(xy 381.132151 -248.703191) (xy 381.101578 -248.743877) (xy 381.064874 -248.779132) (xy 381.02299 -248.808042)
			(xy 380.977011 -248.829859) (xy 380.928127 -248.844019) (xy 380.877606 -248.850153) (xy 380.826754 -248.848104)
			(xy 380.77689 -248.837924) (xy 380.729304 -248.819877) (xy 380.68523 -248.794431) (xy 380.645808 -248.762244)
			(xy 380.61206 -248.72415) (xy 380.584859 -248.681136) (xy 380.564911 -248.634316) (xy 380.552732 -248.584902)
			(xy 380.548637 -248.534174) (xy 380.242826 -248.534174) (xy 380.242336 -248.559163) (xy 380.234517 -248.608526)
			(xy 380.219073 -248.656058) (xy 380.196383 -248.70059) (xy 380.167007 -248.741023) (xy 380.131667 -248.776363)
			(xy 380.091234 -248.805739) (xy 380.046702 -248.828429) (xy 379.99917 -248.843873) (xy 379.949807 -248.851692)
			(xy 379.899829 -248.851692) (xy 379.850466 -248.843873) (xy 379.802934 -248.828429) (xy 379.758402 -248.805739)
			(xy 379.717969 -248.776363) (xy 379.682629 -248.741023) (xy 379.653253 -248.70059) (xy 379.630563 -248.656058)
			(xy 379.615119 -248.608526) (xy 379.6073 -248.559163) (xy 379.299983 -248.559163) (xy 379.299974 -248.55962)
			(xy 379.29181 -248.609854) (xy 379.275694 -248.658128) (xy 379.252043 -248.703191) (xy 379.22147 -248.743877)
			(xy 379.184766 -248.779132) (xy 379.142882 -248.808042) (xy 379.096903 -248.829859) (xy 379.048019 -248.844019)
			(xy 378.997498 -248.850153) (xy 378.946646 -248.848104) (xy 378.896782 -248.837924) (xy 378.849196 -248.819877)
			(xy 378.805122 -248.794431) (xy 378.7657 -248.762244) (xy 378.731952 -248.72415) (xy 378.704751 -248.681136)
			(xy 378.684803 -248.634316) (xy 378.672624 -248.584902) (xy 378.668529 -248.534174) (xy 378.362718 -248.534174)
			(xy 378.362228 -248.559163) (xy 378.354409 -248.608526) (xy 378.338965 -248.656058) (xy 378.316275 -248.70059)
			(xy 378.286899 -248.741023) (xy 378.251559 -248.776363) (xy 378.211126 -248.805739) (xy 378.166594 -248.828429)
			(xy 378.119062 -248.843873) (xy 378.069699 -248.851692) (xy 378.019721 -248.851692) (xy 377.970358 -248.843873)
			(xy 377.922826 -248.828429) (xy 377.878294 -248.805739) (xy 377.837861 -248.776363) (xy 377.802521 -248.741023)
			(xy 377.773145 -248.70059) (xy 377.750455 -248.656058) (xy 377.735011 -248.608526) (xy 377.727192 -248.559163)
			(xy 377.420129 -248.559163) (xy 377.42012 -248.55962) (xy 377.411956 -248.609854) (xy 377.39584 -248.658128)
			(xy 377.372189 -248.703191) (xy 377.341616 -248.743877) (xy 377.304912 -248.779132) (xy 377.263028 -248.808042)
			(xy 377.217049 -248.829859) (xy 377.168165 -248.844019) (xy 377.117644 -248.850153) (xy 377.066792 -248.848104)
			(xy 377.016928 -248.837924) (xy 376.969342 -248.819877) (xy 376.925268 -248.794431) (xy 376.885846 -248.762244)
			(xy 376.852098 -248.72415) (xy 376.824897 -248.681136) (xy 376.804949 -248.634316) (xy 376.79277 -248.584902)
			(xy 376.788675 -248.534174) (xy 376.480578 -248.534174) (xy 376.480066 -248.55962) (xy 376.471902 -248.609854)
			(xy 376.455786 -248.658128) (xy 376.432135 -248.703191) (xy 376.401562 -248.743877) (xy 376.364858 -248.779132)
			(xy 376.322974 -248.808042) (xy 376.276995 -248.829859) (xy 376.228111 -248.844019) (xy 376.17759 -248.850153)
			(xy 376.126738 -248.848104) (xy 376.076874 -248.837924) (xy 376.029288 -248.819877) (xy 375.985214 -248.794431)
			(xy 375.945792 -248.762244) (xy 375.912044 -248.72415) (xy 375.884843 -248.681136) (xy 375.864895 -248.634316)
			(xy 375.852716 -248.584902) (xy 375.848621 -248.534174) (xy 375.54281 -248.534174) (xy 375.54232 -248.559163)
			(xy 375.534501 -248.608526) (xy 375.519057 -248.656058) (xy 375.496367 -248.70059) (xy 375.466991 -248.741023)
			(xy 375.431651 -248.776363) (xy 375.391218 -248.805739) (xy 375.346686 -248.828429) (xy 375.299154 -248.843873)
			(xy 375.249791 -248.851692) (xy 375.199813 -248.851692) (xy 375.15045 -248.843873) (xy 375.102918 -248.828429)
			(xy 375.058386 -248.805739) (xy 375.017953 -248.776363) (xy 374.982613 -248.741023) (xy 374.953237 -248.70059)
			(xy 374.930547 -248.656058) (xy 374.915103 -248.608526) (xy 374.907284 -248.559163) (xy 374.703086 -248.559163)
			(xy 374.703086 -248.950734) (xy 374.70334 -248.952004) (xy 374.70334 -248.960132) (xy 374.704371 -248.967802)
			(xy 374.710443 -248.982029) (xy 374.715278 -248.988072) (xy 374.732804 -249.005598) (xy 374.736127 -249.008714)
			(xy 374.743662 -249.013832) (xy 374.74779 -249.015758) (xy 374.771666 -249.026426) (xy 374.780302 -249.027188)
			(xy 374.80582 -249.029723) (xy 374.855616 -249.041967) (xy 374.902802 -249.062041) (xy 374.946156 -249.089426)
			(xy 374.984555 -249.123412) (xy 375.017004 -249.163119) (xy 375.042661 -249.207517) (xy 375.060863 -249.255456)
			(xy 375.071138 -249.305695) (xy 375.072701 -249.34418) (xy 375.378467 -249.34418) (xy 375.382562 -249.293452)
			(xy 375.394741 -249.244038) (xy 375.414689 -249.197218) (xy 375.44189 -249.154204) (xy 375.475638 -249.11611)
			(xy 375.51506 -249.083923) (xy 375.559134 -249.058477) (xy 375.60672 -249.04043) (xy 375.656584 -249.03025)
			(xy 375.707436 -249.028201) (xy 375.757957 -249.034335) (xy 375.806841 -249.048495) (xy 375.85282 -249.070312)
			(xy 375.894704 -249.099222) (xy 375.931408 -249.134477) (xy 375.961981 -249.175163) (xy 375.985632 -249.220226)
			(xy 376.001748 -249.2685) (xy 376.009912 -249.318734) (xy 376.010424 -249.34418) (xy 376.009921 -249.369169)
			(xy 376.317238 -249.369169) (xy 376.317238 -249.319191) (xy 376.325057 -249.269828) (xy 376.340501 -249.222296)
			(xy 376.363191 -249.177764) (xy 376.392567 -249.137331) (xy 376.427907 -249.101991) (xy 376.46834 -249.072615)
			(xy 376.512872 -249.049925) (xy 376.560404 -249.034481) (xy 376.609767 -249.026662) (xy 376.659745 -249.026662)
			(xy 376.709108 -249.034481) (xy 376.75664 -249.049925) (xy 376.801172 -249.072615) (xy 376.841605 -249.101991)
			(xy 376.876945 -249.137331) (xy 376.906321 -249.177764) (xy 376.929011 -249.222296) (xy 376.944455 -249.269828)
			(xy 376.952274 -249.319191) (xy 376.952764 -249.34418) (xy 376.952274 -249.369169) (xy 377.257292 -249.369169)
			(xy 377.257292 -249.319191) (xy 377.265111 -249.269828) (xy 377.280555 -249.222296) (xy 377.303245 -249.177764)
			(xy 377.332621 -249.137331) (xy 377.367961 -249.101991) (xy 377.408394 -249.072615) (xy 377.452926 -249.049925)
			(xy 377.500458 -249.034481) (xy 377.549821 -249.026662) (xy 377.599799 -249.026662) (xy 377.649162 -249.034481)
			(xy 377.696694 -249.049925) (xy 377.741226 -249.072615) (xy 377.781659 -249.101991) (xy 377.816999 -249.137331)
			(xy 377.846375 -249.177764) (xy 377.869065 -249.222296) (xy 377.884509 -249.269828) (xy 377.892328 -249.319191)
			(xy 377.892818 -249.34418) (xy 379.138683 -249.34418) (xy 379.142778 -249.293452) (xy 379.154957 -249.244038)
			(xy 379.174905 -249.197218) (xy 379.202106 -249.154204) (xy 379.235854 -249.11611) (xy 379.275276 -249.083923)
			(xy 379.31935 -249.058477) (xy 379.366936 -249.04043) (xy 379.4168 -249.03025) (xy 379.467652 -249.028201)
			(xy 379.518173 -249.034335) (xy 379.567057 -249.048495) (xy 379.613036 -249.070312) (xy 379.65492 -249.099222)
			(xy 379.691624 -249.134477) (xy 379.722197 -249.175163) (xy 379.745848 -249.220226) (xy 379.761964 -249.2685)
			(xy 379.770128 -249.318734) (xy 379.77064 -249.34418) (xy 379.770137 -249.369169) (xy 380.0772 -249.369169)
			(xy 380.0772 -249.319191) (xy 380.085019 -249.269828) (xy 380.100463 -249.222296) (xy 380.123153 -249.177764)
			(xy 380.152529 -249.137331) (xy 380.187869 -249.101991) (xy 380.228302 -249.072615) (xy 380.272834 -249.049925)
			(xy 380.320366 -249.034481) (xy 380.369729 -249.026662) (xy 380.419707 -249.026662) (xy 380.46907 -249.034481)
			(xy 380.516602 -249.049925) (xy 380.561134 -249.072615) (xy 380.601567 -249.101991) (xy 380.636907 -249.137331)
			(xy 380.666283 -249.177764) (xy 380.688973 -249.222296) (xy 380.704417 -249.269828) (xy 380.712236 -249.319191)
			(xy 380.712726 -249.34418) (xy 380.712236 -249.369169) (xy 380.704417 -249.418532) (xy 380.688973 -249.466064)
			(xy 380.666283 -249.510596) (xy 380.636907 -249.551029) (xy 380.601567 -249.586369) (xy 380.561134 -249.615745)
			(xy 380.516602 -249.638435) (xy 380.46907 -249.653879) (xy 380.419707 -249.661698) (xy 380.369729 -249.661698)
			(xy 380.320366 -249.653879) (xy 380.272834 -249.638435) (xy 380.228302 -249.615745) (xy 380.187869 -249.586369)
			(xy 380.152529 -249.551029) (xy 380.123153 -249.510596) (xy 380.100463 -249.466064) (xy 380.085019 -249.418532)
			(xy 380.0772 -249.369169) (xy 379.770137 -249.369169) (xy 379.770128 -249.369626) (xy 379.761964 -249.41986)
			(xy 379.745848 -249.468134) (xy 379.722197 -249.513197) (xy 379.691624 -249.553883) (xy 379.65492 -249.589138)
			(xy 379.613036 -249.618048) (xy 379.567057 -249.639865) (xy 379.518173 -249.654025) (xy 379.467652 -249.660159)
			(xy 379.4168 -249.65811) (xy 379.366936 -249.64793) (xy 379.31935 -249.629883) (xy 379.275276 -249.604437)
			(xy 379.235854 -249.57225) (xy 379.202106 -249.534156) (xy 379.174905 -249.491142) (xy 379.154957 -249.444322)
			(xy 379.142778 -249.394908) (xy 379.138683 -249.34418) (xy 377.892818 -249.34418) (xy 377.892328 -249.369169)
			(xy 377.884509 -249.418532) (xy 377.869065 -249.466064) (xy 377.846375 -249.510596) (xy 377.816999 -249.551029)
			(xy 377.781659 -249.586369) (xy 377.741226 -249.615745) (xy 377.696694 -249.638435) (xy 377.649162 -249.653879)
			(xy 377.599799 -249.661698) (xy 377.549821 -249.661698) (xy 377.500458 -249.653879) (xy 377.452926 -249.638435)
			(xy 377.408394 -249.615745) (xy 377.367961 -249.586369) (xy 377.332621 -249.551029) (xy 377.303245 -249.510596)
			(xy 377.280555 -249.466064) (xy 377.265111 -249.418532) (xy 377.257292 -249.369169) (xy 376.952274 -249.369169)
			(xy 376.944455 -249.418532) (xy 376.929011 -249.466064) (xy 376.906321 -249.510596) (xy 376.876945 -249.551029)
			(xy 376.841605 -249.586369) (xy 376.801172 -249.615745) (xy 376.75664 -249.638435) (xy 376.709108 -249.653879)
			(xy 376.659745 -249.661698) (xy 376.609767 -249.661698) (xy 376.560404 -249.653879) (xy 376.512872 -249.638435)
			(xy 376.46834 -249.615745) (xy 376.427907 -249.586369) (xy 376.392567 -249.551029) (xy 376.363191 -249.510596)
			(xy 376.340501 -249.466064) (xy 376.325057 -249.418532) (xy 376.317238 -249.369169) (xy 376.009921 -249.369169)
			(xy 376.009912 -249.369626) (xy 376.001748 -249.41986) (xy 375.985632 -249.468134) (xy 375.961981 -249.513197)
			(xy 375.931408 -249.553883) (xy 375.894704 -249.589138) (xy 375.85282 -249.618048) (xy 375.806841 -249.639865)
			(xy 375.757957 -249.654025) (xy 375.707436 -249.660159) (xy 375.656584 -249.65811) (xy 375.60672 -249.64793)
			(xy 375.559134 -249.629883) (xy 375.51506 -249.604437) (xy 375.475638 -249.57225) (xy 375.44189 -249.534156)
			(xy 375.414689 -249.491142) (xy 375.394741 -249.444322) (xy 375.382562 -249.394908) (xy 375.378467 -249.34418)
			(xy 375.072701 -249.34418) (xy 375.073219 -249.356932) (xy 375.067052 -249.407839) (xy 375.052798 -249.457096)
			(xy 375.030825 -249.503429) (xy 375.001704 -249.545636) (xy 374.966188 -249.582625) (xy 374.925197 -249.613435)
			(xy 374.879795 -249.63727) (xy 374.831156 -249.653512) (xy 374.780541 -249.66174) (xy 374.754902 -249.662188)
			(xy 374.74221 -249.662049) (xy 374.716907 -249.660013) (xy 374.704356 -249.658124) (xy 374.702578 -249.65787)
			(xy 374.69318 -249.656346) (xy 374.683274 -249.65914) (xy 374.678685 -249.660565) (xy 374.67012 -249.664918)
			(xy 374.666256 -249.667776) (xy 374.64111 -249.688858) (xy 374.640602 -249.689366) (xy 374.604788 -249.7201)
			(xy 374.597494 -249.727519) (xy 374.58912 -249.74654) (xy 374.588532 -249.75693) (xy 374.588532 -250.048522)
			(xy 374.58904 -250.055634) (xy 374.590564 -250.066048) (xy 374.590564 -250.066302) (xy 374.596287 -250.08782)
			(xy 374.602407 -250.131923) (xy 374.602756 -250.154186) (xy 375.848621 -250.154186) (xy 375.852716 -250.103458)
			(xy 375.864895 -250.054044) (xy 375.884843 -250.007224) (xy 375.912044 -249.96421) (xy 375.945792 -249.926116)
			(xy 375.985214 -249.893929) (xy 376.029288 -249.868483) (xy 376.076874 -249.850436) (xy 376.126738 -249.840256)
			(xy 376.17759 -249.838207) (xy 376.228111 -249.844341) (xy 376.276995 -249.858501) (xy 376.322974 -249.880318)
			(xy 376.364858 -249.909228) (xy 376.401562 -249.944483) (xy 376.432135 -249.985169) (xy 376.455786 -250.030232)
			(xy 376.471902 -250.078506) (xy 376.480066 -250.12874) (xy 376.480578 -250.154186) (xy 376.480075 -250.179175)
			(xy 376.787392 -250.179175) (xy 376.787392 -250.129197) (xy 376.795211 -250.079834) (xy 376.810655 -250.032302)
			(xy 376.833345 -249.98777) (xy 376.862721 -249.947337) (xy 376.898061 -249.911997) (xy 376.938494 -249.882621)
			(xy 376.983026 -249.859931) (xy 377.030558 -249.844487) (xy 377.079921 -249.836668) (xy 377.129899 -249.836668)
			(xy 377.179262 -249.844487) (xy 377.226794 -249.859931) (xy 377.271326 -249.882621) (xy 377.311759 -249.911997)
			(xy 377.347099 -249.947337) (xy 377.376475 -249.98777) (xy 377.399165 -250.032302) (xy 377.414609 -250.079834)
			(xy 377.422428 -250.129197) (xy 377.422918 -250.154186) (xy 377.422428 -250.179175) (xy 377.727192 -250.179175)
			(xy 377.727192 -250.129197) (xy 377.735011 -250.079834) (xy 377.750455 -250.032302) (xy 377.773145 -249.98777)
			(xy 377.802521 -249.947337) (xy 377.837861 -249.911997) (xy 377.878294 -249.882621) (xy 377.922826 -249.859931)
			(xy 377.970358 -249.844487) (xy 378.019721 -249.836668) (xy 378.069699 -249.836668) (xy 378.119062 -249.844487)
			(xy 378.166594 -249.859931) (xy 378.211126 -249.882621) (xy 378.251559 -249.911997) (xy 378.286899 -249.947337)
			(xy 378.316275 -249.98777) (xy 378.338965 -250.032302) (xy 378.354409 -250.079834) (xy 378.362228 -250.129197)
			(xy 378.362718 -250.154186) (xy 378.668529 -250.154186) (xy 378.672624 -250.103458) (xy 378.684803 -250.054044)
			(xy 378.704751 -250.007224) (xy 378.731952 -249.96421) (xy 378.7657 -249.926116) (xy 378.805122 -249.893929)
			(xy 378.849196 -249.868483) (xy 378.896782 -249.850436) (xy 378.946646 -249.840256) (xy 378.997498 -249.838207)
			(xy 379.048019 -249.844341) (xy 379.096903 -249.858501) (xy 379.142882 -249.880318) (xy 379.184766 -249.909228)
			(xy 379.22147 -249.944483) (xy 379.252043 -249.985169) (xy 379.275694 -250.030232) (xy 379.29181 -250.078506)
			(xy 379.299974 -250.12874) (xy 379.300486 -250.154186) (xy 379.299983 -250.179175) (xy 379.6073 -250.179175)
			(xy 379.6073 -250.129197) (xy 379.615119 -250.079834) (xy 379.630563 -250.032302) (xy 379.653253 -249.98777)
			(xy 379.682629 -249.947337) (xy 379.717969 -249.911997) (xy 379.758402 -249.882621) (xy 379.802934 -249.859931)
			(xy 379.850466 -249.844487) (xy 379.899829 -249.836668) (xy 379.949807 -249.836668) (xy 379.99917 -249.844487)
			(xy 380.046702 -249.859931) (xy 380.091234 -249.882621) (xy 380.131667 -249.911997) (xy 380.167007 -249.947337)
			(xy 380.196383 -249.98777) (xy 380.219073 -250.032302) (xy 380.234517 -250.079834) (xy 380.242336 -250.129197)
			(xy 380.242826 -250.154186) (xy 380.242336 -250.179175) (xy 380.547354 -250.179175) (xy 380.547354 -250.129197)
			(xy 380.555173 -250.079834) (xy 380.570617 -250.032302) (xy 380.593307 -249.98777) (xy 380.622683 -249.947337)
			(xy 380.658023 -249.911997) (xy 380.698456 -249.882621) (xy 380.742988 -249.859931) (xy 380.79052 -249.844487)
			(xy 380.839883 -249.836668) (xy 380.889861 -249.836668) (xy 380.939224 -249.844487) (xy 380.986756 -249.859931)
			(xy 381.031288 -249.882621) (xy 381.071721 -249.911997) (xy 381.107061 -249.947337) (xy 381.136437 -249.98777)
			(xy 381.159127 -250.032302) (xy 381.174571 -250.079834) (xy 381.18239 -250.129197) (xy 381.18288 -250.154186)
			(xy 381.18239 -250.179175) (xy 381.174571 -250.228538) (xy 381.159127 -250.27607) (xy 381.136437 -250.320602)
			(xy 381.107061 -250.361035) (xy 381.071721 -250.396375) (xy 381.031288 -250.425751) (xy 380.986756 -250.448441)
			(xy 380.939224 -250.463885) (xy 380.889861 -250.471704) (xy 380.839883 -250.471704) (xy 380.79052 -250.463885)
			(xy 380.742988 -250.448441) (xy 380.698456 -250.425751) (xy 380.658023 -250.396375) (xy 380.622683 -250.361035)
			(xy 380.593307 -250.320602) (xy 380.570617 -250.27607) (xy 380.555173 -250.228538) (xy 380.547354 -250.179175)
			(xy 380.242336 -250.179175) (xy 380.234517 -250.228538) (xy 380.219073 -250.27607) (xy 380.196383 -250.320602)
			(xy 380.167007 -250.361035) (xy 380.131667 -250.396375) (xy 380.091234 -250.425751) (xy 380.046702 -250.448441)
			(xy 379.99917 -250.463885) (xy 379.949807 -250.471704) (xy 379.899829 -250.471704) (xy 379.850466 -250.463885)
			(xy 379.802934 -250.448441) (xy 379.758402 -250.425751) (xy 379.717969 -250.396375) (xy 379.682629 -250.361035)
			(xy 379.653253 -250.320602) (xy 379.630563 -250.27607) (xy 379.615119 -250.228538) (xy 379.6073 -250.179175)
			(xy 379.299983 -250.179175) (xy 379.299974 -250.179632) (xy 379.29181 -250.229866) (xy 379.275694 -250.27814)
			(xy 379.252043 -250.323203) (xy 379.22147 -250.363889) (xy 379.184766 -250.399144) (xy 379.142882 -250.428054)
			(xy 379.096903 -250.449871) (xy 379.048019 -250.464031) (xy 378.997498 -250.470165) (xy 378.946646 -250.468116)
			(xy 378.896782 -250.457936) (xy 378.849196 -250.439889) (xy 378.805122 -250.414443) (xy 378.7657 -250.382256)
			(xy 378.731952 -250.344162) (xy 378.704751 -250.301148) (xy 378.684803 -250.254328) (xy 378.672624 -250.204914)
			(xy 378.668529 -250.154186) (xy 378.362718 -250.154186) (xy 378.362228 -250.179175) (xy 378.354409 -250.228538)
			(xy 378.338965 -250.27607) (xy 378.316275 -250.320602) (xy 378.286899 -250.361035) (xy 378.251559 -250.396375)
			(xy 378.211126 -250.425751) (xy 378.166594 -250.448441) (xy 378.119062 -250.463885) (xy 378.069699 -250.471704)
			(xy 378.019721 -250.471704) (xy 377.970358 -250.463885) (xy 377.922826 -250.448441) (xy 377.878294 -250.425751)
			(xy 377.837861 -250.396375) (xy 377.802521 -250.361035) (xy 377.773145 -250.320602) (xy 377.750455 -250.27607)
			(xy 377.735011 -250.228538) (xy 377.727192 -250.179175) (xy 377.422428 -250.179175) (xy 377.414609 -250.228538)
			(xy 377.399165 -250.27607) (xy 377.376475 -250.320602) (xy 377.347099 -250.361035) (xy 377.311759 -250.396375)
			(xy 377.271326 -250.425751) (xy 377.226794 -250.448441) (xy 377.179262 -250.463885) (xy 377.129899 -250.471704)
			(xy 377.079921 -250.471704) (xy 377.030558 -250.463885) (xy 376.983026 -250.448441) (xy 376.938494 -250.425751)
			(xy 376.898061 -250.396375) (xy 376.862721 -250.361035) (xy 376.833345 -250.320602) (xy 376.810655 -250.27607)
			(xy 376.795211 -250.228538) (xy 376.787392 -250.179175) (xy 376.480075 -250.179175) (xy 376.480066 -250.179632)
			(xy 376.471902 -250.229866) (xy 376.455786 -250.27814) (xy 376.432135 -250.323203) (xy 376.401562 -250.363889)
			(xy 376.364858 -250.399144) (xy 376.322974 -250.428054) (xy 376.276995 -250.449871) (xy 376.228111 -250.464031)
			(xy 376.17759 -250.470165) (xy 376.126738 -250.468116) (xy 376.076874 -250.457936) (xy 376.029288 -250.439889)
			(xy 375.985214 -250.414443) (xy 375.945792 -250.382256) (xy 375.912044 -250.344162) (xy 375.884843 -250.301148)
			(xy 375.864895 -250.254328) (xy 375.852716 -250.204914) (xy 375.848621 -250.154186) (xy 374.602756 -250.154186)
			(xy 374.602435 -250.176451) (xy 374.59631 -250.220556) (xy 374.590564 -250.24207) (xy 374.588532 -250.248928)
			(xy 374.588532 -250.490736) (xy 374.588003 -250.500577) (xy 374.580428 -250.51875) (xy 374.5738 -250.526042)
			(xy 374.476264 -250.623578) (xy 374.469026 -250.630291) (xy 374.450821 -250.637882) (xy 374.440958 -250.63831)
			(xy 373.593106 -250.63831) (xy 373.583271 -250.638851) (xy 373.565117 -250.646445) (xy 373.5578 -250.653042)
			(xy 373.460264 -250.750578) (xy 373.453548 -250.757815) (xy 373.445945 -250.77602) (xy 373.445532 -250.785884)
			(xy 373.445532 -250.989181) (xy 374.437384 -250.989181) (xy 374.437384 -250.939203) (xy 374.445203 -250.88984)
			(xy 374.460647 -250.842308) (xy 374.483337 -250.797776) (xy 374.512713 -250.757343) (xy 374.548053 -250.722003)
			(xy 374.588486 -250.692627) (xy 374.633018 -250.669937) (xy 374.68055 -250.654493) (xy 374.729913 -250.646674)
			(xy 374.779891 -250.646674) (xy 374.829254 -250.654493) (xy 374.876786 -250.669937) (xy 374.921318 -250.692627)
			(xy 374.961751 -250.722003) (xy 374.997091 -250.757343) (xy 375.026467 -250.797776) (xy 375.049157 -250.842308)
			(xy 375.064601 -250.88984) (xy 375.07242 -250.939203) (xy 375.07291 -250.964192) (xy 375.378467 -250.964192)
			(xy 375.382562 -250.913464) (xy 375.394741 -250.86405) (xy 375.414689 -250.81723) (xy 375.44189 -250.774216)
			(xy 375.475638 -250.736122) (xy 375.51506 -250.703935) (xy 375.559134 -250.678489) (xy 375.60672 -250.660442)
			(xy 375.656584 -250.650262) (xy 375.707436 -250.648213) (xy 375.757957 -250.654347) (xy 375.806841 -250.668507)
			(xy 375.85282 -250.690324) (xy 375.894704 -250.719234) (xy 375.931408 -250.754489) (xy 375.961981 -250.795175)
			(xy 375.985632 -250.840238) (xy 376.001748 -250.888512) (xy 376.009912 -250.938746) (xy 376.010424 -250.964192)
			(xy 376.009921 -250.989181) (xy 376.317238 -250.989181) (xy 376.317238 -250.939203) (xy 376.325057 -250.88984)
			(xy 376.340501 -250.842308) (xy 376.363191 -250.797776) (xy 376.392567 -250.757343) (xy 376.427907 -250.722003)
			(xy 376.46834 -250.692627) (xy 376.512872 -250.669937) (xy 376.560404 -250.654493) (xy 376.609767 -250.646674)
			(xy 376.659745 -250.646674) (xy 376.709108 -250.654493) (xy 376.75664 -250.669937) (xy 376.801172 -250.692627)
			(xy 376.841605 -250.722003) (xy 376.876945 -250.757343) (xy 376.906321 -250.797776) (xy 376.929011 -250.842308)
			(xy 376.944455 -250.88984) (xy 376.952274 -250.939203) (xy 376.952764 -250.964192) (xy 377.258575 -250.964192)
			(xy 377.26267 -250.913464) (xy 377.274849 -250.86405) (xy 377.294797 -250.81723) (xy 377.321998 -250.774216)
			(xy 377.355746 -250.736122) (xy 377.395168 -250.703935) (xy 377.439242 -250.678489) (xy 377.486828 -250.660442)
			(xy 377.536692 -250.650262) (xy 377.587544 -250.648213) (xy 377.638065 -250.654347) (xy 377.686949 -250.668507)
			(xy 377.732928 -250.690324) (xy 377.774812 -250.719234) (xy 377.811516 -250.754489) (xy 377.842089 -250.795175)
			(xy 377.86574 -250.840238) (xy 377.881856 -250.888512) (xy 377.89002 -250.938746) (xy 377.890532 -250.964192)
			(xy 377.890029 -250.989181) (xy 378.197346 -250.989181) (xy 378.197346 -250.939203) (xy 378.205165 -250.88984)
			(xy 378.220609 -250.842308) (xy 378.243299 -250.797776) (xy 378.272675 -250.757343) (xy 378.308015 -250.722003)
			(xy 378.348448 -250.692627) (xy 378.39298 -250.669937) (xy 378.440512 -250.654493) (xy 378.489875 -250.646674)
			(xy 378.539853 -250.646674) (xy 378.589216 -250.654493) (xy 378.636748 -250.669937) (xy 378.68128 -250.692627)
			(xy 378.721713 -250.722003) (xy 378.757053 -250.757343) (xy 378.786429 -250.797776) (xy 378.809119 -250.842308)
			(xy 378.824563 -250.88984) (xy 378.832382 -250.939203) (xy 378.832872 -250.964192) (xy 379.138683 -250.964192)
			(xy 379.142778 -250.913464) (xy 379.154957 -250.86405) (xy 379.174905 -250.81723) (xy 379.202106 -250.774216)
			(xy 379.235854 -250.736122) (xy 379.275276 -250.703935) (xy 379.31935 -250.678489) (xy 379.366936 -250.660442)
			(xy 379.4168 -250.650262) (xy 379.467652 -250.648213) (xy 379.518173 -250.654347) (xy 379.567057 -250.668507)
			(xy 379.613036 -250.690324) (xy 379.65492 -250.719234) (xy 379.691624 -250.754489) (xy 379.722197 -250.795175)
			(xy 379.745848 -250.840238) (xy 379.761964 -250.888512) (xy 379.770128 -250.938746) (xy 379.77064 -250.964192)
			(xy 380.078483 -250.964192) (xy 380.082578 -250.913464) (xy 380.094757 -250.86405) (xy 380.114705 -250.81723)
			(xy 380.141906 -250.774216) (xy 380.175654 -250.736122) (xy 380.215076 -250.703935) (xy 380.25915 -250.678489)
			(xy 380.306736 -250.660442) (xy 380.3566 -250.650262) (xy 380.407452 -250.648213) (xy 380.457973 -250.654347)
			(xy 380.506857 -250.668507) (xy 380.552836 -250.690324) (xy 380.59472 -250.719234) (xy 380.631424 -250.754489)
			(xy 380.661997 -250.795175) (xy 380.685648 -250.840238) (xy 380.701764 -250.888512) (xy 380.709928 -250.938746)
			(xy 380.71044 -250.964192) (xy 380.709928 -250.989638) (xy 380.701764 -251.039872) (xy 380.685648 -251.088146)
			(xy 380.661997 -251.133209) (xy 380.631424 -251.173895) (xy 380.59472 -251.20915) (xy 380.552836 -251.23806)
			(xy 380.506857 -251.259877) (xy 380.457973 -251.274037) (xy 380.407452 -251.280171) (xy 380.3566 -251.278122)
			(xy 380.306736 -251.267942) (xy 380.25915 -251.249895) (xy 380.215076 -251.224449) (xy 380.175654 -251.192262)
			(xy 380.141906 -251.154168) (xy 380.114705 -251.111154) (xy 380.094757 -251.064334) (xy 380.082578 -251.01492)
			(xy 380.078483 -250.964192) (xy 379.77064 -250.964192) (xy 379.770128 -250.989638) (xy 379.761964 -251.039872)
			(xy 379.745848 -251.088146) (xy 379.722197 -251.133209) (xy 379.691624 -251.173895) (xy 379.65492 -251.20915)
			(xy 379.613036 -251.23806) (xy 379.567057 -251.259877) (xy 379.518173 -251.274037) (xy 379.467652 -251.280171)
			(xy 379.4168 -251.278122) (xy 379.366936 -251.267942) (xy 379.31935 -251.249895) (xy 379.275276 -251.224449)
			(xy 379.235854 -251.192262) (xy 379.202106 -251.154168) (xy 379.174905 -251.111154) (xy 379.154957 -251.064334)
			(xy 379.142778 -251.01492) (xy 379.138683 -250.964192) (xy 378.832872 -250.964192) (xy 378.832382 -250.989181)
			(xy 378.824563 -251.038544) (xy 378.809119 -251.086076) (xy 378.786429 -251.130608) (xy 378.757053 -251.171041)
			(xy 378.721713 -251.206381) (xy 378.68128 -251.235757) (xy 378.636748 -251.258447) (xy 378.589216 -251.273891)
			(xy 378.539853 -251.28171) (xy 378.489875 -251.28171) (xy 378.440512 -251.273891) (xy 378.39298 -251.258447)
			(xy 378.348448 -251.235757) (xy 378.308015 -251.206381) (xy 378.272675 -251.171041) (xy 378.243299 -251.130608)
			(xy 378.220609 -251.086076) (xy 378.205165 -251.038544) (xy 378.197346 -250.989181) (xy 377.890029 -250.989181)
			(xy 377.89002 -250.989638) (xy 377.881856 -251.039872) (xy 377.86574 -251.088146) (xy 377.842089 -251.133209)
			(xy 377.811516 -251.173895) (xy 377.774812 -251.20915) (xy 377.732928 -251.23806) (xy 377.686949 -251.259877)
			(xy 377.638065 -251.274037) (xy 377.587544 -251.280171) (xy 377.536692 -251.278122) (xy 377.486828 -251.267942)
			(xy 377.439242 -251.249895) (xy 377.395168 -251.224449) (xy 377.355746 -251.192262) (xy 377.321998 -251.154168)
			(xy 377.294797 -251.111154) (xy 377.274849 -251.064334) (xy 377.26267 -251.01492) (xy 377.258575 -250.964192)
			(xy 376.952764 -250.964192) (xy 376.952274 -250.989181) (xy 376.944455 -251.038544) (xy 376.929011 -251.086076)
			(xy 376.906321 -251.130608) (xy 376.876945 -251.171041) (xy 376.841605 -251.206381) (xy 376.801172 -251.235757)
			(xy 376.75664 -251.258447) (xy 376.709108 -251.273891) (xy 376.659745 -251.28171) (xy 376.609767 -251.28171)
			(xy 376.560404 -251.273891) (xy 376.512872 -251.258447) (xy 376.46834 -251.235757) (xy 376.427907 -251.206381)
			(xy 376.392567 -251.171041) (xy 376.363191 -251.130608) (xy 376.340501 -251.086076) (xy 376.325057 -251.038544)
			(xy 376.317238 -250.989181) (xy 376.009921 -250.989181) (xy 376.009912 -250.989638) (xy 376.001748 -251.039872)
			(xy 375.985632 -251.088146) (xy 375.961981 -251.133209) (xy 375.931408 -251.173895) (xy 375.894704 -251.20915)
			(xy 375.85282 -251.23806) (xy 375.806841 -251.259877) (xy 375.757957 -251.274037) (xy 375.707436 -251.280171)
			(xy 375.656584 -251.278122) (xy 375.60672 -251.267942) (xy 375.559134 -251.249895) (xy 375.51506 -251.224449)
			(xy 375.475638 -251.192262) (xy 375.44189 -251.154168) (xy 375.414689 -251.111154) (xy 375.394741 -251.064334)
			(xy 375.382562 -251.01492) (xy 375.378467 -250.964192) (xy 375.07291 -250.964192) (xy 375.07242 -250.989181)
			(xy 375.064601 -251.038544) (xy 375.049157 -251.086076) (xy 375.026467 -251.130608) (xy 374.997091 -251.171041)
			(xy 374.961751 -251.206381) (xy 374.921318 -251.235757) (xy 374.876786 -251.258447) (xy 374.829254 -251.273891)
			(xy 374.779891 -251.28171) (xy 374.729913 -251.28171) (xy 374.68055 -251.273891) (xy 374.633018 -251.258447)
			(xy 374.588486 -251.235757) (xy 374.548053 -251.206381) (xy 374.512713 -251.171041) (xy 374.483337 -251.130608)
			(xy 374.460647 -251.086076) (xy 374.445203 -251.038544) (xy 374.437384 -250.989181) (xy 373.445532 -250.989181)
			(xy 373.445532 -251.379736) (xy 373.445003 -251.389577) (xy 373.437428 -251.40775) (xy 373.4308 -251.415042)
			(xy 373.333264 -251.512578) (xy 373.326026 -251.519291) (xy 373.307821 -251.526882) (xy 373.297958 -251.52731)
			(xy 372.796308 -251.52731) (xy 372.784568 -251.52793) (xy 372.763622 -251.538533) (xy 372.756176 -251.54763)
			(xy 372.721124 -251.59843) (xy 372.720616 -251.598938) (xy 372.707408 -251.617734) (xy 372.704451 -251.622633)
			(xy 372.700604 -251.633406) (xy 372.699788 -251.63907) (xy 372.698264 -251.6505) (xy 372.702836 -251.662946)
			(xy 372.711889 -251.688831) (xy 372.72198 -251.742727) (xy 372.722902 -251.770134) (xy 372.722902 -251.775976)
			(xy 372.722321 -251.799187) (xy 373.96723 -251.799187) (xy 373.96723 -251.749209) (xy 373.975049 -251.699846)
			(xy 373.990493 -251.652314) (xy 374.013183 -251.607782) (xy 374.042559 -251.567349) (xy 374.077899 -251.532009)
			(xy 374.118332 -251.502633) (xy 374.162864 -251.479943) (xy 374.210396 -251.464499) (xy 374.259759 -251.45668)
			(xy 374.309737 -251.45668) (xy 374.3591 -251.464499) (xy 374.406632 -251.479943) (xy 374.451164 -251.502633)
			(xy 374.491597 -251.532009) (xy 374.526937 -251.567349) (xy 374.556313 -251.607782) (xy 374.579003 -251.652314)
			(xy 374.594447 -251.699846) (xy 374.602266 -251.749209) (xy 374.602756 -251.774198) (xy 375.848621 -251.774198)
			(xy 375.852716 -251.72347) (xy 375.864895 -251.674056) (xy 375.884843 -251.627236) (xy 375.912044 -251.584222)
			(xy 375.945792 -251.546128) (xy 375.985214 -251.513941) (xy 376.029288 -251.488495) (xy 376.076874 -251.470448)
			(xy 376.126738 -251.460268) (xy 376.17759 -251.458219) (xy 376.228111 -251.464353) (xy 376.276995 -251.478513)
			(xy 376.322974 -251.50033) (xy 376.364858 -251.52924) (xy 376.401562 -251.564495) (xy 376.432135 -251.605181)
			(xy 376.455786 -251.650244) (xy 376.471902 -251.698518) (xy 376.480066 -251.748752) (xy 376.480578 -251.774198)
			(xy 376.480075 -251.799187) (xy 376.787392 -251.799187) (xy 376.787392 -251.749209) (xy 376.795211 -251.699846)
			(xy 376.810655 -251.652314) (xy 376.833345 -251.607782) (xy 376.862721 -251.567349) (xy 376.898061 -251.532009)
			(xy 376.938494 -251.502633) (xy 376.983026 -251.479943) (xy 377.030558 -251.464499) (xy 377.079921 -251.45668)
			(xy 377.129899 -251.45668) (xy 377.179262 -251.464499) (xy 377.226794 -251.479943) (xy 377.271326 -251.502633)
			(xy 377.311759 -251.532009) (xy 377.347099 -251.567349) (xy 377.376475 -251.607782) (xy 377.399165 -251.652314)
			(xy 377.414609 -251.699846) (xy 377.422428 -251.749209) (xy 377.422918 -251.774198) (xy 378.668529 -251.774198)
			(xy 378.672624 -251.72347) (xy 378.684803 -251.674056) (xy 378.704751 -251.627236) (xy 378.731952 -251.584222)
			(xy 378.7657 -251.546128) (xy 378.805122 -251.513941) (xy 378.849196 -251.488495) (xy 378.896782 -251.470448)
			(xy 378.946646 -251.460268) (xy 378.997498 -251.458219) (xy 379.048019 -251.464353) (xy 379.096903 -251.478513)
			(xy 379.142882 -251.50033) (xy 379.184766 -251.52924) (xy 379.22147 -251.564495) (xy 379.252043 -251.605181)
			(xy 379.275694 -251.650244) (xy 379.29181 -251.698518) (xy 379.299974 -251.748752) (xy 379.300486 -251.774198)
			(xy 379.299983 -251.799187) (xy 379.6073 -251.799187) (xy 379.6073 -251.749209) (xy 379.615119 -251.699846)
			(xy 379.630563 -251.652314) (xy 379.653253 -251.607782) (xy 379.682629 -251.567349) (xy 379.717969 -251.532009)
			(xy 379.758402 -251.502633) (xy 379.802934 -251.479943) (xy 379.850466 -251.464499) (xy 379.899829 -251.45668)
			(xy 379.949807 -251.45668) (xy 379.99917 -251.464499) (xy 380.046702 -251.479943) (xy 380.091234 -251.502633)
			(xy 380.131667 -251.532009) (xy 380.167007 -251.567349) (xy 380.196383 -251.607782) (xy 380.219073 -251.652314)
			(xy 380.234517 -251.699846) (xy 380.242336 -251.749209) (xy 380.242826 -251.774198) (xy 380.242336 -251.799187)
			(xy 380.547354 -251.799187) (xy 380.547354 -251.749209) (xy 380.555173 -251.699846) (xy 380.570617 -251.652314)
			(xy 380.593307 -251.607782) (xy 380.622683 -251.567349) (xy 380.658023 -251.532009) (xy 380.698456 -251.502633)
			(xy 380.742988 -251.479943) (xy 380.79052 -251.464499) (xy 380.839883 -251.45668) (xy 380.889861 -251.45668)
			(xy 380.939224 -251.464499) (xy 380.986756 -251.479943) (xy 381.031288 -251.502633) (xy 381.071721 -251.532009)
			(xy 381.107061 -251.567349) (xy 381.136437 -251.607782) (xy 381.159127 -251.652314) (xy 381.174571 -251.699846)
			(xy 381.18239 -251.749209) (xy 381.18288 -251.774198) (xy 381.18239 -251.799187) (xy 381.174571 -251.84855)
			(xy 381.159127 -251.896082) (xy 381.136437 -251.940614) (xy 381.107061 -251.981047) (xy 381.071721 -252.016387)
			(xy 381.031288 -252.045763) (xy 380.986756 -252.068453) (xy 380.939224 -252.083897) (xy 380.889861 -252.091716)
			(xy 380.839883 -252.091716) (xy 380.79052 -252.083897) (xy 380.742988 -252.068453) (xy 380.698456 -252.045763)
			(xy 380.658023 -252.016387) (xy 380.622683 -251.981047) (xy 380.593307 -251.940614) (xy 380.570617 -251.896082)
			(xy 380.555173 -251.84855) (xy 380.547354 -251.799187) (xy 380.242336 -251.799187) (xy 380.234517 -251.84855)
			(xy 380.219073 -251.896082) (xy 380.196383 -251.940614) (xy 380.167007 -251.981047) (xy 380.131667 -252.016387)
			(xy 380.091234 -252.045763) (xy 380.046702 -252.068453) (xy 379.99917 -252.083897) (xy 379.949807 -252.091716)
			(xy 379.899829 -252.091716) (xy 379.850466 -252.083897) (xy 379.802934 -252.068453) (xy 379.758402 -252.045763)
			(xy 379.717969 -252.016387) (xy 379.682629 -251.981047) (xy 379.653253 -251.940614) (xy 379.630563 -251.896082)
			(xy 379.615119 -251.84855) (xy 379.6073 -251.799187) (xy 379.299983 -251.799187) (xy 379.299974 -251.799644)
			(xy 379.29181 -251.849878) (xy 379.275694 -251.898152) (xy 379.252043 -251.943215) (xy 379.22147 -251.983901)
			(xy 379.184766 -252.019156) (xy 379.142882 -252.048066) (xy 379.096903 -252.069883) (xy 379.048019 -252.084043)
			(xy 378.997498 -252.090177) (xy 378.946646 -252.088128) (xy 378.896782 -252.077948) (xy 378.849196 -252.059901)
			(xy 378.805122 -252.034455) (xy 378.7657 -252.002268) (xy 378.731952 -251.964174) (xy 378.704751 -251.92116)
			(xy 378.684803 -251.87434) (xy 378.672624 -251.824926) (xy 378.668529 -251.774198) (xy 377.422918 -251.774198)
			(xy 377.422428 -251.799187) (xy 377.414609 -251.84855) (xy 377.399165 -251.896082) (xy 377.376475 -251.940614)
			(xy 377.347099 -251.981047) (xy 377.311759 -252.016387) (xy 377.271326 -252.045763) (xy 377.226794 -252.068453)
			(xy 377.179262 -252.083897) (xy 377.129899 -252.091716) (xy 377.079921 -252.091716) (xy 377.030558 -252.083897)
			(xy 376.983026 -252.068453) (xy 376.938494 -252.045763) (xy 376.898061 -252.016387) (xy 376.862721 -251.981047)
			(xy 376.833345 -251.940614) (xy 376.810655 -251.896082) (xy 376.795211 -251.84855) (xy 376.787392 -251.799187)
			(xy 376.480075 -251.799187) (xy 376.480066 -251.799644) (xy 376.471902 -251.849878) (xy 376.455786 -251.898152)
			(xy 376.432135 -251.943215) (xy 376.401562 -251.983901) (xy 376.364858 -252.019156) (xy 376.322974 -252.048066)
			(xy 376.276995 -252.069883) (xy 376.228111 -252.084043) (xy 376.17759 -252.090177) (xy 376.126738 -252.088128)
			(xy 376.076874 -252.077948) (xy 376.029288 -252.059901) (xy 375.985214 -252.034455) (xy 375.945792 -252.002268)
			(xy 375.912044 -251.964174) (xy 375.884843 -251.92116) (xy 375.864895 -251.87434) (xy 375.852716 -251.824926)
			(xy 375.848621 -251.774198) (xy 374.602756 -251.774198) (xy 374.602266 -251.799187) (xy 374.594447 -251.84855)
			(xy 374.579003 -251.896082) (xy 374.556313 -251.940614) (xy 374.526937 -251.981047) (xy 374.491597 -252.016387)
			(xy 374.451164 -252.045763) (xy 374.406632 -252.068453) (xy 374.3591 -252.083897) (xy 374.309737 -252.091716)
			(xy 374.259759 -252.091716) (xy 374.210396 -252.083897) (xy 374.162864 -252.068453) (xy 374.118332 -252.045763)
			(xy 374.077899 -252.016387) (xy 374.042559 -251.981047) (xy 374.013183 -251.940614) (xy 373.990493 -251.896082)
			(xy 373.975049 -251.84855) (xy 373.96723 -251.799187) (xy 372.722321 -251.799187) (xy 372.722279 -251.800874)
			(xy 372.714241 -251.850022) (xy 372.69864 -251.897317) (xy 372.675857 -251.941602) (xy 372.646449 -251.981794)
			(xy 372.611136 -252.01691) (xy 372.57078 -252.046093) (xy 372.526369 -252.068628) (xy 372.478988 -252.083964)
			(xy 372.429795 -252.091728) (xy 372.379993 -252.091728) (xy 372.3308 -252.083964) (xy 372.283419 -252.068628)
			(xy 372.239008 -252.046093) (xy 372.198652 -252.01691) (xy 372.163339 -251.981794) (xy 372.133931 -251.941602)
			(xy 372.111148 -251.897317) (xy 372.095547 -251.850022) (xy 372.087509 -251.800874) (xy 372.086886 -251.775976)
			(xy 372.086886 -251.773944) (xy 372.087535 -251.745577) (xy 372.097631 -251.689746) (xy 372.106952 -251.662946)
			(xy 372.111524 -251.6505) (xy 372.11 -251.63907) (xy 372.109155 -251.633414) (xy 372.105308 -251.622647)
			(xy 372.10238 -251.617734) (xy 372.089172 -251.598938) (xy 372.088664 -251.59843) (xy 372.053612 -251.54763)
			(xy 372.046124 -251.538587) (xy 372.025201 -251.528003) (xy 372.01348 -251.52731) (xy 370.9162 -251.52731)
			(xy 370.904461 -251.527932) (xy 370.883518 -251.538537) (xy 370.876068 -251.54763) (xy 370.841016 -251.59843)
			(xy 370.840508 -251.598938) (xy 370.8273 -251.617734) (xy 370.824343 -251.622633) (xy 370.820497 -251.633407)
			(xy 370.81968 -251.63907) (xy 370.818156 -251.6505) (xy 370.822728 -251.662946) (xy 370.831781 -251.688831)
			(xy 370.841872 -251.742727) (xy 370.842794 -251.770134) (xy 370.842794 -251.775976) (xy 370.842172 -251.800873)
			(xy 370.834134 -251.850021) (xy 370.818532 -251.897316) (xy 370.795749 -251.9416) (xy 370.766341 -251.981791)
			(xy 370.731028 -252.016906) (xy 370.690672 -252.046087) (xy 370.64626 -252.068621) (xy 370.598879 -252.083955)
			(xy 370.549687 -252.091717) (xy 370.524786 -252.092206) (xy 370.499798 -252.091715) (xy 370.450436 -252.083895)
			(xy 370.402906 -252.068449) (xy 370.358377 -252.045759) (xy 370.317946 -252.016382) (xy 370.282608 -251.981042)
			(xy 370.253233 -251.940609) (xy 370.230545 -251.896079) (xy 370.215102 -251.848548) (xy 370.207284 -251.799186)
			(xy 370.206778 -251.774198) (xy 370.207267 -251.749221) (xy 370.215078 -251.699882) (xy 370.230507 -251.652371)
			(xy 370.253174 -251.607856) (xy 370.282523 -251.567433) (xy 370.31783 -251.532096) (xy 370.358229 -251.502713)
			(xy 370.402725 -251.480009) (xy 370.450223 -251.46454) (xy 370.499556 -251.456688) (xy 370.524532 -251.45619)
			(xy 370.52504 -251.45619) (xy 370.545106 -251.456698) (xy 370.555774 -251.457206) (xy 370.564918 -251.454158)
			(xy 370.569752 -251.45223) (xy 370.578586 -251.44673) (xy 370.582444 -251.443236) (xy 370.635784 -251.393452)
			(xy 370.642871 -251.386083) (xy 370.650996 -251.36734) (xy 370.651532 -251.35713) (xy 370.651532 -250.785884)
			(xy 370.651025 -250.77613) (xy 370.643587 -250.75809) (xy 370.637054 -250.750832) (xy 370.53901 -250.652788)
			(xy 370.531763 -250.646233) (xy 370.513719 -250.638783) (xy 370.503958 -250.63831) (xy 369.910106 -250.63831)
			(xy 369.900271 -250.638851) (xy 369.882117 -250.646445) (xy 369.8748 -250.653042) (xy 369.650772 -250.87707)
			(xy 369.644215 -250.884317) (xy 369.636761 -250.90236) (xy 369.636294 -250.912122) (xy 369.636294 -251.196856)
			(xy 369.635532 -251.196856) (xy 369.635532 -251.379736) (xy 369.635003 -251.389577) (xy 369.627428 -251.40775)
			(xy 369.6208 -251.415042) (xy 369.523264 -251.512578) (xy 369.516026 -251.519291) (xy 369.497821 -251.526882)
			(xy 369.487958 -251.52731) (xy 369.036092 -251.52731) (xy 369.024354 -251.527934) (xy 369.003414 -251.53854)
			(xy 368.99596 -251.54763) (xy 368.960908 -251.59843) (xy 368.9604 -251.598938) (xy 368.947192 -251.617734)
			(xy 368.944236 -251.622633) (xy 368.94039 -251.633407) (xy 368.939572 -251.63907) (xy 368.938048 -251.6505)
			(xy 368.94262 -251.662946) (xy 368.951673 -251.688831) (xy 368.961765 -251.742727) (xy 368.962686 -251.770134)
			(xy 368.962686 -251.775976) (xy 368.962063 -251.800874) (xy 368.954025 -251.850022) (xy 368.938424 -251.897317)
			(xy 368.915641 -251.941602) (xy 368.886233 -251.981794) (xy 368.85092 -252.01691) (xy 368.810564 -252.046093)
			(xy 368.766153 -252.068628) (xy 368.718772 -252.083964) (xy 368.669579 -252.091728) (xy 368.619777 -252.091728)
			(xy 368.570584 -252.083964) (xy 368.523203 -252.068628) (xy 368.478792 -252.046093) (xy 368.438436 -252.01691)
			(xy 368.403123 -251.981794) (xy 368.373715 -251.941602) (xy 368.350932 -251.897317) (xy 368.335331 -251.850022)
			(xy 368.327293 -251.800874) (xy 368.32667 -251.775976) (xy 368.32667 -251.773944) (xy 368.327319 -251.745577)
			(xy 368.337414 -251.689746) (xy 368.346736 -251.662946) (xy 368.351308 -251.6505) (xy 368.349784 -251.63907)
			(xy 368.34894 -251.633413) (xy 368.345099 -251.622643) (xy 368.342164 -251.617734) (xy 368.328956 -251.598938)
			(xy 368.328448 -251.59843) (xy 368.293396 -251.54763) (xy 368.285908 -251.53859) (xy 368.264983 -251.528012)
			(xy 368.253264 -251.52731) (xy 367.273078 -251.52731) (xy 367.263254 -251.52783) (xy 367.245123 -251.535416)
			(xy 367.231264 -251.54935) (xy 367.223776 -251.567521) (xy 367.223294 -251.577348) (xy 367.223294 -252.038866)
			(xy 367.22304 -252.040898) (xy 367.22304 -252.056138) (xy 367.193322 -252.085856) (xy 367.008156 -252.085856)
			(xy 366.997772 -252.086442) (xy 366.978771 -252.094848) (xy 366.971326 -252.102112) (xy 366.9659 -252.108535)
			(xy 366.959278 -252.123979) (xy 366.958372 -252.132338) (xy 366.958372 -252.1458) (xy 366.706404 -252.1458)
			(xy 366.705896 -252.1458) (xy 366.685865 -252.145589) (xy 366.646425 -252.138597) (xy 366.608981 -252.124372)
			(xy 366.574848 -252.103412) (xy 366.545223 -252.076453) (xy 366.521147 -252.044442) (xy 366.503464 -252.008501)
			(xy 366.492795 -251.969894) (xy 366.490758 -251.949966) (xy 366.490504 -251.946664) (xy 366.490504 -251.94514)
			(xy 366.484662 -251.92482) (xy 366.482376 -251.920248) (xy 366.471184 -251.897546) (xy 366.455347 -251.849476)
			(xy 366.447327 -251.799504) (xy 366.446816 -251.774198) (xy 366.446816 -251.768864) (xy 366.447711 -251.743981)
			(xy 366.456292 -251.694937) (xy 366.472423 -251.647834) (xy 366.483646 -251.625608) (xy 366.484916 -251.623068)
			(xy 366.487202 -251.61748) (xy 366.487202 -251.617226) (xy 366.491266 -251.605542) (xy 366.492028 -251.601986)
			(xy 366.492028 -251.601224) (xy 366.492282 -251.599446) (xy 366.492282 -251.599192) (xy 366.495955 -251.57776)
			(xy 366.510837 -251.536911) (xy 366.533669 -251.499913) (xy 366.563508 -251.468294) (xy 366.599122 -251.443359)
			(xy 366.639042 -251.426138) (xy 366.681618 -251.417341) (xy 366.703356 -251.41682) (xy 366.791494 -251.41682)
			(xy 366.801396 -251.416401) (xy 366.819682 -251.408799) (xy 366.833648 -251.394759) (xy 366.841153 -251.376432)
			(xy 366.841532 -251.366528) (xy 366.841532 -250.785884) (xy 366.841025 -250.77613) (xy 366.833587 -250.75809)
			(xy 366.827054 -250.750832) (xy 366.72901 -250.652788) (xy 366.721763 -250.646233) (xy 366.703719 -250.638783)
			(xy 366.693958 -250.63831) (xy 366.100106 -250.63831) (xy 366.090271 -250.638851) (xy 366.072117 -250.646445)
			(xy 366.0648 -250.653042) (xy 365.967264 -250.750578) (xy 365.960548 -250.757815) (xy 365.952945 -250.77602)
			(xy 365.952532 -250.785884) (xy 365.952532 -251.125736) (xy 365.952003 -251.135577) (xy 365.944428 -251.15375)
			(xy 365.9378 -251.161042) (xy 365.713264 -251.385578) (xy 365.706026 -251.392291) (xy 365.687821 -251.399882)
			(xy 365.677958 -251.40031) (xy 365.368078 -251.40031) (xy 365.358254 -251.40083) (xy 365.340123 -251.408416)
			(xy 365.326264 -251.42235) (xy 365.318776 -251.440521) (xy 365.318294 -251.450348) (xy 365.318294 -252.038866)
			(xy 365.31804 -252.040898) (xy 365.31804 -252.056138) (xy 365.288322 -252.085856) (xy 365.103156 -252.085856)
			(xy 365.092772 -252.086442) (xy 365.073771 -252.094848) (xy 365.066326 -252.102112) (xy 365.0609 -252.108535)
			(xy 365.054278 -252.123979) (xy 365.053372 -252.132338) (xy 365.053372 -252.1458) (xy 364.799118 -252.1458)
			(xy 364.777364 -252.145326) (xy 364.734736 -252.13663) (xy 364.694739 -252.119511) (xy 364.65902 -252.094673)
			(xy 364.64367 -252.079252) (xy 364.629928 -252.064136) (xy 364.607924 -252.029721) (xy 364.592881 -251.991744)
			(xy 364.585349 -251.951596) (xy 364.584996 -251.93117) (xy 364.584996 -251.881132) (xy 364.584234 -251.878592)
			(xy 364.582456 -251.873258) (xy 364.575118 -251.849283) (xy 364.567212 -251.799774) (xy 364.566708 -251.774706)
			(xy 364.566708 -251.774198) (xy 364.567184 -251.749065) (xy 364.575092 -251.699426) (xy 364.582456 -251.675392)
			(xy 364.58398 -251.67082) (xy 364.584996 -251.667264) (xy 364.584996 -251.637038) (xy 364.584996 -251.635768)
			(xy 364.584883 -251.618636) (xy 364.589471 -251.584687) (xy 364.59414 -251.568204) (xy 364.594648 -251.567188)
			(xy 364.595156 -251.56541) (xy 364.608872 -251.521468) (xy 364.608618 -251.516642) (xy 364.607602 -251.504704)
			(xy 364.581948 -251.464826) (xy 364.553754 -251.421392) (xy 364.546343 -251.412068) (xy 364.525255 -251.401071)
			(xy 364.513368 -251.40031) (xy 363.590078 -251.40031) (xy 363.580254 -251.40083) (xy 363.562123 -251.408416)
			(xy 363.548264 -251.42235) (xy 363.540776 -251.440521) (xy 363.540294 -251.450348) (xy 363.540294 -252.038866)
			(xy 363.54004 -252.040898) (xy 363.54004 -252.056138) (xy 363.510322 -252.085856) (xy 363.325156 -252.085856)
			(xy 363.314772 -252.086442) (xy 363.295771 -252.094848) (xy 363.288326 -252.102112) (xy 363.2829 -252.108535)
			(xy 363.276278 -252.123979) (xy 363.275372 -252.132338) (xy 363.275372 -252.1458) (xy 363.023404 -252.1458)
			(xy 363.022896 -252.1458) (xy 363.003883 -252.145614) (xy 362.966389 -252.139326) (xy 362.930606 -252.126486)
			(xy 362.91393 -252.117352) (xy 362.894715 -252.105648) (xy 362.861288 -252.075545) (xy 362.847636 -252.057662)
			(xy 362.847382 -252.057408) (xy 362.841794 -252.050804) (xy 362.831634 -252.040898) (xy 362.827824 -252.038358)
			(xy 362.80652 -252.023455) (xy 362.768621 -251.987869) (xy 362.737014 -251.946592) (xy 362.712541 -251.900725)
			(xy 362.695855 -251.851488) (xy 362.687399 -251.800192) (xy 362.686854 -251.774198) (xy 362.687279 -251.750266)
			(xy 362.694437 -251.702941) (xy 362.708605 -251.657222) (xy 362.729464 -251.614143) (xy 362.756543 -251.574676)
			(xy 362.78923 -251.539712) (xy 362.826787 -251.510041) (xy 362.847382 -251.497846) (xy 362.848652 -251.497338)
			(xy 362.853224 -251.494036) (xy 362.862114 -251.486924) (xy 362.863892 -251.4854) (xy 362.864908 -251.483876)
			(xy 362.874452 -251.474089) (xy 362.895599 -251.456764) (xy 362.907072 -251.449332) (xy 362.917232 -251.442982)
			(xy 362.92282 -251.434092) (xy 362.925511 -251.429565) (xy 362.929217 -251.41971) (xy 362.930186 -251.414534)
			(xy 362.935012 -251.373894) (xy 362.935012 -251.373386) (xy 362.93933 -251.334778) (xy 362.939969 -251.323538)
			(xy 362.932579 -251.302305) (xy 362.925106 -251.293884) (xy 362.919264 -251.288042) (xy 362.912545 -251.280806)
			(xy 362.904935 -251.262601) (xy 362.904532 -251.252736) (xy 362.904532 -250.912884) (xy 362.904025 -250.90313)
			(xy 362.896587 -250.88509) (xy 362.890054 -250.877832) (xy 362.79201 -250.779788) (xy 362.784763 -250.773233)
			(xy 362.766719 -250.765783) (xy 362.756958 -250.76531) (xy 362.000546 -250.76531) (xy 361.989923 -250.765848)
			(xy 361.970588 -250.774667) (xy 361.963208 -250.782328) (xy 361.953048 -250.795028) (xy 361.953048 -250.795536)
			(xy 361.911646 -250.848876) (xy 361.908853 -250.853003) (xy 361.90475 -250.862082) (xy 361.903518 -250.86691)
			(xy 361.901232 -250.877578) (xy 361.903518 -250.886976) (xy 361.904026 -250.889008) (xy 361.908216 -250.90752)
			(xy 361.912678 -250.945213) (xy 361.912916 -250.964192) (xy 361.912426 -250.989181) (xy 361.904607 -251.038544)
			(xy 361.889163 -251.086076) (xy 361.866473 -251.130608) (xy 361.837097 -251.171041) (xy 361.801757 -251.206381)
			(xy 361.761324 -251.235757) (xy 361.716792 -251.258447) (xy 361.66926 -251.273891) (xy 361.619897 -251.28171)
			(xy 361.569919 -251.28171) (xy 361.520556 -251.273891) (xy 361.473024 -251.258447) (xy 361.428492 -251.235757)
			(xy 361.388059 -251.206381) (xy 361.352719 -251.171041) (xy 361.323343 -251.130608) (xy 361.300653 -251.086076)
			(xy 361.285209 -251.038544) (xy 361.27739 -250.989181) (xy 361.2769 -250.964192) (xy 361.277146 -250.945214)
			(xy 361.281603 -250.90752) (xy 361.28579 -250.889008) (xy 361.286298 -250.886976) (xy 361.288584 -250.877578)
			(xy 361.286298 -250.86691) (xy 361.285068 -250.862081) (xy 361.280972 -250.852997) (xy 361.27817 -250.848876)
			(xy 361.236768 -250.795536) (xy 361.236768 -250.795028) (xy 361.226608 -250.782328) (xy 361.21923 -250.774667)
			(xy 361.199892 -250.765858) (xy 361.18927 -250.76531) (xy 357.718106 -250.76531) (xy 357.708271 -250.765851)
			(xy 357.690117 -250.773445) (xy 357.6828 -250.780042) (xy 356.950264 -251.512578) (xy 356.943026 -251.519291)
			(xy 356.924821 -251.526882) (xy 356.914958 -251.52731) (xy 356.097078 -251.52731) (xy 356.087254 -251.52783)
			(xy 356.069123 -251.535416) (xy 356.055264 -251.54935) (xy 356.047776 -251.567521) (xy 356.047294 -251.577348)
			(xy 356.047294 -251.774198) (xy 357.053134 -251.774198) (xy 357.053625 -251.749274) (xy 357.061442 -251.70004)
			(xy 357.076822 -251.652622) (xy 357.087678 -251.63018) (xy 357.089744 -251.6258) (xy 357.092293 -251.616458)
			(xy 357.092758 -251.611638) (xy 357.0949 -251.591946) (xy 357.105576 -251.553803) (xy 357.1231 -251.518282)
			(xy 357.146871 -251.4866) (xy 357.176074 -251.459841) (xy 357.209709 -251.438925) (xy 357.246624 -251.424566)
			(xy 357.285552 -251.417257) (xy 357.305356 -251.41682) (xy 357.560372 -251.41682) (xy 357.560372 -251.425964)
			(xy 357.560848 -251.43598) (xy 357.568501 -251.45449) (xy 357.582656 -251.468663) (xy 357.601157 -251.476339)
			(xy 357.611172 -251.476764) (xy 357.77424 -251.476764) (xy 357.784246 -251.477254) (xy 357.802732 -251.48492)
			(xy 357.816882 -251.499072) (xy 357.824546 -251.517558) (xy 357.82504 -251.527564) (xy 357.82504 -251.654056)
			(xy 359.750868 -251.654056) (xy 359.750868 -251.146564) (xy 359.751358 -251.136558) (xy 359.759023 -251.118072)
			(xy 359.773175 -251.103921) (xy 359.791662 -251.096257) (xy 359.801668 -251.095764) (xy 360.015536 -251.095764)
			(xy 360.015536 -251.08662) (xy 360.015937 -251.076596) (xy 360.023607 -251.058072) (xy 360.037786 -251.043898)
			(xy 360.056311 -251.036234) (xy 360.066336 -251.03582) (xy 360.270552 -251.03582) (xy 360.290609 -251.036264)
			(xy 360.330017 -251.043749) (xy 360.367334 -251.058464) (xy 360.401244 -251.079892) (xy 360.430555 -251.107277)
			(xy 360.442764 -251.123196) (xy 360.450384 -251.131578) (xy 360.470934 -251.150148) (xy 360.506573 -251.192542)
			(xy 360.535224 -251.23994) (xy 360.556196 -251.291201) (xy 360.568984 -251.345089) (xy 360.573281 -251.400307)
			(xy 360.568982 -251.455524) (xy 360.556192 -251.509412) (xy 360.535218 -251.560671) (xy 360.506565 -251.608069)
			(xy 360.470925 -251.650462) (xy 360.450384 -251.669042) (xy 360.442764 -251.677424) (xy 360.430522 -251.693315)
			(xy 360.401215 -251.720694) (xy 360.367312 -251.742121) (xy 360.330005 -251.756841) (xy 360.290605 -251.764338)
			(xy 360.270552 -251.7648) (xy 360.015536 -251.7648) (xy 360.015536 -251.755656) (xy 360.015049 -251.74565)
			(xy 360.007381 -251.727164) (xy 359.993229 -251.713014) (xy 359.974742 -251.70535) (xy 359.964736 -251.704856)
			(xy 359.801668 -251.704856) (xy 359.791639 -251.704506) (xy 359.773113 -251.696817) (xy 359.75894 -251.682623)
			(xy 359.751279 -251.664085) (xy 359.750868 -251.654056) (xy 357.82504 -251.654056) (xy 357.82504 -251.774198)
			(xy 360.806746 -251.774198) (xy 360.807174 -251.750505) (xy 360.814188 -251.703642) (xy 360.828074 -251.658338)
			(xy 360.848527 -251.615594) (xy 360.875092 -251.576356) (xy 360.907184 -251.541493) (xy 360.925364 -251.526294)
			(xy 360.928496 -251.523703) (xy 360.933983 -251.517706) (xy 360.936286 -251.514356) (xy 360.948277 -251.496766)
			(xy 360.97798 -251.466283) (xy 361.013139 -251.442296) (xy 361.052356 -251.425759) (xy 361.094075 -251.417329)
			(xy 361.115356 -251.41682) (xy 361.370372 -251.41682) (xy 361.370372 -251.425964) (xy 361.370848 -251.43598)
			(xy 361.378501 -251.45449) (xy 361.392656 -251.468663) (xy 361.411157 -251.476339) (xy 361.421172 -251.476764)
			(xy 361.58424 -251.476764) (xy 361.594246 -251.477254) (xy 361.612732 -251.48492) (xy 361.626882 -251.499072)
			(xy 361.634546 -251.517558) (xy 361.63504 -251.527564) (xy 361.63504 -252.035056) (xy 361.634545 -252.04507)
			(xy 361.626897 -252.063578) (xy 361.612748 -252.07775) (xy 361.594253 -252.085429) (xy 361.58424 -252.085856)
			(xy 361.370372 -252.085856) (xy 361.370372 -252.095) (xy 361.36998 -252.105025) (xy 361.362305 -252.123547)
			(xy 361.348124 -252.13772) (xy 361.329597 -252.145385) (xy 361.319572 -252.1458) (xy 361.115356 -252.1458)
			(xy 361.095489 -252.145331) (xy 361.056434 -252.13802) (xy 361.019408 -252.123603) (xy 360.985693 -252.10258)
			(xy 360.956454 -252.075676) (xy 360.932703 -252.043823) (xy 360.923586 -252.026166) (xy 360.921346 -252.021823)
			(xy 360.915461 -252.014022) (xy 360.911902 -252.010672) (xy 360.892464 -251.992406) (xy 360.859364 -251.950584)
			(xy 360.833694 -251.903832) (xy 360.816172 -251.853456) (xy 360.807287 -251.800866) (xy 360.806746 -251.774198)
			(xy 357.82504 -251.774198) (xy 357.82504 -252.035056) (xy 357.824545 -252.04507) (xy 357.816897 -252.063578)
			(xy 357.802748 -252.07775) (xy 357.784253 -252.085429) (xy 357.77424 -252.085856) (xy 357.560372 -252.085856)
			(xy 357.560372 -252.095) (xy 357.55998 -252.105025) (xy 357.552305 -252.123547) (xy 357.538124 -252.13772)
			(xy 357.519597 -252.145385) (xy 357.509572 -252.1458) (xy 357.305356 -252.1458) (xy 357.284298 -252.145225)
			(xy 357.242997 -252.136983) (xy 357.204112 -252.120806) (xy 357.169151 -252.097322) (xy 357.13947 -252.067442)
			(xy 357.116221 -252.032325) (xy 357.100305 -251.993332) (xy 357.092339 -251.951977) (xy 357.091996 -251.930916)
			(xy 357.091996 -251.926852) (xy 357.079753 -251.903291) (xy 357.062419 -251.853108) (xy 357.053648 -251.800745)
			(xy 357.053134 -251.774198) (xy 356.047294 -251.774198) (xy 356.047294 -252.038866) (xy 356.04704 -252.040898)
			(xy 356.04704 -252.056138) (xy 356.017322 -252.085856) (xy 355.832156 -252.085856) (xy 355.821772 -252.086442)
			(xy 355.802771 -252.094848) (xy 355.795326 -252.102112) (xy 355.7899 -252.108535) (xy 355.783278 -252.123979)
			(xy 355.782372 -252.132338) (xy 355.782372 -252.1458) (xy 355.527356 -252.1458) (xy 355.509291 -252.145467)
			(xy 355.473665 -252.139471) (xy 355.45649 -252.133862) (xy 355.439937 -252.127691) (xy 355.408981 -252.110672)
			(xy 355.381252 -252.088786) (xy 355.369114 -252.07595) (xy 355.368098 -252.07468) (xy 355.362002 -252.068838)
			(xy 355.350318 -252.05944) (xy 355.345746 -252.057154) (xy 355.323797 -252.045341) (xy 355.283553 -252.015935)
			(xy 355.248392 -251.980609) (xy 355.219176 -251.940227) (xy 355.196622 -251.895779) (xy 355.181283 -251.848356)
			(xy 355.173534 -251.79912) (xy 355.173026 -251.774198) (xy 355.173026 -251.77115) (xy 355.173534 -251.756164)
			(xy 355.175319 -251.732312) (xy 355.185134 -251.685501) (xy 355.193092 -251.662946) (xy 355.197664 -251.6505)
			(xy 355.19614 -251.63907) (xy 355.195296 -251.633413) (xy 355.191451 -251.622645) (xy 355.18852 -251.617734)
			(xy 355.175312 -251.598938) (xy 355.174804 -251.59843) (xy 355.139752 -251.54763) (xy 355.132267 -251.538581)
			(xy 355.111344 -251.52798) (xy 355.09962 -251.52731) (xy 354.192078 -251.52731) (xy 354.182254 -251.52783)
			(xy 354.164123 -251.535416) (xy 354.150264 -251.54935) (xy 354.142776 -251.567521) (xy 354.142294 -251.577348)
			(xy 354.142294 -252.038866) (xy 354.14204 -252.040898) (xy 354.14204 -252.056138) (xy 354.112322 -252.085856)
			(xy 353.927156 -252.085856) (xy 353.916772 -252.086442) (xy 353.897771 -252.094848) (xy 353.890326 -252.102112)
			(xy 353.8849 -252.108535) (xy 353.878278 -252.123979) (xy 353.877372 -252.132338) (xy 353.877372 -252.1458)
			(xy 353.62515 -252.1458) (xy 353.624642 -252.1458) (xy 353.603697 -252.145509) (xy 353.562533 -252.137785)
			(xy 353.523662 -252.122192) (xy 353.488571 -252.099327) (xy 353.458606 -252.070066) (xy 353.446334 -252.05309)
			(xy 353.443794 -252.04928) (xy 353.431094 -252.036326) (xy 353.427538 -252.033786) (xy 353.407264 -252.018853)
			(xy 353.371258 -251.983658) (xy 353.341245 -251.943231) (xy 353.317975 -251.89858) (xy 353.302029 -251.850822)
			(xy 353.293805 -251.801148) (xy 353.293172 -251.775976) (xy 353.293172 -251.773944) (xy 353.293821 -251.745577)
			(xy 353.303916 -251.689746) (xy 353.313238 -251.662946) (xy 353.31781 -251.6505) (xy 353.316286 -251.63907)
			(xy 353.315442 -251.633413) (xy 353.311601 -251.622643) (xy 353.308666 -251.617734) (xy 353.295458 -251.598938)
			(xy 353.29495 -251.59843) (xy 353.259898 -251.54763) (xy 353.25241 -251.53859) (xy 353.231486 -251.528011)
			(xy 353.219766 -251.52731) (xy 352.287078 -251.52731) (xy 352.277254 -251.52783) (xy 352.259123 -251.535416)
			(xy 352.245264 -251.54935) (xy 352.237776 -251.567521) (xy 352.237294 -251.577348) (xy 352.237294 -252.038866)
			(xy 352.23704 -252.040898) (xy 352.23704 -252.056138) (xy 352.207322 -252.085856) (xy 352.022156 -252.085856)
			(xy 352.011772 -252.086442) (xy 351.992771 -252.094848) (xy 351.985326 -252.102112) (xy 351.9799 -252.108535)
			(xy 351.973278 -252.123979) (xy 351.972372 -252.132338) (xy 351.972372 -252.1458) (xy 351.717356 -252.1458)
			(xy 351.697334 -252.145342) (xy 351.657994 -252.13787) (xy 351.620736 -252.123196) (xy 351.586866 -252.101834)
			(xy 351.557572 -252.074534) (xy 351.53388 -252.042251) (xy 351.524824 -252.024388) (xy 351.5233 -252.021086)
			(xy 351.522792 -252.02007) (xy 351.519236 -252.01499) (xy 351.511362 -252.004322) (xy 351.508568 -252.001528)
			(xy 351.491831 -251.984579) (xy 351.463116 -251.946574) (xy 351.4404 -251.904707) (xy 351.424191 -251.859917)
			(xy 351.414855 -251.813208) (xy 351.413318 -251.789438) (xy 351.413318 -251.78893) (xy 351.413064 -251.775976)
			(xy 351.413064 -251.773944) (xy 351.413713 -251.745577) (xy 351.423808 -251.689746) (xy 351.43313 -251.662946)
			(xy 351.437702 -251.6505) (xy 351.436178 -251.63907) (xy 351.435334 -251.633413) (xy 351.431492 -251.622643)
			(xy 351.428558 -251.617734) (xy 351.41535 -251.598938) (xy 351.414842 -251.59843) (xy 351.37979 -251.54763)
			(xy 351.372308 -251.538574) (xy 351.351385 -251.527958) (xy 351.339658 -251.52731) (xy 350.304354 -251.52731)
			(xy 350.293752 -251.527782) (xy 350.274407 -251.536459) (xy 350.267016 -251.544074) (xy 350.262698 -251.55144)
			(xy 350.260412 -251.55525) (xy 350.257561 -251.560937) (xy 350.254471 -251.573274) (xy 350.254316 -251.579634)
			(xy 350.254316 -251.590302) (xy 350.352614 -251.760228) (xy 350.353376 -251.761498) (xy 350.35363 -251.762006)
			(xy 350.353884 -251.762514) (xy 350.354138 -251.763022) (xy 350.354392 -251.763022) (xy 350.359218 -251.771658)
			(xy 350.362774 -251.777754) (xy 350.351598 -251.818394) (xy 350.351344 -251.818648) (xy 350.35109 -251.818902)
			(xy 350.345756 -251.838968) (xy 350.343689 -251.848713) (xy 350.346318 -251.868441) (xy 350.350836 -251.877322)
			(xy 350.430338 -252.01499) (xy 350.44507 -252.04039) (xy 350.441006 -252.055376) (xy 350.438105 -252.064959)
			(xy 350.426046 -252.080925) (xy 350.417638 -252.086364) (xy 350.416114 -252.087126) (xy 350.415606 -252.08738)
			(xy 350.41459 -252.087888) (xy 350.288352 -252.160786) (xy 349.955612 -252.35281) (xy 349.91548 -252.342142)
			(xy 349.913702 -252.339094) (xy 349.909225 -252.33203) (xy 349.896654 -252.321016) (xy 349.889064 -252.317504)
			(xy 349.886524 -252.316488) (xy 349.846646 -252.32741) (xy 349.83643 -252.334756) (xy 349.824296 -252.35676)
			(xy 349.823532 -252.36932) (xy 349.823532 -252.670056) (xy 359.731564 -252.670056) (xy 359.731564 -252.162564)
			(xy 359.732058 -252.152558) (xy 359.739722 -252.134073) (xy 359.753873 -252.119922) (xy 359.772358 -252.112258)
			(xy 359.782364 -252.111764) (xy 359.99674 -252.111764) (xy 359.99674 -252.10262) (xy 359.997137 -252.092595)
			(xy 360.004808 -252.074071) (xy 360.018988 -252.059897) (xy 360.037515 -252.052233) (xy 360.04754 -252.05182)
			(xy 360.251502 -252.05182) (xy 360.27156 -252.052229) (xy 360.310971 -252.059723) (xy 360.348288 -252.074446)
			(xy 360.382197 -252.095882) (xy 360.411506 -252.123274) (xy 360.423714 -252.139196) (xy 360.431334 -252.147578)
			(xy 360.451886 -252.166146) (xy 360.48753 -252.208539) (xy 360.516185 -252.255937) (xy 360.53716 -252.307198)
			(xy 360.549951 -252.361087) (xy 360.554248 -252.416307) (xy 360.549948 -252.471526) (xy 360.537156 -252.525415)
			(xy 360.516179 -252.576675) (xy 360.511627 -252.584204) (xy 368.796824 -252.584204) (xy 368.79738 -252.55799)
			(xy 368.805978 -252.506271) (xy 368.822926 -252.456657) (xy 368.847766 -252.410486) (xy 368.87983 -252.369005)
			(xy 368.898678 -252.350778) (xy 368.90338 -252.346115) (xy 368.910458 -252.334929) (xy 368.912648 -252.32868)
			(xy 368.918849 -252.310348) (xy 368.936833 -252.276087) (xy 368.960698 -252.245629) (xy 368.98966 -252.21997)
			(xy 369.022772 -252.19995) (xy 369.05895 -252.186225) (xy 369.097009 -252.179244) (xy 369.116356 -252.17882)
			(xy 369.371372 -252.17882) (xy 369.371372 -252.187964) (xy 369.371848 -252.19798) (xy 369.379501 -252.21649)
			(xy 369.393656 -252.230663) (xy 369.412157 -252.238339) (xy 369.422172 -252.238764) (xy 369.58524 -252.238764)
			(xy 369.595246 -252.239254) (xy 369.613732 -252.24692) (xy 369.627882 -252.261072) (xy 369.635546 -252.279558)
			(xy 369.63604 -252.289564) (xy 369.63604 -252.584204) (xy 370.676678 -252.584204) (xy 370.677139 -252.558984)
			(xy 370.685095 -252.509176) (xy 370.700821 -252.461251) (xy 370.723925 -252.416413) (xy 370.753824 -252.375791)
			(xy 370.789767 -252.340404) (xy 370.810028 -252.325378) (xy 370.815386 -252.321308) (xy 370.823872 -252.310868)
			(xy 370.826792 -252.304804) (xy 370.835603 -252.286355) (xy 370.859111 -252.252912) (xy 370.888559 -252.224559)
			(xy 370.922869 -252.202336) (xy 370.960785 -252.187056) (xy 371.000917 -252.179279) (xy 371.021356 -252.17882)
			(xy 371.276372 -252.17882) (xy 371.276372 -252.187964) (xy 371.276848 -252.19798) (xy 371.284501 -252.21649)
			(xy 371.298656 -252.230663) (xy 371.317157 -252.238339) (xy 371.327172 -252.238764) (xy 371.49024 -252.238764)
			(xy 371.500246 -252.239254) (xy 371.518732 -252.24692) (xy 371.532882 -252.261072) (xy 371.540546 -252.279558)
			(xy 371.54104 -252.289564) (xy 371.54104 -252.584204) (xy 372.556786 -252.584204) (xy 372.557165 -252.562925)
			(xy 372.562895 -252.520754) (xy 372.574186 -252.47972) (xy 372.582186 -252.459998) (xy 372.585996 -252.450346)
			(xy 372.585996 -252.39345) (xy 372.586388 -252.372403) (xy 372.594386 -252.331082) (xy 372.61032 -252.292127)
			(xy 372.633571 -252.257045) (xy 372.663242 -252.227194) (xy 372.698182 -252.20373) (xy 372.73704 -252.187561)
			(xy 372.778312 -252.179312) (xy 372.799356 -252.17882) (xy 373.054372 -252.17882) (xy 373.054372 -252.187964)
			(xy 373.054848 -252.19798) (xy 373.062501 -252.21649) (xy 373.076656 -252.230663) (xy 373.095157 -252.238339)
			(xy 373.105172 -252.238764) (xy 373.26824 -252.238764) (xy 373.278246 -252.239254) (xy 373.296732 -252.24692)
			(xy 373.310882 -252.261072) (xy 373.318546 -252.279558) (xy 373.31904 -252.289564) (xy 373.31904 -252.609193)
			(xy 374.437384 -252.609193) (xy 374.437384 -252.559215) (xy 374.445203 -252.509852) (xy 374.460647 -252.46232)
			(xy 374.483337 -252.417788) (xy 374.512713 -252.377355) (xy 374.548053 -252.342015) (xy 374.588486 -252.312639)
			(xy 374.633018 -252.289949) (xy 374.68055 -252.274505) (xy 374.729913 -252.266686) (xy 374.779891 -252.266686)
			(xy 374.829254 -252.274505) (xy 374.876786 -252.289949) (xy 374.921318 -252.312639) (xy 374.961751 -252.342015)
			(xy 374.997091 -252.377355) (xy 375.026467 -252.417788) (xy 375.049157 -252.46232) (xy 375.064601 -252.509852)
			(xy 375.07242 -252.559215) (xy 375.07291 -252.584204) (xy 375.07242 -252.609193) (xy 375.377184 -252.609193)
			(xy 375.377184 -252.559215) (xy 375.385003 -252.509852) (xy 375.400447 -252.46232) (xy 375.423137 -252.417788)
			(xy 375.452513 -252.377355) (xy 375.487853 -252.342015) (xy 375.528286 -252.312639) (xy 375.572818 -252.289949)
			(xy 375.62035 -252.274505) (xy 375.669713 -252.266686) (xy 375.719691 -252.266686) (xy 375.769054 -252.274505)
			(xy 375.816586 -252.289949) (xy 375.861118 -252.312639) (xy 375.901551 -252.342015) (xy 375.936891 -252.377355)
			(xy 375.966267 -252.417788) (xy 375.988957 -252.46232) (xy 376.004401 -252.509852) (xy 376.01222 -252.559215)
			(xy 376.01271 -252.584204) (xy 376.01222 -252.609193) (xy 376.317238 -252.609193) (xy 376.317238 -252.559215)
			(xy 376.325057 -252.509852) (xy 376.340501 -252.46232) (xy 376.363191 -252.417788) (xy 376.392567 -252.377355)
			(xy 376.427907 -252.342015) (xy 376.46834 -252.312639) (xy 376.512872 -252.289949) (xy 376.560404 -252.274505)
			(xy 376.609767 -252.266686) (xy 376.659745 -252.266686) (xy 376.709108 -252.274505) (xy 376.75664 -252.289949)
			(xy 376.801172 -252.312639) (xy 376.841605 -252.342015) (xy 376.876945 -252.377355) (xy 376.906321 -252.417788)
			(xy 376.929011 -252.46232) (xy 376.944455 -252.509852) (xy 376.952274 -252.559215) (xy 376.952764 -252.584204)
			(xy 377.258575 -252.584204) (xy 377.26267 -252.533476) (xy 377.274849 -252.484062) (xy 377.294797 -252.437242)
			(xy 377.321998 -252.394228) (xy 377.355746 -252.356134) (xy 377.395168 -252.323947) (xy 377.439242 -252.298501)
			(xy 377.486828 -252.280454) (xy 377.536692 -252.270274) (xy 377.587544 -252.268225) (xy 377.638065 -252.274359)
			(xy 377.686949 -252.288519) (xy 377.732928 -252.310336) (xy 377.774812 -252.339246) (xy 377.811516 -252.374501)
			(xy 377.842089 -252.415187) (xy 377.86574 -252.46025) (xy 377.881856 -252.508524) (xy 377.89002 -252.558758)
			(xy 377.890532 -252.584204) (xy 377.890029 -252.609193) (xy 378.197346 -252.609193) (xy 378.197346 -252.559215)
			(xy 378.205165 -252.509852) (xy 378.220609 -252.46232) (xy 378.243299 -252.417788) (xy 378.272675 -252.377355)
			(xy 378.308015 -252.342015) (xy 378.348448 -252.312639) (xy 378.39298 -252.289949) (xy 378.440512 -252.274505)
			(xy 378.489875 -252.266686) (xy 378.539853 -252.266686) (xy 378.589216 -252.274505) (xy 378.636748 -252.289949)
			(xy 378.68128 -252.312639) (xy 378.721713 -252.342015) (xy 378.757053 -252.377355) (xy 378.786429 -252.417788)
			(xy 378.809119 -252.46232) (xy 378.824563 -252.509852) (xy 378.832382 -252.559215) (xy 378.832872 -252.584204)
			(xy 378.832382 -252.609193) (xy 379.1374 -252.609193) (xy 379.1374 -252.559215) (xy 379.145219 -252.509852)
			(xy 379.160663 -252.46232) (xy 379.183353 -252.417788) (xy 379.212729 -252.377355) (xy 379.248069 -252.342015)
			(xy 379.288502 -252.312639) (xy 379.333034 -252.289949) (xy 379.380566 -252.274505) (xy 379.429929 -252.266686)
			(xy 379.479907 -252.266686) (xy 379.52927 -252.274505) (xy 379.576802 -252.289949) (xy 379.621334 -252.312639)
			(xy 379.661767 -252.342015) (xy 379.697107 -252.377355) (xy 379.726483 -252.417788) (xy 379.749173 -252.46232)
			(xy 379.764617 -252.509852) (xy 379.772436 -252.559215) (xy 379.772926 -252.584204) (xy 380.078483 -252.584204)
			(xy 380.082578 -252.533476) (xy 380.094757 -252.484062) (xy 380.114705 -252.437242) (xy 380.141906 -252.394228)
			(xy 380.175654 -252.356134) (xy 380.215076 -252.323947) (xy 380.25915 -252.298501) (xy 380.306736 -252.280454)
			(xy 380.3566 -252.270274) (xy 380.407452 -252.268225) (xy 380.457973 -252.274359) (xy 380.506857 -252.288519)
			(xy 380.552836 -252.310336) (xy 380.59472 -252.339246) (xy 380.631424 -252.374501) (xy 380.661997 -252.415187)
			(xy 380.685648 -252.46025) (xy 380.701764 -252.508524) (xy 380.709928 -252.558758) (xy 380.71044 -252.584204)
			(xy 380.709928 -252.60965) (xy 380.701764 -252.659884) (xy 380.685648 -252.708158) (xy 380.661997 -252.753221)
			(xy 380.631424 -252.793907) (xy 380.59472 -252.829162) (xy 380.552836 -252.858072) (xy 380.506857 -252.879889)
			(xy 380.457973 -252.894049) (xy 380.407452 -252.900183) (xy 380.3566 -252.898134) (xy 380.306736 -252.887954)
			(xy 380.25915 -252.869907) (xy 380.215076 -252.844461) (xy 380.175654 -252.812274) (xy 380.141906 -252.77418)
			(xy 380.114705 -252.731166) (xy 380.094757 -252.684346) (xy 380.082578 -252.634932) (xy 380.078483 -252.584204)
			(xy 379.772926 -252.584204) (xy 379.772436 -252.609193) (xy 379.764617 -252.658556) (xy 379.749173 -252.706088)
			(xy 379.726483 -252.75062) (xy 379.697107 -252.791053) (xy 379.661767 -252.826393) (xy 379.621334 -252.855769)
			(xy 379.576802 -252.878459) (xy 379.52927 -252.893903) (xy 379.479907 -252.901722) (xy 379.429929 -252.901722)
			(xy 379.380566 -252.893903) (xy 379.333034 -252.878459) (xy 379.288502 -252.855769) (xy 379.248069 -252.826393)
			(xy 379.212729 -252.791053) (xy 379.183353 -252.75062) (xy 379.160663 -252.706088) (xy 379.145219 -252.658556)
			(xy 379.1374 -252.609193) (xy 378.832382 -252.609193) (xy 378.824563 -252.658556) (xy 378.809119 -252.706088)
			(xy 378.786429 -252.75062) (xy 378.757053 -252.791053) (xy 378.721713 -252.826393) (xy 378.68128 -252.855769)
			(xy 378.636748 -252.878459) (xy 378.589216 -252.893903) (xy 378.539853 -252.901722) (xy 378.489875 -252.901722)
			(xy 378.440512 -252.893903) (xy 378.39298 -252.878459) (xy 378.348448 -252.855769) (xy 378.308015 -252.826393)
			(xy 378.272675 -252.791053) (xy 378.243299 -252.75062) (xy 378.220609 -252.706088) (xy 378.205165 -252.658556)
			(xy 378.197346 -252.609193) (xy 377.890029 -252.609193) (xy 377.89002 -252.60965) (xy 377.881856 -252.659884)
			(xy 377.86574 -252.708158) (xy 377.842089 -252.753221) (xy 377.811516 -252.793907) (xy 377.774812 -252.829162)
			(xy 377.732928 -252.858072) (xy 377.686949 -252.879889) (xy 377.638065 -252.894049) (xy 377.587544 -252.900183)
			(xy 377.536692 -252.898134) (xy 377.486828 -252.887954) (xy 377.439242 -252.869907) (xy 377.395168 -252.844461)
			(xy 377.355746 -252.812274) (xy 377.321998 -252.77418) (xy 377.294797 -252.731166) (xy 377.274849 -252.684346)
			(xy 377.26267 -252.634932) (xy 377.258575 -252.584204) (xy 376.952764 -252.584204) (xy 376.952274 -252.609193)
			(xy 376.944455 -252.658556) (xy 376.929011 -252.706088) (xy 376.906321 -252.75062) (xy 376.876945 -252.791053)
			(xy 376.841605 -252.826393) (xy 376.801172 -252.855769) (xy 376.75664 -252.878459) (xy 376.709108 -252.893903)
			(xy 376.659745 -252.901722) (xy 376.609767 -252.901722) (xy 376.560404 -252.893903) (xy 376.512872 -252.878459)
			(xy 376.46834 -252.855769) (xy 376.427907 -252.826393) (xy 376.392567 -252.791053) (xy 376.363191 -252.75062)
			(xy 376.340501 -252.706088) (xy 376.325057 -252.658556) (xy 376.317238 -252.609193) (xy 376.01222 -252.609193)
			(xy 376.004401 -252.658556) (xy 375.988957 -252.706088) (xy 375.966267 -252.75062) (xy 375.936891 -252.791053)
			(xy 375.901551 -252.826393) (xy 375.861118 -252.855769) (xy 375.816586 -252.878459) (xy 375.769054 -252.893903)
			(xy 375.719691 -252.901722) (xy 375.669713 -252.901722) (xy 375.62035 -252.893903) (xy 375.572818 -252.878459)
			(xy 375.528286 -252.855769) (xy 375.487853 -252.826393) (xy 375.452513 -252.791053) (xy 375.423137 -252.75062)
			(xy 375.400447 -252.706088) (xy 375.385003 -252.658556) (xy 375.377184 -252.609193) (xy 375.07242 -252.609193)
			(xy 375.064601 -252.658556) (xy 375.049157 -252.706088) (xy 375.026467 -252.75062) (xy 374.997091 -252.791053)
			(xy 374.961751 -252.826393) (xy 374.921318 -252.855769) (xy 374.876786 -252.878459) (xy 374.829254 -252.893903)
			(xy 374.779891 -252.901722) (xy 374.729913 -252.901722) (xy 374.68055 -252.893903) (xy 374.633018 -252.878459)
			(xy 374.588486 -252.855769) (xy 374.548053 -252.826393) (xy 374.512713 -252.791053) (xy 374.483337 -252.75062)
			(xy 374.460647 -252.706088) (xy 374.445203 -252.658556) (xy 374.437384 -252.609193) (xy 373.31904 -252.609193)
			(xy 373.31904 -252.797056) (xy 373.318545 -252.80707) (xy 373.310897 -252.825578) (xy 373.296748 -252.83975)
			(xy 373.278253 -252.847429) (xy 373.26824 -252.847856) (xy 373.054372 -252.847856) (xy 373.054372 -252.857)
			(xy 373.05398 -252.867025) (xy 373.046305 -252.885547) (xy 373.032124 -252.89972) (xy 373.013597 -252.907385)
			(xy 373.003572 -252.9078) (xy 372.799356 -252.9078) (xy 372.777796 -252.907258) (xy 372.735559 -252.898579)
			(xy 372.695921 -252.881605) (xy 372.660493 -252.857024) (xy 372.630717 -252.825836) (xy 372.607802 -252.789308)
			(xy 372.59268 -252.748927) (xy 372.58879 -252.727714) (xy 372.58498 -252.71476) (xy 372.576087 -252.694155)
			(xy 372.56354 -252.651068) (xy 372.557188 -252.606642) (xy 372.556786 -252.584204) (xy 371.54104 -252.584204)
			(xy 371.54104 -252.797056) (xy 371.540545 -252.80707) (xy 371.532897 -252.825578) (xy 371.518748 -252.83975)
			(xy 371.500253 -252.847429) (xy 371.49024 -252.847856) (xy 371.276372 -252.847856) (xy 371.276372 -252.857)
			(xy 371.27598 -252.867025) (xy 371.268305 -252.885547) (xy 371.254124 -252.89972) (xy 371.235597 -252.907385)
			(xy 371.225572 -252.9078) (xy 371.021356 -252.9078) (xy 371.008728 -252.907631) (xy 370.983644 -252.904706)
			(xy 370.971318 -252.901958) (xy 370.96446 -252.900942) (xy 370.938547 -252.897863) (xy 370.888115 -252.884478)
			(xy 370.840543 -252.863043) (xy 370.797107 -252.834133) (xy 370.758971 -252.798521) (xy 370.727158 -252.757164)
			(xy 370.70252 -252.711169) (xy 370.685718 -252.661771) (xy 370.677203 -252.610293) (xy 370.676678 -252.584204)
			(xy 369.63604 -252.584204) (xy 369.63604 -252.797056) (xy 369.635545 -252.80707) (xy 369.627897 -252.825578)
			(xy 369.613748 -252.83975) (xy 369.595253 -252.847429) (xy 369.58524 -252.847856) (xy 369.371372 -252.847856)
			(xy 369.371372 -252.857) (xy 369.37098 -252.867025) (xy 369.363305 -252.885547) (xy 369.349124 -252.89972)
			(xy 369.330597 -252.907385) (xy 369.320572 -252.9078) (xy 369.115848 -252.9078) (xy 369.096281 -252.907365)
			(xy 369.057809 -252.900203) (xy 369.039394 -252.893576) (xy 369.03406 -252.891798) (xy 369.008911 -252.884676)
			(xy 368.961214 -252.863305) (xy 368.917652 -252.834425) (xy 368.879397 -252.798811) (xy 368.84748 -252.757422)
			(xy 368.822759 -252.711372) (xy 368.805898 -252.6619) (xy 368.797353 -252.610337) (xy 368.796824 -252.584204)
			(xy 360.511627 -252.584204) (xy 360.487523 -252.624072) (xy 360.451877 -252.666463) (xy 360.431334 -252.685042)
			(xy 360.423714 -252.693424) (xy 360.411501 -252.709339) (xy 360.382187 -252.736716) (xy 360.348276 -252.758139)
			(xy 360.310962 -252.772854) (xy 360.271557 -252.780343) (xy 360.251502 -252.7808) (xy 359.99674 -252.7808)
			(xy 359.99674 -252.771656) (xy 359.996249 -252.76165) (xy 359.988582 -252.743165) (xy 359.974431 -252.729015)
			(xy 359.955946 -252.72135) (xy 359.94594 -252.720856) (xy 359.782364 -252.720856) (xy 359.772335 -252.720509)
			(xy 359.753809 -252.712819) (xy 359.739636 -252.698624) (xy 359.731975 -252.680086) (xy 359.731564 -252.670056)
			(xy 349.823532 -252.670056) (xy 349.823532 -253.007114) (xy 349.823964 -253.015911) (xy 349.830065 -253.032419)
			(xy 349.83547 -253.039372) (xy 349.853504 -253.058422) (xy 349.856262 -253.060964) (xy 349.862387 -253.065293)
			(xy 349.865696 -253.067058) (xy 349.887794 -253.07798) (xy 349.895922 -253.07925) (xy 349.920884 -253.083282)
			(xy 349.96919 -253.098214) (xy 350.014524 -253.120604) (xy 350.055742 -253.149887) (xy 350.091805 -253.185326)
			(xy 350.121804 -253.226026) (xy 350.144982 -253.270962) (xy 350.160755 -253.319) (xy 350.168726 -253.368929)
			(xy 350.169186 -253.392178) (xy 351.410016 -253.392178) (xy 351.410587 -253.36541) (xy 351.419562 -253.312632)
			(xy 351.437254 -253.262105) (xy 351.463163 -253.215256) (xy 351.496557 -253.173412) (xy 351.53649 -253.137756)
			(xy 351.581833 -253.109295) (xy 351.606358 -253.098554) (xy 351.6122 -253.09576) (xy 351.628334 -253.087008)
			(xy 351.662856 -253.074554) (xy 351.699006 -253.06822) (xy 351.717356 -253.06782) (xy 351.972372 -253.06782)
			(xy 351.972372 -253.076964) (xy 351.972848 -253.08698) (xy 351.980501 -253.10549) (xy 351.994656 -253.119663)
			(xy 352.013157 -253.127339) (xy 352.023172 -253.127764) (xy 352.18624 -253.127764) (xy 352.196246 -253.128254)
			(xy 352.214732 -253.13592) (xy 352.228882 -253.150072) (xy 352.236546 -253.168558) (xy 352.23704 -253.178564)
			(xy 352.23704 -253.392178) (xy 353.28987 -253.392178) (xy 353.290275 -253.36753) (xy 353.297907 -253.318828)
			(xy 353.312954 -253.271883) (xy 353.335056 -253.227819) (xy 353.363685 -253.187688) (xy 353.398157 -253.152448)
			(xy 353.437649 -253.122943) (xy 353.481216 -253.099877) (xy 353.527818 -253.083801) (xy 353.551998 -253.078996)
			(xy 353.558348 -253.077472) (xy 353.573959 -253.072936) (xy 353.606102 -253.068088) (xy 353.622356 -253.06782)
			(xy 353.877372 -253.06782) (xy 353.877372 -253.076964) (xy 353.877848 -253.08698) (xy 353.885501 -253.10549)
			(xy 353.899656 -253.119663) (xy 353.918157 -253.127339) (xy 353.928172 -253.127764) (xy 354.09124 -253.127764)
			(xy 354.101246 -253.128254) (xy 354.119732 -253.13592) (xy 354.133882 -253.150072) (xy 354.141546 -253.168558)
			(xy 354.14204 -253.178564) (xy 354.14204 -253.392178) (xy 355.169978 -253.392178) (xy 355.170488 -253.368105)
			(xy 355.177735 -253.320509) (xy 355.192075 -253.27455) (xy 355.213181 -253.231278) (xy 355.240569 -253.191682)
			(xy 355.273614 -253.156668) (xy 355.31156 -253.127037) (xy 355.35354 -253.103465) (xy 355.398593 -253.086492)
			(xy 355.445691 -253.076506) (xy 355.469698 -253.074678) (xy 355.478334 -253.073408) (xy 355.490415 -253.070761)
			(xy 355.514989 -253.067965) (xy 355.527356 -253.06782) (xy 355.782372 -253.06782) (xy 355.782372 -253.076964)
			(xy 355.782848 -253.08698) (xy 355.790501 -253.10549) (xy 355.804656 -253.119663) (xy 355.823157 -253.127339)
			(xy 355.833172 -253.127764) (xy 355.99624 -253.127764) (xy 356.006246 -253.128254) (xy 356.024732 -253.13592)
			(xy 356.038882 -253.150072) (xy 356.046546 -253.168558) (xy 356.04704 -253.178564) (xy 356.04704 -253.392178)
			(xy 357.050086 -253.392178) (xy 357.050486 -253.370059) (xy 357.056648 -253.326251) (xy 357.068811 -253.283716)
			(xy 357.086739 -253.243272) (xy 357.098092 -253.224284) (xy 357.103172 -253.213616) (xy 357.110801 -253.192759)
			(xy 357.133257 -253.154459) (xy 357.163131 -253.121615) (xy 357.199138 -253.095639) (xy 357.239729 -253.077651)
			(xy 357.283158 -253.068422) (xy 357.305356 -253.06782) (xy 357.560372 -253.06782) (xy 357.560372 -253.076964)
			(xy 357.560848 -253.08698) (xy 357.568501 -253.10549) (xy 357.582656 -253.119663) (xy 357.601157 -253.127339)
			(xy 357.611172 -253.127764) (xy 357.77424 -253.127764) (xy 357.784246 -253.128254) (xy 357.802732 -253.13592)
			(xy 357.816882 -253.150072) (xy 357.824546 -253.168558) (xy 357.82504 -253.178564) (xy 357.82504 -253.686056)
			(xy 359.731564 -253.686056) (xy 359.731564 -253.178564) (xy 359.732058 -253.168558) (xy 359.739722 -253.150073)
			(xy 359.753873 -253.135922) (xy 359.772358 -253.128258) (xy 359.782364 -253.127764) (xy 359.99674 -253.127764)
			(xy 359.99674 -253.11862) (xy 359.997137 -253.108595) (xy 360.004808 -253.090071) (xy 360.018988 -253.075897)
			(xy 360.037515 -253.068233) (xy 360.04754 -253.06782) (xy 360.251502 -253.06782) (xy 360.27156 -253.068229)
			(xy 360.310971 -253.075723) (xy 360.348288 -253.090446) (xy 360.382197 -253.111882) (xy 360.411506 -253.139274)
			(xy 360.423714 -253.155196) (xy 360.431334 -253.163578) (xy 360.451886 -253.182146) (xy 360.48753 -253.224539)
			(xy 360.516185 -253.271937) (xy 360.53716 -253.323198) (xy 360.549951 -253.377087) (xy 360.551125 -253.392178)
			(xy 360.810048 -253.392178) (xy 360.810664 -253.365914) (xy 360.819306 -253.314101) (xy 360.836336 -253.264409)
			(xy 360.861291 -253.218187) (xy 360.893495 -253.176688) (xy 360.932074 -253.141038) (xy 360.975981 -253.112204)
			(xy 360.999786 -253.101094) (xy 361.005628 -253.0983) (xy 361.022298 -253.0888) (xy 361.058189 -253.075244)
			(xy 361.095921 -253.068301) (xy 361.115102 -253.06782) (xy 361.370372 -253.06782) (xy 361.370372 -253.076964)
			(xy 361.370848 -253.08698) (xy 361.378501 -253.10549) (xy 361.392656 -253.119663) (xy 361.411157 -253.127339)
			(xy 361.421172 -253.127764) (xy 361.58424 -253.127764) (xy 361.594246 -253.128254) (xy 361.612732 -253.13592)
			(xy 361.626882 -253.150072) (xy 361.634546 -253.168558) (xy 361.63504 -253.178564) (xy 361.63504 -253.392178)
			(xy 362.689902 -253.392178) (xy 362.69035 -253.367763) (xy 362.697839 -253.319509) (xy 362.712607 -253.272964)
			(xy 362.734309 -253.22922) (xy 362.762434 -253.189301) (xy 362.796325 -253.154145) (xy 362.835185 -253.124575)
			(xy 362.878104 -253.101285) (xy 362.924077 -253.08482) (xy 362.947966 -253.079758) (xy 362.954316 -253.078234)
			(xy 362.970263 -253.073382) (xy 363.003182 -253.068157) (xy 363.019848 -253.06782) (xy 363.275372 -253.06782)
			(xy 363.275372 -253.076964) (xy 363.275848 -253.08698) (xy 363.283501 -253.10549) (xy 363.297656 -253.119663)
			(xy 363.316157 -253.127339) (xy 363.326172 -253.127764) (xy 363.48924 -253.127764) (xy 363.499246 -253.128254)
			(xy 363.517732 -253.13592) (xy 363.531882 -253.150072) (xy 363.539546 -253.168558) (xy 363.54004 -253.178564)
			(xy 363.54004 -253.392178) (xy 364.57001 -253.392178) (xy 364.570377 -253.369314) (xy 364.576879 -253.324051)
			(xy 364.582964 -253.302008) (xy 364.584996 -253.29515) (xy 364.584996 -253.28245) (xy 364.585388 -253.261403)
			(xy 364.593386 -253.220082) (xy 364.60932 -253.181127) (xy 364.632571 -253.146045) (xy 364.662242 -253.116194)
			(xy 364.697182 -253.09273) (xy 364.73604 -253.076561) (xy 364.777312 -253.068312) (xy 364.798356 -253.06782)
			(xy 365.002572 -253.06782) (xy 365.012594 -253.068243) (xy 365.031114 -253.075908) (xy 365.045288 -253.090079)
			(xy 365.052955 -253.108598) (xy 365.053372 -253.11862) (xy 365.053372 -253.120398) (xy 365.064548 -253.127764)
			(xy 365.26724 -253.127764) (xy 365.277246 -253.128254) (xy 365.295732 -253.13592) (xy 365.309882 -253.150072)
			(xy 365.317546 -253.168558) (xy 365.31804 -253.178564) (xy 365.31804 -253.392178) (xy 366.449864 -253.392178)
			(xy 366.450516 -253.363721) (xy 366.460641 -253.307714) (xy 366.480565 -253.2544) (xy 366.494568 -253.229618)
			(xy 366.499648 -253.218442) (xy 366.505705 -253.200018) (xy 366.523631 -253.165627) (xy 366.54747 -253.135037)
			(xy 366.576441 -253.109254) (xy 366.60959 -253.089124) (xy 366.645828 -253.07531) (xy 366.683965 -253.068265)
			(xy 366.703356 -253.06782) (xy 366.958372 -253.06782) (xy 366.958372 -253.076964) (xy 366.958848 -253.08698)
			(xy 366.966501 -253.10549) (xy 366.980656 -253.119663) (xy 366.999157 -253.127339) (xy 367.009172 -253.127764)
			(xy 367.17224 -253.127764) (xy 367.182246 -253.128254) (xy 367.200732 -253.13592) (xy 367.214882 -253.150072)
			(xy 367.222546 -253.168558) (xy 367.22304 -253.178564) (xy 367.22304 -253.419199) (xy 370.207268 -253.419199)
			(xy 370.207268 -253.369221) (xy 370.215087 -253.319858) (xy 370.230531 -253.272326) (xy 370.253221 -253.227794)
			(xy 370.282597 -253.187361) (xy 370.317937 -253.152021) (xy 370.35837 -253.122645) (xy 370.402902 -253.099955)
			(xy 370.450434 -253.084511) (xy 370.499797 -253.076692) (xy 370.549775 -253.076692) (xy 370.599138 -253.084511)
			(xy 370.64667 -253.099955) (xy 370.691202 -253.122645) (xy 370.731635 -253.152021) (xy 370.766975 -253.187361)
			(xy 370.796351 -253.227794) (xy 370.819041 -253.272326) (xy 370.834485 -253.319858) (xy 370.842304 -253.369221)
			(xy 370.842794 -253.39421) (xy 370.842304 -253.419199) (xy 372.087376 -253.419199) (xy 372.087376 -253.369221)
			(xy 372.095195 -253.319858) (xy 372.110639 -253.272326) (xy 372.133329 -253.227794) (xy 372.162705 -253.187361)
			(xy 372.198045 -253.152021) (xy 372.238478 -253.122645) (xy 372.28301 -253.099955) (xy 372.330542 -253.084511)
			(xy 372.379905 -253.076692) (xy 372.429883 -253.076692) (xy 372.479246 -253.084511) (xy 372.526778 -253.099955)
			(xy 372.57131 -253.122645) (xy 372.611743 -253.152021) (xy 372.647083 -253.187361) (xy 372.676459 -253.227794)
			(xy 372.699149 -253.272326) (xy 372.714593 -253.319858) (xy 372.722412 -253.369221) (xy 372.722902 -253.39421)
			(xy 372.722412 -253.419199) (xy 373.96723 -253.419199) (xy 373.96723 -253.369221) (xy 373.975049 -253.319858)
			(xy 373.990493 -253.272326) (xy 374.013183 -253.227794) (xy 374.042559 -253.187361) (xy 374.077899 -253.152021)
			(xy 374.118332 -253.122645) (xy 374.162864 -253.099955) (xy 374.210396 -253.084511) (xy 374.259759 -253.076692)
			(xy 374.309737 -253.076692) (xy 374.3591 -253.084511) (xy 374.406632 -253.099955) (xy 374.451164 -253.122645)
			(xy 374.491597 -253.152021) (xy 374.526937 -253.187361) (xy 374.556313 -253.227794) (xy 374.579003 -253.272326)
			(xy 374.594447 -253.319858) (xy 374.602266 -253.369221) (xy 374.602756 -253.39421) (xy 375.848621 -253.39421)
			(xy 375.852716 -253.343482) (xy 375.864895 -253.294068) (xy 375.884843 -253.247248) (xy 375.912044 -253.204234)
			(xy 375.945792 -253.16614) (xy 375.985214 -253.133953) (xy 376.029288 -253.108507) (xy 376.076874 -253.09046)
			(xy 376.126738 -253.08028) (xy 376.17759 -253.078231) (xy 376.228111 -253.084365) (xy 376.276995 -253.098525)
			(xy 376.322974 -253.120342) (xy 376.364858 -253.149252) (xy 376.401562 -253.184507) (xy 376.432135 -253.225193)
			(xy 376.455786 -253.270256) (xy 376.471902 -253.31853) (xy 376.480066 -253.368764) (xy 376.480578 -253.39421)
			(xy 376.788675 -253.39421) (xy 376.79277 -253.343482) (xy 376.804949 -253.294068) (xy 376.824897 -253.247248)
			(xy 376.852098 -253.204234) (xy 376.885846 -253.16614) (xy 376.925268 -253.133953) (xy 376.969342 -253.108507)
			(xy 377.016928 -253.09046) (xy 377.066792 -253.08028) (xy 377.117644 -253.078231) (xy 377.168165 -253.084365)
			(xy 377.217049 -253.098525) (xy 377.263028 -253.120342) (xy 377.304912 -253.149252) (xy 377.341616 -253.184507)
			(xy 377.372189 -253.225193) (xy 377.39584 -253.270256) (xy 377.411956 -253.31853) (xy 377.42012 -253.368764)
			(xy 377.420632 -253.39421) (xy 377.420129 -253.419199) (xy 377.727192 -253.419199) (xy 377.727192 -253.369221)
			(xy 377.735011 -253.319858) (xy 377.750455 -253.272326) (xy 377.773145 -253.227794) (xy 377.802521 -253.187361)
			(xy 377.837861 -253.152021) (xy 377.878294 -253.122645) (xy 377.922826 -253.099955) (xy 377.970358 -253.084511)
			(xy 378.019721 -253.076692) (xy 378.069699 -253.076692) (xy 378.119062 -253.084511) (xy 378.166594 -253.099955)
			(xy 378.211126 -253.122645) (xy 378.251559 -253.152021) (xy 378.286899 -253.187361) (xy 378.316275 -253.227794)
			(xy 378.338965 -253.272326) (xy 378.354409 -253.319858) (xy 378.362228 -253.369221) (xy 378.362718 -253.39421)
			(xy 378.668529 -253.39421) (xy 378.672624 -253.343482) (xy 378.684803 -253.294068) (xy 378.704751 -253.247248)
			(xy 378.731952 -253.204234) (xy 378.7657 -253.16614) (xy 378.805122 -253.133953) (xy 378.849196 -253.108507)
			(xy 378.896782 -253.09046) (xy 378.946646 -253.08028) (xy 378.997498 -253.078231) (xy 379.048019 -253.084365)
			(xy 379.096903 -253.098525) (xy 379.142882 -253.120342) (xy 379.184766 -253.149252) (xy 379.22147 -253.184507)
			(xy 379.252043 -253.225193) (xy 379.275694 -253.270256) (xy 379.29181 -253.31853) (xy 379.299974 -253.368764)
			(xy 379.300486 -253.39421) (xy 379.299983 -253.419199) (xy 379.6073 -253.419199) (xy 379.6073 -253.369221)
			(xy 379.615119 -253.319858) (xy 379.630563 -253.272326) (xy 379.653253 -253.227794) (xy 379.682629 -253.187361)
			(xy 379.717969 -253.152021) (xy 379.758402 -253.122645) (xy 379.802934 -253.099955) (xy 379.850466 -253.084511)
			(xy 379.899829 -253.076692) (xy 379.949807 -253.076692) (xy 379.99917 -253.084511) (xy 380.046702 -253.099955)
			(xy 380.091234 -253.122645) (xy 380.131667 -253.152021) (xy 380.167007 -253.187361) (xy 380.196383 -253.227794)
			(xy 380.219073 -253.272326) (xy 380.234517 -253.319858) (xy 380.242336 -253.369221) (xy 380.242826 -253.39421)
			(xy 380.548637 -253.39421) (xy 380.552732 -253.343482) (xy 380.564911 -253.294068) (xy 380.584859 -253.247248)
			(xy 380.61206 -253.204234) (xy 380.645808 -253.16614) (xy 380.68523 -253.133953) (xy 380.729304 -253.108507)
			(xy 380.77689 -253.09046) (xy 380.826754 -253.08028) (xy 380.877606 -253.078231) (xy 380.928127 -253.084365)
			(xy 380.977011 -253.098525) (xy 381.02299 -253.120342) (xy 381.064874 -253.149252) (xy 381.101578 -253.184507)
			(xy 381.132151 -253.225193) (xy 381.155802 -253.270256) (xy 381.171918 -253.31853) (xy 381.180082 -253.368764)
			(xy 381.180594 -253.39421) (xy 381.180082 -253.419656) (xy 381.171918 -253.46989) (xy 381.155802 -253.518164)
			(xy 381.132151 -253.563227) (xy 381.101578 -253.603913) (xy 381.064874 -253.639168) (xy 381.02299 -253.668078)
			(xy 380.977011 -253.689895) (xy 380.928127 -253.704055) (xy 380.877606 -253.710189) (xy 380.826754 -253.70814)
			(xy 380.77689 -253.69796) (xy 380.729304 -253.679913) (xy 380.68523 -253.654467) (xy 380.645808 -253.62228)
			(xy 380.61206 -253.584186) (xy 380.584859 -253.541172) (xy 380.564911 -253.494352) (xy 380.552732 -253.444938)
			(xy 380.548637 -253.39421) (xy 380.242826 -253.39421) (xy 380.242336 -253.419199) (xy 380.234517 -253.468562)
			(xy 380.219073 -253.516094) (xy 380.196383 -253.560626) (xy 380.167007 -253.601059) (xy 380.131667 -253.636399)
			(xy 380.091234 -253.665775) (xy 380.046702 -253.688465) (xy 379.99917 -253.703909) (xy 379.949807 -253.711728)
			(xy 379.899829 -253.711728) (xy 379.850466 -253.703909) (xy 379.802934 -253.688465) (xy 379.758402 -253.665775)
			(xy 379.717969 -253.636399) (xy 379.682629 -253.601059) (xy 379.653253 -253.560626) (xy 379.630563 -253.516094)
			(xy 379.615119 -253.468562) (xy 379.6073 -253.419199) (xy 379.299983 -253.419199) (xy 379.299974 -253.419656)
			(xy 379.29181 -253.46989) (xy 379.275694 -253.518164) (xy 379.252043 -253.563227) (xy 379.22147 -253.603913)
			(xy 379.184766 -253.639168) (xy 379.142882 -253.668078) (xy 379.096903 -253.689895) (xy 379.048019 -253.704055)
			(xy 378.997498 -253.710189) (xy 378.946646 -253.70814) (xy 378.896782 -253.69796) (xy 378.849196 -253.679913)
			(xy 378.805122 -253.654467) (xy 378.7657 -253.62228) (xy 378.731952 -253.584186) (xy 378.704751 -253.541172)
			(xy 378.684803 -253.494352) (xy 378.672624 -253.444938) (xy 378.668529 -253.39421) (xy 378.362718 -253.39421)
			(xy 378.362228 -253.419199) (xy 378.354409 -253.468562) (xy 378.338965 -253.516094) (xy 378.316275 -253.560626)
			(xy 378.286899 -253.601059) (xy 378.251559 -253.636399) (xy 378.211126 -253.665775) (xy 378.166594 -253.688465)
			(xy 378.119062 -253.703909) (xy 378.069699 -253.711728) (xy 378.019721 -253.711728) (xy 377.970358 -253.703909)
			(xy 377.922826 -253.688465) (xy 377.878294 -253.665775) (xy 377.837861 -253.636399) (xy 377.802521 -253.601059)
			(xy 377.773145 -253.560626) (xy 377.750455 -253.516094) (xy 377.735011 -253.468562) (xy 377.727192 -253.419199)
			(xy 377.420129 -253.419199) (xy 377.42012 -253.419656) (xy 377.411956 -253.46989) (xy 377.39584 -253.518164)
			(xy 377.372189 -253.563227) (xy 377.341616 -253.603913) (xy 377.304912 -253.639168) (xy 377.263028 -253.668078)
			(xy 377.217049 -253.689895) (xy 377.168165 -253.704055) (xy 377.117644 -253.710189) (xy 377.066792 -253.70814)
			(xy 377.016928 -253.69796) (xy 376.969342 -253.679913) (xy 376.925268 -253.654467) (xy 376.885846 -253.62228)
			(xy 376.852098 -253.584186) (xy 376.824897 -253.541172) (xy 376.804949 -253.494352) (xy 376.79277 -253.444938)
			(xy 376.788675 -253.39421) (xy 376.480578 -253.39421) (xy 376.480066 -253.419656) (xy 376.471902 -253.46989)
			(xy 376.455786 -253.518164) (xy 376.432135 -253.563227) (xy 376.401562 -253.603913) (xy 376.364858 -253.639168)
			(xy 376.322974 -253.668078) (xy 376.276995 -253.689895) (xy 376.228111 -253.704055) (xy 376.17759 -253.710189)
			(xy 376.126738 -253.70814) (xy 376.076874 -253.69796) (xy 376.029288 -253.679913) (xy 375.985214 -253.654467)
			(xy 375.945792 -253.62228) (xy 375.912044 -253.584186) (xy 375.884843 -253.541172) (xy 375.864895 -253.494352)
			(xy 375.852716 -253.444938) (xy 375.848621 -253.39421) (xy 374.602756 -253.39421) (xy 374.602266 -253.419199)
			(xy 374.594447 -253.468562) (xy 374.579003 -253.516094) (xy 374.556313 -253.560626) (xy 374.526937 -253.601059)
			(xy 374.491597 -253.636399) (xy 374.451164 -253.665775) (xy 374.406632 -253.688465) (xy 374.3591 -253.703909)
			(xy 374.309737 -253.711728) (xy 374.259759 -253.711728) (xy 374.210396 -253.703909) (xy 374.162864 -253.688465)
			(xy 374.118332 -253.665775) (xy 374.077899 -253.636399) (xy 374.042559 -253.601059) (xy 374.013183 -253.560626)
			(xy 373.990493 -253.516094) (xy 373.975049 -253.468562) (xy 373.96723 -253.419199) (xy 372.722412 -253.419199)
			(xy 372.714593 -253.468562) (xy 372.699149 -253.516094) (xy 372.676459 -253.560626) (xy 372.647083 -253.601059)
			(xy 372.611743 -253.636399) (xy 372.57131 -253.665775) (xy 372.526778 -253.688465) (xy 372.479246 -253.703909)
			(xy 372.429883 -253.711728) (xy 372.379905 -253.711728) (xy 372.330542 -253.703909) (xy 372.28301 -253.688465)
			(xy 372.238478 -253.665775) (xy 372.198045 -253.636399) (xy 372.162705 -253.601059) (xy 372.133329 -253.560626)
			(xy 372.110639 -253.516094) (xy 372.095195 -253.468562) (xy 372.087376 -253.419199) (xy 370.842304 -253.419199)
			(xy 370.834485 -253.468562) (xy 370.819041 -253.516094) (xy 370.796351 -253.560626) (xy 370.766975 -253.601059)
			(xy 370.731635 -253.636399) (xy 370.691202 -253.665775) (xy 370.64667 -253.688465) (xy 370.599138 -253.703909)
			(xy 370.549775 -253.711728) (xy 370.499797 -253.711728) (xy 370.450434 -253.703909) (xy 370.402902 -253.688465)
			(xy 370.35837 -253.665775) (xy 370.317937 -253.636399) (xy 370.282597 -253.601059) (xy 370.253221 -253.560626)
			(xy 370.230531 -253.516094) (xy 370.215087 -253.468562) (xy 370.207268 -253.419199) (xy 367.22304 -253.419199)
			(xy 367.22304 -253.686056) (xy 367.222545 -253.69607) (xy 367.214897 -253.714578) (xy 367.200748 -253.72875)
			(xy 367.182253 -253.736429) (xy 367.17224 -253.736856) (xy 366.958372 -253.736856) (xy 366.958372 -253.746)
			(xy 366.95798 -253.756025) (xy 366.950305 -253.774547) (xy 366.936124 -253.78872) (xy 366.917597 -253.796385)
			(xy 366.907572 -253.7968) (xy 366.703356 -253.7968) (xy 366.682311 -253.796316) (xy 366.641036 -253.788067)
			(xy 366.602174 -253.771898) (xy 366.567231 -253.748433) (xy 366.537557 -253.718582) (xy 366.514301 -253.683498)
			(xy 366.498364 -253.644541) (xy 366.490362 -253.603218) (xy 366.489996 -253.58217) (xy 366.489996 -253.581916)
			(xy 366.489996 -253.553468) (xy 366.487456 -253.542292) (xy 366.484916 -253.537212) (xy 366.484408 -253.53645)
			(xy 366.473526 -253.513974) (xy 366.458145 -253.466468) (xy 366.450354 -253.417145) (xy 366.449864 -253.392178)
			(xy 365.31804 -253.392178) (xy 365.31804 -253.686056) (xy 365.317545 -253.69607) (xy 365.309897 -253.714578)
			(xy 365.295748 -253.72875) (xy 365.277253 -253.736429) (xy 365.26724 -253.736856) (xy 365.053372 -253.736856)
			(xy 365.053372 -253.746) (xy 365.05298 -253.756025) (xy 365.045305 -253.774547) (xy 365.031124 -253.78872)
			(xy 365.012597 -253.796385) (xy 365.002572 -253.7968) (xy 364.798356 -253.7968) (xy 364.777311 -253.796316)
			(xy 364.736036 -253.788067) (xy 364.697174 -253.771898) (xy 364.662231 -253.748433) (xy 364.632557 -253.718582)
			(xy 364.609301 -253.683498) (xy 364.593364 -253.644541) (xy 364.585362 -253.603218) (xy 364.584996 -253.58217)
			(xy 364.584996 -253.581916) (xy 364.584996 -253.489206) (xy 364.582964 -253.482348) (xy 364.576885 -253.460304)
			(xy 364.570387 -253.415042) (xy 364.57001 -253.392178) (xy 363.54004 -253.392178) (xy 363.54004 -253.686056)
			(xy 363.539545 -253.69607) (xy 363.531897 -253.714578) (xy 363.517748 -253.72875) (xy 363.499253 -253.736429)
			(xy 363.48924 -253.736856) (xy 363.275372 -253.736856) (xy 363.275372 -253.746) (xy 363.27498 -253.756025)
			(xy 363.267305 -253.774547) (xy 363.253124 -253.78872) (xy 363.234597 -253.796385) (xy 363.224572 -253.7968)
			(xy 363.020356 -253.7968) (xy 362.998825 -253.796297) (xy 362.956631 -253.787698) (xy 362.917016 -253.770817)
			(xy 362.881588 -253.746339) (xy 362.851785 -253.715257) (xy 362.828816 -253.678833) (xy 362.820712 -253.658878)
			(xy 362.81816 -253.652745) (xy 362.810452 -253.641937) (xy 362.805472 -253.637542) (xy 362.787723 -253.622348)
			(xy 362.756438 -253.587649) (xy 362.730563 -253.548747) (xy 362.710654 -253.506481) (xy 362.697141 -253.461757)
			(xy 362.690312 -253.415538) (xy 362.689902 -253.392178) (xy 361.63504 -253.392178) (xy 361.63504 -253.686056)
			(xy 361.634545 -253.69607) (xy 361.626897 -253.714578) (xy 361.612748 -253.72875) (xy 361.594253 -253.736429)
			(xy 361.58424 -253.736856) (xy 361.370372 -253.736856) (xy 361.370372 -253.746) (xy 361.36998 -253.756025)
			(xy 361.362305 -253.774547) (xy 361.348124 -253.78872) (xy 361.329597 -253.796385) (xy 361.319572 -253.7968)
			(xy 361.115356 -253.7968) (xy 361.09491 -253.796304) (xy 361.05476 -253.788547) (xy 361.016822 -253.773287)
			(xy 360.982484 -253.751082) (xy 360.953002 -253.722744) (xy 360.929455 -253.689312) (xy 360.912706 -253.652008)
			(xy 360.907584 -253.632208) (xy 360.905919 -253.625797) (xy 360.899747 -253.614084) (xy 360.895392 -253.609094)
			(xy 360.879421 -253.591338) (xy 360.852469 -253.551913) (xy 360.831708 -253.508905) (xy 360.817604 -253.463278)
			(xy 360.810473 -253.416057) (xy 360.810048 -253.392178) (xy 360.551125 -253.392178) (xy 360.554248 -253.432307)
			(xy 360.549948 -253.487526) (xy 360.537156 -253.541415) (xy 360.516179 -253.592675) (xy 360.487523 -253.640072)
			(xy 360.451877 -253.682463) (xy 360.431334 -253.701042) (xy 360.423714 -253.709424) (xy 360.411501 -253.725339)
			(xy 360.382187 -253.752716) (xy 360.348276 -253.774139) (xy 360.310962 -253.788854) (xy 360.271557 -253.796343)
			(xy 360.251502 -253.7968) (xy 359.99674 -253.7968) (xy 359.99674 -253.787656) (xy 359.996249 -253.77765)
			(xy 359.988582 -253.759165) (xy 359.974431 -253.745015) (xy 359.955946 -253.73735) (xy 359.94594 -253.736856)
			(xy 359.782364 -253.736856) (xy 359.772335 -253.736509) (xy 359.753809 -253.728819) (xy 359.739636 -253.714624)
			(xy 359.731975 -253.696086) (xy 359.731564 -253.686056) (xy 357.82504 -253.686056) (xy 357.824545 -253.69607)
			(xy 357.816897 -253.714578) (xy 357.802748 -253.72875) (xy 357.784253 -253.736429) (xy 357.77424 -253.736856)
			(xy 357.560372 -253.736856) (xy 357.560372 -253.746) (xy 357.55998 -253.756025) (xy 357.552305 -253.774547)
			(xy 357.538124 -253.78872) (xy 357.519597 -253.796385) (xy 357.509572 -253.7968) (xy 357.305356 -253.7968)
			(xy 357.284311 -253.796316) (xy 357.243036 -253.788067) (xy 357.204174 -253.771898) (xy 357.169231 -253.748433)
			(xy 357.139557 -253.718582) (xy 357.116301 -253.683498) (xy 357.100364 -253.644541) (xy 357.092362 -253.603218)
			(xy 357.091996 -253.58217) (xy 357.091996 -253.581916) (xy 357.091996 -253.562612) (xy 357.091831 -253.556747)
			(xy 357.089128 -253.545331) (xy 357.086662 -253.540006) (xy 357.086154 -253.53899) (xy 357.074806 -253.516199)
			(xy 357.05875 -253.467887) (xy 357.050603 -253.417633) (xy 357.050086 -253.392178) (xy 356.04704 -253.392178)
			(xy 356.04704 -253.686056) (xy 356.046545 -253.69607) (xy 356.038897 -253.714578) (xy 356.024748 -253.72875)
			(xy 356.006253 -253.736429) (xy 355.99624 -253.736856) (xy 355.782372 -253.736856) (xy 355.782372 -253.746)
			(xy 355.78198 -253.756025) (xy 355.774305 -253.774547) (xy 355.760124 -253.78872) (xy 355.741597 -253.796385)
			(xy 355.731572 -253.7968) (xy 355.527356 -253.7968) (xy 355.507912 -253.796409) (xy 355.469661 -253.789404)
			(xy 355.433315 -253.77558) (xy 355.400078 -253.755394) (xy 355.371051 -253.729516) (xy 355.347199 -253.698804)
			(xy 355.337872 -253.681738) (xy 355.334588 -253.675791) (xy 355.325457 -253.665742) (xy 355.319838 -253.661926)
			(xy 355.297331 -253.647242) (xy 355.257128 -253.611589) (xy 355.223498 -253.569679) (xy 355.197399 -253.522708)
			(xy 355.179577 -253.472015) (xy 355.170538 -253.419045) (xy 355.169978 -253.392178) (xy 354.14204 -253.392178)
			(xy 354.14204 -253.686056) (xy 354.141545 -253.69607) (xy 354.133897 -253.714578) (xy 354.119748 -253.72875)
			(xy 354.101253 -253.736429) (xy 354.09124 -253.736856) (xy 353.877372 -253.736856) (xy 353.877372 -253.746)
			(xy 353.87698 -253.756025) (xy 353.869305 -253.774547) (xy 353.855124 -253.78872) (xy 353.836597 -253.796385)
			(xy 353.826572 -253.7968) (xy 353.622356 -253.7968) (xy 353.601027 -253.796262) (xy 353.559222 -253.787782)
			(xy 353.519932 -253.77117) (xy 353.484724 -253.747085) (xy 353.455001 -253.716489) (xy 353.431945 -253.680599)
			(xy 353.423728 -253.66091) (xy 353.421126 -253.654811) (xy 353.413283 -253.644126) (xy 353.408234 -253.639828)
			(xy 353.39009 -253.624635) (xy 353.358073 -253.589788) (xy 353.33157 -253.550584) (xy 353.311164 -253.507888)
			(xy 353.297306 -253.46264) (xy 353.290302 -253.415839) (xy 353.28987 -253.392178) (xy 352.23704 -253.392178)
			(xy 352.23704 -253.686056) (xy 352.236545 -253.69607) (xy 352.228897 -253.714578) (xy 352.214748 -253.72875)
			(xy 352.196253 -253.736429) (xy 352.18624 -253.736856) (xy 351.972372 -253.736856) (xy 351.972372 -253.746)
			(xy 351.97198 -253.756025) (xy 351.964305 -253.774547) (xy 351.950124 -253.78872) (xy 351.931597 -253.796385)
			(xy 351.921572 -253.7968) (xy 351.717356 -253.7968) (xy 351.697091 -253.796335) (xy 351.657293 -253.788675)
			(xy 351.619656 -253.773639) (xy 351.585535 -253.751767) (xy 351.556157 -253.723847) (xy 351.532578 -253.690882)
			(xy 351.515647 -253.654059) (xy 351.510346 -253.634494) (xy 351.508598 -253.628078) (xy 351.502292 -253.616374)
			(xy 351.4979 -253.61138) (xy 351.481507 -253.593561) (xy 351.453793 -253.55386) (xy 351.432416 -253.510418)
			(xy 351.41787 -253.464238) (xy 351.41049 -253.416386) (xy 351.410016 -253.392178) (xy 350.169186 -253.392178)
			(xy 350.169226 -253.39421) (xy 350.168735 -253.419199) (xy 350.160915 -253.468562) (xy 350.145471 -253.516094)
			(xy 350.122781 -253.560625) (xy 350.093404 -253.601059) (xy 350.058065 -253.636399) (xy 350.017632 -253.665777)
			(xy 349.973102 -253.688468) (xy 349.92557 -253.703914) (xy 349.876207 -253.711734) (xy 349.851218 -253.712218)
			(xy 349.825698 -253.711713) (xy 349.775313 -253.703567) (xy 349.726875 -253.68748) (xy 349.681627 -253.663866)
			(xy 349.64073 -253.63333) (xy 349.605233 -253.596656) (xy 349.576047 -253.554785) (xy 349.553921 -253.50879)
			(xy 349.539423 -253.459854) (xy 349.53575 -253.434596) (xy 349.53575 -253.434342) (xy 349.534226 -253.424436)
			(xy 349.532956 -253.39421) (xy 349.533289 -253.373525) (xy 349.538642 -253.332501) (xy 349.543624 -253.312422)
			(xy 349.545402 -253.306072) (xy 349.545402 -253.305818) (xy 349.548704 -253.29388) (xy 349.546926 -253.283974)
			(xy 349.54585 -253.278529) (xy 349.541628 -253.268268) (xy 349.538544 -253.263654) (xy 349.487236 -253.195582)
			(xy 349.479836 -253.187818) (xy 349.460356 -253.178892) (xy 349.449644 -253.17831) (xy 348.828106 -253.17831)
			(xy 348.818271 -253.178851) (xy 348.800117 -253.186445) (xy 348.7928 -253.193042) (xy 348.695264 -253.290578)
			(xy 348.688548 -253.297815) (xy 348.680945 -253.31602) (xy 348.680532 -253.325884) (xy 348.680532 -253.71298)
			(xy 348.68106 -253.722802) (xy 348.688654 -253.740927) (xy 348.702583 -253.754787) (xy 348.720745 -253.76229)
			(xy 348.73057 -253.762764) (xy 349.113856 -253.762764) (xy 349.124239 -253.762176) (xy 349.143239 -253.75377)
			(xy 349.150686 -253.746508) (xy 349.156113 -253.740085) (xy 349.16274 -253.724642) (xy 349.16364 -253.716282)
			(xy 349.16364 -253.70282) (xy 349.417894 -253.70282) (xy 349.439647 -253.703296) (xy 349.482273 -253.711994)
			(xy 349.522267 -253.729116) (xy 349.557983 -253.753956) (xy 349.573342 -253.769368) (xy 349.587082 -253.784485)
			(xy 349.609081 -253.818901) (xy 349.62412 -253.856878) (xy 349.631648 -253.897024) (xy 349.632016 -253.91745)
			(xy 349.632016 -253.992888) (xy 349.632085 -253.996896) (xy 349.633362 -254.004809) (xy 349.634556 -254.008636)
			(xy 349.636334 -254.014224) (xy 349.64116 -254.021336) (xy 349.654826 -254.041522) (xy 349.676468 -254.0852)
			(xy 349.691188 -254.131671) (xy 349.698642 -254.179843) (xy 349.699072 -254.204216) (xy 349.698606 -254.229205)
			(xy 349.690785 -254.278568) (xy 349.675337 -254.3261) (xy 349.652644 -254.37063) (xy 349.623265 -254.411061)
			(xy 349.587921 -254.446398) (xy 349.547485 -254.475772) (xy 349.502952 -254.498457) (xy 349.455418 -254.513897)
			(xy 349.406053 -254.52171) (xy 349.381064 -254.522224) (xy 349.38081 -254.522224) (xy 349.356862 -254.521797)
			(xy 349.309507 -254.514625) (xy 349.263764 -254.500425) (xy 349.220671 -254.479521) (xy 349.181204 -254.452386)
			(xy 349.146257 -254.419634) (xy 349.131128 -254.401066) (xy 349.127572 -254.396494) (xy 349.123254 -254.392938)
			(xy 349.114364 -254.387096) (xy 349.095822 -254.377444) (xy 349.091789 -254.375525) (xy 349.083228 -254.372979)
			(xy 349.078804 -254.372364) (xy 349.072454 -254.371856) (xy 348.74962 -254.371856) (xy 348.745302 -254.37211)
			(xy 348.740415 -254.372659) (xy 348.730958 -254.375353) (xy 348.726506 -254.377444) (xy 348.711266 -254.385318)
			(xy 348.705932 -254.388366) (xy 348.702884 -254.390652) (xy 348.693486 -254.40005) (xy 348.689676 -254.40513)
			(xy 348.683326 -254.42291) (xy 348.680786 -254.43434) (xy 348.680532 -254.43942) (xy 348.680532 -255.014222)
			(xy 349.53321 -255.014222) (xy 349.533822 -254.985989) (xy 349.543765 -254.930405) (xy 349.563361 -254.877448)
			(xy 349.591995 -254.828781) (xy 349.609918 -254.806958) (xy 349.61703 -254.79629) (xy 349.623634 -254.783844)
			(xy 349.750634 -254.563626) (xy 349.758762 -254.568198) (xy 349.767652 -254.572822) (xy 349.787499 -254.57546)
			(xy 349.806843 -254.570295) (xy 349.822733 -254.558115) (xy 349.828104 -254.549656) (xy 349.909892 -254.407924)
			(xy 349.915236 -254.399442) (xy 349.931138 -254.387257) (xy 349.950495 -254.382088) (xy 349.970355 -254.384725)
			(xy 349.979234 -254.389382) (xy 350.419162 -254.643382) (xy 350.427634 -254.648739) (xy 350.439823 -254.664636)
			(xy 350.444994 -254.683988) (xy 350.442597 -254.702056) (xy 359.731564 -254.702056) (xy 359.731564 -254.194564)
			(xy 359.732058 -254.184558) (xy 359.739722 -254.166073) (xy 359.753873 -254.151922) (xy 359.772358 -254.144258)
			(xy 359.782364 -254.143764) (xy 359.99674 -254.143764) (xy 359.99674 -254.13462) (xy 359.997137 -254.124595)
			(xy 360.004808 -254.106071) (xy 360.018988 -254.091897) (xy 360.037515 -254.084233) (xy 360.04754 -254.08382)
			(xy 360.251502 -254.08382) (xy 360.27156 -254.084229) (xy 360.310971 -254.091723) (xy 360.348288 -254.106446)
			(xy 360.382197 -254.127882) (xy 360.411506 -254.155274) (xy 360.423714 -254.171196) (xy 360.431334 -254.179578)
			(xy 360.451886 -254.198146) (xy 360.45699 -254.204216) (xy 368.796824 -254.204216) (xy 368.797273 -254.180406)
			(xy 368.804364 -254.133318) (xy 368.818405 -254.087815) (xy 368.839081 -254.044919) (xy 368.865928 -254.005589)
			(xy 368.898346 -253.970708) (xy 368.916712 -253.95555) (xy 368.920515 -253.952309) (xy 368.926911 -253.944636)
			(xy 368.929412 -253.94031) (xy 368.938974 -253.923889) (xy 368.962891 -253.89437) (xy 368.991656 -253.869551)
			(xy 369.024359 -253.850214) (xy 369.059969 -253.83697) (xy 369.09736 -253.830238) (xy 369.116356 -253.82982)
			(xy 369.371372 -253.82982) (xy 369.371372 -253.838964) (xy 369.371848 -253.84898) (xy 369.379501 -253.86749)
			(xy 369.393656 -253.881663) (xy 369.412157 -253.889339) (xy 369.422172 -253.889764) (xy 369.58524 -253.889764)
			(xy 369.595246 -253.890254) (xy 369.613732 -253.89792) (xy 369.627882 -253.912072) (xy 369.635546 -253.930558)
			(xy 369.63604 -253.940564) (xy 369.63604 -254.204216) (xy 370.676678 -254.204216) (xy 370.677111 -254.180436)
			(xy 370.684212 -254.133408) (xy 370.698229 -254.087959) (xy 370.718849 -254.045101) (xy 370.745614 -254.005786)
			(xy 370.777929 -253.970889) (xy 370.815074 -253.941186) (xy 370.835428 -253.92888) (xy 370.839731 -253.926189)
			(xy 370.847284 -253.919413) (xy 370.850414 -253.915418) (xy 370.862648 -253.899796) (xy 370.891877 -253.872965)
			(xy 370.925555 -253.85199) (xy 370.962525 -253.837589) (xy 371.001518 -253.830259) (xy 371.021356 -253.82982)
			(xy 371.276372 -253.82982) (xy 371.276372 -253.838964) (xy 371.276848 -253.84898) (xy 371.284501 -253.86749)
			(xy 371.298656 -253.881663) (xy 371.317157 -253.889339) (xy 371.327172 -253.889764) (xy 371.49024 -253.889764)
			(xy 371.500246 -253.890254) (xy 371.518732 -253.89792) (xy 371.532882 -253.912072) (xy 371.540546 -253.930558)
			(xy 371.54104 -253.940564) (xy 371.54104 -254.204724) (xy 372.556786 -254.204724) (xy 372.556786 -254.204216)
			(xy 372.557169 -254.182937) (xy 372.562897 -254.140766) (xy 372.574187 -254.099732) (xy 372.582186 -254.08001)
			(xy 372.585996 -254.070358) (xy 372.585996 -254.04445) (xy 372.586388 -254.023403) (xy 372.594386 -253.982082)
			(xy 372.61032 -253.943127) (xy 372.633571 -253.908045) (xy 372.663242 -253.878194) (xy 372.698182 -253.85473)
			(xy 372.73704 -253.838561) (xy 372.778312 -253.830312) (xy 372.799356 -253.82982) (xy 373.054372 -253.82982)
			(xy 373.054372 -253.838964) (xy 373.054848 -253.84898) (xy 373.062501 -253.86749) (xy 373.076656 -253.881663)
			(xy 373.095157 -253.889339) (xy 373.105172 -253.889764) (xy 373.26824 -253.889764) (xy 373.278246 -253.890254)
			(xy 373.296732 -253.89792) (xy 373.310882 -253.912072) (xy 373.318546 -253.930558) (xy 373.31904 -253.940564)
			(xy 373.31904 -254.229205) (xy 374.437384 -254.229205) (xy 374.437384 -254.179227) (xy 374.445203 -254.129864)
			(xy 374.460647 -254.082332) (xy 374.483337 -254.0378) (xy 374.512713 -253.997367) (xy 374.548053 -253.962027)
			(xy 374.588486 -253.932651) (xy 374.633018 -253.909961) (xy 374.68055 -253.894517) (xy 374.729913 -253.886698)
			(xy 374.779891 -253.886698) (xy 374.829254 -253.894517) (xy 374.876786 -253.909961) (xy 374.921318 -253.932651)
			(xy 374.961751 -253.962027) (xy 374.997091 -253.997367) (xy 375.026467 -254.0378) (xy 375.049157 -254.082332)
			(xy 375.064601 -254.129864) (xy 375.07242 -254.179227) (xy 375.07291 -254.204216) (xy 375.378467 -254.204216)
			(xy 375.382562 -254.153488) (xy 375.394741 -254.104074) (xy 375.414689 -254.057254) (xy 375.44189 -254.01424)
			(xy 375.475638 -253.976146) (xy 375.51506 -253.943959) (xy 375.559134 -253.918513) (xy 375.60672 -253.900466)
			(xy 375.656584 -253.890286) (xy 375.707436 -253.888237) (xy 375.757957 -253.894371) (xy 375.806841 -253.908531)
			(xy 375.85282 -253.930348) (xy 375.894704 -253.959258) (xy 375.931408 -253.994513) (xy 375.961981 -254.035199)
			(xy 375.985632 -254.080262) (xy 376.001748 -254.128536) (xy 376.009912 -254.17877) (xy 376.010424 -254.204216)
			(xy 376.009921 -254.229205) (xy 376.317238 -254.229205) (xy 376.317238 -254.179227) (xy 376.325057 -254.129864)
			(xy 376.340501 -254.082332) (xy 376.363191 -254.0378) (xy 376.392567 -253.997367) (xy 376.427907 -253.962027)
			(xy 376.46834 -253.932651) (xy 376.512872 -253.909961) (xy 376.560404 -253.894517) (xy 376.609767 -253.886698)
			(xy 376.659745 -253.886698) (xy 376.709108 -253.894517) (xy 376.75664 -253.909961) (xy 376.801172 -253.932651)
			(xy 376.841605 -253.962027) (xy 376.876945 -253.997367) (xy 376.906321 -254.0378) (xy 376.929011 -254.082332)
			(xy 376.944455 -254.129864) (xy 376.952274 -254.179227) (xy 376.952764 -254.204216) (xy 377.258575 -254.204216)
			(xy 377.26267 -254.153488) (xy 377.274849 -254.104074) (xy 377.294797 -254.057254) (xy 377.321998 -254.01424)
			(xy 377.355746 -253.976146) (xy 377.395168 -253.943959) (xy 377.439242 -253.918513) (xy 377.486828 -253.900466)
			(xy 377.536692 -253.890286) (xy 377.587544 -253.888237) (xy 377.638065 -253.894371) (xy 377.686949 -253.908531)
			(xy 377.732928 -253.930348) (xy 377.774812 -253.959258) (xy 377.811516 -253.994513) (xy 377.842089 -254.035199)
			(xy 377.86574 -254.080262) (xy 377.881856 -254.128536) (xy 377.89002 -254.17877) (xy 377.890532 -254.204216)
			(xy 379.138683 -254.204216) (xy 379.142778 -254.153488) (xy 379.154957 -254.104074) (xy 379.174905 -254.057254)
			(xy 379.202106 -254.01424) (xy 379.235854 -253.976146) (xy 379.275276 -253.943959) (xy 379.31935 -253.918513)
			(xy 379.366936 -253.900466) (xy 379.4168 -253.890286) (xy 379.467652 -253.888237) (xy 379.518173 -253.894371)
			(xy 379.567057 -253.908531) (xy 379.613036 -253.930348) (xy 379.65492 -253.959258) (xy 379.691624 -253.994513)
			(xy 379.722197 -254.035199) (xy 379.745848 -254.080262) (xy 379.761964 -254.128536) (xy 379.770128 -254.17877)
			(xy 379.77064 -254.204216) (xy 380.078483 -254.204216) (xy 380.082578 -254.153488) (xy 380.094757 -254.104074)
			(xy 380.114705 -254.057254) (xy 380.141906 -254.01424) (xy 380.175654 -253.976146) (xy 380.215076 -253.943959)
			(xy 380.25915 -253.918513) (xy 380.306736 -253.900466) (xy 380.3566 -253.890286) (xy 380.407452 -253.888237)
			(xy 380.457973 -253.894371) (xy 380.506857 -253.908531) (xy 380.552836 -253.930348) (xy 380.59472 -253.959258)
			(xy 380.631424 -253.994513) (xy 380.661997 -254.035199) (xy 380.685648 -254.080262) (xy 380.701764 -254.128536)
			(xy 380.709928 -254.17877) (xy 380.71044 -254.204216) (xy 380.709928 -254.229662) (xy 380.701764 -254.279896)
			(xy 380.685648 -254.32817) (xy 380.661997 -254.373233) (xy 380.631424 -254.413919) (xy 380.59472 -254.449174)
			(xy 380.552836 -254.478084) (xy 380.506857 -254.499901) (xy 380.457973 -254.514061) (xy 380.407452 -254.520195)
			(xy 380.3566 -254.518146) (xy 380.306736 -254.507966) (xy 380.25915 -254.489919) (xy 380.215076 -254.464473)
			(xy 380.175654 -254.432286) (xy 380.141906 -254.394192) (xy 380.114705 -254.351178) (xy 380.094757 -254.304358)
			(xy 380.082578 -254.254944) (xy 380.078483 -254.204216) (xy 379.77064 -254.204216) (xy 379.770128 -254.229662)
			(xy 379.761964 -254.279896) (xy 379.745848 -254.32817) (xy 379.722197 -254.373233) (xy 379.691624 -254.413919)
			(xy 379.65492 -254.449174) (xy 379.613036 -254.478084) (xy 379.567057 -254.499901) (xy 379.518173 -254.514061)
			(xy 379.467652 -254.520195) (xy 379.4168 -254.518146) (xy 379.366936 -254.507966) (xy 379.31935 -254.489919)
			(xy 379.275276 -254.464473) (xy 379.235854 -254.432286) (xy 379.202106 -254.394192) (xy 379.174905 -254.351178)
			(xy 379.154957 -254.304358) (xy 379.142778 -254.254944) (xy 379.138683 -254.204216) (xy 377.890532 -254.204216)
			(xy 377.89002 -254.229662) (xy 377.881856 -254.279896) (xy 377.86574 -254.32817) (xy 377.842089 -254.373233)
			(xy 377.811516 -254.413919) (xy 377.774812 -254.449174) (xy 377.732928 -254.478084) (xy 377.686949 -254.499901)
			(xy 377.638065 -254.514061) (xy 377.587544 -254.520195) (xy 377.536692 -254.518146) (xy 377.486828 -254.507966)
			(xy 377.439242 -254.489919) (xy 377.395168 -254.464473) (xy 377.355746 -254.432286) (xy 377.321998 -254.394192)
			(xy 377.294797 -254.351178) (xy 377.274849 -254.304358) (xy 377.26267 -254.254944) (xy 377.258575 -254.204216)
			(xy 376.952764 -254.204216) (xy 376.952274 -254.229205) (xy 376.944455 -254.278568) (xy 376.929011 -254.3261)
			(xy 376.906321 -254.370632) (xy 376.876945 -254.411065) (xy 376.841605 -254.446405) (xy 376.801172 -254.475781)
			(xy 376.75664 -254.498471) (xy 376.709108 -254.513915) (xy 376.659745 -254.521734) (xy 376.609767 -254.521734)
			(xy 376.560404 -254.513915) (xy 376.512872 -254.498471) (xy 376.46834 -254.475781) (xy 376.427907 -254.446405)
			(xy 376.392567 -254.411065) (xy 376.363191 -254.370632) (xy 376.340501 -254.3261) (xy 376.325057 -254.278568)
			(xy 376.317238 -254.229205) (xy 376.009921 -254.229205) (xy 376.009912 -254.229662) (xy 376.001748 -254.279896)
			(xy 375.985632 -254.32817) (xy 375.961981 -254.373233) (xy 375.931408 -254.413919) (xy 375.894704 -254.449174)
			(xy 375.85282 -254.478084) (xy 375.806841 -254.499901) (xy 375.757957 -254.514061) (xy 375.707436 -254.520195)
			(xy 375.656584 -254.518146) (xy 375.60672 -254.507966) (xy 375.559134 -254.489919) (xy 375.51506 -254.464473)
			(xy 375.475638 -254.432286) (xy 375.44189 -254.394192) (xy 375.414689 -254.351178) (xy 375.394741 -254.304358)
			(xy 375.382562 -254.254944) (xy 375.378467 -254.204216) (xy 375.07291 -254.204216) (xy 375.07242 -254.229205)
			(xy 375.064601 -254.278568) (xy 375.049157 -254.3261) (xy 375.026467 -254.370632) (xy 374.997091 -254.411065)
			(xy 374.961751 -254.446405) (xy 374.921318 -254.475781) (xy 374.876786 -254.498471) (xy 374.829254 -254.513915)
			(xy 374.779891 -254.521734) (xy 374.729913 -254.521734) (xy 374.68055 -254.513915) (xy 374.633018 -254.498471)
			(xy 374.588486 -254.475781) (xy 374.548053 -254.446405) (xy 374.512713 -254.411065) (xy 374.483337 -254.370632)
			(xy 374.460647 -254.3261) (xy 374.445203 -254.278568) (xy 374.437384 -254.229205) (xy 373.31904 -254.229205)
			(xy 373.31904 -254.448056) (xy 373.318545 -254.45807) (xy 373.310897 -254.476578) (xy 373.296748 -254.49075)
			(xy 373.278253 -254.498429) (xy 373.26824 -254.498856) (xy 373.054372 -254.498856) (xy 373.054372 -254.508)
			(xy 373.05398 -254.518025) (xy 373.046305 -254.536547) (xy 373.032124 -254.55072) (xy 373.013597 -254.558385)
			(xy 373.003572 -254.5588) (xy 372.799356 -254.5588) (xy 372.778298 -254.558225) (xy 372.736997 -254.549983)
			(xy 372.698112 -254.533806) (xy 372.663151 -254.510322) (xy 372.63347 -254.480442) (xy 372.610221 -254.445325)
			(xy 372.594305 -254.406332) (xy 372.586339 -254.364977) (xy 372.585996 -254.343916) (xy 372.585996 -254.337566)
			(xy 372.576782 -254.316645) (xy 372.563783 -254.272818) (xy 372.557199 -254.227581) (xy 372.556786 -254.204724)
			(xy 371.54104 -254.204724) (xy 371.54104 -254.448056) (xy 371.540545 -254.45807) (xy 371.532897 -254.476578)
			(xy 371.518748 -254.49075) (xy 371.500253 -254.498429) (xy 371.49024 -254.498856) (xy 371.276372 -254.498856)
			(xy 371.276372 -254.508) (xy 371.27598 -254.518025) (xy 371.268305 -254.536547) (xy 371.254124 -254.55072)
			(xy 371.235597 -254.558385) (xy 371.225572 -254.5588) (xy 371.021356 -254.5588) (xy 371.001623 -254.558376)
			(xy 370.962825 -254.551158) (xy 370.926018 -254.536921) (xy 370.892462 -254.516152) (xy 370.877592 -254.503174)
			(xy 370.87456 -254.500483) (xy 370.867794 -254.496019) (xy 370.86413 -254.494284) (xy 370.840554 -254.48309)
			(xy 370.797106 -254.454183) (xy 370.75896 -254.41857) (xy 370.727141 -254.377208) (xy 370.702501 -254.331205)
			(xy 370.685703 -254.281797) (xy 370.677197 -254.230309) (xy 370.676678 -254.204216) (xy 369.63604 -254.204216)
			(xy 369.63604 -254.448056) (xy 369.635545 -254.45807) (xy 369.627897 -254.476578) (xy 369.613748 -254.49075)
			(xy 369.595253 -254.498429) (xy 369.58524 -254.498856) (xy 369.371372 -254.498856) (xy 369.371372 -254.508)
			(xy 369.37098 -254.518025) (xy 369.363305 -254.536547) (xy 369.349124 -254.55072) (xy 369.330597 -254.558385)
			(xy 369.320572 -254.5588) (xy 369.116356 -254.5588) (xy 369.097379 -254.558364) (xy 369.060031 -254.551606)
			(xy 369.024461 -254.538364) (xy 368.991786 -254.519052) (xy 368.963032 -254.494277) (xy 368.950748 -254.479806)
			(xy 368.948246 -254.476836) (xy 368.94251 -254.471603) (xy 368.939318 -254.469392) (xy 368.917816 -254.454505)
			(xy 368.879514 -254.4189) (xy 368.847555 -254.377509) (xy 368.8228 -254.331445) (xy 368.805914 -254.281952)
			(xy 368.797355 -254.230363) (xy 368.796824 -254.204216) (xy 360.45699 -254.204216) (xy 360.48753 -254.240539)
			(xy 360.516185 -254.287937) (xy 360.53716 -254.339198) (xy 360.549951 -254.393087) (xy 360.554248 -254.448307)
			(xy 360.549948 -254.503526) (xy 360.537156 -254.557415) (xy 360.516179 -254.608675) (xy 360.487523 -254.656072)
			(xy 360.451877 -254.698463) (xy 360.431334 -254.717042) (xy 360.423714 -254.725424) (xy 360.411501 -254.741339)
			(xy 360.382187 -254.768716) (xy 360.348276 -254.790139) (xy 360.310962 -254.804854) (xy 360.271557 -254.812343)
			(xy 360.251502 -254.8128) (xy 359.99674 -254.8128) (xy 359.99674 -254.803656) (xy 359.996249 -254.79365)
			(xy 359.988582 -254.775165) (xy 359.974431 -254.761015) (xy 359.955946 -254.75335) (xy 359.94594 -254.752856)
			(xy 359.782364 -254.752856) (xy 359.772335 -254.752509) (xy 359.753809 -254.744819) (xy 359.739636 -254.730624)
			(xy 359.731975 -254.712086) (xy 359.731564 -254.702056) (xy 350.442597 -254.702056) (xy 350.442359 -254.703846)
			(xy 350.437704 -254.712724) (xy 350.330516 -254.89789) (xy 350.33839 -254.902462) (xy 350.346931 -254.907754)
			(xy 350.35924 -254.923618) (xy 350.364487 -254.943001) (xy 350.36186 -254.962908) (xy 350.357186 -254.971804)
			(xy 350.318253 -255.039211) (xy 370.207268 -255.039211) (xy 370.207268 -254.989233) (xy 370.215087 -254.93987)
			(xy 370.230531 -254.892338) (xy 370.253221 -254.847806) (xy 370.282597 -254.807373) (xy 370.317937 -254.772033)
			(xy 370.35837 -254.742657) (xy 370.402902 -254.719967) (xy 370.450434 -254.704523) (xy 370.499797 -254.696704)
			(xy 370.549775 -254.696704) (xy 370.599138 -254.704523) (xy 370.64667 -254.719967) (xy 370.691202 -254.742657)
			(xy 370.731635 -254.772033) (xy 370.766975 -254.807373) (xy 370.796351 -254.847806) (xy 370.819041 -254.892338)
			(xy 370.834485 -254.93987) (xy 370.842304 -254.989233) (xy 370.842794 -255.014222) (xy 370.842304 -255.039211)
			(xy 372.087376 -255.039211) (xy 372.087376 -254.989233) (xy 372.095195 -254.93987) (xy 372.110639 -254.892338)
			(xy 372.133329 -254.847806) (xy 372.162705 -254.807373) (xy 372.198045 -254.772033) (xy 372.238478 -254.742657)
			(xy 372.28301 -254.719967) (xy 372.330542 -254.704523) (xy 372.379905 -254.696704) (xy 372.429883 -254.696704)
			(xy 372.479246 -254.704523) (xy 372.526778 -254.719967) (xy 372.57131 -254.742657) (xy 372.611743 -254.772033)
			(xy 372.647083 -254.807373) (xy 372.676459 -254.847806) (xy 372.699149 -254.892338) (xy 372.714593 -254.93987)
			(xy 372.722412 -254.989233) (xy 372.722902 -255.014222) (xy 372.722412 -255.039211) (xy 373.96723 -255.039211)
			(xy 373.96723 -254.989233) (xy 373.975049 -254.93987) (xy 373.990493 -254.892338) (xy 374.013183 -254.847806)
			(xy 374.042559 -254.807373) (xy 374.077899 -254.772033) (xy 374.118332 -254.742657) (xy 374.162864 -254.719967)
			(xy 374.210396 -254.704523) (xy 374.259759 -254.696704) (xy 374.309737 -254.696704) (xy 374.3591 -254.704523)
			(xy 374.406632 -254.719967) (xy 374.451164 -254.742657) (xy 374.491597 -254.772033) (xy 374.526937 -254.807373)
			(xy 374.556313 -254.847806) (xy 374.579003 -254.892338) (xy 374.594447 -254.93987) (xy 374.602266 -254.989233)
			(xy 374.602756 -255.014222) (xy 375.848621 -255.014222) (xy 375.852716 -254.963494) (xy 375.864895 -254.91408)
			(xy 375.884843 -254.86726) (xy 375.912044 -254.824246) (xy 375.945792 -254.786152) (xy 375.985214 -254.753965)
			(xy 376.029288 -254.728519) (xy 376.076874 -254.710472) (xy 376.126738 -254.700292) (xy 376.17759 -254.698243)
			(xy 376.228111 -254.704377) (xy 376.276995 -254.718537) (xy 376.322974 -254.740354) (xy 376.364858 -254.769264)
			(xy 376.401562 -254.804519) (xy 376.432135 -254.845205) (xy 376.455786 -254.890268) (xy 376.471902 -254.938542)
			(xy 376.480066 -254.988776) (xy 376.480578 -255.014222) (xy 376.788675 -255.014222) (xy 376.79277 -254.963494)
			(xy 376.804949 -254.91408) (xy 376.824897 -254.86726) (xy 376.852098 -254.824246) (xy 376.885846 -254.786152)
			(xy 376.925268 -254.753965) (xy 376.969342 -254.728519) (xy 377.016928 -254.710472) (xy 377.066792 -254.700292)
			(xy 377.117644 -254.698243) (xy 377.168165 -254.704377) (xy 377.217049 -254.718537) (xy 377.263028 -254.740354)
			(xy 377.304912 -254.769264) (xy 377.341616 -254.804519) (xy 377.372189 -254.845205) (xy 377.39584 -254.890268)
			(xy 377.411956 -254.938542) (xy 377.42012 -254.988776) (xy 377.420632 -255.014222) (xy 377.420129 -255.039211)
			(xy 377.727192 -255.039211) (xy 377.727192 -254.989233) (xy 377.735011 -254.93987) (xy 377.750455 -254.892338)
			(xy 377.773145 -254.847806) (xy 377.802521 -254.807373) (xy 377.837861 -254.772033) (xy 377.878294 -254.742657)
			(xy 377.922826 -254.719967) (xy 377.970358 -254.704523) (xy 378.019721 -254.696704) (xy 378.069699 -254.696704)
			(xy 378.119062 -254.704523) (xy 378.166594 -254.719967) (xy 378.211126 -254.742657) (xy 378.251559 -254.772033)
			(xy 378.286899 -254.807373) (xy 378.316275 -254.847806) (xy 378.338965 -254.892338) (xy 378.354409 -254.93987)
			(xy 378.362228 -254.989233) (xy 378.362718 -255.014222) (xy 378.668529 -255.014222) (xy 378.672624 -254.963494)
			(xy 378.684803 -254.91408) (xy 378.704751 -254.86726) (xy 378.731952 -254.824246) (xy 378.7657 -254.786152)
			(xy 378.805122 -254.753965) (xy 378.849196 -254.728519) (xy 378.896782 -254.710472) (xy 378.946646 -254.700292)
			(xy 378.997498 -254.698243) (xy 379.048019 -254.704377) (xy 379.096903 -254.718537) (xy 379.142882 -254.740354)
			(xy 379.184766 -254.769264) (xy 379.22147 -254.804519) (xy 379.252043 -254.845205) (xy 379.275694 -254.890268)
			(xy 379.29181 -254.938542) (xy 379.299974 -254.988776) (xy 379.300486 -255.014222) (xy 379.299983 -255.039211)
			(xy 379.6073 -255.039211) (xy 379.6073 -254.989233) (xy 379.615119 -254.93987) (xy 379.630563 -254.892338)
			(xy 379.653253 -254.847806) (xy 379.682629 -254.807373) (xy 379.717969 -254.772033) (xy 379.758402 -254.742657)
			(xy 379.802934 -254.719967) (xy 379.850466 -254.704523) (xy 379.899829 -254.696704) (xy 379.949807 -254.696704)
			(xy 379.99917 -254.704523) (xy 380.046702 -254.719967) (xy 380.091234 -254.742657) (xy 380.131667 -254.772033)
			(xy 380.167007 -254.807373) (xy 380.196383 -254.847806) (xy 380.219073 -254.892338) (xy 380.234517 -254.93987)
			(xy 380.242336 -254.989233) (xy 380.242826 -255.014222) (xy 380.548637 -255.014222) (xy 380.552732 -254.963494)
			(xy 380.564911 -254.91408) (xy 380.584859 -254.86726) (xy 380.61206 -254.824246) (xy 380.645808 -254.786152)
			(xy 380.68523 -254.753965) (xy 380.729304 -254.728519) (xy 380.77689 -254.710472) (xy 380.826754 -254.700292)
			(xy 380.877606 -254.698243) (xy 380.928127 -254.704377) (xy 380.977011 -254.718537) (xy 381.02299 -254.740354)
			(xy 381.064874 -254.769264) (xy 381.101578 -254.804519) (xy 381.132151 -254.845205) (xy 381.155802 -254.890268)
			(xy 381.171918 -254.938542) (xy 381.180082 -254.988776) (xy 381.180594 -255.014222) (xy 381.180082 -255.039668)
			(xy 381.171918 -255.089902) (xy 381.155802 -255.138176) (xy 381.132151 -255.183239) (xy 381.101578 -255.223925)
			(xy 381.064874 -255.25918) (xy 381.02299 -255.28809) (xy 380.977011 -255.309907) (xy 380.928127 -255.324067)
			(xy 380.877606 -255.330201) (xy 380.826754 -255.328152) (xy 380.77689 -255.317972) (xy 380.729304 -255.299925)
			(xy 380.68523 -255.274479) (xy 380.645808 -255.242292) (xy 380.61206 -255.204198) (xy 380.584859 -255.161184)
			(xy 380.564911 -255.114364) (xy 380.552732 -255.06495) (xy 380.548637 -255.014222) (xy 380.242826 -255.014222)
			(xy 380.242336 -255.039211) (xy 380.234517 -255.088574) (xy 380.219073 -255.136106) (xy 380.196383 -255.180638)
			(xy 380.167007 -255.221071) (xy 380.131667 -255.256411) (xy 380.091234 -255.285787) (xy 380.046702 -255.308477)
			(xy 379.99917 -255.323921) (xy 379.949807 -255.33174) (xy 379.899829 -255.33174) (xy 379.850466 -255.323921)
			(xy 379.802934 -255.308477) (xy 379.758402 -255.285787) (xy 379.717969 -255.256411) (xy 379.682629 -255.221071)
			(xy 379.653253 -255.180638) (xy 379.630563 -255.136106) (xy 379.615119 -255.088574) (xy 379.6073 -255.039211)
			(xy 379.299983 -255.039211) (xy 379.299974 -255.039668) (xy 379.29181 -255.089902) (xy 379.275694 -255.138176)
			(xy 379.252043 -255.183239) (xy 379.22147 -255.223925) (xy 379.184766 -255.25918) (xy 379.142882 -255.28809)
			(xy 379.096903 -255.309907) (xy 379.048019 -255.324067) (xy 378.997498 -255.330201) (xy 378.946646 -255.328152)
			(xy 378.896782 -255.317972) (xy 378.849196 -255.299925) (xy 378.805122 -255.274479) (xy 378.7657 -255.242292)
			(xy 378.731952 -255.204198) (xy 378.704751 -255.161184) (xy 378.684803 -255.114364) (xy 378.672624 -255.06495)
			(xy 378.668529 -255.014222) (xy 378.362718 -255.014222) (xy 378.362228 -255.039211) (xy 378.354409 -255.088574)
			(xy 378.338965 -255.136106) (xy 378.316275 -255.180638) (xy 378.286899 -255.221071) (xy 378.251559 -255.256411)
			(xy 378.211126 -255.285787) (xy 378.166594 -255.308477) (xy 378.119062 -255.323921) (xy 378.069699 -255.33174)
			(xy 378.019721 -255.33174) (xy 377.970358 -255.323921) (xy 377.922826 -255.308477) (xy 377.878294 -255.285787)
			(xy 377.837861 -255.256411) (xy 377.802521 -255.221071) (xy 377.773145 -255.180638) (xy 377.750455 -255.136106)
			(xy 377.735011 -255.088574) (xy 377.727192 -255.039211) (xy 377.420129 -255.039211) (xy 377.42012 -255.039668)
			(xy 377.411956 -255.089902) (xy 377.39584 -255.138176) (xy 377.372189 -255.183239) (xy 377.341616 -255.223925)
			(xy 377.304912 -255.25918) (xy 377.263028 -255.28809) (xy 377.217049 -255.309907) (xy 377.168165 -255.324067)
			(xy 377.117644 -255.330201) (xy 377.066792 -255.328152) (xy 377.016928 -255.317972) (xy 376.969342 -255.299925)
			(xy 376.925268 -255.274479) (xy 376.885846 -255.242292) (xy 376.852098 -255.204198) (xy 376.824897 -255.161184)
			(xy 376.804949 -255.114364) (xy 376.79277 -255.06495) (xy 376.788675 -255.014222) (xy 376.480578 -255.014222)
			(xy 376.480066 -255.039668) (xy 376.471902 -255.089902) (xy 376.455786 -255.138176) (xy 376.432135 -255.183239)
			(xy 376.401562 -255.223925) (xy 376.364858 -255.25918) (xy 376.322974 -255.28809) (xy 376.276995 -255.309907)
			(xy 376.228111 -255.324067) (xy 376.17759 -255.330201) (xy 376.126738 -255.328152) (xy 376.076874 -255.317972)
			(xy 376.029288 -255.299925) (xy 375.985214 -255.274479) (xy 375.945792 -255.242292) (xy 375.912044 -255.204198)
			(xy 375.884843 -255.161184) (xy 375.864895 -255.114364) (xy 375.852716 -255.06495) (xy 375.848621 -255.014222)
			(xy 374.602756 -255.014222) (xy 374.602266 -255.039211) (xy 374.594447 -255.088574) (xy 374.579003 -255.136106)
			(xy 374.556313 -255.180638) (xy 374.526937 -255.221071) (xy 374.491597 -255.256411) (xy 374.451164 -255.285787)
			(xy 374.406632 -255.308477) (xy 374.3591 -255.323921) (xy 374.309737 -255.33174) (xy 374.259759 -255.33174)
			(xy 374.210396 -255.323921) (xy 374.162864 -255.308477) (xy 374.118332 -255.285787) (xy 374.077899 -255.256411)
			(xy 374.042559 -255.221071) (xy 374.013183 -255.180638) (xy 373.990493 -255.136106) (xy 373.975049 -255.088574)
			(xy 373.96723 -255.039211) (xy 372.722412 -255.039211) (xy 372.714593 -255.088574) (xy 372.699149 -255.136106)
			(xy 372.676459 -255.180638) (xy 372.647083 -255.221071) (xy 372.611743 -255.256411) (xy 372.57131 -255.285787)
			(xy 372.526778 -255.308477) (xy 372.479246 -255.323921) (xy 372.429883 -255.33174) (xy 372.379905 -255.33174)
			(xy 372.330542 -255.323921) (xy 372.28301 -255.308477) (xy 372.238478 -255.285787) (xy 372.198045 -255.256411)
			(xy 372.162705 -255.221071) (xy 372.133329 -255.180638) (xy 372.110639 -255.136106) (xy 372.095195 -255.088574)
			(xy 372.087376 -255.039211) (xy 370.842304 -255.039211) (xy 370.834485 -255.088574) (xy 370.819041 -255.136106)
			(xy 370.796351 -255.180638) (xy 370.766975 -255.221071) (xy 370.731635 -255.256411) (xy 370.691202 -255.285787)
			(xy 370.64667 -255.308477) (xy 370.599138 -255.323921) (xy 370.549775 -255.33174) (xy 370.499797 -255.33174)
			(xy 370.450434 -255.323921) (xy 370.402902 -255.308477) (xy 370.35837 -255.285787) (xy 370.317937 -255.256411)
			(xy 370.282597 -255.221071) (xy 370.253221 -255.180638) (xy 370.230531 -255.136106) (xy 370.215087 -255.088574)
			(xy 370.207268 -255.039211) (xy 350.318253 -255.039211) (xy 350.255078 -255.148588) (xy 350.243668 -255.167254)
			(xy 350.214546 -255.199893) (xy 350.179402 -255.225935) (xy 350.139701 -255.244296) (xy 350.097098 -255.25421)
			(xy 350.075246 -255.255268) (xy 350.067205 -255.255763) (xy 350.052052 -255.26121) (xy 350.045528 -255.265936)
			(xy 350.024527 -255.281523) (xy 349.978459 -255.306278) (xy 349.928961 -255.323157) (xy 349.877367 -255.331706)
			(xy 349.851218 -255.33223) (xy 349.82623 -255.331701) (xy 349.77687 -255.323886) (xy 349.72934 -255.308446)
			(xy 349.68481 -255.28576) (xy 349.644378 -255.256388) (xy 349.609038 -255.221053) (xy 349.579661 -255.180624)
			(xy 349.55697 -255.136097) (xy 349.541523 -255.088569) (xy 349.533702 -255.03921) (xy 349.53321 -255.014222)
			(xy 348.680532 -255.014222) (xy 348.680532 -255.58877) (xy 348.680786 -255.594866) (xy 348.683326 -255.60528)
			(xy 348.6912 -255.627632) (xy 348.695772 -255.633728) (xy 348.710644 -255.654498) (xy 348.734272 -255.699784)
			(xy 348.750368 -255.748262) (xy 348.758518 -255.798688) (xy 348.759018 -255.824228) (xy 349.063056 -255.824228)
			(xy 349.063769 -255.792848) (xy 349.076055 -255.731304) (xy 349.08744 -255.702054) (xy 349.089064 -255.697911)
			(xy 349.090982 -255.689223) (xy 349.09125 -255.684782) (xy 349.092571 -255.664442) (xy 349.102046 -255.624803)
			(xy 349.118871 -255.587683) (xy 349.142434 -255.554429) (xy 349.171879 -255.526251) (xy 349.206136 -255.504172)
			(xy 349.243961 -255.488995) (xy 349.283978 -255.481272) (xy 349.304356 -255.48082) (xy 349.559372 -255.48082)
			(xy 349.559372 -255.489964) (xy 349.559848 -255.49998) (xy 349.567501 -255.51849) (xy 349.581656 -255.532663)
			(xy 349.600157 -255.540339) (xy 349.610172 -255.540764) (xy 349.77324 -255.540764) (xy 349.783246 -255.541254)
			(xy 349.801732 -255.54892) (xy 349.815882 -255.563072) (xy 349.823546 -255.581558) (xy 349.82404 -255.591564)
			(xy 349.82404 -256.099056) (xy 351.749868 -256.099056) (xy 351.749868 -255.591564) (xy 351.750358 -255.581558)
			(xy 351.758023 -255.563072) (xy 351.772175 -255.548921) (xy 351.790662 -255.541257) (xy 351.800668 -255.540764)
			(xy 352.014536 -255.540764) (xy 352.014536 -255.53162) (xy 352.014937 -255.521596) (xy 352.022607 -255.503072)
			(xy 352.036786 -255.488898) (xy 352.055311 -255.481234) (xy 352.065336 -255.48082) (xy 352.269552 -255.48082)
			(xy 352.289095 -255.481207) (xy 352.327523 -255.488347) (xy 352.364011 -255.50236) (xy 352.39734 -255.522779)
			(xy 352.405473 -255.530096) (xy 353.074732 -255.530096) (xy 353.075209 -255.502109) (xy 353.083966 -255.446823)
			(xy 353.101265 -255.393588) (xy 353.126679 -255.343715) (xy 353.159583 -255.298432) (xy 353.199166 -255.258854)
			(xy 353.244453 -255.225956) (xy 353.294329 -255.200548) (xy 353.347566 -255.183256) (xy 353.402852 -255.174505)
			(xy 353.43084 -255.173988) (xy 353.456207 -255.174406) (xy 353.506436 -255.181549) (xy 353.530916 -255.188212)
			(xy 353.537774 -255.190244) (xy 353.595178 -255.190244) (xy 353.624896 -255.219962) (xy 353.624896 -255.231646)
			(xy 353.638358 -255.24079) (xy 353.644935 -255.245129) (xy 353.659946 -255.249901) (xy 353.667822 -255.250188)
			(xy 354.108258 -255.250188) (xy 354.116133 -255.249911) (xy 354.131137 -255.245119) (xy 354.137722 -255.24079)
			(xy 354.146855 -255.234373) (xy 354.16579 -255.222551) (xy 354.175568 -255.217168) (xy 354.175568 -255.190244)
			(xy 354.238306 -255.190244) (xy 354.245164 -255.188212) (xy 354.269639 -255.181525) (xy 354.319871 -255.174381)
			(xy 354.34524 -255.173988) (xy 354.372738 -255.174479) (xy 354.427085 -255.182902) (xy 354.453444 -255.190752)
			(xy 354.461572 -255.19253) (xy 354.480315 -255.195723) (xy 354.516341 -255.207868) (xy 354.549642 -255.22621)
			(xy 354.579161 -255.250167) (xy 354.603963 -255.27898) (xy 354.613972 -255.295146) (xy 354.618798 -255.302004)
			(xy 354.634325 -255.321297) (xy 354.660444 -255.363374) (xy 354.680486 -255.408661) (xy 354.694066 -255.456287)
			(xy 354.700923 -255.505334) (xy 354.701348 -255.530096) (xy 354.701344 -255.53035) (xy 365.02467 -255.53035)
			(xy 365.02467 -255.530096) (xy 365.025089 -255.505087) (xy 365.032094 -255.455561) (xy 365.045966 -255.407505)
			(xy 365.066431 -255.361865) (xy 365.093086 -255.31954) (xy 365.125405 -255.281365) (xy 365.143796 -255.264412)
			(xy 365.147606 -255.260602) (xy 365.162292 -255.245151) (xy 365.196584 -255.219841) (xy 365.235214 -255.201834)
			(xy 365.25581 -255.19634) (xy 365.26089 -255.194816) (xy 365.289906 -255.185101) (xy 365.350186 -255.174623)
			(xy 365.380778 -255.173988) (xy 365.406145 -255.174419) (xy 365.456373 -255.181553) (xy 365.480854 -255.188212)
			(xy 365.487712 -255.190244) (xy 365.560356 -255.190244) (xy 365.560356 -255.194816) (xy 365.560985 -255.207231)
			(xy 365.572562 -255.229198) (xy 365.582454 -255.236726) (xy 365.588296 -255.24079) (xy 365.594887 -255.245105)
			(xy 365.609887 -255.249892) (xy 365.61776 -255.250188) (xy 365.774732 -255.250188) (xy 365.78474 -255.250662)
			(xy 365.80323 -255.258329) (xy 365.817382 -255.272486) (xy 365.825042 -255.29098) (xy 365.825532 -255.300988)
			(xy 365.825532 -255.808988) (xy 365.825003 -255.818991) (xy 365.822836 -255.824228) (xy 368.796824 -255.824228)
			(xy 368.797259 -255.800111) (xy 368.804527 -255.752427) (xy 368.818915 -255.706388) (xy 368.840095 -255.663052)
			(xy 368.867578 -255.623413) (xy 368.900734 -255.588381) (xy 368.938803 -255.558761) (xy 368.959638 -255.546606)
			(xy 368.969798 -255.53924) (xy 368.984774 -255.525645) (xy 369.018843 -255.503855) (xy 369.056414 -255.488888)
			(xy 369.096135 -255.481282) (xy 369.116356 -255.48082) (xy 369.371372 -255.48082) (xy 369.371372 -255.489964)
			(xy 369.371848 -255.49998) (xy 369.379501 -255.51849) (xy 369.393656 -255.532663) (xy 369.412157 -255.540339)
			(xy 369.422172 -255.540764) (xy 369.58524 -255.540764) (xy 369.595246 -255.541254) (xy 369.613732 -255.54892)
			(xy 369.627882 -255.563072) (xy 369.635546 -255.581558) (xy 369.63604 -255.591564) (xy 369.63604 -255.824228)
			(xy 370.676678 -255.824228) (xy 370.677179 -255.799765) (xy 370.684682 -255.751418) (xy 370.699499 -255.704789)
			(xy 370.721283 -255.66098) (xy 370.749517 -255.621023) (xy 370.783537 -255.585861) (xy 370.822541 -255.556323)
			(xy 370.865607 -255.533105) (xy 370.888514 -255.524508) (xy 370.900198 -255.518412) (xy 370.91817 -255.506702)
			(xy 370.957636 -255.489915) (xy 370.999658 -255.481349) (xy 371.021102 -255.48082) (xy 371.276372 -255.48082)
			(xy 371.276372 -255.489964) (xy 371.276848 -255.49998) (xy 371.284501 -255.51849) (xy 371.298656 -255.532663)
			(xy 371.317157 -255.540339) (xy 371.327172 -255.540764) (xy 371.49024 -255.540764) (xy 371.500246 -255.541254)
			(xy 371.518732 -255.54892) (xy 371.532882 -255.563072) (xy 371.540546 -255.581558) (xy 371.54104 -255.591564)
			(xy 371.54104 -255.824228) (xy 372.556786 -255.824228) (xy 372.557148 -255.802811) (xy 372.562909 -255.760367)
			(xy 372.574328 -255.719084) (xy 372.58244 -255.69926) (xy 372.584132 -255.695129) (xy 372.58617 -255.686439)
			(xy 372.586504 -255.681988) (xy 372.588121 -255.661862) (xy 372.597993 -255.622715) (xy 372.61504 -255.586118)
			(xy 372.638655 -255.553372) (xy 372.667998 -255.525643) (xy 372.702026 -255.503916) (xy 372.739528 -255.488965)
			(xy 372.77917 -255.48132) (xy 372.799356 -255.48082) (xy 373.054372 -255.48082) (xy 373.054372 -255.489964)
			(xy 373.054848 -255.49998) (xy 373.062501 -255.51849) (xy 373.076656 -255.532663) (xy 373.095157 -255.540339)
			(xy 373.105172 -255.540764) (xy 373.26824 -255.540764) (xy 373.278246 -255.541254) (xy 373.296732 -255.54892)
			(xy 373.310882 -255.563072) (xy 373.318546 -255.581558) (xy 373.31904 -255.591564) (xy 373.31904 -255.849217)
			(xy 374.437384 -255.849217) (xy 374.437384 -255.799239) (xy 374.445203 -255.749876) (xy 374.460647 -255.702344)
			(xy 374.483337 -255.657812) (xy 374.512713 -255.617379) (xy 374.548053 -255.582039) (xy 374.588486 -255.552663)
			(xy 374.633018 -255.529973) (xy 374.68055 -255.514529) (xy 374.729913 -255.50671) (xy 374.779891 -255.50671)
			(xy 374.829254 -255.514529) (xy 374.876786 -255.529973) (xy 374.921318 -255.552663) (xy 374.961751 -255.582039)
			(xy 374.997091 -255.617379) (xy 375.026467 -255.657812) (xy 375.049157 -255.702344) (xy 375.064601 -255.749876)
			(xy 375.07242 -255.799239) (xy 375.07291 -255.824228) (xy 375.378467 -255.824228) (xy 375.382562 -255.7735)
			(xy 375.394741 -255.724086) (xy 375.414689 -255.677266) (xy 375.44189 -255.634252) (xy 375.475638 -255.596158)
			(xy 375.51506 -255.563971) (xy 375.559134 -255.538525) (xy 375.60672 -255.520478) (xy 375.656584 -255.510298)
			(xy 375.707436 -255.508249) (xy 375.757957 -255.514383) (xy 375.806841 -255.528543) (xy 375.85282 -255.55036)
			(xy 375.894704 -255.57927) (xy 375.931408 -255.614525) (xy 375.961981 -255.655211) (xy 375.985632 -255.700274)
			(xy 376.001748 -255.748548) (xy 376.009912 -255.798782) (xy 376.010424 -255.824228) (xy 376.009921 -255.849217)
			(xy 376.317238 -255.849217) (xy 376.317238 -255.799239) (xy 376.325057 -255.749876) (xy 376.340501 -255.702344)
			(xy 376.363191 -255.657812) (xy 376.392567 -255.617379) (xy 376.427907 -255.582039) (xy 376.46834 -255.552663)
			(xy 376.512872 -255.529973) (xy 376.560404 -255.514529) (xy 376.609767 -255.50671) (xy 376.659745 -255.50671)
			(xy 376.709108 -255.514529) (xy 376.75664 -255.529973) (xy 376.801172 -255.552663) (xy 376.841605 -255.582039)
			(xy 376.876945 -255.617379) (xy 376.906321 -255.657812) (xy 376.929011 -255.702344) (xy 376.944455 -255.749876)
			(xy 376.952274 -255.799239) (xy 376.952764 -255.824228) (xy 377.258575 -255.824228) (xy 377.26267 -255.7735)
			(xy 377.274849 -255.724086) (xy 377.294797 -255.677266) (xy 377.321998 -255.634252) (xy 377.355746 -255.596158)
			(xy 377.395168 -255.563971) (xy 377.439242 -255.538525) (xy 377.486828 -255.520478) (xy 377.536692 -255.510298)
			(xy 377.587544 -255.508249) (xy 377.638065 -255.514383) (xy 377.686949 -255.528543) (xy 377.732928 -255.55036)
			(xy 377.774812 -255.57927) (xy 377.811516 -255.614525) (xy 377.842089 -255.655211) (xy 377.86574 -255.700274)
			(xy 377.881856 -255.748548) (xy 377.89002 -255.798782) (xy 377.890532 -255.824228) (xy 377.890029 -255.849217)
			(xy 378.197346 -255.849217) (xy 378.197346 -255.799239) (xy 378.205165 -255.749876) (xy 378.220609 -255.702344)
			(xy 378.243299 -255.657812) (xy 378.272675 -255.617379) (xy 378.308015 -255.582039) (xy 378.348448 -255.552663)
			(xy 378.39298 -255.529973) (xy 378.440512 -255.514529) (xy 378.489875 -255.50671) (xy 378.539853 -255.50671)
			(xy 378.589216 -255.514529) (xy 378.636748 -255.529973) (xy 378.68128 -255.552663) (xy 378.721713 -255.582039)
			(xy 378.757053 -255.617379) (xy 378.786429 -255.657812) (xy 378.809119 -255.702344) (xy 378.824563 -255.749876)
			(xy 378.832382 -255.799239) (xy 378.832872 -255.824228) (xy 379.138683 -255.824228) (xy 379.142778 -255.7735)
			(xy 379.154957 -255.724086) (xy 379.174905 -255.677266) (xy 379.202106 -255.634252) (xy 379.235854 -255.596158)
			(xy 379.275276 -255.563971) (xy 379.31935 -255.538525) (xy 379.366936 -255.520478) (xy 379.4168 -255.510298)
			(xy 379.467652 -255.508249) (xy 379.518173 -255.514383) (xy 379.567057 -255.528543) (xy 379.613036 -255.55036)
			(xy 379.65492 -255.57927) (xy 379.691624 -255.614525) (xy 379.722197 -255.655211) (xy 379.745848 -255.700274)
			(xy 379.761964 -255.748548) (xy 379.770128 -255.798782) (xy 379.77064 -255.824228) (xy 380.078483 -255.824228)
			(xy 380.082578 -255.7735) (xy 380.094757 -255.724086) (xy 380.114705 -255.677266) (xy 380.141906 -255.634252)
			(xy 380.175654 -255.596158) (xy 380.215076 -255.563971) (xy 380.25915 -255.538525) (xy 380.306736 -255.520478)
			(xy 380.3566 -255.510298) (xy 380.407452 -255.508249) (xy 380.457973 -255.514383) (xy 380.506857 -255.528543)
			(xy 380.552836 -255.55036) (xy 380.59472 -255.57927) (xy 380.631424 -255.614525) (xy 380.661997 -255.655211)
			(xy 380.685648 -255.700274) (xy 380.701764 -255.748548) (xy 380.709928 -255.798782) (xy 380.71044 -255.824228)
			(xy 380.709928 -255.849674) (xy 380.701764 -255.899908) (xy 380.685648 -255.948182) (xy 380.661997 -255.993245)
			(xy 380.631424 -256.033931) (xy 380.59472 -256.069186) (xy 380.552836 -256.098096) (xy 380.506857 -256.119913)
			(xy 380.457973 -256.134073) (xy 380.407452 -256.140207) (xy 380.3566 -256.138158) (xy 380.306736 -256.127978)
			(xy 380.25915 -256.109931) (xy 380.215076 -256.084485) (xy 380.175654 -256.052298) (xy 380.141906 -256.014204)
			(xy 380.114705 -255.97119) (xy 380.094757 -255.92437) (xy 380.082578 -255.874956) (xy 380.078483 -255.824228)
			(xy 379.77064 -255.824228) (xy 379.770128 -255.849674) (xy 379.761964 -255.899908) (xy 379.745848 -255.948182)
			(xy 379.722197 -255.993245) (xy 379.691624 -256.033931) (xy 379.65492 -256.069186) (xy 379.613036 -256.098096)
			(xy 379.567057 -256.119913) (xy 379.518173 -256.134073) (xy 379.467652 -256.140207) (xy 379.4168 -256.138158)
			(xy 379.366936 -256.127978) (xy 379.31935 -256.109931) (xy 379.275276 -256.084485) (xy 379.235854 -256.052298)
			(xy 379.202106 -256.014204) (xy 379.174905 -255.97119) (xy 379.154957 -255.92437) (xy 379.142778 -255.874956)
			(xy 379.138683 -255.824228) (xy 378.832872 -255.824228) (xy 378.832382 -255.849217) (xy 378.824563 -255.89858)
			(xy 378.809119 -255.946112) (xy 378.786429 -255.990644) (xy 378.757053 -256.031077) (xy 378.721713 -256.066417)
			(xy 378.68128 -256.095793) (xy 378.636748 -256.118483) (xy 378.589216 -256.133927) (xy 378.539853 -256.141746)
			(xy 378.489875 -256.141746) (xy 378.440512 -256.133927) (xy 378.39298 -256.118483) (xy 378.348448 -256.095793)
			(xy 378.308015 -256.066417) (xy 378.272675 -256.031077) (xy 378.243299 -255.990644) (xy 378.220609 -255.946112)
			(xy 378.205165 -255.89858) (xy 378.197346 -255.849217) (xy 377.890029 -255.849217) (xy 377.89002 -255.849674)
			(xy 377.881856 -255.899908) (xy 377.86574 -255.948182) (xy 377.842089 -255.993245) (xy 377.811516 -256.033931)
			(xy 377.774812 -256.069186) (xy 377.732928 -256.098096) (xy 377.686949 -256.119913) (xy 377.638065 -256.134073)
			(xy 377.587544 -256.140207) (xy 377.536692 -256.138158) (xy 377.486828 -256.127978) (xy 377.439242 -256.109931)
			(xy 377.395168 -256.084485) (xy 377.355746 -256.052298) (xy 377.321998 -256.014204) (xy 377.294797 -255.97119)
			(xy 377.274849 -255.92437) (xy 377.26267 -255.874956) (xy 377.258575 -255.824228) (xy 376.952764 -255.824228)
			(xy 376.952274 -255.849217) (xy 376.944455 -255.89858) (xy 376.929011 -255.946112) (xy 376.906321 -255.990644)
			(xy 376.876945 -256.031077) (xy 376.841605 -256.066417) (xy 376.801172 -256.095793) (xy 376.75664 -256.118483)
			(xy 376.709108 -256.133927) (xy 376.659745 -256.141746) (xy 376.609767 -256.141746) (xy 376.560404 -256.133927)
			(xy 376.512872 -256.118483) (xy 376.46834 -256.095793) (xy 376.427907 -256.066417) (xy 376.392567 -256.031077)
			(xy 376.363191 -255.990644) (xy 376.340501 -255.946112) (xy 376.325057 -255.89858) (xy 376.317238 -255.849217)
			(xy 376.009921 -255.849217) (xy 376.009912 -255.849674) (xy 376.001748 -255.899908) (xy 375.985632 -255.948182)
			(xy 375.961981 -255.993245) (xy 375.931408 -256.033931) (xy 375.894704 -256.069186) (xy 375.85282 -256.098096)
			(xy 375.806841 -256.119913) (xy 375.757957 -256.134073) (xy 375.707436 -256.140207) (xy 375.656584 -256.138158)
			(xy 375.60672 -256.127978) (xy 375.559134 -256.109931) (xy 375.51506 -256.084485) (xy 375.475638 -256.052298)
			(xy 375.44189 -256.014204) (xy 375.414689 -255.97119) (xy 375.394741 -255.92437) (xy 375.382562 -255.874956)
			(xy 375.378467 -255.824228) (xy 375.07291 -255.824228) (xy 375.07242 -255.849217) (xy 375.064601 -255.89858)
			(xy 375.049157 -255.946112) (xy 375.026467 -255.990644) (xy 374.997091 -256.031077) (xy 374.961751 -256.066417)
			(xy 374.921318 -256.095793) (xy 374.876786 -256.118483) (xy 374.829254 -256.133927) (xy 374.779891 -256.141746)
			(xy 374.729913 -256.141746) (xy 374.68055 -256.133927) (xy 374.633018 -256.118483) (xy 374.588486 -256.095793)
			(xy 374.548053 -256.066417) (xy 374.512713 -256.031077) (xy 374.483337 -255.990644) (xy 374.460647 -255.946112)
			(xy 374.445203 -255.89858) (xy 374.437384 -255.849217) (xy 373.31904 -255.849217) (xy 373.31904 -256.099056)
			(xy 373.318545 -256.10907) (xy 373.310897 -256.127578) (xy 373.296748 -256.14175) (xy 373.278253 -256.149429)
			(xy 373.26824 -256.149856) (xy 373.054372 -256.149856) (xy 373.054372 -256.159) (xy 373.05398 -256.169025)
			(xy 373.046305 -256.187547) (xy 373.032124 -256.20172) (xy 373.013597 -256.209385) (xy 373.003572 -256.2098)
			(xy 372.799356 -256.2098) (xy 372.778311 -256.209316) (xy 372.737036 -256.201067) (xy 372.698174 -256.184898)
			(xy 372.663231 -256.161433) (xy 372.633557 -256.131582) (xy 372.610301 -256.096498) (xy 372.594364 -256.057541)
			(xy 372.586362 -256.016218) (xy 372.585996 -255.99517) (xy 372.585996 -255.994916) (xy 372.585996 -255.958086)
			(xy 372.582186 -255.948434) (xy 372.574176 -255.928715) (xy 372.562866 -255.887684) (xy 372.557145 -255.845508)
			(xy 372.556786 -255.824228) (xy 371.54104 -255.824228) (xy 371.54104 -256.099056) (xy 371.540545 -256.10907)
			(xy 371.532897 -256.127578) (xy 371.518748 -256.14175) (xy 371.500253 -256.149429) (xy 371.49024 -256.149856)
			(xy 371.276372 -256.149856) (xy 371.276372 -256.159) (xy 371.27598 -256.169025) (xy 371.268305 -256.187547)
			(xy 371.254124 -256.20172) (xy 371.235597 -256.209385) (xy 371.225572 -256.2098) (xy 371.021356 -256.2098)
			(xy 370.999655 -256.209213) (xy 370.957149 -256.200432) (xy 370.917288 -256.18326) (xy 370.881708 -256.158403)
			(xy 370.851871 -256.126882) (xy 370.84 -256.108708) (xy 370.836837 -256.103948) (xy 370.828759 -256.095868)
			(xy 370.823998 -256.092706) (xy 370.801825 -256.07793) (xy 370.762277 -256.042227) (xy 370.729225 -256.000437)
			(xy 370.703593 -255.953728) (xy 370.686095 -255.903403) (xy 370.67722 -255.850868) (xy 370.676678 -255.824228)
			(xy 369.63604 -255.824228) (xy 369.63604 -256.099056) (xy 369.635545 -256.10907) (xy 369.627897 -256.127578)
			(xy 369.613748 -256.14175) (xy 369.595253 -256.149429) (xy 369.58524 -256.149856) (xy 369.371372 -256.149856)
			(xy 369.371372 -256.159) (xy 369.37098 -256.169025) (xy 369.363305 -256.187547) (xy 369.349124 -256.20172)
			(xy 369.330597 -256.209385) (xy 369.320572 -256.2098) (xy 369.116356 -256.2098) (xy 369.09593 -256.209355)
			(xy 369.055823 -256.201597) (xy 369.017923 -256.186353) (xy 368.983613 -256.16418) (xy 368.954147 -256.135886)
			(xy 368.930598 -256.102505) (xy 368.921792 -256.08407) (xy 368.919363 -256.079038) (xy 368.912698 -256.070071)
			(xy 368.908584 -256.06629) (xy 368.888012 -256.047987) (xy 368.852879 -256.005595) (xy 368.825567 -255.957788)
			(xy 368.806892 -255.905993) (xy 368.79741 -255.851757) (xy 368.796824 -255.824228) (xy 365.822836 -255.824228)
			(xy 365.817353 -255.837476) (xy 365.803213 -255.851629) (xy 365.784735 -255.859294) (xy 365.774732 -255.859788)
			(xy 365.560356 -255.859788) (xy 365.560356 -255.868932) (xy 365.560006 -255.878961) (xy 365.552317 -255.897487)
			(xy 365.538123 -255.91166) (xy 365.519585 -255.919321) (xy 365.509556 -255.919732) (xy 365.305594 -255.919732)
			(xy 365.285013 -255.919211) (xy 365.244615 -255.911319) (xy 365.206479 -255.895828) (xy 365.172021 -255.873313)
			(xy 365.142518 -255.84461) (xy 365.119066 -255.810783) (xy 365.102533 -255.773087) (xy 365.097568 -255.753108)
			(xy 365.096338 -255.748279) (xy 365.092234 -255.7392) (xy 365.08944 -255.735074) (xy 365.074156 -255.712471)
			(xy 365.049946 -255.663574) (xy 365.033486 -255.611554) (xy 365.025162 -255.557631) (xy 365.02467 -255.53035)
			(xy 354.701344 -255.53035) (xy 354.700938 -255.554669) (xy 354.694176 -255.603348) (xy 354.680791 -255.650637)
			(xy 354.661039 -255.695639) (xy 354.648516 -255.716786) (xy 354.645834 -255.721298) (xy 354.642253 -255.731164)
			(xy 354.641404 -255.736344) (xy 354.637798 -255.757847) (xy 354.623031 -255.798863) (xy 354.600263 -255.836038)
			(xy 354.570438 -255.867831) (xy 354.534792 -255.892925) (xy 354.494802 -255.910279) (xy 354.452126 -255.919174)
			(xy 354.43033 -255.919732) (xy 354.175568 -255.919732) (xy 354.175568 -255.910588) (xy 354.175189 -255.900562)
			(xy 354.16751 -255.882039) (xy 354.153324 -255.867866) (xy 354.134794 -255.860202) (xy 354.124768 -255.859788)
			(xy 353.624896 -255.859788) (xy 353.624896 -255.868932) (xy 353.624438 -255.878942) (xy 353.616767 -255.897435)
			(xy 353.602605 -255.911587) (xy 353.584107 -255.919245) (xy 353.574096 -255.919732) (xy 353.370134 -255.919732)
			(xy 353.348204 -255.919222) (xy 353.305263 -255.910292) (xy 353.265051 -255.892782) (xy 353.229262 -255.867428)
			(xy 353.199405 -255.8353) (xy 353.176738 -255.797752) (xy 353.168966 -255.777238) (xy 353.167362 -255.772826)
			(xy 353.162753 -255.764649) (xy 353.159822 -255.760982) (xy 353.143841 -255.741574) (xy 353.116925 -255.699113)
			(xy 353.096255 -255.653286) (xy 353.082242 -255.605005) (xy 353.075165 -255.555233) (xy 353.074732 -255.530096)
			(xy 352.405473 -255.530096) (xy 352.426397 -255.548921) (xy 352.450211 -255.579915) (xy 352.467989 -255.614724)
			(xy 352.479135 -255.652187) (xy 352.481642 -255.671574) (xy 352.482199 -255.675781) (xy 352.484495 -255.68395)
			(xy 352.486214 -255.68783) (xy 352.495605 -255.708926) (xy 352.508845 -255.753163) (xy 352.515525 -255.798854)
			(xy 352.515932 -255.821942) (xy 352.515932 -255.822196) (xy 352.515521 -255.844864) (xy 352.509059 -255.889737)
			(xy 352.496281 -255.933235) (xy 352.48723 -255.954022) (xy 352.482912 -255.963928) (xy 352.482912 -255.994916)
			(xy 352.482912 -255.99517) (xy 352.48263 -256.016223) (xy 352.474624 -256.057555) (xy 352.458679 -256.09652)
			(xy 352.435412 -256.131608) (xy 352.405725 -256.16146) (xy 352.370766 -256.184921) (xy 352.33189 -256.201082)
			(xy 352.290603 -256.209317) (xy 352.269552 -256.2098) (xy 352.014536 -256.2098) (xy 352.014536 -256.200656)
			(xy 352.014049 -256.19065) (xy 352.006381 -256.172164) (xy 351.992229 -256.158014) (xy 351.973742 -256.15035)
			(xy 351.963736 -256.149856) (xy 351.800668 -256.149856) (xy 351.790639 -256.149506) (xy 351.772113 -256.141817)
			(xy 351.75794 -256.127623) (xy 351.750279 -256.109085) (xy 351.749868 -256.099056) (xy 349.82404 -256.099056)
			(xy 349.823545 -256.10907) (xy 349.815897 -256.127578) (xy 349.801748 -256.14175) (xy 349.783253 -256.149429)
			(xy 349.77324 -256.149856) (xy 349.559372 -256.149856) (xy 349.559372 -256.159) (xy 349.55898 -256.169025)
			(xy 349.551305 -256.187547) (xy 349.537124 -256.20172) (xy 349.518597 -256.209385) (xy 349.508572 -256.2098)
			(xy 349.304356 -256.2098) (xy 349.283311 -256.209316) (xy 349.242036 -256.201067) (xy 349.203174 -256.184898)
			(xy 349.168231 -256.161433) (xy 349.138557 -256.131582) (xy 349.115301 -256.096498) (xy 349.099364 -256.057541)
			(xy 349.091362 -256.016218) (xy 349.090996 -255.99517) (xy 349.090996 -255.994916) (xy 349.090996 -255.955292)
			(xy 349.087186 -255.945894) (xy 349.075891 -255.916758) (xy 349.063741 -255.855469) (xy 349.063056 -255.824228)
			(xy 348.759018 -255.824228) (xy 348.758537 -255.849772) (xy 348.750416 -255.900209) (xy 348.734325 -255.948695)
			(xy 348.710678 -255.993979) (xy 348.695772 -256.014728) (xy 348.6912 -256.020824) (xy 348.683326 -256.042922)
			(xy 348.68209 -256.046679) (xy 348.680692 -256.054464) (xy 348.680532 -256.058416) (xy 348.680532 -256.237232)
			(xy 348.681172 -256.249065) (xy 348.691901 -256.270157) (xy 348.701106 -256.277618) (xy 348.733872 -256.30124)
			(xy 348.76867 -256.326386) (xy 348.773335 -256.329255) (xy 348.783589 -256.333099) (xy 348.78899 -256.334006)
			(xy 348.80042 -256.335784) (xy 348.802452 -256.335022) (xy 348.80423 -256.334514) (xy 348.812104 -256.331974)
			(xy 348.834974 -256.324929) (xy 348.882167 -256.317014) (xy 348.906084 -256.316226) (xy 348.913958 -256.316226)
			(xy 348.938523 -256.316904) (xy 348.98701 -256.324897) (xy 349.03369 -256.340252) (xy 349.077454 -256.362604)
			(xy 349.117259 -256.391419) (xy 349.152159 -256.426014) (xy 349.181324 -256.465565) (xy 349.204059 -256.50913)
			(xy 349.219824 -256.555674) (xy 349.228243 -256.604088) (xy 349.229172 -256.628646) (xy 349.229172 -256.635758)
			(xy 349.228478 -256.662973) (xy 349.218961 -256.716572) (xy 349.200485 -256.767777) (xy 349.187516 -256.791714)
			(xy 349.183706 -256.798318) (xy 349.180912 -256.808986) (xy 349.180912 -256.883916) (xy 349.180912 -256.88417)
			(xy 349.180546 -256.905215) (xy 349.172543 -256.946531) (xy 349.156604 -256.98548) (xy 349.154896 -256.988056)
			(xy 350.352868 -256.988056) (xy 350.352868 -256.480564) (xy 350.353358 -256.470558) (xy 350.361023 -256.452072)
			(xy 350.375175 -256.437921) (xy 350.393662 -256.430257) (xy 350.403668 -256.429764) (xy 350.523048 -256.429764)
			(xy 350.533389 -256.429311) (xy 350.552403 -256.421177) (xy 350.559878 -256.414016) (xy 350.578013 -256.395618)
			(xy 350.619134 -256.364352) (xy 350.664766 -256.340142) (xy 350.713711 -256.323622) (xy 350.764682 -256.315229)
			(xy 350.79051 -256.314702) (xy 350.8155 -256.315173) (xy 350.864864 -256.322993) (xy 350.912398 -256.338439)
			(xy 350.956929 -256.361131) (xy 350.997363 -256.39051) (xy 351.032703 -256.425852) (xy 351.062079 -256.466288)
			(xy 351.069094 -256.480056) (xy 353.074732 -256.480056) (xy 353.075201 -256.45207) (xy 353.083963 -256.396787)
			(xy 353.101266 -256.343556) (xy 353.126683 -256.293687) (xy 353.159589 -256.248408) (xy 353.199172 -256.208834)
			(xy 353.244459 -256.175939) (xy 353.294334 -256.150534) (xy 353.347569 -256.133244) (xy 353.402854 -256.124494)
			(xy 353.43084 -256.123948) (xy 353.431602 -256.123948) (xy 353.45698 -256.124395) (xy 353.507213 -256.131666)
			(xy 353.531678 -256.138426) (xy 353.53879 -256.140712) (xy 353.595178 -256.140712) (xy 353.624896 -256.17043)
			(xy 353.624896 -256.181606) (xy 353.638866 -256.191258) (xy 353.645523 -256.195587) (xy 353.660649 -256.200385)
			(xy 353.668584 -256.200656) (xy 354.107496 -256.200656) (xy 354.115451 -256.20033) (xy 354.130584 -256.195413)
			(xy 354.137214 -256.191004) (xy 354.146464 -256.184508) (xy 354.165655 -256.172559) (xy 354.175568 -256.167128)
			(xy 354.175568 -256.140712) (xy 354.23729 -256.140712) (xy 354.244402 -256.138426) (xy 354.269058 -256.131648)
			(xy 354.319673 -256.124376) (xy 354.34524 -256.123948) (xy 354.373138 -256.124475) (xy 354.428255 -256.133158)
			(xy 354.454968 -256.14122) (xy 354.462842 -256.142998) (xy 354.481338 -256.146294) (xy 354.51689 -256.158421)
			(xy 354.549763 -256.176595) (xy 354.57894 -256.200254) (xy 354.603516 -256.228662) (xy 354.613464 -256.244598)
			(xy 354.61829 -256.251202) (xy 354.633921 -256.270535) (xy 354.660219 -256.312724) (xy 354.680395 -256.358161)
			(xy 354.688735 -256.387346) (xy 355.231954 -256.387346) (xy 355.232561 -256.35908) (xy 355.241575 -256.30327)
			(xy 355.259275 -256.249578) (xy 355.285216 -256.199348) (xy 355.30155 -256.176272) (xy 355.306126 -256.169572)
			(xy 355.311164 -256.154155) (xy 355.311456 -256.146046) (xy 355.311456 -256.073148) (xy 355.311958 -256.063135)
			(xy 355.319604 -256.044628) (xy 355.33375 -256.030455) (xy 355.352244 -256.022776) (xy 355.362256 -256.022348)
			(xy 355.869748 -256.022348) (xy 355.879765 -256.02275) (xy 355.898267 -256.030434) (xy 355.91242 -256.044614)
			(xy 355.920069 -256.06313) (xy 355.920548 -256.073148) (xy 355.920548 -256.250948) (xy 355.92066 -256.255357)
			(xy 355.922188 -256.264041) (xy 355.923596 -256.26822) (xy 355.929946 -256.287524) (xy 355.950774 -256.287524)
			(xy 355.980492 -256.317242) (xy 355.980492 -256.387346) (xy 356.181914 -256.387346) (xy 356.18251 -256.35908)
			(xy 356.191526 -256.303268) (xy 356.209228 -256.249576) (xy 356.235174 -256.199347) (xy 356.25151 -256.176272)
			(xy 356.256082 -256.16957) (xy 356.261123 -256.154155) (xy 356.261416 -256.146046) (xy 356.261416 -256.073148)
			(xy 356.261859 -256.063128) (xy 356.269516 -256.044609) (xy 356.283682 -256.030434) (xy 356.302196 -256.022765)
			(xy 356.312216 -256.022348) (xy 356.819708 -256.022348) (xy 356.829736 -256.022714) (xy 356.848262 -256.030396)
			(xy 356.862436 -256.044585) (xy 356.870097 -256.06312) (xy 356.870508 -256.073148) (xy 356.870508 -256.250948)
			(xy 356.870622 -256.255356) (xy 356.872149 -256.264041) (xy 356.873556 -256.26822) (xy 356.879906 -256.287524)
			(xy 356.900734 -256.287524) (xy 356.930452 -256.317242) (xy 356.930452 -256.387346) (xy 357.131874 -256.387346)
			(xy 357.132478 -256.35908) (xy 357.141492 -256.303269) (xy 357.159192 -256.249578) (xy 357.185135 -256.199348)
			(xy 357.20147 -256.176272) (xy 357.206038 -256.169567) (xy 357.211083 -256.154154) (xy 357.211376 -256.146046)
			(xy 357.211376 -256.073148) (xy 357.211858 -256.063133) (xy 357.219508 -256.044621) (xy 357.233661 -256.030448)
			(xy 357.252161 -256.022772) (xy 357.262176 -256.022348) (xy 357.769668 -256.022348) (xy 357.779693 -256.022747)
			(xy 357.798219 -256.030415) (xy 357.812394 -256.044595) (xy 357.820056 -256.063123) (xy 357.820468 -256.073148)
			(xy 357.820468 -256.250948) (xy 357.820579 -256.255357) (xy 357.822108 -256.264041) (xy 357.823516 -256.26822)
			(xy 357.829866 -256.287524) (xy 357.850694 -256.287524) (xy 357.880412 -256.317242) (xy 357.880412 -256.387346)
			(xy 358.081834 -256.387346) (xy 358.082426 -256.359079) (xy 358.091442 -256.303268) (xy 358.109145 -256.249576)
			(xy 358.135093 -256.199347) (xy 358.15143 -256.176272) (xy 358.156004 -256.169571) (xy 358.161044 -256.154155)
			(xy 358.161336 -256.146046) (xy 358.161336 -256.073148) (xy 358.16176 -256.063125) (xy 358.169421 -256.044603)
			(xy 358.183592 -256.030427) (xy 358.202113 -256.022762) (xy 358.212136 -256.022348) (xy 358.719628 -256.022348)
			(xy 358.729657 -256.022698) (xy 358.748184 -256.030386) (xy 358.762357 -256.04458) (xy 358.770017 -256.063118)
			(xy 358.770428 -256.073148) (xy 358.770428 -256.250948) (xy 358.770541 -256.255357) (xy 358.772069 -256.264041)
			(xy 358.773476 -256.26822) (xy 358.779826 -256.287524) (xy 358.800654 -256.287524) (xy 358.830372 -256.317242)
			(xy 358.830372 -256.387346) (xy 359.031794 -256.387346) (xy 359.031794 -256.386838) (xy 359.032353 -256.358536)
			(xy 359.041315 -256.302646) (xy 359.059017 -256.248881) (xy 359.085014 -256.198599) (xy 359.10139 -256.17551)
			(xy 359.105886 -256.168839) (xy 359.110933 -256.153574) (xy 359.111296 -256.145538) (xy 359.111296 -256.073148)
			(xy 359.111759 -256.06313) (xy 359.119412 -256.044615) (xy 359.133571 -256.030441) (xy 359.152079 -256.022769)
			(xy 359.162096 -256.022348) (xy 359.670096 -256.022348) (xy 359.680123 -256.022724) (xy 359.698649 -256.030402)
			(xy 359.712823 -256.044588) (xy 359.720485 -256.063121) (xy 359.720896 -256.073148) (xy 359.720896 -256.251964)
			(xy 359.720984 -256.256235) (xy 359.72239 -256.264659) (xy 359.72369 -256.268728) (xy 359.729786 -256.287524)
			(xy 359.73004 -256.287524) (xy 359.740053 -256.287956) (xy 359.75855 -256.295633) (xy 359.772703 -256.309803)
			(xy 359.780357 -256.32831) (xy 359.78084 -256.338324) (xy 359.78084 -256.387346) (xy 359.981754 -256.387346)
			(xy 359.981754 -256.386838) (xy 359.982302 -256.358535) (xy 359.991265 -256.302644) (xy 360.00897 -256.248879)
			(xy 360.034971 -256.198598) (xy 360.05135 -256.17551) (xy 360.055852 -256.168842) (xy 360.060894 -256.153575)
			(xy 360.061256 -256.145538) (xy 360.061256 -256.073148) (xy 360.061758 -256.063135) (xy 360.069404 -256.044628)
			(xy 360.08355 -256.030455) (xy 360.102044 -256.022776) (xy 360.112056 -256.022348) (xy 360.620056 -256.022348)
			(xy 360.63008 -256.022757) (xy 360.648606 -256.030421) (xy 360.662781 -256.044598) (xy 360.670444 -256.063124)
			(xy 360.670856 -256.073148) (xy 360.670856 -256.251964) (xy 360.670946 -256.256234) (xy 360.672351 -256.264659)
			(xy 360.67365 -256.268728) (xy 360.679746 -256.287524) (xy 360.68 -256.287524) (xy 360.690024 -256.28792)
			(xy 360.708546 -256.295595) (xy 360.722719 -256.309774) (xy 360.730385 -256.3283) (xy 360.7308 -256.338324)
			(xy 360.7308 -256.387346) (xy 360.931968 -256.387346) (xy 360.932505 -256.359054) (xy 360.941408 -256.303177)
			(xy 360.959045 -256.249413) (xy 360.98497 -256.19912) (xy 361.00131 -256.176018) (xy 361.005805 -256.169346)
			(xy 361.010852 -256.154082) (xy 361.011216 -256.146046) (xy 361.011216 -256.073148) (xy 361.011659 -256.063128)
			(xy 361.019316 -256.044609) (xy 361.033482 -256.030434) (xy 361.051996 -256.022765) (xy 361.062016 -256.022348)
			(xy 361.570016 -256.022348) (xy 361.580044 -256.022708) (xy 361.598571 -256.030392) (xy 361.612744 -256.044583)
			(xy 361.620405 -256.063119) (xy 361.620816 -256.073148) (xy 361.620816 -256.251202) (xy 361.620894 -256.255473)
			(xy 361.622306 -256.263898) (xy 361.62361 -256.267966) (xy 361.62996 -256.287524) (xy 361.639982 -256.287953)
			(xy 361.658502 -256.295614) (xy 361.672677 -256.309784) (xy 361.680344 -256.328302) (xy 361.68076 -256.338324)
			(xy 361.68076 -256.387346) (xy 361.881928 -256.387346) (xy 361.882473 -256.359055) (xy 361.891375 -256.303178)
			(xy 361.909009 -256.249415) (xy 361.934932 -256.19912) (xy 361.95127 -256.176018) (xy 361.955761 -256.169344)
			(xy 361.960811 -256.154082) (xy 361.961176 -256.146046) (xy 361.961176 -256.073148) (xy 361.961658 -256.063133)
			(xy 361.969308 -256.044621) (xy 361.983461 -256.030448) (xy 362.001961 -256.022772) (xy 362.011976 -256.022348)
			(xy 362.519976 -256.022348) (xy 362.530002 -256.022741) (xy 362.548527 -256.030412) (xy 362.562702 -256.044593)
			(xy 362.570364 -256.063122) (xy 362.570776 -256.073148) (xy 362.570776 -256.251202) (xy 362.570856 -256.255473)
			(xy 362.572267 -256.263898) (xy 362.57357 -256.267966) (xy 362.57992 -256.287524) (xy 362.589946 -256.287904)
			(xy 362.608467 -256.295585) (xy 362.62264 -256.30977) (xy 362.630305 -256.328298) (xy 362.63072 -256.338324)
			(xy 362.63072 -256.387346) (xy 362.831888 -256.387346) (xy 362.83244 -256.359055) (xy 362.841341 -256.303179)
			(xy 362.858974 -256.249416) (xy 362.884893 -256.199121) (xy 362.90123 -256.176018) (xy 362.905727 -256.169347)
			(xy 362.910773 -256.154082) (xy 362.911136 -256.146046) (xy 362.911136 -256.073148) (xy 362.91156 -256.063125)
			(xy 362.919221 -256.044603) (xy 362.933392 -256.030427) (xy 362.951913 -256.022762) (xy 362.961936 -256.022348)
			(xy 363.469936 -256.022348) (xy 363.479966 -256.022691) (xy 363.498493 -256.030382) (xy 363.512665 -256.044578)
			(xy 363.520325 -256.063118) (xy 363.520736 -256.073148) (xy 363.520736 -256.251202) (xy 363.520818 -256.255473)
			(xy 363.522228 -256.263897) (xy 363.52353 -256.267966) (xy 363.52988 -256.287524) (xy 363.539903 -256.287937)
			(xy 363.558424 -256.295605) (xy 363.572598 -256.309779) (xy 363.580264 -256.328301) (xy 363.58068 -256.338324)
			(xy 363.58068 -256.387346) (xy 363.781848 -256.387346) (xy 363.782389 -256.359054) (xy 363.791291 -256.303177)
			(xy 363.808927 -256.249414) (xy 363.834851 -256.19912) (xy 363.85119 -256.176018) (xy 363.855682 -256.169345)
			(xy 363.860732 -256.154082) (xy 363.861096 -256.146046) (xy 363.861096 -256.073148) (xy 363.861559 -256.06313)
			(xy 363.869212 -256.044615) (xy 363.883371 -256.030441) (xy 363.901879 -256.022769) (xy 363.911896 -256.022348)
			(xy 364.419896 -256.022348) (xy 364.429923 -256.022724) (xy 364.448449 -256.030402) (xy 364.462623 -256.044588)
			(xy 364.470285 -256.063121) (xy 364.470696 -256.073148) (xy 364.470696 -256.251202) (xy 364.470775 -256.255473)
			(xy 364.472187 -256.263898) (xy 364.47349 -256.267966) (xy 364.47984 -256.287524) (xy 364.489853 -256.287956)
			(xy 364.50835 -256.295633) (xy 364.522503 -256.309803) (xy 364.530157 -256.32831) (xy 364.53064 -256.338324)
			(xy 364.53064 -256.480056) (xy 365.02467 -256.480056) (xy 365.025085 -256.454925) (xy 365.032158 -256.405163)
			(xy 365.046156 -256.35689) (xy 365.066803 -256.311065) (xy 365.093688 -256.268597) (xy 365.126276 -256.230331)
			(xy 365.144812 -256.213356) (xy 365.148622 -256.209546) (xy 365.163009 -256.194636) (xy 365.196365 -256.170069)
			(xy 365.233819 -256.152366) (xy 365.253778 -256.146808) (xy 365.258858 -256.145284) (xy 365.288339 -256.135284)
			(xy 365.349653 -256.124547) (xy 365.380778 -256.123948) (xy 365.406347 -256.124368) (xy 365.456964 -256.131629)
			(xy 365.481616 -256.138426) (xy 365.488728 -256.140712) (xy 365.560356 -256.140712) (xy 365.560356 -256.144776)
			(xy 365.561009 -256.157188) (xy 365.572569 -256.179155) (xy 365.582454 -256.186686) (xy 365.588804 -256.191258)
			(xy 365.595452 -256.195602) (xy 365.610585 -256.20039) (xy 365.618522 -256.200656) (xy 365.774732 -256.200656)
			(xy 365.784736 -256.201161) (xy 365.80322 -256.208823) (xy 365.817371 -256.22297) (xy 365.825037 -256.241452)
			(xy 365.825532 -256.251456) (xy 365.825532 -256.659223) (xy 370.207268 -256.659223) (xy 370.207268 -256.609245)
			(xy 370.215087 -256.559882) (xy 370.230531 -256.51235) (xy 370.253221 -256.467818) (xy 370.282597 -256.427385)
			(xy 370.317937 -256.392045) (xy 370.35837 -256.362669) (xy 370.402902 -256.339979) (xy 370.450434 -256.324535)
			(xy 370.499797 -256.316716) (xy 370.549775 -256.316716) (xy 370.599138 -256.324535) (xy 370.64667 -256.339979)
			(xy 370.691202 -256.362669) (xy 370.731635 -256.392045) (xy 370.766975 -256.427385) (xy 370.796351 -256.467818)
			(xy 370.819041 -256.51235) (xy 370.834485 -256.559882) (xy 370.842304 -256.609245) (xy 370.842794 -256.634234)
			(xy 370.842304 -256.659223) (xy 372.087376 -256.659223) (xy 372.087376 -256.609245) (xy 372.095195 -256.559882)
			(xy 372.110639 -256.51235) (xy 372.133329 -256.467818) (xy 372.162705 -256.427385) (xy 372.198045 -256.392045)
			(xy 372.238478 -256.362669) (xy 372.28301 -256.339979) (xy 372.330542 -256.324535) (xy 372.379905 -256.316716)
			(xy 372.429883 -256.316716) (xy 372.479246 -256.324535) (xy 372.526778 -256.339979) (xy 372.57131 -256.362669)
			(xy 372.611743 -256.392045) (xy 372.647083 -256.427385) (xy 372.676459 -256.467818) (xy 372.699149 -256.51235)
			(xy 372.714593 -256.559882) (xy 372.722412 -256.609245) (xy 372.722902 -256.634234) (xy 372.722412 -256.659223)
			(xy 373.96723 -256.659223) (xy 373.96723 -256.609245) (xy 373.975049 -256.559882) (xy 373.990493 -256.51235)
			(xy 374.013183 -256.467818) (xy 374.042559 -256.427385) (xy 374.077899 -256.392045) (xy 374.118332 -256.362669)
			(xy 374.162864 -256.339979) (xy 374.210396 -256.324535) (xy 374.259759 -256.316716) (xy 374.309737 -256.316716)
			(xy 374.3591 -256.324535) (xy 374.406632 -256.339979) (xy 374.451164 -256.362669) (xy 374.491597 -256.392045)
			(xy 374.526937 -256.427385) (xy 374.556313 -256.467818) (xy 374.579003 -256.51235) (xy 374.594447 -256.559882)
			(xy 374.602266 -256.609245) (xy 374.602756 -256.634234) (xy 374.602266 -256.659223) (xy 375.847338 -256.659223)
			(xy 375.847338 -256.609245) (xy 375.855157 -256.559882) (xy 375.870601 -256.51235) (xy 375.893291 -256.467818)
			(xy 375.922667 -256.427385) (xy 375.958007 -256.392045) (xy 375.99844 -256.362669) (xy 376.042972 -256.339979)
			(xy 376.090504 -256.324535) (xy 376.139867 -256.316716) (xy 376.189845 -256.316716) (xy 376.239208 -256.324535)
			(xy 376.28674 -256.339979) (xy 376.331272 -256.362669) (xy 376.371705 -256.392045) (xy 376.407045 -256.427385)
			(xy 376.436421 -256.467818) (xy 376.459111 -256.51235) (xy 376.474555 -256.559882) (xy 376.482374 -256.609245)
			(xy 376.482864 -256.634234) (xy 376.788675 -256.634234) (xy 376.79277 -256.583506) (xy 376.804949 -256.534092)
			(xy 376.824897 -256.487272) (xy 376.852098 -256.444258) (xy 376.885846 -256.406164) (xy 376.925268 -256.373977)
			(xy 376.969342 -256.348531) (xy 377.016928 -256.330484) (xy 377.066792 -256.320304) (xy 377.117644 -256.318255)
			(xy 377.168165 -256.324389) (xy 377.217049 -256.338549) (xy 377.263028 -256.360366) (xy 377.304912 -256.389276)
			(xy 377.341616 -256.424531) (xy 377.372189 -256.465217) (xy 377.39584 -256.51028) (xy 377.411956 -256.558554)
			(xy 377.42012 -256.608788) (xy 377.420632 -256.634234) (xy 377.420129 -256.659223) (xy 378.667246 -256.659223)
			(xy 378.667246 -256.609245) (xy 378.675065 -256.559882) (xy 378.690509 -256.51235) (xy 378.713199 -256.467818)
			(xy 378.742575 -256.427385) (xy 378.777915 -256.392045) (xy 378.818348 -256.362669) (xy 378.86288 -256.339979)
			(xy 378.910412 -256.324535) (xy 378.959775 -256.316716) (xy 379.009753 -256.316716) (xy 379.059116 -256.324535)
			(xy 379.106648 -256.339979) (xy 379.15118 -256.362669) (xy 379.191613 -256.392045) (xy 379.226953 -256.427385)
			(xy 379.256329 -256.467818) (xy 379.279019 -256.51235) (xy 379.294463 -256.559882) (xy 379.302282 -256.609245)
			(xy 379.302772 -256.634234) (xy 379.302282 -256.659223) (xy 379.6073 -256.659223) (xy 379.6073 -256.609245)
			(xy 379.615119 -256.559882) (xy 379.630563 -256.51235) (xy 379.653253 -256.467818) (xy 379.682629 -256.427385)
			(xy 379.717969 -256.392045) (xy 379.758402 -256.362669) (xy 379.802934 -256.339979) (xy 379.850466 -256.324535)
			(xy 379.899829 -256.316716) (xy 379.949807 -256.316716) (xy 379.99917 -256.324535) (xy 380.046702 -256.339979)
			(xy 380.091234 -256.362669) (xy 380.131667 -256.392045) (xy 380.167007 -256.427385) (xy 380.196383 -256.467818)
			(xy 380.219073 -256.51235) (xy 380.234517 -256.559882) (xy 380.242336 -256.609245) (xy 380.242826 -256.634234)
			(xy 380.548637 -256.634234) (xy 380.552732 -256.583506) (xy 380.564911 -256.534092) (xy 380.584859 -256.487272)
			(xy 380.61206 -256.444258) (xy 380.645808 -256.406164) (xy 380.68523 -256.373977) (xy 380.729304 -256.348531)
			(xy 380.77689 -256.330484) (xy 380.826754 -256.320304) (xy 380.877606 -256.318255) (xy 380.928127 -256.324389)
			(xy 380.977011 -256.338549) (xy 381.02299 -256.360366) (xy 381.064874 -256.389276) (xy 381.101578 -256.424531)
			(xy 381.132151 -256.465217) (xy 381.155802 -256.51028) (xy 381.171918 -256.558554) (xy 381.180082 -256.608788)
			(xy 381.180594 -256.634234) (xy 381.180082 -256.65968) (xy 381.171918 -256.709914) (xy 381.155802 -256.758188)
			(xy 381.132151 -256.803251) (xy 381.101578 -256.843937) (xy 381.064874 -256.879192) (xy 381.02299 -256.908102)
			(xy 380.977011 -256.929919) (xy 380.928127 -256.944079) (xy 380.877606 -256.950213) (xy 380.826754 -256.948164)
			(xy 380.77689 -256.937984) (xy 380.729304 -256.919937) (xy 380.68523 -256.894491) (xy 380.645808 -256.862304)
			(xy 380.61206 -256.82421) (xy 380.584859 -256.781196) (xy 380.564911 -256.734376) (xy 380.552732 -256.684962)
			(xy 380.548637 -256.634234) (xy 380.242826 -256.634234) (xy 380.242336 -256.659223) (xy 380.234517 -256.708586)
			(xy 380.219073 -256.756118) (xy 380.196383 -256.80065) (xy 380.167007 -256.841083) (xy 380.131667 -256.876423)
			(xy 380.091234 -256.905799) (xy 380.046702 -256.928489) (xy 379.99917 -256.943933) (xy 379.949807 -256.951752)
			(xy 379.899829 -256.951752) (xy 379.850466 -256.943933) (xy 379.802934 -256.928489) (xy 379.758402 -256.905799)
			(xy 379.717969 -256.876423) (xy 379.682629 -256.841083) (xy 379.653253 -256.80065) (xy 379.630563 -256.756118)
			(xy 379.615119 -256.708586) (xy 379.6073 -256.659223) (xy 379.302282 -256.659223) (xy 379.294463 -256.708586)
			(xy 379.279019 -256.756118) (xy 379.256329 -256.80065) (xy 379.226953 -256.841083) (xy 379.191613 -256.876423)
			(xy 379.15118 -256.905799) (xy 379.106648 -256.928489) (xy 379.059116 -256.943933) (xy 379.009753 -256.951752)
			(xy 378.959775 -256.951752) (xy 378.910412 -256.943933) (xy 378.86288 -256.928489) (xy 378.818348 -256.905799)
			(xy 378.777915 -256.876423) (xy 378.742575 -256.841083) (xy 378.713199 -256.80065) (xy 378.690509 -256.756118)
			(xy 378.675065 -256.708586) (xy 378.667246 -256.659223) (xy 377.420129 -256.659223) (xy 377.42012 -256.65968)
			(xy 377.411956 -256.709914) (xy 377.39584 -256.758188) (xy 377.372189 -256.803251) (xy 377.341616 -256.843937)
			(xy 377.304912 -256.879192) (xy 377.263028 -256.908102) (xy 377.217049 -256.929919) (xy 377.168165 -256.944079)
			(xy 377.117644 -256.950213) (xy 377.066792 -256.948164) (xy 377.016928 -256.937984) (xy 376.969342 -256.919937)
			(xy 376.925268 -256.894491) (xy 376.885846 -256.862304) (xy 376.852098 -256.82421) (xy 376.824897 -256.781196)
			(xy 376.804949 -256.734376) (xy 376.79277 -256.684962) (xy 376.788675 -256.634234) (xy 376.482864 -256.634234)
			(xy 376.482374 -256.659223) (xy 376.474555 -256.708586) (xy 376.459111 -256.756118) (xy 376.436421 -256.80065)
			(xy 376.407045 -256.841083) (xy 376.371705 -256.876423) (xy 376.331272 -256.905799) (xy 376.28674 -256.928489)
			(xy 376.239208 -256.943933) (xy 376.189845 -256.951752) (xy 376.139867 -256.951752) (xy 376.090504 -256.943933)
			(xy 376.042972 -256.928489) (xy 375.99844 -256.905799) (xy 375.958007 -256.876423) (xy 375.922667 -256.841083)
			(xy 375.893291 -256.80065) (xy 375.870601 -256.756118) (xy 375.855157 -256.708586) (xy 375.847338 -256.659223)
			(xy 374.602266 -256.659223) (xy 374.594447 -256.708586) (xy 374.579003 -256.756118) (xy 374.556313 -256.80065)
			(xy 374.526937 -256.841083) (xy 374.491597 -256.876423) (xy 374.451164 -256.905799) (xy 374.406632 -256.928489)
			(xy 374.3591 -256.943933) (xy 374.309737 -256.951752) (xy 374.259759 -256.951752) (xy 374.210396 -256.943933)
			(xy 374.162864 -256.928489) (xy 374.118332 -256.905799) (xy 374.077899 -256.876423) (xy 374.042559 -256.841083)
			(xy 374.013183 -256.80065) (xy 373.990493 -256.756118) (xy 373.975049 -256.708586) (xy 373.96723 -256.659223)
			(xy 372.722412 -256.659223) (xy 372.714593 -256.708586) (xy 372.699149 -256.756118) (xy 372.676459 -256.80065)
			(xy 372.647083 -256.841083) (xy 372.611743 -256.876423) (xy 372.57131 -256.905799) (xy 372.526778 -256.928489)
			(xy 372.479246 -256.943933) (xy 372.429883 -256.951752) (xy 372.379905 -256.951752) (xy 372.330542 -256.943933)
			(xy 372.28301 -256.928489) (xy 372.238478 -256.905799) (xy 372.198045 -256.876423) (xy 372.162705 -256.841083)
			(xy 372.133329 -256.80065) (xy 372.110639 -256.756118) (xy 372.095195 -256.708586) (xy 372.087376 -256.659223)
			(xy 370.842304 -256.659223) (xy 370.834485 -256.708586) (xy 370.819041 -256.756118) (xy 370.796351 -256.80065)
			(xy 370.766975 -256.841083) (xy 370.731635 -256.876423) (xy 370.691202 -256.905799) (xy 370.64667 -256.928489)
			(xy 370.599138 -256.943933) (xy 370.549775 -256.951752) (xy 370.499797 -256.951752) (xy 370.450434 -256.943933)
			(xy 370.402902 -256.928489) (xy 370.35837 -256.905799) (xy 370.317937 -256.876423) (xy 370.282597 -256.841083)
			(xy 370.253221 -256.80065) (xy 370.230531 -256.756118) (xy 370.215087 -256.708586) (xy 370.207268 -256.659223)
			(xy 365.825532 -256.659223) (xy 365.825532 -256.758948) (xy 365.825052 -256.768955) (xy 365.817383 -256.787441)
			(xy 365.803228 -256.801592) (xy 365.784739 -256.809255) (xy 365.774732 -256.809748) (xy 365.560356 -256.809748)
			(xy 365.560356 -256.818892) (xy 365.559973 -256.828918) (xy 365.552297 -256.847443) (xy 365.538113 -256.861618)
			(xy 365.519583 -256.86928) (xy 365.509556 -256.869692) (xy 365.305594 -256.869692) (xy 365.284996 -256.869244)
			(xy 365.244572 -256.861306) (xy 365.20642 -256.845765) (xy 365.171956 -256.823197) (xy 365.142458 -256.794439)
			(xy 365.119022 -256.760559) (xy 365.102516 -256.722815) (xy 365.097568 -256.702814) (xy 365.096337 -256.697986)
			(xy 365.092233 -256.688907) (xy 365.08944 -256.68478) (xy 365.074188 -256.662158) (xy 365.049986 -256.613264)
			(xy 365.033527 -256.56125) (xy 365.025195 -256.507334) (xy 365.02467 -256.480056) (xy 364.53064 -256.480056)
			(xy 364.53064 -256.542286) (xy 364.530163 -256.563349) (xy 364.52191 -256.604659) (xy 364.50572 -256.64355)
			(xy 364.482223 -256.678514) (xy 364.452328 -256.708195) (xy 364.417197 -256.731442) (xy 364.37819 -256.747352)
			(xy 364.336822 -256.755309) (xy 364.315756 -256.755646) (xy 364.315502 -256.755392) (xy 364.01629 -256.755392)
			(xy 364.016036 -256.755646) (xy 363.994971 -256.755305) (xy 363.953605 -256.747347) (xy 363.9146 -256.731436)
			(xy 363.87947 -256.70819) (xy 363.849578 -256.678509) (xy 363.826082 -256.643546) (xy 363.809893 -256.604657)
			(xy 363.80164 -256.563348) (xy 363.801152 -256.542286) (xy 363.801152 -256.503678) (xy 363.798866 -256.496058)
			(xy 363.790918 -256.469586) (xy 363.782369 -256.414981) (xy 363.781848 -256.387346) (xy 363.58068 -256.387346)
			(xy 363.58068 -256.542286) (xy 363.580163 -256.563347) (xy 363.571912 -256.604652) (xy 363.555726 -256.643539)
			(xy 363.532234 -256.678501) (xy 363.502346 -256.708181) (xy 363.467221 -256.731429) (xy 363.428221 -256.747342)
			(xy 363.38686 -256.755305) (xy 363.365796 -256.755646) (xy 363.365542 -256.755392) (xy 363.06633 -256.755392)
			(xy 363.066076 -256.755646) (xy 363.045009 -256.75536) (xy 363.00364 -256.747391) (xy 362.964635 -256.73147)
			(xy 362.929506 -256.708215) (xy 362.899614 -256.678528) (xy 362.876119 -256.643559) (xy 362.859932 -256.604664)
			(xy 362.85168 -256.563351) (xy 362.851192 -256.542286) (xy 362.851192 -256.503678) (xy 362.848906 -256.496058)
			(xy 362.840956 -256.469586) (xy 362.832409 -256.414981) (xy 362.831888 -256.387346) (xy 362.63072 -256.387346)
			(xy 362.63072 -256.542286) (xy 362.630263 -256.56335) (xy 362.622009 -256.604663) (xy 362.605818 -256.643556)
			(xy 362.582317 -256.678521) (xy 362.55242 -256.708203) (xy 362.517284 -256.731448) (xy 362.478275 -256.747357)
			(xy 362.436903 -256.755311) (xy 362.415836 -256.755646) (xy 362.415582 -256.755392) (xy 362.11637 -256.755392)
			(xy 362.116116 -256.755646) (xy 362.09505 -256.755323) (xy 362.053683 -256.747361) (xy 362.014679 -256.731447)
			(xy 361.979549 -256.708198) (xy 361.949657 -256.678515) (xy 361.926161 -256.64355) (xy 361.909973 -256.604659)
			(xy 361.90172 -256.563349) (xy 361.901232 -256.542286) (xy 361.901232 -256.503678) (xy 361.898946 -256.496058)
			(xy 361.890997 -256.469586) (xy 361.882449 -256.414981) (xy 361.881928 -256.387346) (xy 361.68076 -256.387346)
			(xy 361.68076 -256.542286) (xy 361.680263 -256.563348) (xy 361.672011 -256.604656) (xy 361.655823 -256.643545)
			(xy 361.632328 -256.678508) (xy 361.602437 -256.708188) (xy 361.567309 -256.731435) (xy 361.528306 -256.747347)
			(xy 361.486941 -256.755307) (xy 361.465876 -256.755646) (xy 361.465622 -256.755392) (xy 361.16641 -256.755392)
			(xy 361.166156 -256.755646) (xy 361.145091 -256.755286) (xy 361.103726 -256.747332) (xy 361.064722 -256.731425)
			(xy 361.029592 -256.708181) (xy 360.999699 -256.678504) (xy 360.976202 -256.643543) (xy 360.960013 -256.604654)
			(xy 360.95176 -256.563348) (xy 360.951272 -256.542286) (xy 360.951272 -256.503678) (xy 360.948986 -256.496058)
			(xy 360.941038 -256.469585) (xy 360.932489 -256.414981) (xy 360.931968 -256.387346) (xy 360.7308 -256.387346)
			(xy 360.7308 -256.542286) (xy 360.730263 -256.563345) (xy 360.722013 -256.604648) (xy 360.705829 -256.643534)
			(xy 360.682339 -256.678494) (xy 360.652454 -256.708174) (xy 360.617333 -256.731422) (xy 360.578337 -256.747338)
			(xy 360.536978 -256.755303) (xy 360.515916 -256.755646) (xy 360.515662 -256.755392) (xy 360.21645 -256.755392)
			(xy 360.216196 -256.755646) (xy 360.19513 -256.755341) (xy 360.153762 -256.747376) (xy 360.114757 -256.731458)
			(xy 360.079628 -256.708206) (xy 360.049736 -256.678521) (xy 360.02624 -256.643554) (xy 360.010053 -256.604661)
			(xy 360.0018 -256.56335) (xy 360.001312 -256.542286) (xy 360.001312 -256.50444) (xy 359.999026 -256.49682)
			(xy 359.990972 -256.47017) (xy 359.982292 -256.415181) (xy 359.981754 -256.387346) (xy 359.78084 -256.387346)
			(xy 359.78084 -256.542286) (xy 359.780363 -256.563349) (xy 359.77211 -256.604659) (xy 359.75592 -256.64355)
			(xy 359.732423 -256.678514) (xy 359.702528 -256.708195) (xy 359.667397 -256.731442) (xy 359.62839 -256.747352)
			(xy 359.587022 -256.755309) (xy 359.565956 -256.755646) (xy 359.565702 -256.755392) (xy 359.26649 -256.755392)
			(xy 359.266236 -256.755646) (xy 359.245171 -256.755305) (xy 359.203805 -256.747347) (xy 359.1648 -256.731436)
			(xy 359.12967 -256.70819) (xy 359.099778 -256.678509) (xy 359.076282 -256.643546) (xy 359.060093 -256.604657)
			(xy 359.05184 -256.563348) (xy 359.051352 -256.542286) (xy 359.051352 -256.50444) (xy 359.049066 -256.49682)
			(xy 359.041013 -256.47017) (xy 359.032332 -256.415181) (xy 359.031794 -256.387346) (xy 358.830372 -256.387346)
			(xy 358.830372 -256.542286) (xy 358.829863 -256.563331) (xy 358.821624 -256.604607) (xy 358.805461 -256.643471)
			(xy 358.782001 -256.678417) (xy 358.752152 -256.708092) (xy 358.71707 -256.731348) (xy 358.678113 -256.747284)
			(xy 358.63679 -256.755282) (xy 358.615742 -256.755646) (xy 358.615488 -256.755392) (xy 358.316276 -256.755392)
			(xy 358.316022 -256.755646) (xy 358.294971 -256.755338) (xy 358.253642 -256.747332) (xy 358.214681 -256.731388)
			(xy 358.179595 -256.708125) (xy 358.149743 -256.678442) (xy 358.126282 -256.643488) (xy 358.110118 -256.604618)
			(xy 358.101878 -256.563335) (xy 358.101392 -256.542286) (xy 358.101392 -256.503678) (xy 358.098852 -256.496058)
			(xy 358.090903 -256.469586) (xy 358.082355 -256.414981) (xy 358.081834 -256.387346) (xy 357.880412 -256.387346)
			(xy 357.880412 -256.542286) (xy 357.879963 -256.563335) (xy 357.871721 -256.604618) (xy 357.855553 -256.643487)
			(xy 357.832085 -256.678437) (xy 357.802226 -256.708114) (xy 357.767134 -256.731368) (xy 357.728166 -256.747298)
			(xy 357.686834 -256.755288) (xy 357.665782 -256.755646) (xy 357.665528 -256.755392) (xy 357.366316 -256.755392)
			(xy 357.366062 -256.755646) (xy 357.345012 -256.755301) (xy 357.303685 -256.747302) (xy 357.264724 -256.731365)
			(xy 357.229638 -256.708108) (xy 357.199786 -256.67843) (xy 357.176323 -256.64348) (xy 357.160159 -256.604613)
			(xy 357.151919 -256.563333) (xy 357.151432 -256.542286) (xy 357.151432 -256.503678) (xy 357.148892 -256.496058)
			(xy 357.140942 -256.469586) (xy 357.132395 -256.414981) (xy 357.131874 -256.387346) (xy 356.930452 -256.387346)
			(xy 356.930452 -256.542286) (xy 356.929963 -256.563332) (xy 356.921723 -256.604611) (xy 356.905558 -256.643476)
			(xy 356.882096 -256.678423) (xy 356.852243 -256.708099) (xy 356.817158 -256.731354) (xy 356.778197 -256.747288)
			(xy 356.736871 -256.755284) (xy 356.715822 -256.755646) (xy 356.715568 -256.755392) (xy 356.416356 -256.755392)
			(xy 356.416102 -256.755646) (xy 356.395054 -256.755264) (xy 356.353728 -256.747273) (xy 356.314767 -256.731343)
			(xy 356.279681 -256.708091) (xy 356.249828 -256.678418) (xy 356.226364 -256.643472) (xy 356.210199 -256.604609)
			(xy 356.201959 -256.563332) (xy 356.201472 -256.542286) (xy 356.201472 -256.503678) (xy 356.198932 -256.496058)
			(xy 356.190983 -256.469586) (xy 356.182435 -256.414981) (xy 356.181914 -256.387346) (xy 355.980492 -256.387346)
			(xy 355.980492 -256.542286) (xy 355.979963 -256.56333) (xy 355.971725 -256.604604) (xy 355.955564 -256.643465)
			(xy 355.932107 -256.67841) (xy 355.902261 -256.708085) (xy 355.867182 -256.731341) (xy 355.828229 -256.747279)
			(xy 355.786908 -256.75528) (xy 355.765862 -256.755646) (xy 355.765608 -256.755392) (xy 355.466396 -256.755392)
			(xy 355.466142 -256.755646) (xy 355.445092 -256.755319) (xy 355.403764 -256.747317) (xy 355.364802 -256.731377)
			(xy 355.329717 -256.708116) (xy 355.299865 -256.678435) (xy 355.276403 -256.643484) (xy 355.260239 -256.604615)
			(xy 355.251999 -256.563334) (xy 355.251512 -256.542286) (xy 355.251512 -256.503678) (xy 355.248972 -256.496058)
			(xy 355.241024 -256.469586) (xy 355.232475 -256.414981) (xy 355.231954 -256.387346) (xy 354.688735 -256.387346)
			(xy 354.694054 -256.405962) (xy 354.700933 -256.455198) (xy 354.701348 -256.480056) (xy 354.70092 -256.504628)
			(xy 354.694163 -256.553307) (xy 354.680784 -256.600595) (xy 354.661036 -256.645598) (xy 354.648516 -256.666746)
			(xy 354.645844 -256.671264) (xy 354.642257 -256.681125) (xy 354.641404 -256.686304) (xy 354.637768 -256.707801)
			(xy 354.623009 -256.748817) (xy 354.600247 -256.785993) (xy 354.570427 -256.817788) (xy 354.534785 -256.842883)
			(xy 354.494798 -256.860238) (xy 354.452124 -256.869134) (xy 354.43033 -256.869692) (xy 354.175568 -256.869692)
			(xy 354.175568 -256.860548) (xy 354.17514 -256.850526) (xy 354.16748 -256.832004) (xy 354.15331 -256.817829)
			(xy 354.13479 -256.810163) (xy 354.124768 -256.809748) (xy 353.624896 -256.809748) (xy 353.624896 -256.818892)
			(xy 353.624474 -256.828913) (xy 353.616806 -256.847431) (xy 353.602634 -256.861604) (xy 353.584117 -256.869273)
			(xy 353.574096 -256.869692) (xy 353.370134 -256.869692) (xy 353.348168 -256.869229) (xy 353.305158 -256.860279)
			(xy 353.264885 -256.842728) (xy 353.229048 -256.817319) (xy 353.199159 -256.785122) (xy 353.176481 -256.747497)
			(xy 353.168712 -256.726944) (xy 353.167101 -256.722535) (xy 353.162496 -256.714357) (xy 353.159568 -256.710688)
			(xy 353.143648 -256.691277) (xy 353.116811 -256.648851) (xy 353.096201 -256.603076) (xy 353.082227 -256.554859)
			(xy 353.075166 -256.505157) (xy 353.074732 -256.480056) (xy 351.069094 -256.480056) (xy 351.084768 -256.510821)
			(xy 351.100211 -256.558355) (xy 351.108028 -256.60772) (xy 351.108518 -256.63271) (xy 351.108518 -256.632964)
			(xy 351.107923 -256.660993) (xy 351.098078 -256.716181) (xy 351.08896 -256.742692) (xy 351.085912 -256.751074)
			(xy 351.085912 -256.883916) (xy 351.085912 -256.88417) (xy 351.08563 -256.905223) (xy 351.077624 -256.946555)
			(xy 351.061679 -256.98552) (xy 351.038412 -257.020608) (xy 351.008725 -257.05046) (xy 350.973766 -257.073921)
			(xy 350.93489 -257.090082) (xy 350.893603 -257.098317) (xy 350.872552 -257.0988) (xy 350.617536 -257.0988)
			(xy 350.617536 -257.089656) (xy 350.617049 -257.07965) (xy 350.609381 -257.061164) (xy 350.595229 -257.047014)
			(xy 350.576742 -257.03935) (xy 350.566736 -257.038856) (xy 350.403668 -257.038856) (xy 350.393639 -257.038506)
			(xy 350.375113 -257.030817) (xy 350.36094 -257.016623) (xy 350.353279 -256.998085) (xy 350.352868 -256.988056)
			(xy 349.154896 -256.988056) (xy 349.133346 -257.020554) (xy 349.103671 -257.050395) (xy 349.068726 -257.073846)
			(xy 349.029866 -257.090001) (xy 348.988594 -257.098233) (xy 348.967552 -257.0988) (xy 348.73057 -257.0988)
			(xy 348.720674 -257.099225) (xy 348.702404 -257.106834) (xy 348.688454 -257.120874) (xy 348.680963 -257.139193)
			(xy 348.680532 -257.149092) (xy 348.680532 -257.430016) (xy 353.074732 -257.430016) (xy 353.075227 -257.402029)
			(xy 353.083982 -257.346744) (xy 353.101278 -257.29351) (xy 353.12669 -257.243637) (xy 353.159591 -257.198354)
			(xy 353.199172 -257.158776) (xy 353.244457 -257.125877) (xy 353.294332 -257.100469) (xy 353.347568 -257.083176)
			(xy 353.402853 -257.074426) (xy 353.43084 -257.073908) (xy 353.431602 -257.073908) (xy 353.45698 -257.074357)
			(xy 353.507213 -257.081626) (xy 353.531678 -257.088386) (xy 353.53879 -257.090672) (xy 353.595178 -257.090672)
			(xy 353.624896 -257.12039) (xy 353.624896 -257.131566) (xy 353.638866 -257.141218) (xy 353.645525 -257.145544)
			(xy 353.660649 -257.150344) (xy 353.668584 -257.150616) (xy 354.107496 -257.150616) (xy 354.11545 -257.15028)
			(xy 354.130583 -257.145368) (xy 354.137214 -257.140964) (xy 354.146463 -257.134466) (xy 354.165654 -257.122518)
			(xy 354.175568 -257.117088) (xy 354.175568 -257.090672) (xy 354.23729 -257.090672) (xy 354.244402 -257.088386)
			(xy 354.269058 -257.081607) (xy 354.319673 -257.074335) (xy 354.34524 -257.073908) (xy 354.373138 -257.074432)
			(xy 354.428255 -257.083116) (xy 354.454968 -257.09118) (xy 354.462842 -257.092958) (xy 354.481343 -257.096227)
			(xy 354.516897 -257.108358) (xy 354.549771 -257.126538) (xy 354.578947 -257.150203) (xy 354.603518 -257.178619)
			(xy 354.613464 -257.194558) (xy 354.61829 -257.201162) (xy 354.633902 -257.220509) (xy 354.660203 -257.262694)
			(xy 354.680382 -257.308127) (xy 354.694047 -257.355925) (xy 354.700931 -257.405159) (xy 354.701348 -257.430016)
			(xy 354.700948 -257.454589) (xy 354.694182 -257.503269) (xy 354.680795 -257.550557) (xy 354.66104 -257.595559)
			(xy 354.648516 -257.616706) (xy 354.645855 -257.621229) (xy 354.642261 -257.631087) (xy 354.641404 -257.636264)
			(xy 354.637813 -257.65777) (xy 354.623043 -257.698785) (xy 354.600272 -257.73596) (xy 354.591813 -257.744976)
			(xy 355.501702 -257.744976) (xy 355.502075 -257.721102) (xy 355.508469 -257.673784) (xy 355.521139 -257.627748)
			(xy 355.539857 -257.583822) (xy 355.55174 -257.563112) (xy 355.553718 -257.559588) (xy 355.556654 -257.552059)
			(xy 355.557582 -257.548126) (xy 355.562466 -257.528038) (xy 355.578902 -257.49011) (xy 355.60232 -257.456048)
			(xy 355.631848 -257.427121) (xy 355.666384 -257.404408) (xy 355.704642 -257.388756) (xy 355.745195 -257.380748)
			(xy 355.765862 -257.380232) (xy 355.990906 -257.380232) (xy 356.020624 -257.40995) (xy 356.020624 -257.428238)
			(xy 356.031292 -257.433826) (xy 356.03697 -257.436727) (xy 356.049304 -257.439942) (xy 356.055676 -257.440176)
			(xy 356.571296 -257.440176) (xy 356.571296 -257.431032) (xy 356.571746 -257.421013) (xy 356.579404 -257.402498)
			(xy 356.593568 -257.388325) (xy 356.612078 -257.380653) (xy 356.622096 -257.380232) (xy 356.826058 -257.380232)
			(xy 356.84613 -257.380666) (xy 356.885563 -257.388189) (xy 356.922891 -257.402957) (xy 356.956797 -257.42445)
			(xy 356.986082 -257.451907) (xy 356.99827 -257.467862) (xy 357.00589 -257.476244) (xy 357.026411 -257.494847)
			(xy 357.062059 -257.537233) (xy 357.090718 -257.584625) (xy 357.111698 -257.635882) (xy 357.124492 -257.689768)
			(xy 357.128793 -257.744984) (xy 357.124497 -257.800201) (xy 357.111707 -257.854088) (xy 357.090732 -257.905347)
			(xy 357.062077 -257.952742) (xy 357.026433 -257.995131) (xy 357.022181 -257.998976) (xy 358.806496 -257.998976)
			(xy 358.806496 -257.490976) (xy 358.806968 -257.480967) (xy 358.814635 -257.462476) (xy 358.828792 -257.448324)
			(xy 358.847287 -257.440664) (xy 358.857296 -257.440176) (xy 359.071164 -257.440176) (xy 359.071164 -257.431032)
			(xy 359.071713 -257.421031) (xy 359.079356 -257.402547) (xy 359.093489 -257.388394) (xy 359.111963 -257.380727)
			(xy 359.121964 -257.380232) (xy 359.32618 -257.380232) (xy 359.346253 -257.38065) (xy 359.385686 -257.388177)
			(xy 359.423015 -257.402949) (xy 359.456921 -257.424445) (xy 359.486205 -257.451906) (xy 359.498392 -257.467862)
			(xy 359.506012 -257.476244) (xy 359.526532 -257.494847) (xy 359.562178 -257.537234) (xy 359.590835 -257.584627)
			(xy 359.611813 -257.635883) (xy 359.624607 -257.689768) (xy 359.628908 -257.744984) (xy 359.624612 -257.800201)
			(xy 359.611823 -257.854087) (xy 359.590849 -257.905345) (xy 359.562196 -257.95274) (xy 359.526554 -257.99513)
			(xy 359.522301 -257.998976) (xy 361.056428 -257.998976) (xy 361.056428 -257.490976) (xy 361.056801 -257.48095)
			(xy 361.064484 -257.462427) (xy 361.078671 -257.448255) (xy 361.097201 -257.440591) (xy 361.107228 -257.440176)
			(xy 361.321096 -257.440176) (xy 361.321096 -257.431032) (xy 361.321546 -257.421013) (xy 361.329204 -257.402498)
			(xy 361.343368 -257.388325) (xy 361.361878 -257.380653) (xy 361.371896 -257.380232) (xy 361.576112 -257.380232)
			(xy 361.596182 -257.380699) (xy 361.635614 -257.388213) (xy 361.672942 -257.402974) (xy 361.706849 -257.424459)
			(xy 361.736135 -257.45191) (xy 361.748324 -257.467862) (xy 361.755944 -257.476244) (xy 361.776462 -257.494848)
			(xy 361.812105 -257.537236) (xy 361.84076 -257.584629) (xy 361.861736 -257.635885) (xy 361.874528 -257.689769)
			(xy 361.878829 -257.744984) (xy 361.874533 -257.800199) (xy 361.861746 -257.854085) (xy 361.840774 -257.905343)
			(xy 361.812123 -257.952738) (xy 361.776484 -257.995129) (xy 361.772231 -257.998976) (xy 363.656372 -257.998976)
			(xy 363.656372 -257.490976) (xy 363.656868 -257.48097) (xy 363.66453 -257.462483) (xy 363.67868 -257.448332)
			(xy 363.697166 -257.440668) (xy 363.707172 -257.440176) (xy 363.92104 -257.440176) (xy 363.92104 -257.431032)
			(xy 363.921447 -257.421008) (xy 363.929114 -257.402484) (xy 363.943291 -257.388309) (xy 363.961816 -257.380645)
			(xy 363.97184 -257.380232) (xy 364.176056 -257.380232) (xy 364.196128 -257.380668) (xy 364.235561 -257.38819)
			(xy 364.272889 -257.402958) (xy 364.306795 -257.42445) (xy 364.312732 -257.430016) (xy 365.02467 -257.430016)
			(xy 365.025126 -257.404886) (xy 365.03219 -257.355126) (xy 365.046181 -257.306854) (xy 365.06682 -257.261028)
			(xy 365.093697 -257.21856) (xy 365.126279 -257.180292) (xy 365.144812 -257.163316) (xy 365.148622 -257.159506)
			(xy 365.163003 -257.144589) (xy 365.196362 -257.120026) (xy 365.233818 -257.102325) (xy 365.253778 -257.096768)
			(xy 365.258858 -257.095244) (xy 365.288338 -257.085243) (xy 365.349653 -257.074507) (xy 365.380778 -257.073908)
			(xy 365.406346 -257.074329) (xy 365.456964 -257.08159) (xy 365.481616 -257.088386) (xy 365.488728 -257.090672)
			(xy 365.560356 -257.090672) (xy 365.560356 -257.094736) (xy 365.560973 -257.107153) (xy 365.572559 -257.129119)
			(xy 365.582454 -257.136646) (xy 365.588804 -257.141218) (xy 365.595455 -257.145559) (xy 365.610585 -257.15035)
			(xy 365.618522 -257.150616) (xy 365.774732 -257.150616) (xy 365.784744 -257.151062) (xy 365.803239 -257.158735)
			(xy 365.817392 -257.172901) (xy 365.825047 -257.191404) (xy 365.825532 -257.201416) (xy 365.825532 -257.708908)
			(xy 365.825019 -257.718912) (xy 365.817363 -257.737398) (xy 365.803218 -257.751549) (xy 365.784736 -257.759214)
			(xy 365.774732 -257.759708) (xy 365.560356 -257.759708) (xy 365.560356 -257.768852) (xy 365.55994 -257.778876)
			(xy 365.552278 -257.7974) (xy 365.538103 -257.811576) (xy 365.51958 -257.819239) (xy 365.509556 -257.819652)
			(xy 365.305594 -257.819652) (xy 365.284999 -257.819157) (xy 365.244581 -257.811222) (xy 365.206433 -257.795686)
			(xy 365.171971 -257.773125) (xy 365.142473 -257.744376) (xy 365.119033 -257.710506) (xy 365.102521 -257.67277)
			(xy 365.097568 -257.652774) (xy 365.096322 -257.64795) (xy 365.092229 -257.638869) (xy 365.08944 -257.63474)
			(xy 365.074171 -257.612129) (xy 365.049973 -257.563231) (xy 365.033518 -257.511214) (xy 365.025192 -257.457295)
			(xy 365.02467 -257.430016) (xy 364.312732 -257.430016) (xy 364.33608 -257.451907) (xy 364.348268 -257.467862)
			(xy 364.355888 -257.476244) (xy 364.376409 -257.494847) (xy 364.412057 -257.537233) (xy 364.440717 -257.584625)
			(xy 364.461696 -257.635882) (xy 364.474491 -257.689767) (xy 364.478792 -257.744984) (xy 364.474496 -257.800201)
			(xy 364.461706 -257.854088) (xy 364.440731 -257.905347) (xy 364.425748 -257.930128) (xy 368.793081 -257.930128)
			(xy 368.797374 -257.874915) (xy 368.810159 -257.821031) (xy 368.831128 -257.769774) (xy 368.859776 -257.72238)
			(xy 368.895412 -257.679989) (xy 368.91595 -257.66141) (xy 368.92357 -257.653028) (xy 368.935779 -257.637111)
			(xy 368.965096 -257.609736) (xy 368.999008 -257.588315) (xy 369.036322 -257.573601) (xy 369.075727 -257.56611)
			(xy 369.095782 -257.565652) (xy 369.350544 -257.565652) (xy 369.350544 -257.574796) (xy 369.350924 -257.584823)
			(xy 369.358601 -257.603348) (xy 369.372786 -257.617522) (xy 369.391317 -257.625184) (xy 369.401344 -257.625596)
			(xy 369.56492 -257.625596) (xy 369.574928 -257.626071) (xy 369.59342 -257.633737) (xy 369.607572 -257.647893)
			(xy 369.615232 -257.666387) (xy 369.61572 -257.676396) (xy 369.61572 -257.930128) (xy 370.718664 -257.930128)
			(xy 370.722957 -257.874915) (xy 370.735741 -257.821032) (xy 370.756708 -257.769776) (xy 370.785353 -257.722382)
			(xy 370.820987 -257.67999) (xy 370.841524 -257.66141) (xy 370.849144 -257.653028) (xy 370.861368 -257.637123)
			(xy 370.890681 -257.609748) (xy 370.924589 -257.588325) (xy 370.9619 -257.573607) (xy 371.001302 -257.566113)
			(xy 371.021356 -257.565652) (xy 371.276372 -257.565652) (xy 371.276372 -257.574796) (xy 371.276891 -257.5848)
			(xy 371.284544 -257.603286) (xy 371.298687 -257.617438) (xy 371.317168 -257.625103) (xy 371.327172 -257.625596)
			(xy 371.49024 -257.625596) (xy 371.50025 -257.626055) (xy 371.518742 -257.633727) (xy 371.532893 -257.647889)
			(xy 371.540552 -257.666386) (xy 371.54104 -257.676396) (xy 371.54104 -257.930128) (xy 372.496664 -257.930128)
			(xy 372.500957 -257.874915) (xy 372.513741 -257.821032) (xy 372.534708 -257.769776) (xy 372.563353 -257.722382)
			(xy 372.598987 -257.67999) (xy 372.619524 -257.66141) (xy 372.627144 -257.653028) (xy 372.639368 -257.637123)
			(xy 372.668681 -257.609748) (xy 372.702589 -257.588325) (xy 372.7399 -257.573607) (xy 372.779302 -257.566113)
			(xy 372.799356 -257.565652) (xy 373.054372 -257.565652) (xy 373.054372 -257.574796) (xy 373.054891 -257.5848)
			(xy 373.062544 -257.603286) (xy 373.076687 -257.617438) (xy 373.095168 -257.625103) (xy 373.105172 -257.625596)
			(xy 373.26824 -257.625596) (xy 373.27825 -257.626055) (xy 373.296742 -257.633727) (xy 373.310893 -257.647889)
			(xy 373.318552 -257.666386) (xy 373.31904 -257.676396) (xy 373.31904 -258.183888) (xy 373.318503 -258.19389)
			(xy 373.310855 -258.212374) (xy 373.296717 -258.226526) (xy 373.278241 -258.234193) (xy 373.26824 -258.234688)
			(xy 373.054372 -258.234688) (xy 373.054372 -258.243832) (xy 373.053937 -258.253845) (xy 373.046262 -258.272343)
			(xy 373.032093 -258.286496) (xy 373.013586 -258.294149) (xy 373.003572 -258.294632) (xy 372.799356 -258.294632)
			(xy 372.779301 -258.294161) (xy 372.739895 -258.28668) (xy 372.70258 -258.27197) (xy 372.668669 -258.250549)
			(xy 372.639355 -258.223171) (xy 372.627144 -258.207256) (xy 372.619524 -258.198874) (xy 372.599026 -258.18025)
			(xy 372.563386 -258.137863) (xy 372.534733 -258.090473) (xy 372.513758 -258.03922) (xy 372.500965 -257.985339)
			(xy 372.496664 -257.930128) (xy 371.54104 -257.930128) (xy 371.54104 -258.183888) (xy 371.540503 -258.19389)
			(xy 371.532855 -258.212374) (xy 371.518717 -258.226526) (xy 371.500241 -258.234193) (xy 371.49024 -258.234688)
			(xy 371.276372 -258.234688) (xy 371.276372 -258.243832) (xy 371.275937 -258.253845) (xy 371.268262 -258.272343)
			(xy 371.254093 -258.286496) (xy 371.235586 -258.294149) (xy 371.225572 -258.294632) (xy 371.021356 -258.294632)
			(xy 371.001301 -258.294161) (xy 370.961895 -258.28668) (xy 370.92458 -258.27197) (xy 370.890669 -258.250549)
			(xy 370.861355 -258.223171) (xy 370.849144 -258.207256) (xy 370.841524 -258.198874) (xy 370.821026 -258.18025)
			(xy 370.785386 -258.137863) (xy 370.756733 -258.090473) (xy 370.735758 -258.03922) (xy 370.722965 -257.985339)
			(xy 370.718664 -257.930128) (xy 369.61572 -257.930128) (xy 369.61572 -258.183888) (xy 369.615203 -258.193892)
			(xy 369.607551 -258.21238) (xy 369.593407 -258.226533) (xy 369.574924 -258.234196) (xy 369.56492 -258.234688)
			(xy 369.350544 -258.234688) (xy 369.350544 -258.243832) (xy 369.350039 -258.253836) (xy 369.342377 -258.27232)
			(xy 369.32823 -258.286471) (xy 369.309748 -258.294137) (xy 369.299744 -258.294632) (xy 369.095782 -258.294632)
			(xy 369.075728 -258.294142) (xy 369.036323 -258.286666) (xy 368.999008 -258.27196) (xy 368.965096 -258.250544)
			(xy 368.935782 -258.22317) (xy 368.92357 -258.207256) (xy 368.91595 -258.198874) (xy 368.89545 -258.18025)
			(xy 368.859808 -258.137865) (xy 368.831153 -258.090475) (xy 368.810176 -258.039222) (xy 368.797383 -257.98534)
			(xy 368.793081 -257.930128) (xy 364.425748 -257.930128) (xy 364.412076 -257.952742) (xy 364.376431 -257.995131)
			(xy 364.355888 -258.013708) (xy 364.348268 -258.02209) (xy 364.336058 -258.03802) (xy 364.306754 -258.065438)
			(xy 364.272849 -258.086909) (xy 364.235535 -258.10168) (xy 364.196121 -258.109231) (xy 364.176056 -258.10972)
			(xy 363.92104 -258.10972) (xy 363.92104 -258.100576) (xy 363.920533 -258.090572) (xy 363.912873 -258.072087)
			(xy 363.898726 -258.057936) (xy 363.880244 -258.05027) (xy 363.87024 -258.049776) (xy 363.707172 -258.049776)
			(xy 363.69716 -258.049334) (xy 363.678663 -258.041661) (xy 363.66451 -258.027494) (xy 363.656855 -258.008989)
			(xy 363.656372 -257.998976) (xy 361.772231 -257.998976) (xy 361.755944 -258.013708) (xy 361.748324 -258.02209)
			(xy 361.73614 -258.038041) (xy 361.706829 -258.065457) (xy 361.672918 -258.086925) (xy 361.635598 -258.10169)
			(xy 361.596179 -258.109235) (xy 361.576112 -258.10972) (xy 361.321096 -258.10972) (xy 361.321096 -258.100576)
			(xy 361.320632 -258.090566) (xy 361.312963 -258.072073) (xy 361.298803 -258.057921) (xy 361.280306 -258.050263)
			(xy 361.270296 -258.049776) (xy 361.107228 -258.049776) (xy 361.097206 -258.049357) (xy 361.078685 -258.041692)
			(xy 361.064511 -258.027519) (xy 361.056844 -258.008998) (xy 361.056428 -257.998976) (xy 359.522301 -257.998976)
			(xy 359.506012 -258.013708) (xy 359.498392 -258.02209) (xy 359.486168 -258.038008) (xy 359.456867 -258.065428)
			(xy 359.422966 -258.086901) (xy 359.385655 -258.101674) (xy 359.346244 -258.109229) (xy 359.32618 -258.10972)
			(xy 359.071164 -258.10972) (xy 359.071164 -258.100576) (xy 359.070799 -258.090549) (xy 359.063114 -258.072024)
			(xy 359.048925 -258.057852) (xy 359.030392 -258.050189) (xy 359.020364 -258.049776) (xy 358.857296 -258.049776)
			(xy 358.847271 -258.049383) (xy 358.82875 -258.041707) (xy 358.814577 -258.027527) (xy 358.806911 -258.009001)
			(xy 358.806496 -257.998976) (xy 357.022181 -257.998976) (xy 357.00589 -258.013708) (xy 356.99827 -258.02209)
			(xy 356.986059 -258.038019) (xy 356.956755 -258.065437) (xy 356.922851 -258.086909) (xy 356.885537 -258.101679)
			(xy 356.846123 -258.109231) (xy 356.826058 -258.10972) (xy 356.571296 -258.10972) (xy 356.571296 -258.100576)
			(xy 356.570832 -258.090566) (xy 356.563163 -258.072073) (xy 356.549003 -258.057921) (xy 356.530506 -258.050263)
			(xy 356.520496 -258.049776) (xy 356.055676 -258.049776) (xy 356.0493 -258.049983) (xy 356.036957 -258.053194)
			(xy 356.031292 -258.056126) (xy 356.020624 -258.061714) (xy 356.020624 -258.080002) (xy 355.990906 -258.10972)
			(xy 355.765862 -258.10972) (xy 355.745186 -258.10929) (xy 355.704612 -258.101303) (xy 355.666334 -258.085655)
			(xy 355.631785 -258.062931) (xy 355.602256 -258.033981) (xy 355.578853 -257.999887) (xy 355.562451 -257.961927)
			(xy 355.557582 -257.941826) (xy 355.556639 -257.937897) (xy 355.553713 -257.930366) (xy 355.55174 -257.92684)
			(xy 355.539886 -257.906117) (xy 355.521193 -257.862186) (xy 355.508525 -257.816156) (xy 355.502109 -257.768847)
			(xy 355.501702 -257.744976) (xy 354.591813 -257.744976) (xy 354.570444 -257.767753) (xy 354.534795 -257.792846)
			(xy 354.494804 -257.810199) (xy 354.452126 -257.819094) (xy 354.43033 -257.819652) (xy 354.175568 -257.819652)
			(xy 354.175568 -257.810508) (xy 354.175173 -257.800483) (xy 354.1675 -257.78196) (xy 354.15332 -257.767787)
			(xy 354.134793 -257.760122) (xy 354.124768 -257.759708) (xy 353.624896 -257.759708) (xy 353.624896 -257.768852)
			(xy 353.624441 -257.778871) (xy 353.616786 -257.797387) (xy 353.602624 -257.811561) (xy 353.584114 -257.819232)
			(xy 353.574096 -257.819652) (xy 353.370134 -257.819652) (xy 353.348171 -257.819149) (xy 353.305166 -257.810202)
			(xy 353.264896 -257.792657) (xy 353.22906 -257.767255) (xy 353.199169 -257.735068) (xy 353.176485 -257.697453)
			(xy 353.168712 -257.676904) (xy 353.167088 -257.672501) (xy 353.162492 -257.664319) (xy 353.159568 -257.660648)
			(xy 353.143629 -257.641252) (xy 353.116795 -257.598822) (xy 353.096189 -257.553043) (xy 353.08222 -257.504822)
			(xy 353.075164 -257.455118) (xy 353.074732 -257.430016) (xy 348.680532 -257.430016) (xy 348.680532 -257.51536)
			(xy 348.680903 -257.525265) (xy 348.688414 -257.543592) (xy 348.702381 -257.557635) (xy 348.720667 -257.565244)
			(xy 348.73057 -257.565652) (xy 348.94901 -257.565652) (xy 348.968904 -257.566087) (xy 349.008004 -257.573448)
			(xy 349.045061 -257.587932) (xy 349.078789 -257.609036) (xy 349.10802 -257.636029) (xy 349.120206 -257.651758)
			(xy 349.121984 -257.654044) (xy 349.128588 -257.661156) (xy 349.13062 -257.662934) (xy 349.150904 -257.681487)
			(xy 349.186071 -257.723735) (xy 349.214329 -257.770885) (xy 349.235005 -257.821817) (xy 349.247609 -257.875322)
			(xy 349.251841 -257.930128) (xy 349.25184 -257.930142) (xy 349.524574 -257.930142) (xy 349.524981 -257.906269)
			(xy 349.531365 -257.858953) (xy 349.544026 -257.812917) (xy 349.562734 -257.768989) (xy 349.574612 -257.748278)
			(xy 349.576602 -257.74476) (xy 349.57953 -257.737227) (xy 349.580454 -257.733292) (xy 349.585327 -257.713207)
			(xy 349.601746 -257.675283) (xy 349.625162 -257.641233) (xy 349.654697 -257.612329) (xy 349.689246 -257.589655)
			(xy 349.727515 -257.574059) (xy 349.768071 -257.566125) (xy 349.788734 -257.565652) (xy 350.013778 -257.565652)
			(xy 350.043496 -257.59537) (xy 350.043496 -257.613404) (xy 350.05391 -257.618992) (xy 350.059691 -257.622007)
			(xy 350.072287 -257.625357) (xy 350.078802 -257.625596) (xy 350.594168 -257.625596) (xy 350.594168 -257.616452)
			(xy 350.594648 -257.606445) (xy 350.602317 -257.587959) (xy 350.616472 -257.573808) (xy 350.634961 -257.566145)
			(xy 350.644968 -257.565652) (xy 350.84893 -257.565652) (xy 350.868984 -257.56614) (xy 350.908389 -257.573618)
			(xy 350.945704 -257.588324) (xy 350.979615 -257.609741) (xy 351.00893 -257.637115) (xy 351.021142 -257.653028)
			(xy 351.028762 -257.66141) (xy 351.049345 -257.679945) (xy 351.084986 -257.722344) (xy 351.113638 -257.769747)
			(xy 351.13461 -257.821012) (xy 351.147396 -257.874905) (xy 351.15169 -257.930128) (xy 351.147388 -257.985349)
			(xy 351.134593 -258.03924) (xy 351.113613 -258.090503) (xy 351.084954 -258.137901) (xy 351.049306 -258.180294)
			(xy 351.028762 -258.198874) (xy 351.021142 -258.207256) (xy 351.008922 -258.223164) (xy 350.979608 -258.25054)
			(xy 350.945699 -258.271963) (xy 350.908388 -258.28668) (xy 350.868985 -258.294173) (xy 350.84893 -258.294632)
			(xy 350.594168 -258.294632) (xy 350.594168 -258.285488) (xy 350.593789 -258.275462) (xy 350.58611 -258.256939)
			(xy 350.571924 -258.242766) (xy 350.553394 -258.235102) (xy 350.543368 -258.234688) (xy 350.078802 -258.234688)
			(xy 350.07228 -258.234883) (xy 350.059674 -258.238234) (xy 350.05391 -258.241292) (xy 350.043496 -258.24688)
			(xy 350.043496 -258.264914) (xy 350.013778 -258.294632) (xy 349.788734 -258.294632) (xy 349.768081 -258.294128)
			(xy 349.727553 -258.286143) (xy 349.689313 -258.270522) (xy 349.654786 -258.247848) (xy 349.625256 -258.218963)
			(xy 349.601825 -258.184945) (xy 349.585364 -258.147059) (xy 349.580454 -258.126992) (xy 349.579521 -258.12306)
			(xy 349.576588 -258.115531) (xy 349.574612 -258.112006) (xy 349.562751 -258.091286) (xy 349.544058 -258.047355)
			(xy 349.531392 -258.001323) (xy 349.524979 -257.954013) (xy 349.524574 -257.930142) (xy 349.25184 -257.930142)
			(xy 349.2476 -257.984933) (xy 349.234988 -258.038436) (xy 349.214304 -258.089365) (xy 349.186039 -258.13651)
			(xy 349.150865 -258.178752) (xy 349.13062 -258.19735) (xy 349.128588 -258.199128) (xy 349.121984 -258.20624)
			(xy 349.120206 -258.208526) (xy 349.107983 -258.22422) (xy 349.078747 -258.25119) (xy 349.045025 -258.272282)
			(xy 349.007982 -258.28677) (xy 348.968897 -258.294151) (xy 348.94901 -258.294632) (xy 348.73057 -258.294632)
			(xy 348.720669 -258.295056) (xy 348.702387 -258.302663) (xy 348.68842 -258.3167) (xy 348.680906 -258.335021)
			(xy 348.680532 -258.344924) (xy 348.680532 -258.379976) (xy 353.074732 -258.379976) (xy 353.07519 -258.351988)
			(xy 353.083951 -258.296702) (xy 353.101252 -258.243467) (xy 353.126669 -258.193593) (xy 353.159575 -258.148311)
			(xy 353.199159 -258.108733) (xy 353.244448 -258.075835) (xy 353.294326 -258.050428) (xy 353.347564 -258.033136)
			(xy 353.402852 -258.024385) (xy 353.43084 -258.023868) (xy 353.431602 -258.023868) (xy 353.45698 -258.024315)
			(xy 353.507213 -258.031585) (xy 353.531678 -258.038346) (xy 353.53879 -258.040632) (xy 353.595178 -258.040632)
			(xy 353.624896 -258.07035) (xy 353.624896 -258.081526) (xy 353.638866 -258.091178) (xy 353.645522 -258.095509)
			(xy 353.660649 -258.100305) (xy 353.668584 -258.100576) (xy 354.107496 -258.100576) (xy 354.115451 -258.100247)
			(xy 354.130584 -258.095331) (xy 354.137214 -258.090924) (xy 354.146465 -258.084428) (xy 354.165655 -258.072479)
			(xy 354.175568 -258.067048) (xy 354.175568 -258.040632) (xy 354.23729 -258.040632) (xy 354.244402 -258.038346)
			(xy 354.269059 -258.031569) (xy 354.319673 -258.024296) (xy 354.34524 -258.023868) (xy 354.373138 -258.024394)
			(xy 354.428255 -258.033077) (xy 354.454968 -258.04114) (xy 354.462842 -258.042918) (xy 354.48134 -258.046205)
			(xy 354.516892 -258.058333) (xy 354.549766 -258.07651) (xy 354.578943 -258.10017) (xy 354.603517 -258.128581)
			(xy 354.613464 -258.144518) (xy 354.61829 -258.151122) (xy 354.63393 -258.170448) (xy 354.660227 -258.212639)
			(xy 354.680401 -258.258077) (xy 354.694058 -258.30588) (xy 354.700935 -258.355118) (xy 354.701348 -258.379976)
			(xy 365.02467 -258.379976) (xy 365.025098 -258.354846) (xy 365.032168 -258.305084) (xy 365.046165 -258.256811)
			(xy 365.066809 -258.210986) (xy 365.093691 -258.168518) (xy 365.126277 -258.130252) (xy 365.144812 -258.113276)
			(xy 365.148622 -258.109466) (xy 365.162996 -258.094542) (xy 365.196359 -258.069982) (xy 365.233817 -258.052284)
			(xy 365.253778 -258.046728) (xy 365.258858 -258.045204) (xy 365.288338 -258.035201) (xy 365.349653 -258.024467)
			(xy 365.380778 -258.023868) (xy 365.406346 -258.024291) (xy 365.456964 -258.031551) (xy 365.481616 -258.038346)
			(xy 365.488728 -258.040632) (xy 365.560356 -258.040632) (xy 365.560356 -258.044696) (xy 365.560997 -258.05711)
			(xy 365.572566 -258.079077) (xy 365.582454 -258.086606) (xy 365.588804 -258.091178) (xy 365.595451 -258.095524)
			(xy 365.610585 -258.10031) (xy 365.618522 -258.100576) (xy 365.774732 -258.100576) (xy 365.784739 -258.101061)
			(xy 365.803227 -258.108727) (xy 365.817378 -258.12288) (xy 365.82504 -258.141369) (xy 365.825532 -258.151376)
			(xy 365.825532 -258.658868) (xy 365.824987 -258.66887) (xy 365.817344 -258.687355) (xy 365.803208 -258.701508)
			(xy 365.784733 -258.709174) (xy 365.774732 -258.709668) (xy 365.560356 -258.709668) (xy 365.560356 -258.718812)
			(xy 365.559989 -258.72884) (xy 365.552307 -258.747365) (xy 365.538118 -258.761538) (xy 365.519584 -258.7692)
			(xy 365.509556 -258.769612) (xy 365.305594 -258.769612) (xy 365.284997 -258.769148) (xy 365.244575 -258.761211)
			(xy 365.206425 -258.745672) (xy 365.171961 -258.723106) (xy 365.142463 -258.694351) (xy 365.119025 -258.660475)
			(xy 365.102518 -258.622733) (xy 365.097568 -258.602734) (xy 365.096332 -258.597907) (xy 365.092232 -258.588827)
			(xy 365.08944 -258.5847) (xy 365.074154 -258.5621) (xy 365.04996 -258.513198) (xy 365.03351 -258.461177)
			(xy 365.025189 -258.407256) (xy 365.02467 -258.379976) (xy 354.701348 -258.379976) (xy 354.700929 -258.404549)
			(xy 354.694169 -258.453227) (xy 354.680787 -258.500516) (xy 354.661037 -258.545519) (xy 354.648516 -258.566666)
			(xy 354.645839 -258.571181) (xy 354.642255 -258.581045) (xy 354.641404 -258.586224) (xy 354.637783 -258.607724)
			(xy 354.62302 -258.64874) (xy 354.600255 -258.685916) (xy 354.570432 -258.71771) (xy 354.534788 -258.742804)
			(xy 354.4948 -258.760159) (xy 354.452125 -258.769054) (xy 354.43033 -258.769612) (xy 354.175568 -258.769612)
			(xy 354.175568 -258.760468) (xy 354.175137 -258.750454) (xy 354.167461 -258.731956) (xy 354.153291 -258.717803)
			(xy 354.134782 -258.71015) (xy 354.124768 -258.709668) (xy 353.624896 -258.709668) (xy 353.624896 -258.718812)
			(xy 353.624421 -258.728821) (xy 353.616757 -258.747314) (xy 353.6026 -258.761466) (xy 353.584105 -258.769125)
			(xy 353.574096 -258.769612) (xy 353.370134 -258.769612) (xy 353.348169 -258.769135) (xy 353.305161 -258.760186)
			(xy 353.264889 -258.742638) (xy 353.229052 -258.717231) (xy 353.199163 -258.685037) (xy 353.176482 -258.647416)
			(xy 353.168712 -258.626864) (xy 353.167096 -258.622457) (xy 353.162495 -258.614278) (xy 353.159568 -258.610608)
			(xy 353.14361 -258.591226) (xy 353.116779 -258.548792) (xy 353.096177 -258.503009) (xy 353.082212 -258.454786)
			(xy 353.075161 -258.405079) (xy 353.074732 -258.379976) (xy 348.680532 -258.379976) (xy 348.680532 -258.415536)
			(xy 348.681053 -258.425364) (xy 348.688638 -258.443503) (xy 348.702569 -258.457377) (xy 348.72074 -258.464888)
			(xy 348.73057 -258.46532) (xy 348.949518 -258.46532) (xy 348.95768 -258.465406) (xy 348.973953 -258.46668)
			(xy 348.98203 -258.46786) (xy 348.982538 -258.46786) (xy 349.002874 -258.471631) (xy 349.041674 -258.485942)
			(xy 349.077 -258.507443) (xy 349.107536 -258.535332) (xy 349.120206 -258.55168) (xy 349.121984 -258.553966)
			(xy 349.128588 -258.561078) (xy 349.13062 -258.562856) (xy 349.15091 -258.58141) (xy 349.186089 -258.623659)
			(xy 349.214358 -258.670813) (xy 349.235045 -258.72175) (xy 349.247659 -258.775262) (xy 349.251898 -258.830064)
			(xy 349.524574 -258.830064) (xy 349.524946 -258.80619) (xy 349.531341 -258.758872) (xy 349.544012 -258.712836)
			(xy 349.562729 -258.66891) (xy 349.574612 -258.6482) (xy 349.576598 -258.64468) (xy 349.579529 -258.637148)
			(xy 349.580454 -258.633214) (xy 349.585331 -258.613122) (xy 349.601759 -258.575188) (xy 349.625175 -258.54112)
			(xy 349.654704 -258.512189) (xy 349.689244 -258.489477) (xy 349.727507 -258.473829) (xy 349.768065 -258.46583)
			(xy 349.788734 -258.46532) (xy 350.013778 -258.46532) (xy 350.043496 -258.495038) (xy 350.043496 -258.513326)
			(xy 350.054164 -258.518914) (xy 350.059832 -258.521838) (xy 350.072174 -258.525039) (xy 350.078548 -258.525264)
			(xy 350.594168 -258.525264) (xy 350.594168 -258.51612) (xy 350.594704 -258.506118) (xy 350.602351 -258.487632)
			(xy 350.616489 -258.47348) (xy 350.634966 -258.465814) (xy 350.644968 -258.46532) (xy 350.84893 -258.46532)
			(xy 350.869001 -258.465779) (xy 350.908432 -258.473296) (xy 350.94576 -258.488059) (xy 350.979667 -258.509546)
			(xy 351.008953 -258.536998) (xy 351.021142 -258.55295) (xy 351.028762 -258.561332) (xy 351.049267 -258.57995)
			(xy 351.084908 -258.622336) (xy 351.113562 -258.669727) (xy 351.134538 -258.720981) (xy 351.14733 -258.774864)
			(xy 351.1489 -258.795012) (xy 355.501702 -258.795012) (xy 355.502091 -258.771139) (xy 355.508481 -258.723822)
			(xy 355.521146 -258.677785) (xy 355.539859 -258.633859) (xy 355.55174 -258.613148) (xy 355.553711 -258.60962)
			(xy 355.556652 -258.602094) (xy 355.557582 -258.598162) (xy 355.56249 -258.57808) (xy 355.57892 -258.540152)
			(xy 355.602333 -258.506088) (xy 355.631857 -258.47716) (xy 355.66639 -258.454446) (xy 355.704645 -258.438793)
			(xy 355.745196 -258.430784) (xy 355.765862 -258.430268) (xy 355.990906 -258.430268) (xy 356.020624 -258.459986)
			(xy 356.020624 -258.478274) (xy 356.031292 -258.483862) (xy 356.036973 -258.486758) (xy 356.049305 -258.489977)
			(xy 356.055676 -258.490212) (xy 356.571296 -258.490212) (xy 356.571296 -258.481068) (xy 356.571762 -258.471059)
			(xy 356.579431 -258.452567) (xy 356.593591 -258.438415) (xy 356.612087 -258.430756) (xy 356.622096 -258.430268)
			(xy 356.826058 -258.430268) (xy 356.846128 -258.430728) (xy 356.885558 -258.438248) (xy 356.922885 -258.453012)
			(xy 356.956792 -258.474498) (xy 356.98608 -258.501947) (xy 356.99827 -258.517898) (xy 357.00589 -258.52628)
			(xy 357.026447 -258.544845) (xy 357.062095 -258.587236) (xy 357.090753 -258.634634) (xy 357.111731 -258.685896)
			(xy 357.124523 -258.739787) (xy 357.12882 -258.795008) (xy 357.12882 -258.795012) (xy 358.001824 -258.795012)
			(xy 358.00221 -258.771139) (xy 358.0086 -258.723821) (xy 358.021266 -258.677785) (xy 358.039981 -258.633859)
			(xy 358.051862 -258.613148) (xy 358.053835 -258.609621) (xy 358.056774 -258.602094) (xy 358.057704 -258.598162)
			(xy 358.062592 -258.578074) (xy 358.079024 -258.540144) (xy 358.10244 -258.50608) (xy 358.131967 -258.477152)
			(xy 358.166504 -258.454439) (xy 358.204763 -258.438788) (xy 358.245317 -258.430782) (xy 358.265984 -258.430268)
			(xy 358.491282 -258.430268) (xy 358.521 -258.459986) (xy 358.521 -258.478274) (xy 358.53116 -258.483862)
			(xy 358.536942 -258.486844) (xy 358.549548 -258.490051) (xy 358.556052 -258.490212) (xy 359.071164 -258.490212)
			(xy 359.071164 -258.481068) (xy 359.071661 -258.471063) (xy 359.079324 -258.452577) (xy 359.093474 -258.438427)
			(xy 359.111959 -258.430762) (xy 359.121964 -258.430268) (xy 359.32618 -258.430268) (xy 359.346251 -258.430712)
			(xy 359.385682 -258.438236) (xy 359.423009 -258.453003) (xy 359.456915 -258.474493) (xy 359.486203 -258.501945)
			(xy 359.498392 -258.517898) (xy 359.506012 -258.52628) (xy 359.526567 -258.544845) (xy 359.562214 -258.587238)
			(xy 359.59087 -258.634636) (xy 359.611847 -258.685897) (xy 359.624637 -258.739787) (xy 359.628935 -258.795008)
			(xy 359.624635 -258.850228) (xy 359.611842 -258.904118) (xy 359.590863 -258.955378) (xy 359.562204 -259.002775)
			(xy 359.526556 -259.045166) (xy 359.522303 -259.049012) (xy 361.056428 -259.049012) (xy 361.056428 -258.541012)
			(xy 361.05683 -258.530988) (xy 361.064501 -258.512466) (xy 361.078679 -258.498292) (xy 361.097204 -258.490627)
			(xy 361.107228 -258.490212) (xy 361.321096 -258.490212) (xy 361.321096 -258.481068) (xy 361.321562 -258.471059)
			(xy 361.329231 -258.452567) (xy 361.343391 -258.438415) (xy 361.361887 -258.430756) (xy 361.371896 -258.430268)
			(xy 361.576112 -258.430268) (xy 361.596181 -258.430761) (xy 361.635609 -258.438273) (xy 361.672936 -258.453028)
			(xy 361.706843 -258.474507) (xy 361.736133 -258.50195) (xy 361.748324 -258.517898) (xy 361.755944 -258.52628)
			(xy 361.776498 -258.544846) (xy 361.812141 -258.58724) (xy 361.840795 -258.634638) (xy 361.861769 -258.685899)
			(xy 361.874559 -258.739789) (xy 361.878856 -258.795008) (xy 361.874556 -258.850227) (xy 361.861764 -258.904116)
			(xy 361.840788 -258.955376) (xy 361.812132 -259.002773) (xy 361.776487 -259.045165) (xy 361.772233 -259.049012)
			(xy 363.656372 -259.049012) (xy 363.656372 -258.541012) (xy 363.656897 -258.531009) (xy 363.664548 -258.512522)
			(xy 363.678689 -258.49837) (xy 363.697169 -258.490705) (xy 363.707172 -258.490212) (xy 363.92104 -258.490212)
			(xy 363.92104 -258.481068) (xy 363.921394 -258.47104) (xy 363.929082 -258.452514) (xy 363.943275 -258.438342)
			(xy 363.961811 -258.43068) (xy 363.97184 -258.430268) (xy 364.176056 -258.430268) (xy 364.196126 -258.43073)
			(xy 364.235556 -258.438249) (xy 364.272883 -258.453012) (xy 364.306789 -258.474498) (xy 364.336078 -258.501947)
			(xy 364.348268 -258.517898) (xy 364.355888 -258.52628) (xy 364.376445 -258.544845) (xy 364.412093 -258.587236)
			(xy 364.440752 -258.634634) (xy 364.461729 -258.685896) (xy 364.474521 -258.739787) (xy 364.478819 -258.795008)
			(xy 364.476088 -258.830076) (xy 368.793022 -258.830076) (xy 368.797324 -258.774855) (xy 368.810119 -258.720964)
			(xy 368.831099 -258.669702) (xy 368.859758 -258.622304) (xy 368.895406 -258.579911) (xy 368.91595 -258.561332)
			(xy 368.92357 -258.55295) (xy 368.935769 -258.537011) (xy 368.965074 -258.509591) (xy 368.998981 -258.48812)
			(xy 369.036299 -258.473352) (xy 369.075716 -258.465806) (xy 369.095782 -258.46532) (xy 369.350544 -258.46532)
			(xy 369.350544 -258.474464) (xy 369.35095 -258.484488) (xy 369.358616 -258.503013) (xy 369.372794 -258.517188)
			(xy 369.39132 -258.524851) (xy 369.401344 -258.525264) (xy 369.56492 -258.525264) (xy 369.574925 -258.525771)
			(xy 369.59341 -258.53343) (xy 369.607561 -258.547577) (xy 369.615226 -258.56606) (xy 369.61572 -258.576064)
			(xy 369.61572 -258.830076) (xy 370.718605 -258.830076) (xy 370.722907 -258.774856) (xy 370.735701 -258.720966)
			(xy 370.756679 -258.669704) (xy 370.785335 -258.622306) (xy 370.820981 -258.579912) (xy 370.841524 -258.561332)
			(xy 370.849144 -258.55295) (xy 370.861358 -258.537023) (xy 370.89066 -258.509602) (xy 370.924563 -258.488129)
			(xy 370.961877 -258.473359) (xy 371.001291 -258.465808) (xy 371.021356 -258.46532) (xy 371.276372 -258.46532)
			(xy 371.276372 -258.474464) (xy 371.276848 -258.48448) (xy 371.284501 -258.50299) (xy 371.298656 -258.517163)
			(xy 371.317157 -258.524839) (xy 371.327172 -258.525264) (xy 371.49024 -258.525264) (xy 371.500246 -258.525754)
			(xy 371.518732 -258.53342) (xy 371.532882 -258.547572) (xy 371.540546 -258.566058) (xy 371.54104 -258.576064)
			(xy 371.54104 -258.830076) (xy 372.496605 -258.830076) (xy 372.500907 -258.774856) (xy 372.513701 -258.720966)
			(xy 372.534679 -258.669704) (xy 372.563335 -258.622306) (xy 372.598981 -258.579912) (xy 372.619524 -258.561332)
			(xy 372.627144 -258.55295) (xy 372.639358 -258.537023) (xy 372.66866 -258.509602) (xy 372.702563 -258.488129)
			(xy 372.739877 -258.473359) (xy 372.779291 -258.465808) (xy 372.799356 -258.46532) (xy 373.054372 -258.46532)
			(xy 373.054372 -258.474464) (xy 373.054848 -258.48448) (xy 373.062501 -258.50299) (xy 373.076656 -258.517163)
			(xy 373.095157 -258.524839) (xy 373.105172 -258.525264) (xy 373.26824 -258.525264) (xy 373.278246 -258.525754)
			(xy 373.296732 -258.53342) (xy 373.310882 -258.547572) (xy 373.318546 -258.566058) (xy 373.31904 -258.576064)
			(xy 373.31904 -259.084064) (xy 373.318484 -259.094065) (xy 373.310843 -259.112548) (xy 373.296712 -259.126701)
			(xy 373.27824 -259.134369) (xy 373.26824 -259.134864) (xy 373.054372 -259.134864) (xy 373.054372 -259.144008)
			(xy 373.053986 -259.154033) (xy 373.046308 -259.172556) (xy 373.032125 -259.186729) (xy 373.013598 -259.194393)
			(xy 373.003572 -259.194808) (xy 372.799356 -259.194808) (xy 372.779286 -259.194348) (xy 372.739855 -259.186829)
			(xy 372.702527 -259.172066) (xy 372.668621 -259.15058) (xy 372.639334 -259.12313) (xy 372.627144 -259.107178)
			(xy 372.619524 -259.098796) (xy 372.598948 -259.080254) (xy 372.563308 -259.037856) (xy 372.534657 -258.990454)
			(xy 372.513686 -258.939189) (xy 372.500899 -258.885298) (xy 372.496605 -258.830076) (xy 371.54104 -258.830076)
			(xy 371.54104 -259.084064) (xy 371.540484 -259.094065) (xy 371.532843 -259.112548) (xy 371.518712 -259.126701)
			(xy 371.50024 -259.134369) (xy 371.49024 -259.134864) (xy 371.276372 -259.134864) (xy 371.276372 -259.144008)
			(xy 371.275986 -259.154033) (xy 371.268308 -259.172556) (xy 371.254125 -259.186729) (xy 371.235598 -259.194393)
			(xy 371.225572 -259.194808) (xy 371.021356 -259.194808) (xy 371.001286 -259.194348) (xy 370.961855 -259.186829)
			(xy 370.924527 -259.172066) (xy 370.890621 -259.15058) (xy 370.861334 -259.12313) (xy 370.849144 -259.107178)
			(xy 370.841524 -259.098796) (xy 370.820948 -259.080254) (xy 370.785308 -259.037856) (xy 370.756657 -258.990454)
			(xy 370.735686 -258.939189) (xy 370.722899 -258.885298) (xy 370.718605 -258.830076) (xy 369.61572 -258.830076)
			(xy 369.61572 -259.084064) (xy 369.615251 -259.09408) (xy 369.607597 -259.112593) (xy 369.59344 -259.126766)
			(xy 369.574936 -259.13444) (xy 369.56492 -259.134864) (xy 369.350544 -259.134864) (xy 369.350544 -259.144008)
			(xy 369.350019 -259.154011) (xy 369.342365 -259.172494) (xy 369.328224 -259.186645) (xy 369.309746 -259.194312)
			(xy 369.299744 -259.194808) (xy 369.095782 -259.194808) (xy 369.075712 -259.194329) (xy 369.036283 -259.186815)
			(xy 368.998955 -259.172057) (xy 368.965049 -259.150575) (xy 368.93576 -259.123128) (xy 368.92357 -259.107178)
			(xy 368.91595 -259.098796) (xy 368.895372 -259.080255) (xy 368.85973 -259.037858) (xy 368.831077 -258.990456)
			(xy 368.810104 -258.939191) (xy 368.797317 -258.885298) (xy 368.793022 -258.830076) (xy 364.476088 -258.830076)
			(xy 364.474519 -258.850229) (xy 364.461725 -258.904119) (xy 364.440744 -258.95538) (xy 364.412084 -259.002777)
			(xy 364.376434 -259.045167) (xy 364.355888 -259.063744) (xy 364.348268 -259.072126) (xy 364.336041 -259.088042)
			(xy 364.306743 -259.115465) (xy 364.272843 -259.13694) (xy 364.235532 -259.151714) (xy 364.19612 -259.159266)
			(xy 364.176056 -259.159756) (xy 363.92104 -259.159756) (xy 363.92104 -259.150612) (xy 363.920503 -259.14061)
			(xy 363.912855 -259.122126) (xy 363.898717 -259.107974) (xy 363.880241 -259.100307) (xy 363.87024 -259.099812)
			(xy 363.707172 -259.099812) (xy 363.697164 -259.099335) (xy 363.678674 -259.091669) (xy 363.664522 -259.077513)
			(xy 363.656862 -259.05902) (xy 363.656372 -259.049012) (xy 361.772233 -259.049012) (xy 361.755944 -259.063744)
			(xy 361.748324 -259.072126) (xy 361.736123 -259.088063) (xy 361.706818 -259.115484) (xy 361.672912 -259.136956)
			(xy 361.635595 -259.151725) (xy 361.596178 -259.15927) (xy 361.576112 -259.159756) (xy 361.321096 -259.159756)
			(xy 361.321096 -259.150612) (xy 361.320671 -259.140591) (xy 361.313004 -259.122073) (xy 361.298833 -259.107901)
			(xy 361.280317 -259.100231) (xy 361.270296 -259.099812) (xy 361.107228 -259.099812) (xy 361.09721 -259.099358)
			(xy 361.078696 -259.091699) (xy 361.064523 -259.077538) (xy 361.05685 -259.05903) (xy 361.056428 -259.049012)
			(xy 359.522303 -259.049012) (xy 359.506012 -259.063744) (xy 359.498392 -259.072126) (xy 359.486151 -259.088031)
			(xy 359.456857 -259.115455) (xy 359.422961 -259.136932) (xy 359.385653 -259.151708) (xy 359.346243 -259.159264)
			(xy 359.32618 -259.159756) (xy 359.071164 -259.159756) (xy 359.071164 -259.150612) (xy 359.07077 -259.140587)
			(xy 359.063097 -259.122063) (xy 359.048916 -259.107889) (xy 359.030389 -259.100225) (xy 359.020364 -259.099812)
			(xy 358.556052 -259.099812) (xy 358.549546 -259.099955) (xy 358.536943 -259.103177) (xy 358.53116 -259.106162)
			(xy 358.521 -259.11175) (xy 358.521 -259.130038) (xy 358.491282 -259.159756) (xy 358.265984 -259.159756)
			(xy 358.245311 -259.159279) (xy 358.204741 -259.151297) (xy 358.166466 -259.135656) (xy 358.131918 -259.112939)
			(xy 358.102389 -259.083997) (xy 358.078983 -259.049912) (xy 358.062576 -259.011959) (xy 358.057704 -258.991862)
			(xy 358.056782 -258.987927) (xy 358.053842 -258.980399) (xy 358.051862 -258.976876) (xy 358.039984 -258.956165)
			(xy 358.021297 -258.91223) (xy 358.008635 -258.866196) (xy 358.002226 -258.818884) (xy 358.001824 -258.795012)
			(xy 357.12882 -258.795012) (xy 357.12452 -258.850229) (xy 357.111726 -258.904119) (xy 357.090746 -258.95538)
			(xy 357.062086 -259.002777) (xy 357.026436 -259.045167) (xy 357.00589 -259.063744) (xy 356.99827 -259.072126)
			(xy 356.986042 -259.088042) (xy 356.956744 -259.115464) (xy 356.922845 -259.13694) (xy 356.885534 -259.151713)
			(xy 356.846122 -259.159266) (xy 356.826058 -259.159756) (xy 356.571296 -259.159756) (xy 356.571296 -259.150612)
			(xy 356.570871 -259.140591) (xy 356.563204 -259.122073) (xy 356.549033 -259.107901) (xy 356.530517 -259.100231)
			(xy 356.520496 -259.099812) (xy 356.055676 -259.099812) (xy 356.049299 -259.100015) (xy 356.036957 -259.103228)
			(xy 356.031292 -259.106162) (xy 356.020624 -259.11175) (xy 356.020624 -259.130038) (xy 355.990906 -259.159756)
			(xy 355.765862 -259.159756) (xy 355.745188 -259.159298) (xy 355.704617 -259.151313) (xy 355.666342 -259.135668)
			(xy 355.631794 -259.112948) (xy 355.602265 -259.084003) (xy 355.57886 -259.049915) (xy 355.562454 -259.01196)
			(xy 355.557582 -258.991862) (xy 355.556653 -258.987929) (xy 355.553717 -258.9804) (xy 355.55174 -258.976876)
			(xy 355.53986 -258.956167) (xy 355.521174 -258.912231) (xy 355.508513 -258.866196) (xy 355.502104 -258.818884)
			(xy 355.501702 -258.795012) (xy 351.1489 -258.795012) (xy 351.151631 -258.830076) (xy 351.147338 -258.88529)
			(xy 351.134552 -258.939174) (xy 351.113583 -258.99043) (xy 351.084936 -259.037825) (xy 351.0493 -259.080217)
			(xy 351.028762 -259.098796) (xy 351.021142 -259.107178) (xy 351.008944 -259.123118) (xy 350.979637 -259.150536)
			(xy 350.94573 -259.172006) (xy 350.908413 -259.186774) (xy 350.868996 -259.194321) (xy 350.84893 -259.194808)
			(xy 350.594168 -259.194808) (xy 350.594168 -259.185664) (xy 350.593741 -259.17565) (xy 350.586063 -259.157151)
			(xy 350.571891 -259.142999) (xy 350.553383 -259.135346) (xy 350.543368 -259.134864) (xy 350.078548 -259.134864)
			(xy 350.072171 -259.135062) (xy 350.059829 -259.138279) (xy 350.054164 -259.141214) (xy 350.043496 -259.146802)
			(xy 350.043496 -259.16509) (xy 350.013778 -259.194808) (xy 349.788734 -259.194808) (xy 349.768065 -259.194246)
			(xy 349.727502 -259.186276) (xy 349.689231 -259.170648) (xy 349.654685 -259.147945) (xy 349.625154 -259.119017)
			(xy 349.601744 -259.084946) (xy 349.585331 -259.047006) (xy 349.580454 -259.026914) (xy 349.579516 -259.022983)
			(xy 349.576587 -259.015453) (xy 349.574612 -259.011928) (xy 349.56276 -258.991203) (xy 349.544065 -258.947274)
			(xy 349.531396 -258.901244) (xy 349.52498 -258.853935) (xy 349.524574 -258.830064) (xy 349.251898 -258.830064)
			(xy 349.251899 -258.830076) (xy 349.247666 -258.884891) (xy 349.23506 -258.938404) (xy 349.214379 -258.989345)
			(xy 349.186117 -259.036502) (xy 349.150943 -259.078756) (xy 349.13062 -259.097272) (xy 349.128588 -259.09905)
			(xy 349.121984 -259.106162) (xy 349.120206 -259.108448) (xy 349.108038 -259.12414) (xy 349.078915 -259.151126)
			(xy 349.045303 -259.172262) (xy 349.008363 -259.186817) (xy 348.969369 -259.194291) (xy 348.949518 -259.194808)
			(xy 348.73057 -259.194808) (xy 348.720751 -259.195289) (xy 348.702604 -259.202793) (xy 348.688693 -259.216655)
			(xy 348.681124 -259.234775) (xy 348.680532 -259.244592) (xy 348.680532 -259.315204) (xy 348.680893 -259.325116)
			(xy 348.682968 -259.33019) (xy 353.074732 -259.33019) (xy 353.075203 -259.302202) (xy 353.083961 -259.246916)
			(xy 353.101261 -259.193682) (xy 353.126676 -259.143809) (xy 353.15958 -259.098526) (xy 353.199164 -259.058948)
			(xy 353.244451 -259.02605) (xy 353.294328 -259.000642) (xy 353.347565 -258.98335) (xy 353.402852 -258.974599)
			(xy 353.43084 -258.974082) (xy 353.456207 -258.9745) (xy 353.506436 -258.981643) (xy 353.530916 -258.988306)
			(xy 353.537774 -258.990592) (xy 353.595178 -258.990592) (xy 353.624896 -259.02031) (xy 353.624896 -259.03174)
			(xy 353.638358 -259.040884) (xy 353.644962 -259.045345) (xy 353.660111 -259.050266) (xy 353.668076 -259.050536)
			(xy 354.108004 -259.050536) (xy 354.115958 -259.0502) (xy 354.131091 -259.045288) (xy 354.137722 -259.040884)
			(xy 354.146855 -259.034467) (xy 354.16579 -259.022644) (xy 354.175568 -259.017262) (xy 354.175568 -258.990592)
			(xy 354.238306 -258.990592) (xy 354.245164 -258.988306) (xy 354.269639 -258.981619) (xy 354.319871 -258.974474)
			(xy 354.34524 -258.974082) (xy 354.372738 -258.974573) (xy 354.427085 -258.982996) (xy 354.453444 -258.990846)
			(xy 354.461572 -258.992624) (xy 354.480315 -258.99582) (xy 354.51634 -259.007964) (xy 354.549641 -259.026305)
			(xy 354.57916 -259.050262) (xy 354.603963 -259.079075) (xy 354.613972 -259.09524) (xy 354.618798 -259.102098)
			(xy 354.634322 -259.121394) (xy 354.660441 -259.16347) (xy 354.680484 -259.208756) (xy 354.694065 -259.256381)
			(xy 354.700922 -259.305428) (xy 354.701348 -259.33019) (xy 354.701344 -259.330444) (xy 365.02467 -259.330444)
			(xy 365.02467 -259.33019) (xy 365.025085 -259.305181) (xy 365.032091 -259.255655) (xy 365.045964 -259.207598)
			(xy 365.066429 -259.161958) (xy 365.093085 -259.119634) (xy 365.125405 -259.081459) (xy 365.143796 -259.064506)
			(xy 365.147606 -259.060696) (xy 365.162291 -259.045244) (xy 365.196584 -259.019935) (xy 365.235214 -259.001928)
			(xy 365.25581 -258.996434) (xy 365.26089 -258.99491) (xy 365.289906 -258.985195) (xy 365.350186 -258.974717)
			(xy 365.380778 -258.974082) (xy 365.406145 -258.974513) (xy 365.456373 -258.981647) (xy 365.480854 -258.988306)
			(xy 365.487712 -258.990592) (xy 365.560356 -258.990592) (xy 365.560356 -258.99491) (xy 365.560989 -259.007325)
			(xy 365.572563 -259.029291) (xy 365.582454 -259.03682) (xy 365.588296 -259.040884) (xy 365.594891 -259.04536)
			(xy 365.610047 -259.050272) (xy 365.618014 -259.050536) (xy 365.774732 -259.050536) (xy 365.78476 -259.050894)
			(xy 365.803284 -259.058581) (xy 365.817457 -259.072773) (xy 365.825119 -259.091308) (xy 365.825532 -259.101336)
			(xy 365.825532 -259.608828) (xy 365.825036 -259.618834) (xy 365.817373 -259.63732) (xy 365.803223 -259.651471)
			(xy 365.784737 -259.659135) (xy 365.774732 -259.659628) (xy 365.560356 -259.659628) (xy 365.560356 -259.668772)
			(xy 365.559956 -259.678797) (xy 365.552287 -259.697322) (xy 365.538108 -259.711496) (xy 365.519581 -259.719159)
			(xy 365.509556 -259.719572) (xy 365.305594 -259.719572) (xy 365.28503 -259.719099) (xy 365.244667 -259.711192)
			(xy 365.206563 -259.69571) (xy 365.172124 -259.673225) (xy 365.142623 -259.644567) (xy 365.119148 -259.610795)
			(xy 365.102567 -259.573155) (xy 365.097568 -259.553202) (xy 365.096315 -259.54838) (xy 365.092227 -259.539297)
			(xy 365.08944 -259.535168) (xy 365.074153 -259.512567) (xy 365.049944 -259.463669) (xy 365.033485 -259.411649)
			(xy 365.025162 -259.357725) (xy 365.02467 -259.330444) (xy 354.701344 -259.330444) (xy 354.700936 -259.354763)
			(xy 354.694174 -259.403442) (xy 354.68079 -259.45073) (xy 354.661038 -259.495733) (xy 354.648516 -259.51688)
			(xy 354.645835 -259.521393) (xy 354.642254 -259.531258) (xy 354.641404 -259.536438) (xy 354.637777 -259.55793)
			(xy 354.623029 -259.598936) (xy 354.600268 -259.636096) (xy 354.57044 -259.667866) (xy 354.534788 -259.692923)
			(xy 354.494792 -259.710225) (xy 354.452119 -259.719052) (xy 354.43033 -259.719572) (xy 354.175568 -259.719572)
			(xy 354.175568 -259.710428) (xy 354.175157 -259.700405) (xy 354.16749 -259.681882) (xy 354.153314 -259.667708)
			(xy 354.134791 -259.660043) (xy 354.124768 -259.659628) (xy 353.624896 -259.659628) (xy 353.624896 -259.668772)
			(xy 353.624457 -259.678792) (xy 353.616796 -259.697309) (xy 353.602629 -259.711482) (xy 353.584116 -259.719153)
			(xy 353.574096 -259.719572) (xy 353.370134 -259.719572) (xy 353.348226 -259.719008) (xy 353.305329 -259.710088)
			(xy 353.265148 -259.692616) (xy 353.22937 -259.667323) (xy 353.199495 -259.635272) (xy 353.176777 -259.597807)
			(xy 353.168966 -259.577332) (xy 353.167363 -259.57292) (xy 353.162753 -259.564743) (xy 353.159822 -259.561076)
			(xy 353.143839 -259.54167) (xy 353.116923 -259.499209) (xy 353.096253 -259.453381) (xy 353.082241 -259.4051)
			(xy 353.075165 -259.355327) (xy 353.074732 -259.33019) (xy 348.682968 -259.33019) (xy 348.688394 -259.343462)
			(xy 348.702363 -259.357523) (xy 348.72066 -259.365143) (xy 348.73057 -259.365496) (xy 348.94901 -259.365496)
			(xy 348.968903 -259.365931) (xy 349.008002 -259.373294) (xy 349.045057 -259.38778) (xy 349.078782 -259.408887)
			(xy 349.108008 -259.435882) (xy 349.120206 -259.451602) (xy 349.121984 -259.453888) (xy 349.128588 -259.461)
			(xy 349.13062 -259.462778) (xy 349.150908 -259.481332) (xy 349.186084 -259.52358) (xy 349.21435 -259.570733)
			(xy 349.235034 -259.621669) (xy 349.247645 -259.675179) (xy 349.251883 -259.729986) (xy 349.524574 -259.729986)
			(xy 349.524956 -259.706112) (xy 349.531348 -259.658795) (xy 349.544016 -259.612759) (xy 349.562731 -259.568833)
			(xy 349.574612 -259.548122) (xy 349.576594 -259.5446) (xy 349.579527 -259.53707) (xy 349.580454 -259.533136)
			(xy 349.585289 -259.513041) (xy 349.601718 -259.475119) (xy 349.625141 -259.44107) (xy 349.654683 -259.412168)
			(xy 349.689237 -259.389496) (xy 349.72751 -259.373902) (xy 349.76807 -259.365969) (xy 349.788734 -259.365496)
			(xy 350.013778 -259.365496) (xy 350.043496 -259.395214) (xy 350.043496 -259.413248) (xy 350.05391 -259.418836)
			(xy 350.059693 -259.421848) (xy 350.072287 -259.4252) (xy 350.078802 -259.42544) (xy 350.594168 -259.42544)
			(xy 350.594168 -259.416296) (xy 350.594684 -259.406292) (xy 350.602339 -259.387806) (xy 350.616483 -259.373655)
			(xy 350.634964 -259.36599) (xy 350.644968 -259.365496) (xy 350.84893 -259.365496) (xy 350.868985 -259.365966)
			(xy 350.908392 -259.373446) (xy 350.945708 -259.388155) (xy 350.979619 -259.409577) (xy 351.008932 -259.436956)
			(xy 351.021142 -259.452872) (xy 351.028762 -259.461254) (xy 351.049289 -259.479848) (xy 351.08493 -259.522238)
			(xy 351.113583 -259.569633) (xy 351.134558 -259.62089) (xy 351.147349 -259.674775) (xy 351.151648 -259.729991)
			(xy 351.147352 -259.785206) (xy 351.134564 -259.839092) (xy 351.132127 -259.845048) (xy 355.501702 -259.845048)
			(xy 355.502107 -259.821175) (xy 355.508492 -259.773859) (xy 355.521153 -259.727822) (xy 355.539862 -259.683895)
			(xy 355.55174 -259.663184) (xy 355.553724 -259.659663) (xy 355.556656 -259.652132) (xy 355.557582 -259.648198)
			(xy 355.562514 -259.628122) (xy 355.578938 -259.590193) (xy 355.602346 -259.556129) (xy 355.631866 -259.5272)
			(xy 355.666396 -259.504484) (xy 355.704648 -259.48883) (xy 355.745197 -259.48082) (xy 355.765862 -259.480304)
			(xy 355.990906 -259.480304) (xy 356.020624 -259.510022) (xy 356.020624 -259.52831) (xy 356.031292 -259.533898)
			(xy 356.036971 -259.536797) (xy 356.049304 -259.540014) (xy 356.055676 -259.540248) (xy 356.571296 -259.540248)
			(xy 356.571296 -259.531104) (xy 356.571791 -259.521097) (xy 356.579449 -259.502606) (xy 356.593599 -259.488453)
			(xy 356.612089 -259.480793) (xy 356.622096 -259.480304) (xy 356.826058 -259.480304) (xy 356.846129 -259.48075)
			(xy 356.885561 -259.488271) (xy 356.922889 -259.503037) (xy 356.956795 -259.524527) (xy 356.986081 -259.551981)
			(xy 356.99827 -259.567934) (xy 357.00589 -259.576316) (xy 357.026483 -259.594842) (xy 357.062131 -259.63724)
			(xy 357.090788 -259.684643) (xy 357.111764 -259.73591) (xy 357.124553 -259.789806) (xy 357.128848 -259.845032)
			(xy 357.128847 -259.845048) (xy 358.001824 -259.845048) (xy 358.002226 -259.821175) (xy 358.008611 -259.773858)
			(xy 358.021273 -259.727822) (xy 358.039983 -259.683895) (xy 358.051862 -259.663184) (xy 358.053847 -259.659664)
			(xy 358.056779 -259.652132) (xy 358.057704 -259.648198) (xy 358.062616 -259.628117) (xy 358.079042 -259.590186)
			(xy 358.102453 -259.556121) (xy 358.131976 -259.527191) (xy 358.16651 -259.504477) (xy 358.204766 -259.488824)
			(xy 358.245318 -259.480818) (xy 358.265984 -259.480304) (xy 358.491282 -259.480304) (xy 358.521 -259.510022)
			(xy 358.521 -259.52831) (xy 358.53116 -259.533898) (xy 358.536941 -259.536882) (xy 358.549547 -259.540087)
			(xy 358.556052 -259.540248) (xy 359.071164 -259.540248) (xy 359.071164 -259.531104) (xy 359.071691 -259.521101)
			(xy 359.079342 -259.502616) (xy 359.093483 -259.488464) (xy 359.111961 -259.480798) (xy 359.121964 -259.480304)
			(xy 359.32618 -259.480304) (xy 359.346252 -259.480734) (xy 359.385684 -259.488259) (xy 359.423012 -259.503029)
			(xy 359.456918 -259.524522) (xy 359.486204 -259.551979) (xy 359.498392 -259.567934) (xy 359.506012 -259.576316)
			(xy 359.526603 -259.594843) (xy 359.562249 -259.637241) (xy 359.590905 -259.684645) (xy 359.61188 -259.735912)
			(xy 359.624668 -259.789807) (xy 359.628962 -259.845032) (xy 359.628961 -259.845048) (xy 360.251756 -259.845048)
			(xy 360.252168 -259.821176) (xy 360.258551 -259.773859) (xy 360.27121 -259.727823) (xy 360.289917 -259.683896)
			(xy 360.301794 -259.663184) (xy 360.303782 -259.659665) (xy 360.306711 -259.652133) (xy 360.307636 -259.648198)
			(xy 360.312519 -259.628108) (xy 360.328948 -259.590175) (xy 360.352363 -259.556109) (xy 360.381891 -259.527179)
			(xy 360.41643 -259.504466) (xy 360.454692 -259.488817) (xy 360.495248 -259.480815) (xy 360.515916 -259.480304)
			(xy 360.741214 -259.480304) (xy 360.770932 -259.510022) (xy 360.770932 -259.52831) (xy 360.781092 -259.533898)
			(xy 360.786884 -259.536859) (xy 360.799482 -259.540079) (xy 360.805984 -259.540248) (xy 361.321096 -259.540248)
			(xy 361.321096 -259.531104) (xy 361.321591 -259.521097) (xy 361.329249 -259.502606) (xy 361.343399 -259.488453)
			(xy 361.361889 -259.480793) (xy 361.371896 -259.480304) (xy 361.576112 -259.480304) (xy 361.596182 -259.480782)
			(xy 361.635612 -259.488295) (xy 361.672939 -259.503054) (xy 361.706846 -259.524536) (xy 361.736134 -259.551984)
			(xy 361.748324 -259.567934) (xy 361.755944 -259.576316) (xy 361.776534 -259.594844) (xy 361.812177 -259.637243)
			(xy 361.84083 -259.684647) (xy 361.861802 -259.735913) (xy 361.874589 -259.789808) (xy 361.878883 -259.845032)
			(xy 361.878882 -259.845048) (xy 362.8517 -259.845048) (xy 362.852106 -259.821175) (xy 362.85849 -259.773859)
			(xy 362.871151 -259.727823) (xy 362.88986 -259.683895) (xy 362.901738 -259.663184) (xy 362.903722 -259.659663)
			(xy 362.906654 -259.652132) (xy 362.90758 -259.648198) (xy 362.912514 -259.628123) (xy 362.928937 -259.590194)
			(xy 362.952345 -259.55613) (xy 362.981865 -259.5272) (xy 363.016394 -259.504485) (xy 363.054647 -259.48883)
			(xy 363.095195 -259.480821) (xy 363.11586 -259.480304) (xy 363.341158 -259.480304) (xy 363.370876 -259.510022)
			(xy 363.370876 -259.52831) (xy 363.381036 -259.533898) (xy 363.386821 -259.536874) (xy 363.399424 -259.540084)
			(xy 363.405928 -259.540248) (xy 363.92104 -259.540248) (xy 363.92104 -259.531104) (xy 363.921424 -259.521078)
			(xy 363.9291 -259.502553) (xy 363.943284 -259.48838) (xy 363.961814 -259.480717) (xy 363.97184 -259.480304)
			(xy 364.176056 -259.480304) (xy 364.196127 -259.480751) (xy 364.235559 -259.488272) (xy 364.272887 -259.503038)
			(xy 364.306793 -259.524527) (xy 364.336079 -259.551981) (xy 364.348268 -259.567934) (xy 364.355888 -259.576316)
			(xy 364.376481 -259.594842) (xy 364.412129 -259.63724) (xy 364.440786 -259.684643) (xy 364.459341 -259.729991)
			(xy 368.793039 -259.729991) (xy 368.797338 -259.674772) (xy 368.81013 -259.620883) (xy 368.831107 -259.569622)
			(xy 368.859763 -259.522225) (xy 368.895407 -259.479833) (xy 368.91595 -259.461254) (xy 368.92357 -259.452872)
			(xy 368.935791 -259.436964) (xy 368.965103 -259.409586) (xy 368.999012 -259.388163) (xy 369.036324 -259.373446)
			(xy 369.075727 -259.365954) (xy 369.095782 -259.365496) (xy 369.350544 -259.365496) (xy 369.350544 -259.37464)
			(xy 369.350888 -259.384669) (xy 369.358579 -259.403196) (xy 369.372775 -259.417368) (xy 369.391314 -259.425029)
			(xy 369.401344 -259.42544) (xy 369.56492 -259.42544) (xy 369.574948 -259.425804) (xy 369.593473 -259.433488)
			(xy 369.607645 -259.447678) (xy 369.615308 -259.466212) (xy 369.61572 -259.47624) (xy 369.61572 -259.729991)
			(xy 370.718622 -259.729991) (xy 370.722921 -259.674773) (xy 370.735712 -259.620884) (xy 370.756687 -259.569624)
			(xy 370.78534 -259.522227) (xy 370.820983 -259.479834) (xy 370.841524 -259.461254) (xy 370.849144 -259.452872)
			(xy 370.86138 -259.436976) (xy 370.890689 -259.409598) (xy 370.924593 -259.388172) (xy 370.961902 -259.373452)
			(xy 371.001302 -259.365957) (xy 371.021356 -259.365496) (xy 371.276372 -259.365496) (xy 371.276372 -259.37464)
			(xy 371.276855 -259.384647) (xy 371.284522 -259.403134) (xy 371.298676 -259.417285) (xy 371.317165 -259.424948)
			(xy 371.327172 -259.42544) (xy 371.49024 -259.42544) (xy 371.500255 -259.425856) (xy 371.518755 -259.433536)
			(xy 371.532908 -259.447712) (xy 371.540559 -259.466224) (xy 371.54104 -259.47624) (xy 371.54104 -259.729991)
			(xy 372.496622 -259.729991) (xy 372.500921 -259.674773) (xy 372.513712 -259.620884) (xy 372.534687 -259.569624)
			(xy 372.56334 -259.522227) (xy 372.598983 -259.479834) (xy 372.619524 -259.461254) (xy 372.627144 -259.452872)
			(xy 372.63938 -259.436976) (xy 372.668689 -259.409598) (xy 372.702593 -259.388172) (xy 372.739902 -259.373452)
			(xy 372.779302 -259.365957) (xy 372.799356 -259.365496) (xy 373.054372 -259.365496) (xy 373.054372 -259.37464)
			(xy 373.054855 -259.384647) (xy 373.062522 -259.403134) (xy 373.076676 -259.417285) (xy 373.095165 -259.424948)
			(xy 373.105172 -259.42544) (xy 373.26824 -259.42544) (xy 373.278255 -259.425856) (xy 373.296755 -259.433536)
			(xy 373.310908 -259.447712) (xy 373.318559 -259.466224) (xy 373.31904 -259.47624) (xy 373.31904 -259.983732)
			(xy 373.318539 -259.993737) (xy 373.310877 -260.012222) (xy 373.296728 -260.026372) (xy 373.278245 -260.034038)
			(xy 373.26824 -260.034532) (xy 373.054372 -260.034532) (xy 373.054372 -260.043676) (xy 373.05396 -260.053699)
			(xy 373.046293 -260.072221) (xy 373.032118 -260.086395) (xy 373.013595 -260.094061) (xy 373.003572 -260.094476)
			(xy 372.799356 -260.094476) (xy 372.7793 -260.094028) (xy 372.739891 -260.086544) (xy 372.702574 -260.07183)
			(xy 372.668664 -260.050403) (xy 372.639353 -260.023019) (xy 372.627144 -260.0071) (xy 372.619524 -259.998718)
			(xy 372.59897 -259.980153) (xy 372.56333 -259.937758) (xy 372.534679 -259.890359) (xy 372.513706 -259.839098)
			(xy 372.500918 -259.785209) (xy 372.496622 -259.729991) (xy 371.54104 -259.729991) (xy 371.54104 -259.983732)
			(xy 371.540539 -259.993737) (xy 371.532877 -260.012222) (xy 371.518728 -260.026372) (xy 371.500245 -260.034038)
			(xy 371.49024 -260.034532) (xy 371.276372 -260.034532) (xy 371.276372 -260.043676) (xy 371.27596 -260.053699)
			(xy 371.268293 -260.072221) (xy 371.254118 -260.086395) (xy 371.235595 -260.094061) (xy 371.225572 -260.094476)
			(xy 371.021356 -260.094476) (xy 371.0013 -260.094028) (xy 370.961891 -260.086544) (xy 370.924574 -260.07183)
			(xy 370.890664 -260.050403) (xy 370.861353 -260.023019) (xy 370.849144 -260.0071) (xy 370.841524 -259.998718)
			(xy 370.82097 -259.980153) (xy 370.78533 -259.937758) (xy 370.756679 -259.890359) (xy 370.735706 -259.839098)
			(xy 370.722918 -259.785209) (xy 370.718622 -259.729991) (xy 369.61572 -259.729991) (xy 369.61572 -259.983732)
			(xy 369.615239 -259.993739) (xy 369.607572 -260.012228) (xy 369.593418 -260.026379) (xy 369.574927 -260.034041)
			(xy 369.56492 -260.034532) (xy 369.350544 -260.034532) (xy 369.350544 -260.043676) (xy 369.349994 -260.053677)
			(xy 369.34235 -260.07216) (xy 369.328217 -260.086312) (xy 369.309744 -260.09398) (xy 369.299744 -260.094476)
			(xy 369.095782 -260.094476) (xy 369.075726 -260.094009) (xy 369.036319 -260.08653) (xy 368.999002 -260.071821)
			(xy 368.965091 -260.050398) (xy 368.93578 -260.023017) (xy 368.92357 -260.0071) (xy 368.91595 -259.998718)
			(xy 368.895394 -259.980154) (xy 368.859752 -259.93776) (xy 368.831099 -259.890361) (xy 368.810125 -259.8391)
			(xy 368.797335 -259.78521) (xy 368.793039 -259.729991) (xy 364.459341 -259.729991) (xy 364.461763 -259.73591)
			(xy 364.474552 -259.789806) (xy 364.478846 -259.845032) (xy 364.474542 -259.900257) (xy 364.461743 -259.95415)
			(xy 364.440758 -260.005414) (xy 364.412092 -260.052812) (xy 364.376436 -260.095203) (xy 364.355888 -260.11378)
			(xy 364.348268 -260.122162) (xy 364.336051 -260.138086) (xy 364.306749 -260.165506) (xy 364.272847 -260.186979)
			(xy 364.235534 -260.201751) (xy 364.19612 -260.209303) (xy 364.176056 -260.209792) (xy 363.92104 -260.209792)
			(xy 363.92104 -260.200648) (xy 363.920542 -260.190635) (xy 363.912895 -260.172126) (xy 363.898747 -260.157954)
			(xy 363.880252 -260.150275) (xy 363.87024 -260.149848) (xy 363.405928 -260.149848) (xy 363.399421 -260.149978)
			(xy 363.386817 -260.153208) (xy 363.381036 -260.156198) (xy 363.370876 -260.161786) (xy 363.370876 -260.180074)
			(xy 363.341158 -260.209792) (xy 363.11586 -260.209792) (xy 363.095187 -260.209308) (xy 363.05462 -260.201324)
			(xy 363.016347 -260.185681) (xy 362.981801 -260.162966) (xy 362.952272 -260.134026) (xy 362.928865 -260.099944)
			(xy 362.912454 -260.061994) (xy 362.90758 -260.041898) (xy 362.906643 -260.037967) (xy 362.903713 -260.030437)
			(xy 362.901738 -260.026912) (xy 362.889882 -260.006189) (xy 362.871188 -259.962259) (xy 362.85852 -259.916228)
			(xy 362.852106 -259.868919) (xy 362.8517 -259.845048) (xy 361.878882 -259.845048) (xy 361.87458 -259.900255)
			(xy 361.861783 -259.954147) (xy 361.840801 -260.005409) (xy 361.81214 -260.052808) (xy 361.77649 -260.095201)
			(xy 361.755944 -260.11378) (xy 361.748324 -260.122162) (xy 361.736132 -260.138107) (xy 361.706824 -260.165525)
			(xy 361.672916 -260.186995) (xy 361.635597 -260.201762) (xy 361.596178 -260.209307) (xy 361.576112 -260.209792)
			(xy 361.321096 -260.209792) (xy 361.321096 -260.200648) (xy 361.320641 -260.190629) (xy 361.312986 -260.172113)
			(xy 361.298824 -260.157939) (xy 361.280314 -260.150268) (xy 361.270296 -260.149848) (xy 360.805984 -260.149848)
			(xy 360.799479 -260.149999) (xy 360.786875 -260.153215) (xy 360.781092 -260.156198) (xy 360.770932 -260.161786)
			(xy 360.770932 -260.180074) (xy 360.741214 -260.209792) (xy 360.515916 -260.209792) (xy 360.495245 -260.209258)
			(xy 360.45468 -260.201285) (xy 360.416408 -260.185652) (xy 360.381861 -260.162944) (xy 360.352331 -260.134012)
			(xy 360.328923 -260.099936) (xy 360.312511 -260.061992) (xy 360.307636 -260.041898) (xy 360.306703 -260.037966)
			(xy 360.303771 -260.030437) (xy 360.301794 -260.026912) (xy 360.289934 -260.006192) (xy 360.271241 -259.962261)
			(xy 360.258575 -259.916229) (xy 360.252161 -259.868919) (xy 360.251756 -259.845048) (xy 359.628961 -259.845048)
			(xy 359.624658 -259.900256) (xy 359.61186 -259.954149) (xy 359.590877 -260.005412) (xy 359.562213 -260.05281)
			(xy 359.526559 -260.095202) (xy 359.506012 -260.11378) (xy 359.498392 -260.122162) (xy 359.486161 -260.138075)
			(xy 359.456863 -260.165496) (xy 359.422964 -260.18697) (xy 359.385654 -260.201745) (xy 359.346243 -260.2093)
			(xy 359.32618 -260.209792) (xy 359.071164 -260.209792) (xy 359.071164 -260.200648) (xy 359.07074 -260.190625)
			(xy 359.063079 -260.172103) (xy 359.048908 -260.157927) (xy 359.030387 -260.150262) (xy 359.020364 -260.149848)
			(xy 358.556052 -260.149848) (xy 358.549546 -260.149988) (xy 358.536942 -260.153211) (xy 358.53116 -260.156198)
			(xy 358.521 -260.161786) (xy 358.521 -260.180074) (xy 358.491282 -260.209792) (xy 358.265984 -260.209792)
			(xy 358.245312 -260.209287) (xy 358.204746 -260.201307) (xy 358.166473 -260.185669) (xy 358.131927 -260.162956)
			(xy 358.102397 -260.13402) (xy 358.078989 -260.09994) (xy 358.062579 -260.061993) (xy 358.057704 -260.041898)
			(xy 358.056774 -260.037965) (xy 358.05384 -260.030436) (xy 358.051862 -260.026912) (xy 358.039999 -260.006194)
			(xy 358.021307 -259.962262) (xy 358.008642 -259.916229) (xy 358.002229 -259.868919) (xy 358.001824 -259.845048)
			(xy 357.128847 -259.845048) (xy 357.124543 -259.900256) (xy 357.111745 -259.95415) (xy 357.09076 -260.005413)
			(xy 357.062094 -260.052812) (xy 357.026438 -260.095203) (xy 357.00589 -260.11378) (xy 356.99827 -260.122162)
			(xy 356.986051 -260.138085) (xy 356.95675 -260.165505) (xy 356.922848 -260.186978) (xy 356.885536 -260.20175)
			(xy 356.846122 -260.209302) (xy 356.826058 -260.209792) (xy 356.571296 -260.209792) (xy 356.571296 -260.200648)
			(xy 356.570841 -260.190629) (xy 356.563186 -260.172113) (xy 356.549024 -260.157939) (xy 356.530514 -260.150268)
			(xy 356.520496 -260.149848) (xy 356.055676 -260.149848) (xy 356.049299 -260.150047) (xy 356.036956 -260.153262)
			(xy 356.031292 -260.156198) (xy 356.020624 -260.161786) (xy 356.020624 -260.180074) (xy 355.990906 -260.209792)
			(xy 355.765862 -260.209792) (xy 355.745189 -260.209306) (xy 355.704622 -260.201322) (xy 355.666349 -260.18568)
			(xy 355.631803 -260.162965) (xy 355.602274 -260.134025) (xy 355.578867 -260.099943) (xy 355.562456 -260.061994)
			(xy 355.557582 -260.041898) (xy 355.556645 -260.037967) (xy 355.553715 -260.030437) (xy 355.55174 -260.026912)
			(xy 355.539875 -260.006195) (xy 355.521184 -259.962262) (xy 355.50852 -259.91623) (xy 355.502107 -259.868919)
			(xy 355.501702 -259.845048) (xy 351.132127 -259.845048) (xy 351.113592 -259.890351) (xy 351.084941 -259.937747)
			(xy 351.049302 -259.980139) (xy 351.028762 -259.998718) (xy 351.021142 -260.0071) (xy 351.008933 -260.023017)
			(xy 350.979615 -260.05039) (xy 350.945703 -260.07181) (xy 350.90839 -260.086525) (xy 350.868985 -260.094017)
			(xy 350.84893 -260.094476) (xy 350.594168 -260.094476) (xy 350.594168 -260.085332) (xy 350.593753 -260.075309)
			(xy 350.586088 -260.056787) (xy 350.571913 -260.042612) (xy 350.553391 -260.034947) (xy 350.543368 -260.034532)
			(xy 350.078802 -260.034532) (xy 350.072281 -260.034734) (xy 350.059675 -260.038081) (xy 350.05391 -260.041136)
			(xy 350.043496 -260.046724) (xy 350.043496 -260.064758) (xy 350.013778 -260.094476) (xy 349.788734 -260.094476)
			(xy 349.768078 -260.094015) (xy 349.727545 -260.086028) (xy 349.689301 -260.070403) (xy 349.654772 -260.047721)
			(xy 349.625243 -260.018829) (xy 349.601814 -259.984801) (xy 349.58536 -259.946907) (xy 349.580454 -259.926836)
			(xy 349.579533 -259.922901) (xy 349.576592 -259.915373) (xy 349.574612 -259.91185) (xy 349.562768 -259.891121)
			(xy 349.544071 -259.847193) (xy 349.5314 -259.801164) (xy 349.524981 -259.753856) (xy 349.524574 -259.729986)
			(xy 349.251883 -259.729986) (xy 349.251883 -259.729991) (xy 349.247647 -259.784803) (xy 349.235039 -259.838313)
			(xy 349.214358 -259.88925) (xy 349.186095 -259.936404) (xy 349.150921 -259.978655) (xy 349.13062 -259.997194)
			(xy 349.128588 -259.998972) (xy 349.121984 -260.006084) (xy 349.120206 -260.00837) (xy 349.107981 -260.024061)
			(xy 349.078743 -260.051025) (xy 349.045021 -260.072114) (xy 349.007979 -260.086598) (xy 348.968896 -260.093978)
			(xy 348.94901 -260.094476) (xy 348.73057 -260.094476) (xy 348.720673 -260.094901) (xy 348.702397 -260.102509)
			(xy 348.688442 -260.116548) (xy 348.680943 -260.134868) (xy 348.680532 -260.144768) (xy 348.680532 -261.12597)
			(xy 348.89313 -261.12597) (xy 348.893529 -261.100976) (xy 348.901354 -261.051604) (xy 348.916805 -261.004064)
			(xy 348.939504 -260.959527) (xy 348.96889 -260.919089) (xy 349.004241 -260.883746) (xy 349.044685 -260.854368)
			(xy 349.089227 -260.831679) (xy 349.136771 -260.816238) (xy 349.186144 -260.808424) (xy 349.211138 -260.807962)
			(xy 349.211646 -260.807962) (xy 349.227567 -260.808159) (xy 349.25925 -260.811337) (xy 349.274892 -260.814312)
			(xy 349.288354 -260.815328) (xy 349.304102 -260.81482) (xy 349.30461 -260.81482) (xy 349.559372 -260.81482)
			(xy 349.559372 -260.823964) (xy 349.559848 -260.83398) (xy 349.567501 -260.85249) (xy 349.581656 -260.866663)
			(xy 349.600157 -260.874339) (xy 349.610172 -260.874764) (xy 349.77324 -260.874764) (xy 349.783246 -260.875254)
			(xy 349.801732 -260.88292) (xy 349.815882 -260.897072) (xy 349.823546 -260.915558) (xy 349.82404 -260.925564)
			(xy 349.82404 -261.433056) (xy 351.622868 -261.433056) (xy 351.622868 -260.925564) (xy 351.623358 -260.915558)
			(xy 351.631023 -260.897072) (xy 351.645175 -260.882921) (xy 351.663662 -260.875257) (xy 351.673668 -260.874764)
			(xy 351.81921 -260.874764) (xy 351.82692 -260.874547) (xy 351.841656 -260.870012) (xy 351.848166 -260.865874)
			(xy 351.857639 -260.859487) (xy 351.877343 -260.847919) (xy 351.887536 -260.84276) (xy 351.887536 -260.81482)
			(xy 351.973388 -260.81482) (xy 351.977452 -260.814058) (xy 351.990003 -260.812169) (xy 352.015306 -260.810134)
			(xy 352.027998 -260.809994) (xy 352.040691 -260.810112) (xy 352.065995 -260.812148) (xy 352.078544 -260.814058)
			(xy 352.082608 -260.81482) (xy 352.142552 -260.81482) (xy 352.163596 -260.815367) (xy 352.204869 -260.8236)
			(xy 352.243732 -260.839757) (xy 352.278677 -260.863211) (xy 352.308353 -260.893054) (xy 352.33161 -260.928132)
			(xy 352.347547 -260.967085) (xy 352.355548 -261.008404) (xy 352.355912 -261.02945) (xy 352.355912 -261.029704)
			(xy 352.355912 -261.328916) (xy 352.355912 -261.32917) (xy 352.35563 -261.350223) (xy 352.347624 -261.391555)
			(xy 352.331679 -261.43052) (xy 352.308412 -261.465608) (xy 352.278725 -261.49546) (xy 352.243766 -261.518921)
			(xy 352.20489 -261.535082) (xy 352.163603 -261.543317) (xy 352.142552 -261.5438) (xy 351.887536 -261.5438)
			(xy 351.887536 -261.534656) (xy 351.887049 -261.52465) (xy 351.879381 -261.506164) (xy 351.865229 -261.492014)
			(xy 351.846742 -261.48435) (xy 351.836736 -261.483856) (xy 351.673668 -261.483856) (xy 351.663639 -261.483506)
			(xy 351.645113 -261.475817) (xy 351.63094 -261.461623) (xy 351.623279 -261.443085) (xy 351.622868 -261.433056)
			(xy 349.82404 -261.433056) (xy 349.823545 -261.44307) (xy 349.815897 -261.461578) (xy 349.801748 -261.47575)
			(xy 349.783253 -261.483429) (xy 349.77324 -261.483856) (xy 349.610172 -261.483856) (xy 349.600168 -261.484364)
			(xy 349.581684 -261.492025) (xy 349.567534 -261.506171) (xy 349.559867 -261.524652) (xy 349.559372 -261.534656)
			(xy 349.559372 -261.574026) (xy 349.559866 -261.584032) (xy 349.567529 -261.602519) (xy 349.581679 -261.61667)
			(xy 349.600166 -261.624334) (xy 349.610172 -261.624826) (xy 349.614998 -261.624826) (xy 349.619824 -261.62381)
			(xy 349.634978 -261.621062) (xy 349.665638 -261.618132) (xy 349.681038 -261.617968) (xy 349.706024 -261.618523)
			(xy 349.75538 -261.626346) (xy 349.802904 -261.641794) (xy 349.847427 -261.664486) (xy 349.887852 -261.693863)
			(xy 349.923183 -261.729203) (xy 349.952551 -261.769634) (xy 349.975233 -261.814162) (xy 349.99067 -261.86169)
			(xy 349.998482 -261.911047) (xy 349.998477 -261.961019) (xy 349.990655 -262.010375) (xy 349.975208 -262.0579)
			(xy 349.952516 -262.102423) (xy 349.92314 -262.142848) (xy 349.887801 -262.17818) (xy 349.84737 -262.207549)
			(xy 349.802842 -262.230231) (xy 349.755315 -262.245669) (xy 349.705957 -262.253482) (xy 349.655985 -262.253478)
			(xy 349.606629 -262.245656) (xy 349.559105 -262.23021) (xy 349.514581 -262.207519) (xy 349.474156 -262.178143)
			(xy 349.438823 -262.142804) (xy 349.409454 -262.102374) (xy 349.38677 -262.057847) (xy 349.371332 -262.010319)
			(xy 349.363518 -261.960962) (xy 349.36303 -261.935976) (xy 349.36303 -261.935722) (xy 349.363459 -261.911417)
			(xy 349.37088 -261.863376) (xy 349.38552 -261.817022) (xy 349.40704 -261.773434) (xy 349.43494 -261.733627)
			(xy 349.451422 -261.715758) (xy 349.46209 -261.704836) (xy 349.467678 -261.674864) (xy 349.425006 -261.574788)
			(xy 349.420707 -261.565817) (xy 349.406589 -261.551829) (xy 349.388207 -261.544271) (xy 349.37827 -261.5438)
			(xy 349.304356 -261.5438) (xy 349.282801 -261.543263) (xy 349.240569 -261.534597) (xy 349.200931 -261.517644)
			(xy 349.165493 -261.493093) (xy 349.135694 -261.461938) (xy 349.123762 -261.443978) (xy 349.119128 -261.437162)
			(xy 349.10644 -261.426661) (xy 349.09887 -261.423404) (xy 349.076518 -261.414501) (xy 349.034575 -261.390931)
			(xy 348.996662 -261.361312) (xy 348.963643 -261.326319) (xy 348.936273 -261.286751) (xy 348.915177 -261.243511)
			(xy 348.900836 -261.197587) (xy 348.893577 -261.150026) (xy 348.89313 -261.12597) (xy 348.680532 -261.12597)
			(xy 348.680532 -261.460742) (xy 348.680943 -261.469511) (xy 348.686912 -261.486006) (xy 348.692216 -261.493)
			(xy 348.697042 -261.499096) (xy 348.712028 -261.50824) (xy 348.721934 -261.510018) (xy 348.741749 -261.514261)
			(xy 348.779415 -261.529192) (xy 348.813579 -261.550974) (xy 348.84301 -261.57882) (xy 348.866648 -261.611728)
			(xy 348.875604 -261.629906) (xy 348.878652 -261.63651) (xy 348.898972 -261.659624) (xy 348.90583 -261.663688)
			(xy 348.92885 -261.678272) (xy 348.969982 -261.71401) (xy 349.004428 -261.756231) (xy 349.031179 -261.803702)
			(xy 349.049456 -261.855035) (xy 349.058723 -261.908731) (xy 349.059246 -261.935976) (xy 349.058722 -261.962058)
			(xy 349.050209 -262.013521) (xy 349.033407 -262.062904) (xy 349.008766 -262.10888) (xy 348.97695 -262.150217)
			(xy 348.938811 -262.185803) (xy 348.895373 -262.214684) (xy 348.847802 -262.236085) (xy 348.797375 -262.249431)
			(xy 348.771464 -262.25246) (xy 348.76486 -262.253222) (xy 348.761812 -262.253476) (xy 348.753938 -262.257286)
			(xy 348.75055 -262.259094) (xy 348.744304 -262.26356) (xy 348.741492 -262.266176) (xy 348.708218 -262.302244)
			(xy 348.70771 -262.302752) (xy 348.692724 -262.319262) (xy 348.687141 -262.326276) (xy 348.680903 -262.34307)
			(xy 348.680532 -262.352028) (xy 348.680532 -262.745982) (xy 348.89313 -262.745982) (xy 348.893582 -262.721402)
			(xy 348.901143 -262.672826) (xy 348.916096 -262.625996) (xy 348.938085 -262.582027) (xy 348.966586 -262.541972)
			(xy 349.000916 -262.506784) (xy 349.040258 -262.477306) (xy 349.083671 -262.45424) (xy 349.106744 -262.445754)
			(xy 349.114033 -262.442935) (xy 349.126577 -262.433629) (xy 349.131382 -262.427466) (xy 349.143525 -262.411315)
			(xy 349.172871 -262.383543) (xy 349.206926 -262.3618) (xy 349.244469 -262.346867) (xy 349.284154 -262.33928)
			(xy 349.304356 -262.33882) (xy 349.559372 -262.33882) (xy 349.559372 -262.347964) (xy 349.559848 -262.35798)
			(xy 349.567501 -262.37649) (xy 349.581656 -262.390663) (xy 349.600157 -262.398339) (xy 349.610172 -262.398764)
			(xy 349.77324 -262.398764) (xy 349.783246 -262.399254) (xy 349.801732 -262.40692) (xy 349.815882 -262.421072)
			(xy 349.823546 -262.439558) (xy 349.82404 -262.449564) (xy 349.82404 -262.957056) (xy 351.622868 -262.957056)
			(xy 351.622868 -262.449564) (xy 351.623358 -262.439558) (xy 351.631023 -262.421072) (xy 351.645175 -262.406921)
			(xy 351.663662 -262.399257) (xy 351.673668 -262.398764) (xy 351.887536 -262.398764) (xy 351.887536 -262.38962)
			(xy 351.887937 -262.379596) (xy 351.895607 -262.361072) (xy 351.909786 -262.346898) (xy 351.928311 -262.339234)
			(xy 351.938336 -262.33882) (xy 352.142552 -262.33882) (xy 352.163596 -262.339367) (xy 352.204869 -262.3476)
			(xy 352.243732 -262.363757) (xy 352.278677 -262.387211) (xy 352.308353 -262.417054) (xy 352.33161 -262.452132)
			(xy 352.347547 -262.491085) (xy 352.355548 -262.532404) (xy 352.355912 -262.55345) (xy 352.355912 -262.553704)
			(xy 352.355912 -262.85317) (xy 352.35563 -262.874223) (xy 352.347624 -262.915555) (xy 352.331679 -262.95452)
			(xy 352.308412 -262.989608) (xy 352.278725 -263.01946) (xy 352.243766 -263.042921) (xy 352.20489 -263.059082)
			(xy 352.163603 -263.067317) (xy 352.142552 -263.0678) (xy 351.917254 -263.0678) (xy 351.887536 -263.038082)
			(xy 351.887536 -263.033256) (xy 351.856802 -263.015984) (xy 351.850582 -263.012213) (xy 351.836641 -263.008084)
			(xy 351.82937 -263.007856) (xy 351.673668 -263.007856) (xy 351.663639 -263.007506) (xy 351.645113 -262.999817)
			(xy 351.63094 -262.985623) (xy 351.623279 -262.967085) (xy 351.622868 -262.957056) (xy 349.82404 -262.957056)
			(xy 349.823545 -262.96707) (xy 349.815897 -262.985578) (xy 349.801748 -262.99975) (xy 349.783253 -263.007429)
			(xy 349.77324 -263.007856) (xy 349.559372 -263.007856) (xy 349.559372 -263.017) (xy 349.55898 -263.027025)
			(xy 349.551305 -263.045547) (xy 349.537124 -263.05972) (xy 349.518597 -263.067385) (xy 349.508572 -263.0678)
			(xy 349.304356 -263.0678) (xy 349.293097 -263.067699) (xy 349.270698 -263.065406) (xy 349.259652 -263.063228)
			(xy 349.255758 -263.06251) (xy 349.247849 -263.06213) (xy 349.243904 -263.062466) (xy 349.211138 -263.06399)
			(xy 349.186147 -263.063508) (xy 349.13678 -263.055694) (xy 349.089243 -263.040253) (xy 349.044707 -263.017564)
			(xy 349.004269 -262.988188) (xy 348.968925 -262.952846) (xy 348.939546 -262.91241) (xy 348.916855 -262.867876)
			(xy 348.901411 -262.82034) (xy 348.893594 -262.770973) (xy 348.89313 -262.745982) (xy 348.680532 -262.745982)
			(xy 348.680532 -263.063736) (xy 348.681042 -263.073489) (xy 348.68848 -263.091527) (xy 348.69501 -263.098788)
			(xy 348.774512 -263.17829) (xy 348.78137 -263.181846) (xy 348.803852 -263.194508) (xy 348.842387 -263.228802)
			(xy 348.85757 -263.249664) (xy 348.859602 -263.252458) (xy 348.878906 -263.269222) (xy 348.884494 -263.272016)
			(xy 348.902399 -263.28143) (xy 348.935901 -263.304105) (xy 348.951296 -263.317228) (xy 348.969016 -263.333411)
			(xy 348.999878 -263.370157) (xy 349.024898 -263.411106) (xy 349.034608 -263.433052) (xy 349.038418 -263.442196)
			(xy 349.193358 -263.597136) (xy 349.200015 -263.603213) (xy 349.216434 -263.610615) (xy 349.234406 -263.611801)
			(xy 349.243142 -263.609582) (xy 349.33128 -263.576562) (xy 349.33799 -263.573837) (xy 349.349598 -263.565186)
			(xy 349.35414 -263.559544) (xy 349.358204 -263.55421) (xy 349.363284 -263.540494) (xy 349.363792 -263.532874)
			(xy 349.366238 -263.506492) (xy 349.37878 -263.455017) (xy 349.399682 -263.406334) (xy 349.428364 -263.361788)
			(xy 349.464033 -263.322614) (xy 349.505703 -263.289893) (xy 349.552219 -263.264533) (xy 349.602296 -263.247233)
			(xy 349.654547 -263.238474) (xy 349.681038 -263.23798) (xy 349.706026 -263.238473) (xy 349.755385 -263.246296)
			(xy 349.802913 -263.261744) (xy 349.847439 -263.284435) (xy 349.887868 -263.313812) (xy 349.923205 -263.349151)
			(xy 349.952579 -263.389583) (xy 349.975266 -263.434111) (xy 349.99071 -263.481641) (xy 349.998529 -263.531)
			(xy 349.999046 -263.555988) (xy 349.998949 -263.568035) (xy 349.997168 -263.592064) (xy 349.99549 -263.603994)
			(xy 349.993712 -263.615424) (xy 349.99676 -263.62533) (xy 349.99836 -263.630539) (xy 350.003483 -263.640152)
			(xy 350.00692 -263.64438) (xy 350.024954 -263.665208) (xy 350.058228 -263.703816) (xy 350.065572 -263.710796)
			(xy 350.084177 -263.718777) (xy 350.094296 -263.71931)
		)
		(stroke
			(width 0)
			(type solid)
		)
		(fill yes)
		(layer "B.Cu")
		(net "PVDDCR_SOC_P0")
	)
	(gr_poly
		(pts
			(xy 339.563964 -293.307516) (xy 339.590634 -293.296594) (xy 339.597238 -293.290498) (xy 339.618066 -293.273226)
			(xy 339.637595 -293.258862) (xy 339.680124 -293.235596) (xy 339.725693 -293.219057) (xy 339.773244 -293.209629)
			(xy 339.821676 -293.207531) (xy 339.869864 -293.212811) (xy 339.893402 -293.218616) (xy 339.896958 -293.219632)
			(xy 339.92947 -293.230808) (xy 339.955539 -293.241903) (xy 340.003585 -293.271919) (xy 340.024974 -293.290498)
			(xy 340.031578 -293.296594) (xy 340.058248 -293.307516) (xy 340.07171 -293.31031) (xy 340.16188 -293.31031)
			(xy 340.171717 -293.309773) (xy 340.189876 -293.302184) (xy 340.197186 -293.295578) (xy 340.292436 -293.200328)
			(xy 340.298258 -293.193978) (xy 340.305572 -293.178395) (xy 340.307184 -293.161256) (xy 340.30539 -293.15283)
			(xy 340.275672 -293.063168) (xy 340.273224 -293.057028) (xy 340.265636 -293.046211) (xy 340.260686 -293.041832)
			(xy 340.255606 -293.037514) (xy 340.242906 -293.031672) (xy 340.235286 -293.030656) (xy 340.210401 -293.026553)
			(xy 340.162264 -293.011515) (xy 340.117103 -292.989066) (xy 340.076053 -292.95977) (xy 340.040142 -292.924361)
			(xy 340.01027 -292.883728) (xy 339.987188 -292.838888) (xy 339.971473 -292.790967) (xy 339.963519 -292.741166)
			(xy 339.962998 -292.71595) (xy 339.963459 -292.690956) (xy 339.971271 -292.641584) (xy 339.986713 -292.594041)
			(xy 340.009402 -292.5495) (xy 340.03878 -292.509057) (xy 340.074124 -292.473708) (xy 340.114562 -292.444325)
			(xy 340.1591 -292.421629) (xy 340.206641 -292.406182) (xy 340.256012 -292.398362) (xy 340.281006 -292.397942)
			(xy 340.306224 -292.398425) (xy 340.356028 -292.406386) (xy 340.403952 -292.422107) (xy 340.448793 -292.445194)
			(xy 340.489429 -292.47507) (xy 340.524841 -292.510984) (xy 340.554141 -292.552036) (xy 340.576595 -292.597199)
			(xy 340.59164 -292.645339) (xy 340.595712 -292.67023) (xy 340.596728 -292.67785) (xy 340.60257 -292.69055)
			(xy 340.606888 -292.69563) (xy 340.611303 -292.700541) (xy 340.622105 -292.708131) (xy 340.628224 -292.710616)
			(xy 340.717886 -292.740334) (xy 340.726313 -292.742085) (xy 340.743433 -292.740443) (xy 340.759021 -292.733175)
			(xy 340.765384 -292.72738) (xy 340.925658 -292.567106) (xy 340.929214 -292.560502) (xy 340.941114 -292.539105)
			(xy 340.970252 -292.499761) (xy 341.004872 -292.465143) (xy 341.044217 -292.436007) (xy 341.065612 -292.424104)
			(xy 341.072216 -292.420548) (xy 341.39378 -292.098984) (xy 341.396774 -292.095888) (xy 341.401756 -292.088864)
			(xy 341.403686 -292.085014) (xy 341.403686 -292.053264) (xy 341.403505 -292.048094) (xy 341.401338 -292.037981)
			(xy 341.399368 -292.033198) (xy 341.391093 -292.013104) (xy 341.379441 -291.971239) (xy 341.37357 -291.92818)
			(xy 341.373206 -291.906452) (xy 341.373206 -291.900102) (xy 341.374096 -291.875702) (xy 341.382436 -291.827597)
			(xy 341.398029 -291.78133) (xy 341.42051 -291.73799) (xy 341.44935 -291.698595) (xy 341.483872 -291.66407)
			(xy 341.523264 -291.635226) (xy 341.566602 -291.612741) (xy 341.612867 -291.597143) (xy 341.660972 -291.588799)
			(xy 341.685372 -291.587936) (xy 341.694008 -291.587936) (xy 341.715271 -291.588427) (xy 341.757379 -291.594406)
			(xy 341.79831 -291.60596) (xy 341.81796 -291.614098) (xy 341.827612 -291.618416) (xy 341.870284 -291.618416)
			(xy 341.874131 -291.616481) (xy 341.881158 -291.611503) (xy 341.884254 -291.60851) (xy 341.987378 -291.505386)
			(xy 341.994031 -291.498124) (xy 342.001509 -291.479921) (xy 342.001856 -291.47008) (xy 341.99576 -291.389562)
			(xy 341.995043 -291.384224) (xy 341.991706 -291.373986) (xy 341.989156 -291.369242) (xy 341.984076 -291.360606)
			(xy 341.974678 -291.353748) (xy 341.954674 -291.338688) (xy 341.919218 -291.303335) (xy 341.889735 -291.262865)
			(xy 341.866954 -291.218278) (xy 341.851437 -291.170674) (xy 341.843566 -291.121227) (xy 341.843106 -291.096192)
			(xy 341.843106 -291.095938) (xy 341.843568 -291.070945) (xy 341.851382 -291.021574) (xy 341.866824 -290.974034)
			(xy 341.889514 -290.929495) (xy 341.918892 -290.889054) (xy 341.954236 -290.853708) (xy 341.994675 -290.824326)
			(xy 342.039212 -290.801633) (xy 342.086751 -290.786188) (xy 342.136121 -290.778369) (xy 342.161114 -290.77793)
			(xy 342.161368 -290.77793) (xy 342.186404 -290.778397) (xy 342.235857 -290.786244) (xy 342.283468 -290.801751)
			(xy 342.328057 -290.824532) (xy 342.368522 -290.854025) (xy 342.403861 -290.889498) (xy 342.418924 -290.909502)
			(xy 342.419432 -290.910264) (xy 342.422694 -290.914452) (xy 342.43063 -290.9215) (xy 342.43518 -290.924234)
			(xy 342.44407 -290.929568) (xy 342.535764 -290.93668) (xy 342.545452 -290.936136) (xy 342.563355 -290.928697)
			(xy 342.570562 -290.922202) (xy 342.71839 -290.774374) (xy 342.724945 -290.767109) (xy 342.732436 -290.749054)
			(xy 342.732546 -290.729506) (xy 342.729312 -290.720272) (xy 342.710008 -290.67633) (xy 342.690704 -290.632134)
			(xy 342.686101 -290.623561) (xy 342.671709 -290.610492) (xy 342.653446 -290.603829) (xy 342.643714 -290.603686)
			(xy 342.631014 -290.60394) (xy 342.606019 -290.603477) (xy 342.556646 -290.595658) (xy 342.509103 -290.580213)
			(xy 342.464562 -290.557519) (xy 342.424119 -290.528138) (xy 342.388771 -290.492791) (xy 342.359387 -290.452349)
			(xy 342.336692 -290.407809) (xy 342.321244 -290.360267) (xy 342.313424 -290.310893) (xy 342.313425 -290.260904)
			(xy 342.321245 -290.211531) (xy 342.336693 -290.163989) (xy 342.359389 -290.119448) (xy 342.388772 -290.079007)
			(xy 342.424121 -290.043661) (xy 342.464564 -290.014279) (xy 342.509105 -289.991586) (xy 342.556648 -289.976141)
			(xy 342.606022 -289.968323) (xy 342.656011 -289.968326) (xy 342.705384 -289.976149) (xy 342.752926 -289.991599)
			(xy 342.797465 -290.014297) (xy 342.837904 -290.043682) (xy 342.873249 -290.079033) (xy 342.902629 -290.119477)
			(xy 342.92532 -290.164019) (xy 342.940763 -290.211563) (xy 342.948578 -290.260937) (xy 342.949022 -290.285932)
			(xy 342.948768 -290.298632) (xy 342.948876 -290.308365) (xy 342.955563 -290.326626) (xy 342.968638 -290.341022)
			(xy 342.977216 -290.345622) (xy 343.021158 -290.36518) (xy 343.021666 -290.36518) (xy 343.064084 -290.383722)
			(xy 343.073438 -290.38733) (xy 343.093469 -290.387592) (xy 343.112023 -290.38004) (xy 343.119456 -290.373308)
			(xy 343.240868 -290.251896) (xy 343.24798 -290.243006) (xy 343.249504 -290.240466) (xy 343.25941 -290.222432)
			(xy 343.260172 -290.218622) (xy 343.266182 -290.193301) (xy 343.285318 -290.144909) (xy 343.312076 -290.100277)
			(xy 343.34574 -290.060594) (xy 343.385415 -290.02692) (xy 343.430041 -290.000152) (xy 343.478428 -289.981004)
			(xy 343.503758 -289.975036) (xy 343.507568 -289.974274) (xy 343.525348 -289.964368) (xy 343.533222 -289.959288)
			(xy 343.536778 -289.955986) (xy 343.773252 -289.719512) (xy 343.779931 -289.712194) (xy 343.787388 -289.693855)
			(xy 343.78773 -289.683952) (xy 343.779094 -289.656266) (xy 343.777062 -289.652964) (xy 343.776046 -289.651694)
			(xy 343.77503 -289.649916) (xy 343.762772 -289.630422) (xy 343.743397 -289.588648) (xy 343.730249 -289.544517)
			(xy 343.723604 -289.49895) (xy 343.723214 -289.475926) (xy 343.723677 -289.450934) (xy 343.731493 -289.401565)
			(xy 343.746936 -289.354027) (xy 343.769627 -289.30949) (xy 343.799006 -289.269052) (xy 343.834349 -289.233708)
			(xy 343.874787 -289.204329) (xy 343.919323 -289.181638) (xy 343.966861 -289.166194) (xy 344.01623 -289.158377)
			(xy 344.041222 -289.157918) (xy 344.065164 -289.158352) (xy 344.112507 -289.165528) (xy 344.15824 -289.179715)
			(xy 344.201333 -289.200593) (xy 344.221308 -289.213798) (xy 344.228674 -289.218878) (xy 344.245438 -289.223196)
			(xy 344.25382 -289.222434) (xy 344.259892 -289.221715) (xy 344.271448 -289.217726) (xy 344.27668 -289.21456)
			(xy 344.285062 -289.207702) (xy 344.612722 -288.880042) (xy 344.619442 -288.872806) (xy 344.627055 -288.854602)
			(xy 344.627454 -288.844736) (xy 344.627454 -287.463738) (xy 344.627072 -287.454422) (xy 344.620269 -287.437076)
			(xy 344.614246 -287.429956) (xy 344.583766 -287.400746) (xy 344.559128 -287.377124) (xy 344.551648 -287.370806)
			(xy 344.533356 -287.363872) (xy 344.523568 -287.363662) (xy 344.523314 -287.363662) (xy 344.511122 -287.363916)
			(xy 344.486129 -287.363453) (xy 344.436758 -287.355637) (xy 344.389218 -287.340193) (xy 344.344679 -287.317502)
			(xy 344.304238 -287.288123) (xy 344.268892 -287.252779) (xy 344.23951 -287.21234) (xy 344.216816 -287.167803)
			(xy 344.201368 -287.120263) (xy 344.193549 -287.070893) (xy 344.193549 -287.020907) (xy 344.201368 -286.971537)
			(xy 344.216816 -286.923997) (xy 344.23951 -286.87946) (xy 344.268892 -286.839021) (xy 344.304238 -286.803677)
			(xy 344.344679 -286.774298) (xy 344.389218 -286.751607) (xy 344.436758 -286.736163) (xy 344.486129 -286.728347)
			(xy 344.511122 -286.7279) (xy 344.523314 -286.728154) (xy 344.523568 -286.728154) (xy 344.533609 -286.728007)
			(xy 344.552336 -286.720801) (xy 344.55989 -286.714184) (xy 344.61196 -286.664146) (xy 344.618947 -286.656804)
			(xy 344.626947 -286.6382) (xy 344.627454 -286.628078) (xy 344.627454 -284.223968) (xy 344.627077 -284.21465)
			(xy 344.620282 -284.197297) (xy 344.614246 -284.190186) (xy 344.583766 -284.160976) (xy 344.559128 -284.137354)
			(xy 344.551649 -284.131033) (xy 344.533357 -284.124095) (xy 344.523568 -284.123892) (xy 344.523314 -284.123892)
			(xy 344.511122 -284.124146) (xy 344.486127 -284.123683) (xy 344.436751 -284.115866) (xy 344.389206 -284.100421)
			(xy 344.344663 -284.077728) (xy 344.304219 -284.048345) (xy 344.268869 -284.012998) (xy 344.239484 -283.972556)
			(xy 344.216788 -283.928014) (xy 344.201339 -283.88047) (xy 344.193519 -283.831095) (xy 344.193519 -283.781105)
			(xy 344.201339 -283.73173) (xy 344.216788 -283.684186) (xy 344.239484 -283.639644) (xy 344.268869 -283.599202)
			(xy 344.304219 -283.563855) (xy 344.344663 -283.534472) (xy 344.389206 -283.511779) (xy 344.436751 -283.496334)
			(xy 344.486127 -283.488517) (xy 344.511122 -283.48813) (xy 344.523314 -283.488384) (xy 344.523568 -283.488384)
			(xy 344.533608 -283.488235) (xy 344.552328 -283.481021) (xy 344.55989 -283.474414) (xy 344.61196 -283.424376)
			(xy 344.618936 -283.41703) (xy 344.626911 -283.398426) (xy 344.627454 -283.388308) (xy 344.627454 -280.983944)
			(xy 344.627073 -280.974627) (xy 344.620271 -280.95728) (xy 344.614246 -280.950162) (xy 344.583766 -280.920952)
			(xy 344.559128 -280.89733) (xy 344.551648 -280.891012) (xy 344.533356 -280.884077) (xy 344.523568 -280.883868)
			(xy 344.523314 -280.883868) (xy 344.511122 -280.884122) (xy 344.486129 -280.883659) (xy 344.436757 -280.875843)
			(xy 344.389215 -280.860398) (xy 344.344676 -280.837707) (xy 344.304234 -280.808327) (xy 344.268887 -280.772982)
			(xy 344.239504 -280.732543) (xy 344.21681 -280.688005) (xy 344.201363 -280.640465) (xy 344.193543 -280.591093)
			(xy 344.193543 -280.541107) (xy 344.201363 -280.491735) (xy 344.21681 -280.444195) (xy 344.239504 -280.399657)
			(xy 344.268887 -280.359218) (xy 344.304234 -280.323873) (xy 344.344676 -280.294493) (xy 344.389215 -280.271802)
			(xy 344.436757 -280.256357) (xy 344.486129 -280.248541) (xy 344.511122 -280.248106) (xy 344.523314 -280.24836)
			(xy 344.523568 -280.24836) (xy 344.533607 -280.248211) (xy 344.552326 -280.240994) (xy 344.55989 -280.23439)
			(xy 344.61196 -280.184352) (xy 344.618948 -280.17701) (xy 344.62695 -280.158406) (xy 344.627454 -280.148284)
			(xy 344.627454 -279.363932) (xy 344.627071 -279.354616) (xy 344.620266 -279.337272) (xy 344.614246 -279.33015)
			(xy 344.583766 -279.30094) (xy 344.559128 -279.277318) (xy 344.551648 -279.271001) (xy 344.533356 -279.264068)
			(xy 344.523568 -279.263856) (xy 344.523314 -279.263856) (xy 344.511122 -279.26411) (xy 344.486129 -279.263647)
			(xy 344.436759 -279.255831) (xy 344.38922 -279.240387) (xy 344.344682 -279.217697) (xy 344.304242 -279.188318)
			(xy 344.268896 -279.152975) (xy 344.239515 -279.112537) (xy 344.216821 -279.068) (xy 344.201374 -279.020462)
			(xy 344.193554 -278.971092) (xy 344.193554 -278.921108) (xy 344.201374 -278.871738) (xy 344.216821 -278.8242)
			(xy 344.239515 -278.779663) (xy 344.268896 -278.739225) (xy 344.304242 -278.703882) (xy 344.344682 -278.674503)
			(xy 344.38922 -278.651813) (xy 344.436759 -278.636369) (xy 344.486129 -278.628553) (xy 344.511122 -278.628094)
			(xy 344.523314 -278.628348) (xy 344.523568 -278.628348) (xy 344.533609 -278.6282) (xy 344.552335 -278.620994)
			(xy 344.55989 -278.614378) (xy 344.61196 -278.56434) (xy 344.618946 -278.556997) (xy 344.626944 -278.538394)
			(xy 344.627454 -278.528272) (xy 344.627454 -276.123908) (xy 344.627084 -276.114587) (xy 344.620299 -276.097224)
			(xy 344.614246 -276.090126) (xy 344.583766 -276.060916) (xy 344.559128 -276.037294) (xy 344.551651 -276.030969)
			(xy 344.533358 -276.024025) (xy 344.523568 -276.023832) (xy 344.523314 -276.023832) (xy 344.511122 -276.024086)
			(xy 344.486131 -276.023623) (xy 344.436765 -276.015807) (xy 344.389229 -276.000365) (xy 344.344695 -275.977676)
			(xy 344.304258 -275.948299) (xy 344.268915 -275.912959) (xy 344.239536 -275.872524) (xy 344.216844 -275.827991)
			(xy 344.201398 -275.780456) (xy 344.193579 -275.731091) (xy 344.193579 -275.681109) (xy 344.201398 -275.631744)
			(xy 344.216844 -275.584209) (xy 344.239536 -275.539676) (xy 344.268915 -275.499241) (xy 344.304258 -275.463901)
			(xy 344.344695 -275.434524) (xy 344.389229 -275.411835) (xy 344.436765 -275.396393) (xy 344.486131 -275.388577)
			(xy 344.511122 -275.38807) (xy 344.523314 -275.388324) (xy 344.523568 -275.388324) (xy 344.533608 -275.388176)
			(xy 344.552332 -275.380967) (xy 344.55989 -275.374354) (xy 344.61196 -275.324316) (xy 344.618942 -275.316972)
			(xy 344.626931 -275.298368) (xy 344.627454 -275.288248) (xy 344.627454 -272.883884) (xy 344.62708 -272.874564)
			(xy 344.620289 -272.857208) (xy 344.614246 -272.850102) (xy 344.583766 -272.820892) (xy 344.559128 -272.79727)
			(xy 344.55165 -272.790948) (xy 344.533357 -272.784007) (xy 344.523568 -272.783808) (xy 344.523314 -272.783808)
			(xy 344.511122 -272.784062) (xy 344.486133 -272.783599) (xy 344.436771 -272.775784) (xy 344.389239 -272.760343)
			(xy 344.344707 -272.737655) (xy 344.304274 -272.708281) (xy 344.268933 -272.672943) (xy 344.239556 -272.632511)
			(xy 344.216866 -272.587982) (xy 344.201421 -272.540451) (xy 344.193603 -272.491089) (xy 344.193603 -272.441111)
			(xy 344.201421 -272.391749) (xy 344.216866 -272.344218) (xy 344.239556 -272.299689) (xy 344.268933 -272.259257)
			(xy 344.304274 -272.223919) (xy 344.344707 -272.194545) (xy 344.389239 -272.171857) (xy 344.436771 -272.156416)
			(xy 344.486133 -272.148601) (xy 344.511122 -272.148046) (xy 344.523314 -272.1483) (xy 344.523568 -272.1483)
			(xy 344.533608 -272.148151) (xy 344.55233 -272.140939) (xy 344.55989 -272.13433) (xy 344.61196 -272.084292)
			(xy 344.618939 -272.076947) (xy 344.626919 -272.058343) (xy 344.627454 -272.048224) (xy 344.627454 -269.64386)
			(xy 344.627076 -269.634542) (xy 344.620278 -269.617191) (xy 344.614246 -269.610078) (xy 344.583766 -269.580868)
			(xy 344.559128 -269.557246) (xy 344.551649 -269.550926) (xy 344.533357 -269.543989) (xy 344.523568 -269.543784)
			(xy 344.523314 -269.543784) (xy 344.511122 -269.544038) (xy 344.486127 -269.543575) (xy 344.436753 -269.535758)
			(xy 344.389209 -269.520313) (xy 344.344667 -269.497621) (xy 344.304224 -269.468239) (xy 344.268875 -269.432893)
			(xy 344.239491 -269.392451) (xy 344.216795 -269.347911) (xy 344.201347 -269.300369) (xy 344.193527 -269.250995)
			(xy 344.193527 -269.201005) (xy 344.201347 -269.151631) (xy 344.216795 -269.104089) (xy 344.239491 -269.059549)
			(xy 344.268875 -269.019107) (xy 344.304224 -268.983761) (xy 344.344667 -268.954379) (xy 344.389209 -268.931687)
			(xy 344.436753 -268.916242) (xy 344.486127 -268.908425) (xy 344.511122 -268.908022) (xy 344.523314 -268.908276)
			(xy 344.523568 -268.908276) (xy 344.533607 -268.908127) (xy 344.552327 -268.900912) (xy 344.55989 -268.894306)
			(xy 344.61196 -268.844268) (xy 344.61895 -268.836927) (xy 344.626959 -268.818323) (xy 344.627454 -268.8082)
			(xy 344.627454 -268.023848) (xy 344.627074 -268.014531) (xy 344.620273 -267.997183) (xy 344.614246 -267.990066)
			(xy 344.583766 -267.960856) (xy 344.559128 -267.937234) (xy 344.551648 -267.930915) (xy 344.533356 -267.92398)
			(xy 344.523568 -267.923772) (xy 344.523314 -267.923772) (xy 344.511122 -267.924026) (xy 344.486128 -267.923563)
			(xy 344.436756 -267.915746) (xy 344.389214 -267.900302) (xy 344.344674 -267.87761) (xy 344.304232 -267.84823)
			(xy 344.268884 -267.812885) (xy 344.239501 -267.772445) (xy 344.216806 -267.727906) (xy 344.201359 -267.680366)
			(xy 344.193539 -267.630994) (xy 344.193539 -267.581006) (xy 344.201359 -267.531634) (xy 344.216806 -267.484094)
			(xy 344.239501 -267.439555) (xy 344.268884 -267.399115) (xy 344.304232 -267.36377) (xy 344.344674 -267.33439)
			(xy 344.389214 -267.311698) (xy 344.436756 -267.296254) (xy 344.486128 -267.288437) (xy 344.511122 -267.28801)
			(xy 344.511122 -267.287756) (xy 344.53747 -267.288274) (xy 344.589445 -267.296966) (xy 344.639275 -267.314109)
			(xy 344.685597 -267.339232) (xy 344.727143 -267.371649) (xy 344.762775 -267.410472) (xy 344.777568 -267.432282)
			(xy 344.778076 -267.43279) (xy 344.783918 -267.44168) (xy 344.810334 -267.458698) (xy 344.815156 -267.461708)
			(xy 344.8258 -267.465693) (xy 344.831416 -267.466572) (xy 344.901266 -267.474954) (xy 344.911829 -267.475085)
			(xy 344.931561 -267.467593) (xy 344.939366 -267.460476) (xy 345.3638 -267.036042) (xy 345.370523 -267.028808)
			(xy 345.378139 -267.010603) (xy 345.378532 -267.000736) (xy 345.378532 -266.787884) (xy 345.379059 -266.778043)
			(xy 345.386636 -266.759871) (xy 345.393264 -266.752578) (xy 345.793822 -266.35202) (xy 345.797886 -266.342622)
			(xy 345.804754 -266.327461) (xy 345.825684 -266.301598) (xy 345.853098 -266.282745) (xy 345.868752 -266.27709)
			(xy 345.8718 -266.274042) (xy 345.87904 -266.267332) (xy 345.897244 -266.259741) (xy 345.907106 -266.25931)
			(xy 346.010738 -266.25931) (xy 346.022497 -266.258612) (xy 346.043424 -266.247866) (xy 346.05087 -266.238736)
			(xy 346.075508 -266.20089) (xy 346.098368 -266.16533) (xy 346.104241 -266.155009) (xy 346.10661 -266.131414)
			(xy 346.10294 -266.120118) (xy 346.10167 -266.117324) (xy 346.092686 -266.09661) (xy 346.08001 -266.053275)
			(xy 346.073606 -266.008581) (xy 346.073222 -265.986006) (xy 346.073712 -265.961017) (xy 346.081531 -265.911654)
			(xy 346.096975 -265.864122) (xy 346.119665 -265.81959) (xy 346.149041 -265.779157) (xy 346.184381 -265.743817)
			(xy 346.224814 -265.714441) (xy 346.269346 -265.691751) (xy 346.316878 -265.676307) (xy 346.366241 -265.668488)
			(xy 346.416219 -265.668488) (xy 346.465582 -265.676307) (xy 346.513114 -265.691751) (xy 346.557646 -265.714441)
			(xy 346.598079 -265.743817) (xy 346.633419 -265.779157) (xy 346.662795 -265.81959) (xy 346.685485 -265.864122)
			(xy 346.700929 -265.911654) (xy 346.708748 -265.961017) (xy 346.709238 -265.986006) (xy 346.708825 -266.008579)
			(xy 346.702415 -266.053269) (xy 346.689768 -266.096609) (xy 346.68079 -266.117324) (xy 346.67952 -266.120118)
			(xy 346.675865 -266.131412) (xy 346.678247 -266.154998) (xy 346.684092 -266.16533) (xy 346.706952 -266.20089)
			(xy 346.73159 -266.238736) (xy 346.739037 -266.247857) (xy 346.759968 -266.258579) (xy 346.771722 -266.25931)
			(xy 347.516958 -266.25931) (xy 347.526797 -266.258777) (xy 347.544962 -266.251194) (xy 347.552264 -266.244578)
			(xy 348.2848 -265.512042) (xy 348.29204 -265.505332) (xy 348.310244 -265.497741) (xy 348.320106 -265.49731)
			(xy 348.79788 -265.49731) (xy 348.807717 -265.496773) (xy 348.825876 -265.489184) (xy 348.833186 -265.482578)
			(xy 348.930722 -265.385042) (xy 348.937442 -265.377806) (xy 348.945055 -265.359602) (xy 348.945454 -265.349736)
			(xy 348.945454 -265.009884) (xy 348.944947 -265.00013) (xy 348.937512 -264.982088) (xy 348.930976 -264.974832)
			(xy 348.833186 -264.877042) (xy 348.826465 -264.869807) (xy 348.818851 -264.851602) (xy 348.818454 -264.841736)
			(xy 348.818454 -263.728962) (xy 348.818983 -263.719121) (xy 348.826557 -263.700947) (xy 348.833186 -263.693656)
			(xy 348.9452 -263.581642) (xy 348.951791 -263.574333) (xy 348.959287 -263.556156) (xy 348.959297 -263.536494)
			(xy 348.95182 -263.51831) (xy 348.9452 -263.51103) (xy 348.706186 -263.272016) (xy 348.705932 -263.272016)
			(xy 348.614238 -263.180322) (xy 348.614238 -263.180068) (xy 348.610682 -263.176512) (xy 348.58071 -263.14654)
			(xy 348.574474 -263.139751) (xy 348.56694 -263.122944) (xy 348.565978 -263.113774) (xy 348.565216 -263.101328)
			(xy 348.559882 -263.091676) (xy 348.557581 -263.087818) (xy 348.551835 -263.080915) (xy 348.548452 -263.07796)
			(xy 348.543372 -263.07415) (xy 348.46768 -263.02843) (xy 348.462031 -263.025399) (xy 348.449697 -263.021922)
			(xy 348.443296 -263.021572) (xy 348.43085 -263.021318) (xy 348.419166 -263.027414) (xy 348.396204 -263.038943)
			(xy 348.347483 -263.05525) (xy 348.296773 -263.06351) (xy 348.271084 -263.06399) (xy 348.246097 -263.063499)
			(xy 348.196739 -263.055679) (xy 348.149211 -263.040234) (xy 348.104685 -263.017545) (xy 348.064256 -262.98817)
			(xy 348.02892 -262.952832) (xy 347.999547 -262.912401) (xy 347.97686 -262.867874) (xy 347.961418 -262.820346)
			(xy 347.9536 -262.770987) (xy 347.9536 -262.721013) (xy 347.961418 -262.671654) (xy 347.97686 -262.624126)
			(xy 347.999547 -262.579599) (xy 348.02892 -262.539168) (xy 348.064256 -262.50383) (xy 348.104685 -262.474455)
			(xy 348.149211 -262.451766) (xy 348.196739 -262.436321) (xy 348.246097 -262.428501) (xy 348.271084 -262.427974)
			(xy 348.296773 -262.428465) (xy 348.347483 -262.436719) (xy 348.396208 -262.453014) (xy 348.419166 -262.46455)
			(xy 348.41942 -262.46455) (xy 348.425124 -262.467332) (xy 348.437459 -262.470299) (xy 348.443804 -262.470392)
			(xy 348.457012 -262.470138) (xy 348.502732 -262.442452) (xy 348.543372 -262.417814) (xy 348.552397 -262.41118)
			(xy 348.563992 -262.392052) (xy 348.565724 -262.380984) (xy 348.565724 -262.352282) (xy 348.565978 -262.34644)
			(xy 348.565978 -262.298434) (xy 348.565504 -262.288569) (xy 348.557967 -262.270336) (xy 348.544026 -262.256375)
			(xy 348.525804 -262.248811) (xy 348.51594 -262.248396) (xy 348.443804 -262.248396) (xy 348.41434 -262.218932)
			(xy 348.3991 -262.203438) (xy 348.391703 -262.196587) (xy 348.373105 -262.188847) (xy 348.363032 -262.188452)
			(xy 348.149418 -262.188452) (xy 348.149418 -262.175752) (xy 348.028006 -262.175752) (xy 348.019778 -262.176035)
			(xy 348.004204 -262.181351) (xy 347.997526 -262.186166) (xy 347.997272 -262.18642) (xy 347.976171 -262.202285)
			(xy 347.929801 -262.227516) (xy 347.879897 -262.244729) (xy 347.827833 -262.253451) (xy 347.801438 -262.253984)
			(xy 347.795088 -262.253984) (xy 347.77143 -262.253097) (xy 347.724752 -262.245196) (xy 347.702124 -262.238236)
			(xy 347.694504 -262.235696) (xy 347.62186 -262.235696) (xy 347.600651 -262.235207) (xy 347.559063 -262.226862)
			(xy 347.519942 -262.210469) (xy 347.484828 -262.186674) (xy 347.455104 -262.156414) (xy 347.431941 -262.12088)
			(xy 347.41625 -262.081472) (xy 347.408651 -262.039741) (xy 347.4085 -262.018526) (xy 347.4085 -261.724394)
			(xy 347.4085 -261.723378) (xy 347.408665 -261.70218) (xy 347.416349 -261.660498) (xy 347.432088 -261.621144)
			(xy 347.455266 -261.585658) (xy 347.484974 -261.555428) (xy 347.520052 -261.531637) (xy 347.559126 -261.515216)
			(xy 347.600669 -261.506807) (xy 347.62186 -261.506208) (xy 347.826076 -261.506208) (xy 347.8361 -261.506623)
			(xy 347.854624 -261.514289) (xy 347.868802 -261.528463) (xy 347.876473 -261.546984) (xy 347.876876 -261.557008)
			(xy 347.876876 -261.566152) (xy 348.149418 -261.566152) (xy 348.149418 -261.553452) (xy 348.364048 -261.553452)
			(xy 348.3739 -261.552963) (xy 348.392101 -261.545411) (xy 348.40603 -261.531472) (xy 348.41357 -261.513267)
			(xy 348.414086 -261.503414) (xy 348.414086 -261.482078) (xy 348.413668 -261.472861) (xy 348.407047 -261.455657)
			(xy 348.394695 -261.441974) (xy 348.378256 -261.433633) (xy 348.369128 -261.432294) (xy 348.356936 -261.432294)
			(xy 348.350586 -261.433818) (xy 348.331053 -261.438558) (xy 348.291181 -261.443648) (xy 348.271084 -261.443978)
			(xy 348.246098 -261.443487) (xy 348.196742 -261.435667) (xy 348.149216 -261.420223) (xy 348.104691 -261.397534)
			(xy 348.064264 -261.36816) (xy 348.028929 -261.332824) (xy 347.999557 -261.292395) (xy 347.976871 -261.247869)
			(xy 347.961429 -261.200343) (xy 347.953612 -261.150986) (xy 347.953612 -261.101014) (xy 347.961429 -261.051657)
			(xy 347.976871 -261.004131) (xy 347.999557 -260.959605) (xy 348.028929 -260.919176) (xy 348.064264 -260.88384)
			(xy 348.104691 -260.854466) (xy 348.149216 -260.831777) (xy 348.196742 -260.816333) (xy 348.246098 -260.808513)
			(xy 348.271084 -260.807962) (xy 348.271338 -260.807962) (xy 348.281847 -260.808059) (xy 348.302819 -260.809456)
			(xy 348.313248 -260.810756) (xy 348.324424 -260.81228) (xy 348.334076 -260.809232) (xy 348.339054 -260.807679)
			(xy 348.348277 -260.802818) (xy 348.352364 -260.79958) (xy 348.372176 -260.782054) (xy 348.411546 -260.74751)
			(xy 348.418359 -260.740244) (xy 348.426079 -260.721901) (xy 348.426532 -260.71195) (xy 348.426532 -256.500884)
			(xy 348.426025 -256.49113) (xy 348.418587 -256.47309) (xy 348.412054 -256.465832) (xy 348.18701 -256.240788)
			(xy 348.179763 -256.234233) (xy 348.161719 -256.226783) (xy 348.151958 -256.22631) (xy 347.313758 -256.22631)
			(xy 347.304331 -256.226708) (xy 347.286783 -256.233601) (xy 347.272958 -256.24642) (xy 347.268546 -256.254758)
			(xy 347.232986 -256.345944) (xy 347.23074 -256.353031) (xy 347.229972 -256.367871) (xy 347.231462 -256.375154)
			(xy 347.234002 -256.385822) (xy 347.247464 -256.398268) (xy 347.266647 -256.416613) (xy 347.299265 -256.458483)
			(xy 347.324544 -256.505152) (xy 347.341794 -256.555347) (xy 347.350544 -256.607696) (xy 347.351096 -256.634234)
			(xy 347.351096 -256.634488) (xy 347.35053 -256.661346) (xy 347.341518 -256.714301) (xy 347.32378 -256.765004)
			(xy 347.297815 -256.812029) (xy 347.2815 -256.83337) (xy 347.27896 -256.836672) (xy 347.275912 -256.845816)
			(xy 347.275912 -256.883916) (xy 347.275912 -256.88417) (xy 347.275546 -256.905215) (xy 347.267543 -256.946531)
			(xy 347.251604 -256.98548) (xy 347.228346 -257.020554) (xy 347.198671 -257.050395) (xy 347.163726 -257.073846)
			(xy 347.124866 -257.090001) (xy 347.083594 -257.098233) (xy 347.062552 -257.0988) (xy 346.858336 -257.0988)
			(xy 346.84831 -257.098387) (xy 346.829781 -257.090723) (xy 346.815597 -257.07655) (xy 346.80792 -257.058026)
			(xy 346.807536 -257.048) (xy 346.807536 -257.038856) (xy 346.572586 -257.038856) (xy 346.542868 -257.009138)
			(xy 346.542868 -256.993898) (xy 346.542614 -256.991866) (xy 346.542614 -256.476754) (xy 346.542868 -256.474722)
			(xy 346.542868 -256.459482) (xy 346.572586 -256.429764) (xy 346.75572 -256.429764) (xy 346.75953 -256.42951)
			(xy 346.763648 -256.429146) (xy 346.77169 -256.427227) (xy 346.775532 -256.4257) (xy 346.785946 -256.421128)
			(xy 346.79255 -256.414524) (xy 346.79939 -256.407124) (xy 346.807105 -256.388525) (xy 346.807536 -256.378456)
			(xy 346.807536 -256.36982) (xy 346.846906 -256.36982) (xy 346.85351 -256.367788) (xy 346.854272 -256.36728)
			(xy 346.876821 -256.352991) (xy 346.92559 -256.331288) (xy 346.9513 -256.3241) (xy 346.952062 -256.3241)
			(xy 346.97289 -256.318258) (xy 346.98178 -256.310638) (xy 346.98178 -256.242058) (xy 346.974367 -256.234922)
			(xy 346.955483 -256.226802) (xy 346.945204 -256.22631) (xy 345.433904 -256.22631) (xy 345.42433 -256.226782)
			(xy 345.406575 -256.233968) (xy 345.392734 -256.247208) (xy 345.388438 -256.255774) (xy 345.364308 -256.31775)
			(xy 345.353132 -256.346198) (xy 345.350882 -256.353285) (xy 345.350101 -256.368127) (xy 345.351608 -256.375408)
			(xy 345.353132 -256.382012) (xy 345.360498 -256.394458) (xy 345.36634 -256.400046) (xy 345.385387 -256.418247)
			(xy 345.417775 -256.459795) (xy 345.442873 -256.506113) (xy 345.459994 -256.555933) (xy 345.46867 -256.607894)
			(xy 345.46921 -256.634234) (xy 345.468717 -256.659221) (xy 345.460895 -256.708581) (xy 345.445447 -256.756108)
			(xy 345.422756 -256.800635) (xy 345.393379 -256.841064) (xy 345.358039 -256.8764) (xy 345.317608 -256.905773)
			(xy 345.273079 -256.92846) (xy 345.225549 -256.943902) (xy 345.17619 -256.95172) (xy 345.151202 -256.952242)
			(xy 345.126326 -256.951761) (xy 345.07718 -256.944014) (xy 345.029841 -256.928709) (xy 344.985462 -256.906219)
			(xy 344.945126 -256.877093) (xy 344.909818 -256.842042) (xy 344.880398 -256.80192) (xy 344.857585 -256.757706)
			(xy 344.841935 -256.71048) (xy 344.833829 -256.661392) (xy 344.833194 -256.63652) (xy 344.833194 -256.633726)
			(xy 344.833758 -256.60745) (xy 344.842445 -256.555622) (xy 344.859538 -256.505927) (xy 344.884571 -256.45972)
			(xy 344.916862 -256.41826) (xy 344.93581 -256.400046) (xy 344.938604 -256.397506) (xy 344.942979 -256.392573)
			(xy 344.949288 -256.380999) (xy 344.95105 -256.374646) (xy 344.952574 -256.367788) (xy 344.952066 -256.360168)
			(xy 344.951752 -256.356265) (xy 344.950088 -256.348614) (xy 344.948764 -256.344928) (xy 344.913966 -256.255774)
			(xy 344.909659 -256.247202) (xy 344.895858 -256.233902) (xy 344.878083 -256.226731) (xy 344.8685 -256.22631)
			(xy 344.38209 -256.22631) (xy 344.372247 -256.225785) (xy 344.35407 -256.218215) (xy 344.346784 -256.211578)
			(xy 344.15095 -256.015744) (xy 344.144233 -256.008507) (xy 344.136624 -255.990303) (xy 344.136218 -255.980438)
			(xy 344.136218 -255.95199) (xy 344.135752 -255.941885) (xy 344.127819 -255.923296) (xy 344.11323 -255.909309)
			(xy 344.10396 -255.905254) (xy 344.0811 -255.905254) (xy 344.075766 -255.905508) (xy 344.069441 -255.906404)
			(xy 344.057486 -255.910895) (xy 344.052144 -255.914398) (xy 344.045032 -255.919478) (xy 344.040714 -255.930654)
			(xy 344.03919 -255.934464) (xy 344.03919 -255.934718) (xy 344.030364 -255.957233) (xy 344.006887 -255.999509)
			(xy 343.97728 -256.037744) (xy 343.942226 -256.071055) (xy 343.902532 -256.098675) (xy 343.859114 -256.119968)
			(xy 343.812973 -256.134441) (xy 343.765173 -256.141761) (xy 343.740994 -256.142236) (xy 343.716004 -256.141745)
			(xy 343.66664 -256.133926) (xy 343.619107 -256.118482) (xy 343.574575 -256.095792) (xy 343.53414 -256.066416)
			(xy 343.498798 -256.031077) (xy 343.469419 -255.990644) (xy 343.446726 -255.946113) (xy 343.431279 -255.898581)
			(xy 343.423456 -255.849218) (xy 343.422986 -255.824228) (xy 343.423498 -255.798713) (xy 343.431655 -255.748339)
			(xy 343.447751 -255.699913) (xy 343.47137 -255.654678) (xy 343.501908 -255.613793) (xy 343.538581 -255.578308)
			(xy 343.580449 -255.549132) (xy 343.626437 -255.527015) (xy 343.675366 -255.512523) (xy 343.700608 -255.50876)
			(xy 343.709752 -255.50749) (xy 343.73307 -255.505604) (xy 343.779794 -255.507876) (xy 343.825683 -255.516966)
			(xy 343.869745 -255.532678) (xy 343.911032 -255.554672) (xy 343.948653 -255.582475) (xy 343.96553 -255.598676)
			(xy 343.966038 -255.599184) (xy 343.97146 -255.604214) (xy 343.984499 -255.61118) (xy 343.991692 -255.6129)
			(xy 343.998296 -255.61417) (xy 344.005662 -255.613408) (xy 344.009317 -255.612976) (xy 344.016458 -255.611192)
			(xy 344.019886 -255.609852) (xy 344.107262 -255.573276) (xy 344.115661 -255.568884) (xy 344.128656 -255.555106)
			(xy 344.135711 -255.53753) (xy 344.136218 -255.528064) (xy 344.136218 -255.360424) (xy 344.13571 -255.353058)
			(xy 344.134876 -255.348318) (xy 344.131676 -255.339243) (xy 344.12936 -255.335024) (xy 344.127074 -255.331468)
			(xy 344.118184 -255.318768) (xy 344.112088 -255.316736) (xy 344.103198 -255.313434) (xy 344.078927 -255.304133)
			(xy 344.033552 -255.278789) (xy 343.9929 -255.246406) (xy 343.958053 -255.207845) (xy 343.929939 -255.164132)
			(xy 343.909305 -255.11643) (xy 343.896701 -255.066008) (xy 343.892461 -255.014207) (xy 343.896698 -254.962407)
			(xy 343.909301 -254.911985) (xy 343.929932 -254.864282) (xy 343.958044 -254.820567) (xy 343.992889 -254.782004)
			(xy 344.033539 -254.749619) (xy 344.078914 -254.724273) (xy 344.103198 -254.71501) (xy 344.112088 -254.711708)
			(xy 344.118184 -254.709676) (xy 344.127074 -254.696976) (xy 344.12936 -254.69342) (xy 344.131693 -254.689209)
			(xy 344.13488 -254.680128) (xy 344.13571 -254.675386) (xy 344.136218 -254.66802) (xy 344.136218 -254.50038)
			(xy 344.135826 -254.490918) (xy 344.128876 -254.473316) (xy 344.115926 -254.459518) (xy 344.107516 -254.455168)
			(xy 344.092784 -254.448818) (xy 344.092276 -254.448818) (xy 344.02014 -254.418846) (xy 344.013108 -254.416129)
			(xy 343.998117 -254.414585) (xy 343.990676 -254.415798) (xy 343.984072 -254.417068) (xy 343.971372 -254.423926)
			(xy 343.965276 -254.429768) (xy 343.965022 -254.430022) (xy 343.947023 -254.447186) (xy 343.906685 -254.476275)
			(xy 343.862313 -254.498734) (xy 343.814987 -254.514018) (xy 343.76586 -254.521753) (xy 343.740994 -254.522224)
			(xy 343.716005 -254.521733) (xy 343.666641 -254.513914) (xy 343.619109 -254.49847) (xy 343.574578 -254.47578)
			(xy 343.534144 -254.446404) (xy 343.498803 -254.411064) (xy 343.469425 -254.370631) (xy 343.446734 -254.3261)
			(xy 343.431288 -254.278568) (xy 343.423468 -254.229205) (xy 343.422986 -254.204216) (xy 343.423491 -254.178696)
			(xy 343.431638 -254.128312) (xy 343.447725 -254.079874) (xy 343.471339 -254.034627) (xy 343.501875 -253.99373)
			(xy 343.538549 -253.958234) (xy 343.580421 -253.929049) (xy 343.626415 -253.906924) (xy 343.675351 -253.892426)
			(xy 343.700608 -253.888748) (xy 343.709752 -253.887478) (xy 343.73307 -253.885592) (xy 343.779795 -253.887864)
			(xy 343.825683 -253.896954) (xy 343.869746 -253.912665) (xy 343.911034 -253.934659) (xy 343.948655 -253.962461)
			(xy 343.96553 -253.978664) (xy 343.966038 -253.979172) (xy 343.971459 -253.984203) (xy 343.984498 -253.991171)
			(xy 343.991692 -253.992888) (xy 343.998296 -253.994158) (xy 344.005662 -253.993396) (xy 344.009317 -253.992964)
			(xy 344.016458 -253.991179) (xy 344.019886 -253.98984) (xy 344.107262 -253.953264) (xy 344.115659 -253.948871)
			(xy 344.128652 -253.935093) (xy 344.135703 -253.917517) (xy 344.136218 -253.908052) (xy 344.136218 -253.740412)
			(xy 344.13571 -253.733046) (xy 344.134875 -253.728307) (xy 344.131674 -253.719232) (xy 344.12936 -253.715012)
			(xy 344.127074 -253.711456) (xy 344.118184 -253.698756) (xy 344.112088 -253.696724) (xy 344.103198 -253.693422)
			(xy 344.078928 -253.684121) (xy 344.033555 -253.658778) (xy 343.992905 -253.626395) (xy 343.95806 -253.587835)
			(xy 343.929947 -253.544123) (xy 343.909315 -253.496422) (xy 343.896711 -253.446002) (xy 343.892472 -253.394203)
			(xy 343.89671 -253.342405) (xy 343.909313 -253.291984) (xy 343.929944 -253.244283) (xy 343.958056 -253.200571)
			(xy 343.9929 -253.16201) (xy 344.033549 -253.129626) (xy 344.078922 -253.104282) (xy 344.103198 -253.094998)
			(xy 344.112088 -253.091696) (xy 344.118184 -253.089664) (xy 344.127074 -253.076964) (xy 344.12936 -253.073408)
			(xy 344.131692 -253.069197) (xy 344.134877 -253.060115) (xy 344.13571 -253.055374) (xy 344.136218 -253.048008)
			(xy 344.136218 -252.880368) (xy 344.135824 -252.870907) (xy 344.128872 -252.853309) (xy 344.115921 -252.839514)
			(xy 344.107516 -252.835156) (xy 344.092784 -252.828806) (xy 344.092276 -252.828806) (xy 344.02014 -252.798834)
			(xy 344.013108 -252.796117) (xy 343.998117 -252.794574) (xy 343.990676 -252.795786) (xy 343.984072 -252.797056)
			(xy 343.971372 -252.803914) (xy 343.965276 -252.809756) (xy 343.965022 -252.81001) (xy 343.947024 -252.827175)
			(xy 343.906686 -252.856264) (xy 343.862314 -252.878725) (xy 343.814988 -252.894009) (xy 343.76586 -252.901745)
			(xy 343.740994 -252.902212) (xy 343.716005 -252.901721) (xy 343.666642 -252.893902) (xy 343.619111 -252.878458)
			(xy 343.57458 -252.855768) (xy 343.534147 -252.826391) (xy 343.498808 -252.791051) (xy 343.469431 -252.750618)
			(xy 343.446742 -252.706087) (xy 343.431297 -252.658556) (xy 343.423479 -252.609193) (xy 343.422986 -252.584204)
			(xy 343.423492 -252.558685) (xy 343.43164 -252.508302) (xy 343.447728 -252.459866) (xy 343.471343 -252.41462)
			(xy 343.50188 -252.373725) (xy 343.538554 -252.338231) (xy 343.580424 -252.309047) (xy 343.626418 -252.286922)
			(xy 343.675353 -252.272425) (xy 343.700608 -252.268736) (xy 343.709752 -252.267466) (xy 343.73307 -252.265581)
			(xy 343.779795 -252.267852) (xy 343.825684 -252.276942) (xy 343.869747 -252.292652) (xy 343.911035 -252.314646)
			(xy 343.948657 -252.342447) (xy 343.96553 -252.358652) (xy 343.966038 -252.35916) (xy 343.971459 -252.364192)
			(xy 343.984497 -252.371162) (xy 343.991692 -252.372876) (xy 343.998296 -252.374146) (xy 344.005662 -252.373384)
			(xy 344.009317 -252.372952) (xy 344.016458 -252.371167) (xy 344.019886 -252.369828) (xy 344.107262 -252.333252)
			(xy 344.115658 -252.328858) (xy 344.128647 -252.31508) (xy 344.135694 -252.297504) (xy 344.136218 -252.28804)
			(xy 344.136218 -252.1204) (xy 344.13571 -252.113034) (xy 344.134874 -252.108295) (xy 344.131671 -252.099222)
			(xy 344.12936 -252.095) (xy 344.127074 -252.091444) (xy 344.118184 -252.078744) (xy 344.112088 -252.076712)
			(xy 344.103198 -252.07341) (xy 344.078929 -252.064109) (xy 344.033558 -252.038766) (xy 343.99291 -252.006384)
			(xy 343.958066 -251.967825) (xy 343.929955 -251.924114) (xy 343.909324 -251.876415) (xy 343.896722 -251.825996)
			(xy 343.892484 -251.774199) (xy 343.896722 -251.722403) (xy 343.909325 -251.671984) (xy 343.929956 -251.624285)
			(xy 343.958067 -251.580574) (xy 343.992911 -251.542015) (xy 344.033559 -251.509633) (xy 344.07893 -251.48429)
			(xy 344.103198 -251.474986) (xy 344.112088 -251.471684) (xy 344.118184 -251.469652) (xy 344.127074 -251.456952)
			(xy 344.12936 -251.453396) (xy 344.131699 -251.449187) (xy 344.1349 -251.440108) (xy 344.13571 -251.435362)
			(xy 344.136218 -251.427996) (xy 344.136218 -251.260356) (xy 344.135822 -251.250896) (xy 344.128867 -251.233302)
			(xy 344.115916 -251.219511) (xy 344.107516 -251.215144) (xy 344.092784 -251.208794) (xy 344.092276 -251.208794)
			(xy 344.02014 -251.178822) (xy 344.013108 -251.176105) (xy 343.998117 -251.174562) (xy 343.990676 -251.175774)
			(xy 343.984072 -251.177044) (xy 343.971372 -251.183902) (xy 343.965276 -251.189744) (xy 343.965022 -251.189998)
			(xy 343.947022 -251.207159) (xy 343.906681 -251.23624) (xy 343.862309 -251.258694) (xy 343.814984 -251.273974)
			(xy 343.765859 -251.281708) (xy 343.740994 -251.2822) (xy 343.716003 -251.281735) (xy 343.666637 -251.273915)
			(xy 343.619103 -251.258469) (xy 343.574569 -251.235777) (xy 343.534134 -251.206398) (xy 343.498793 -251.171055)
			(xy 343.469415 -251.130619) (xy 343.446725 -251.086084) (xy 343.431281 -251.038549) (xy 343.423464 -250.989183)
			(xy 343.422986 -250.964192) (xy 343.423493 -250.938674) (xy 343.431642 -250.888292) (xy 343.447732 -250.839858)
			(xy 343.471347 -250.794613) (xy 343.501884 -250.75372) (xy 343.538558 -250.718227) (xy 343.580428 -250.689044)
			(xy 343.626421 -250.666921) (xy 343.675355 -250.652425) (xy 343.700608 -250.648724) (xy 343.709752 -250.647454)
			(xy 343.73307 -250.645569) (xy 343.779795 -250.64784) (xy 343.825684 -250.656929) (xy 343.869748 -250.67264)
			(xy 343.911036 -250.694632) (xy 343.948659 -250.722433) (xy 343.96553 -250.73864) (xy 343.966038 -250.739148)
			(xy 343.971458 -250.744181) (xy 343.984496 -250.751152) (xy 343.991692 -250.752864) (xy 343.998296 -250.754134)
			(xy 344.005662 -250.753372) (xy 344.009317 -250.752941) (xy 344.016459 -250.751159) (xy 344.019886 -250.749816)
			(xy 344.107262 -250.71324) (xy 344.115668 -250.708851) (xy 344.12868 -250.695077) (xy 344.135757 -250.677499)
			(xy 344.136218 -250.668028) (xy 344.136218 -250.500388) (xy 344.13571 -250.493022) (xy 344.134873 -250.488283)
			(xy 344.131668 -250.479211) (xy 344.12936 -250.474988) (xy 344.127074 -250.471432) (xy 344.118184 -250.458732)
			(xy 344.112088 -250.4567) (xy 344.103198 -250.453398) (xy 344.07893 -250.444097) (xy 344.03356 -250.418754)
			(xy 343.992914 -250.386373) (xy 343.958073 -250.347815) (xy 343.929963 -250.304105) (xy 343.909334 -250.256407)
			(xy 343.896732 -250.20599) (xy 343.892495 -250.154195) (xy 343.896734 -250.1024) (xy 343.909337 -250.051984)
			(xy 343.929968 -250.004287) (xy 343.958079 -249.960578) (xy 343.992921 -249.922021) (xy 344.033568 -249.88964)
			(xy 344.078939 -249.864299) (xy 344.103198 -249.854974) (xy 344.112088 -249.851672) (xy 344.118184 -249.84964)
			(xy 344.127074 -249.83694) (xy 344.12936 -249.833384) (xy 344.131698 -249.829175) (xy 344.134897 -249.820095)
			(xy 344.13571 -249.81535) (xy 344.136218 -249.807984) (xy 344.136218 -249.640344) (xy 344.13582 -249.630885)
			(xy 344.128863 -249.613294) (xy 344.115911 -249.599507) (xy 344.107516 -249.595132) (xy 344.092784 -249.588782)
			(xy 344.092276 -249.588782) (xy 344.02014 -249.55881) (xy 344.013108 -249.556094) (xy 343.998118 -249.554551)
			(xy 343.990676 -249.555762) (xy 343.984072 -249.557032) (xy 343.971372 -249.56389) (xy 343.965276 -249.569732)
			(xy 343.965022 -249.569986) (xy 343.947022 -249.587147) (xy 343.906682 -249.61623) (xy 343.86231 -249.638685)
			(xy 343.814985 -249.653965) (xy 343.765859 -249.661699) (xy 343.740994 -249.662188) (xy 343.716007 -249.661697)
			(xy 343.666647 -249.653879) (xy 343.619119 -249.638435) (xy 343.574592 -249.615746) (xy 343.534162 -249.586372)
			(xy 343.498825 -249.551034) (xy 343.46945 -249.510603) (xy 343.446763 -249.466075) (xy 343.43132 -249.418547)
			(xy 343.423502 -249.369187) (xy 343.423502 -249.319213) (xy 343.43132 -249.269853) (xy 343.446763 -249.222325)
			(xy 343.46945 -249.177797) (xy 343.498825 -249.137366) (xy 343.534162 -249.102028) (xy 343.574592 -249.072654)
			(xy 343.619119 -249.049965) (xy 343.666647 -249.034521) (xy 343.716007 -249.026703) (xy 343.740994 -249.026172)
			(xy 343.765175 -249.026623) (xy 343.812978 -249.033944) (xy 343.859122 -249.048418) (xy 343.902543 -249.069712)
			(xy 343.942239 -249.097335) (xy 343.977296 -249.130649) (xy 344.006904 -249.168887) (xy 344.030382 -249.211167)
			(xy 344.03919 -249.23369) (xy 344.03919 -249.233944) (xy 344.039952 -249.235468) (xy 344.042894 -249.242104)
			(xy 344.051929 -249.253459) (xy 344.057732 -249.25782) (xy 344.065352 -249.263154) (xy 344.10396 -249.263154)
			(xy 344.113242 -249.259126) (xy 344.127818 -249.245116) (xy 344.135761 -249.226525) (xy 344.136218 -249.216418)
			(xy 344.136218 -249.140726) (xy 344.136755 -249.130889) (xy 344.144345 -249.112731) (xy 344.15095 -249.10542)
			(xy 344.23604 -249.02033) (xy 344.242025 -249.013822) (xy 344.249408 -248.997769) (xy 344.250814 -248.980155)
			(xy 344.24874 -248.971562) (xy 344.222578 -248.89714) (xy 344.220012 -248.890439) (xy 344.211758 -248.87871)
			(xy 344.206322 -248.874026) (xy 344.202766 -248.871232) (xy 344.186002 -248.858278) (xy 344.176096 -248.852182)
			(xy 344.170254 -248.849642) (xy 344.163142 -248.848626) (xy 344.138406 -248.844373) (xy 344.090596 -248.829103)
			(xy 344.045778 -248.806511) (xy 344.005067 -248.777158) (xy 343.969472 -248.741775) (xy 343.939878 -248.701239)
			(xy 343.91702 -248.656557) (xy 343.901465 -248.608838) (xy 343.8936 -248.559269) (xy 343.89314 -248.534174)
			(xy 343.893607 -248.509186) (xy 343.901429 -248.459824) (xy 343.916878 -248.412295) (xy 343.939571 -248.367767)
			(xy 343.968952 -248.327338) (xy 344.004295 -248.292003) (xy 344.044731 -248.262633) (xy 344.089263 -248.239949)
			(xy 344.136797 -248.224512) (xy 344.186159 -248.216701) (xy 344.211148 -248.216166) (xy 344.236252 -248.216643)
			(xy 344.285837 -248.224537) (xy 344.333566 -248.240122) (xy 344.378254 -248.26301) (xy 344.418792 -248.292634)
			(xy 344.454174 -248.328257) (xy 344.483521 -248.368996) (xy 344.506105 -248.413839) (xy 344.521365 -248.461673)
			(xy 344.5256 -248.486422) (xy 344.527632 -248.49963) (xy 344.551 -248.529348) (xy 344.555678 -248.53479)
			(xy 344.567413 -248.543035) (xy 344.574114 -248.545604) (xy 344.648536 -248.571766) (xy 344.657134 -248.573808)
			(xy 344.674741 -248.572411) (xy 344.690792 -248.56504) (xy 344.697304 -248.559066) (xy 344.8685 -248.38787)
			(xy 344.870532 -248.38406) (xy 344.870532 -248.1326) (xy 344.870019 -248.121819) (xy 344.861071 -248.102201)
			(xy 344.85326 -248.094754) (xy 344.829384 -248.07545) (xy 344.788998 -248.043192) (xy 344.784952 -248.040337)
			(xy 344.775994 -248.036119) (xy 344.771218 -248.03481) (xy 344.760296 -248.03227) (xy 344.753184 -248.033794)
			(xy 344.74912 -248.03481) (xy 344.732313 -248.038258) (xy 344.698203 -248.041952) (xy 344.681048 -248.042176)
			(xy 344.656057 -248.041715) (xy 344.606689 -248.033903) (xy 344.559151 -248.018463) (xy 344.514615 -247.995776)
			(xy 344.474175 -247.966401) (xy 344.43883 -247.931061) (xy 344.409449 -247.890626) (xy 344.386755 -247.846093)
			(xy 344.371309 -247.798558) (xy 344.363489 -247.749191) (xy 344.363489 -247.699209) (xy 344.371309 -247.649842)
			(xy 344.386755 -247.602307) (xy 344.409449 -247.557774) (xy 344.43883 -247.517339) (xy 344.474175 -247.481999)
			(xy 344.514615 -247.452624) (xy 344.559151 -247.429937) (xy 344.606689 -247.414497) (xy 344.656057 -247.406685)
			(xy 344.681048 -247.40616) (xy 344.698203 -247.406391) (xy 344.732312 -247.410087) (xy 344.74912 -247.413526)
			(xy 344.753184 -247.414542) (xy 344.760296 -247.416066) (xy 344.771218 -247.413526) (xy 344.775987 -247.412198)
			(xy 344.784939 -247.407977) (xy 344.788998 -247.405144) (xy 344.829384 -247.372886) (xy 344.85326 -247.353582)
			(xy 344.861077 -247.346137) (xy 344.870035 -247.326519) (xy 344.870532 -247.315736) (xy 344.870532 -247.080786)
			(xy 344.869516 -247.071134) (xy 344.866722 -247.058942) (xy 344.862912 -247.048528) (xy 344.862912 -247.048274)
			(xy 344.853885 -247.027991) (xy 344.840913 -246.985533) (xy 344.833975 -246.941683) (xy 344.833194 -246.919496)
			(xy 344.833194 -246.912892) (xy 344.833681 -246.889841) (xy 344.840481 -246.844239) (xy 344.853779 -246.800093)
			(xy 344.863166 -246.779034) (xy 344.865452 -246.774208) (xy 344.869516 -246.757698) (xy 344.870532 -246.747792)
			(xy 344.870532 -246.512588) (xy 344.870016 -246.501808) (xy 344.861066 -246.482194) (xy 344.85326 -246.474742)
			(xy 344.829384 -246.455438) (xy 344.788998 -246.42318) (xy 344.784951 -246.420326) (xy 344.775994 -246.416109)
			(xy 344.771218 -246.414798) (xy 344.760296 -246.412258) (xy 344.753184 -246.413782) (xy 344.74912 -246.414798)
			(xy 344.732313 -246.418246) (xy 344.698203 -246.42194) (xy 344.681048 -246.422164) (xy 344.656058 -246.421703)
			(xy 344.606692 -246.413891) (xy 344.559156 -246.398452) (xy 344.514621 -246.375766) (xy 344.474183 -246.346392)
			(xy 344.438839 -246.311053) (xy 344.409459 -246.27062) (xy 344.386767 -246.226089) (xy 344.37132 -246.178555)
			(xy 344.363501 -246.12919) (xy 344.363501 -246.07921) (xy 344.37132 -246.029845) (xy 344.386767 -245.982311)
			(xy 344.409459 -245.93778) (xy 344.438839 -245.897347) (xy 344.474183 -245.862008) (xy 344.514621 -245.832634)
			(xy 344.559156 -245.809948) (xy 344.606692 -245.794509) (xy 344.656058 -245.786697) (xy 344.681048 -245.786148)
			(xy 344.681048 -245.785894) (xy 344.698139 -245.786133) (xy 344.732122 -245.789825) (xy 344.748866 -245.79326)
			(xy 344.761058 -245.7958) (xy 344.770964 -245.79326) (xy 344.775795 -245.792034) (xy 344.784884 -245.787946)
			(xy 344.788998 -245.785132) (xy 344.854276 -245.732808) (xy 344.861576 -245.725392) (xy 344.869959 -245.70637)
			(xy 344.870532 -245.695978) (xy 344.870532 -245.460774) (xy 344.869516 -245.451122) (xy 344.866722 -245.43893)
			(xy 344.862912 -245.428516) (xy 344.862912 -245.428262) (xy 344.853886 -245.407979) (xy 344.840915 -245.365521)
			(xy 344.833979 -245.321671) (xy 344.833194 -245.299484) (xy 344.833194 -245.29288) (xy 344.833682 -245.269829)
			(xy 344.840483 -245.224228) (xy 344.853783 -245.180083) (xy 344.863166 -245.159022) (xy 344.865452 -245.154196)
			(xy 344.869516 -245.137686) (xy 344.870532 -245.12778) (xy 344.870532 -244.892576) (xy 344.870014 -244.881797)
			(xy 344.861061 -244.862187) (xy 344.85326 -244.85473) (xy 344.829638 -244.83568) (xy 344.82913 -244.835172)
			(xy 344.78849 -244.802914) (xy 344.784545 -244.800168) (xy 344.775848 -244.796076) (xy 344.771218 -244.794786)
			(xy 344.761058 -244.7925) (xy 344.748866 -244.79504) (xy 344.735118 -244.797897) (xy 344.707264 -244.801457)
			(xy 344.69324 -244.802152) (xy 344.681048 -244.802152) (xy 344.656051 -244.801691) (xy 344.606671 -244.793877)
			(xy 344.559122 -244.778434) (xy 344.514575 -244.755741) (xy 344.474126 -244.726359) (xy 344.438772 -244.691011)
			(xy 344.409384 -244.650566) (xy 344.386685 -244.606022) (xy 344.371234 -244.558476) (xy 344.363413 -244.509097)
			(xy 344.363413 -244.459103) (xy 344.371234 -244.409724) (xy 344.386685 -244.362178) (xy 344.409384 -244.317634)
			(xy 344.438772 -244.277189) (xy 344.474126 -244.241841) (xy 344.514575 -244.212459) (xy 344.559122 -244.189766)
			(xy 344.606671 -244.174323) (xy 344.656051 -244.166509) (xy 344.681048 -244.166136) (xy 344.681048 -244.165882)
			(xy 344.698139 -244.166121) (xy 344.732122 -244.169812) (xy 344.748866 -244.173248) (xy 344.761058 -244.175788)
			(xy 344.770964 -244.173248) (xy 344.775795 -244.172022) (xy 344.784884 -244.167933) (xy 344.788998 -244.16512)
			(xy 344.854276 -244.112796) (xy 344.86159 -244.105385) (xy 344.870005 -244.086363) (xy 344.870532 -244.075966)
			(xy 344.870532 -243.840762) (xy 344.869516 -243.83111) (xy 344.866722 -243.818918) (xy 344.862912 -243.808504)
			(xy 344.862912 -243.80825) (xy 344.853881 -243.787968) (xy 344.840898 -243.745511) (xy 344.83395 -243.701661)
			(xy 344.833194 -243.679472) (xy 344.833194 -243.672868) (xy 344.833683 -243.649817) (xy 344.840486 -243.604217)
			(xy 344.853787 -243.560072) (xy 344.863166 -243.53901) (xy 344.865452 -243.534184) (xy 344.869516 -243.517674)
			(xy 344.870532 -243.507768) (xy 344.870532 -243.272564) (xy 344.870012 -243.261787) (xy 344.861055 -243.24218)
			(xy 344.85326 -243.234718) (xy 344.829384 -243.215414) (xy 344.788998 -243.183156) (xy 344.784951 -243.180303)
			(xy 344.775993 -243.176088) (xy 344.771218 -243.174774) (xy 344.760296 -243.172234) (xy 344.753184 -243.173758)
			(xy 344.74912 -243.174774) (xy 344.732313 -243.178221) (xy 344.698203 -243.181915) (xy 344.681048 -243.18214)
			(xy 344.656052 -243.181679) (xy 344.606674 -243.173865) (xy 344.559127 -243.158423) (xy 344.514581 -243.135731)
			(xy 344.474134 -243.10635) (xy 344.438781 -243.071003) (xy 344.409394 -243.03056) (xy 344.386696 -242.986018)
			(xy 344.371246 -242.938473) (xy 344.363425 -242.889096) (xy 344.363425 -242.839104) (xy 344.371246 -242.789727)
			(xy 344.386696 -242.742182) (xy 344.409394 -242.69764) (xy 344.438781 -242.657197) (xy 344.474134 -242.62185)
			(xy 344.514581 -242.592469) (xy 344.559127 -242.569777) (xy 344.606674 -242.554335) (xy 344.656052 -242.546521)
			(xy 344.681048 -242.546124) (xy 344.698203 -242.546355) (xy 344.732312 -242.550051) (xy 344.74912 -242.55349)
			(xy 344.753184 -242.554506) (xy 344.760296 -242.55603) (xy 344.771218 -242.55349) (xy 344.775986 -242.552161)
			(xy 344.784937 -242.547938) (xy 344.788998 -242.545108) (xy 344.829384 -242.51285) (xy 344.85326 -242.493546)
			(xy 344.861071 -242.486099) (xy 344.870015 -242.466481) (xy 344.870532 -242.4557) (xy 344.870532 -242.22075)
			(xy 344.869516 -242.211098) (xy 344.866722 -242.198906) (xy 344.862912 -242.188492) (xy 344.862912 -242.188238)
			(xy 344.853881 -242.167956) (xy 344.8409 -242.125499) (xy 344.833954 -242.081649) (xy 344.833194 -242.05946)
			(xy 344.833194 -242.052856) (xy 344.833684 -242.029805) (xy 344.840488 -241.984206) (xy 344.853791 -241.940062)
			(xy 344.863166 -241.918998) (xy 344.865452 -241.914172) (xy 344.869516 -241.897662) (xy 344.870532 -241.887756)
			(xy 344.870532 -241.652552) (xy 344.870009 -241.641776) (xy 344.86105 -241.622172) (xy 344.85326 -241.614706)
			(xy 344.829638 -241.595656) (xy 344.82913 -241.595148) (xy 344.78849 -241.56289) (xy 344.784546 -241.560141)
			(xy 344.775851 -241.556043) (xy 344.771218 -241.554762) (xy 344.761058 -241.552476) (xy 344.748866 -241.555016)
			(xy 344.735118 -241.557873) (xy 344.707264 -241.561433) (xy 344.69324 -241.562128) (xy 344.681048 -241.562128)
			(xy 344.656053 -241.561667) (xy 344.606677 -241.553854) (xy 344.559131 -241.538411) (xy 344.514587 -241.515721)
			(xy 344.474141 -241.486341) (xy 344.43879 -241.450995) (xy 344.409404 -241.410554) (xy 344.386707 -241.366013)
			(xy 344.371258 -241.31847) (xy 344.363437 -241.269095) (xy 344.363437 -241.219105) (xy 344.371258 -241.16973)
			(xy 344.386707 -241.122187) (xy 344.409404 -241.077646) (xy 344.43879 -241.037205) (xy 344.474141 -241.001859)
			(xy 344.514587 -240.972479) (xy 344.559131 -240.949789) (xy 344.606677 -240.934346) (xy 344.656053 -240.926533)
			(xy 344.681048 -240.926112) (xy 344.681048 -240.925858) (xy 344.698139 -240.926097) (xy 344.732122 -240.929788)
			(xy 344.748866 -240.933224) (xy 344.761058 -240.935764) (xy 344.770964 -240.933224) (xy 344.775795 -240.931997)
			(xy 344.784882 -240.927907) (xy 344.788998 -240.925096) (xy 344.854276 -240.872772) (xy 344.861586 -240.865359)
			(xy 344.869993 -240.846338) (xy 344.870532 -240.835942) (xy 344.870532 -240.600738) (xy 344.869516 -240.591086)
			(xy 344.866722 -240.578894) (xy 344.862912 -240.56848) (xy 344.862912 -240.568226) (xy 344.853882 -240.547944)
			(xy 344.840903 -240.505487) (xy 344.833958 -240.461636) (xy 344.833194 -240.439448) (xy 344.833194 -240.432844)
			(xy 344.833684 -240.409794) (xy 344.840491 -240.364195) (xy 344.853795 -240.320052) (xy 344.863166 -240.298986)
			(xy 344.865452 -240.29416) (xy 344.869516 -240.27765) (xy 344.870532 -240.267744) (xy 344.870532 -240.03254)
			(xy 344.870007 -240.021765) (xy 344.861045 -240.002165) (xy 344.85326 -239.994694) (xy 344.829638 -239.975644)
			(xy 344.82913 -239.975136) (xy 344.78849 -239.942878) (xy 344.784546 -239.940129) (xy 344.775851 -239.936033)
			(xy 344.771218 -239.93475) (xy 344.761058 -239.932464) (xy 344.748866 -239.935004) (xy 344.735118 -239.937861)
			(xy 344.707264 -239.941421) (xy 344.69324 -239.942116) (xy 344.681048 -239.942116) (xy 344.656054 -239.941655)
			(xy 344.60668 -239.933842) (xy 344.559136 -239.9184) (xy 344.514593 -239.895711) (xy 344.474149 -239.866332)
			(xy 344.438799 -239.830987) (xy 344.409414 -239.790548) (xy 344.386718 -239.746009) (xy 344.371269 -239.698467)
			(xy 344.363449 -239.649094) (xy 344.363449 -239.599106) (xy 344.371269 -239.549733) (xy 344.386718 -239.502191)
			(xy 344.409414 -239.457652) (xy 344.438799 -239.417213) (xy 344.474149 -239.381868) (xy 344.514593 -239.352489)
			(xy 344.559136 -239.3298) (xy 344.60668 -239.314358) (xy 344.656054 -239.306545) (xy 344.681048 -239.3061)
			(xy 344.681048 -239.305846) (xy 344.698139 -239.306085) (xy 344.732122 -239.309776) (xy 344.748866 -239.313212)
			(xy 344.761058 -239.315752) (xy 344.770964 -239.313212) (xy 344.775795 -239.311985) (xy 344.784882 -239.307894)
			(xy 344.788998 -239.305084) (xy 344.854276 -239.25276) (xy 344.861584 -239.245347) (xy 344.869986 -239.226325)
			(xy 344.870532 -239.21593) (xy 344.870532 -238.980726) (xy 344.869516 -238.971074) (xy 344.866722 -238.958882)
			(xy 344.862912 -238.948468) (xy 344.862912 -238.948214) (xy 344.853883 -238.927931) (xy 344.840905 -238.885474)
			(xy 344.833962 -238.841624) (xy 344.833194 -238.819436) (xy 344.833194 -238.812832) (xy 344.833678 -238.78978)
			(xy 344.840473 -238.744177) (xy 344.853766 -238.700028) (xy 344.863166 -238.678974) (xy 344.865452 -238.674148)
			(xy 344.869516 -238.657638) (xy 344.870532 -238.647732) (xy 344.870532 -237.360714) (xy 344.869516 -237.351062)
			(xy 344.866722 -237.33887) (xy 344.862912 -237.328456) (xy 344.862912 -237.328202) (xy 344.853884 -237.307919)
			(xy 344.840907 -237.265462) (xy 344.833966 -237.221612) (xy 344.833194 -237.199424) (xy 344.833194 -237.19282)
			(xy 344.833679 -237.169768) (xy 344.840475 -237.124165) (xy 344.85377 -237.080017) (xy 344.863166 -237.058962)
			(xy 344.865452 -237.054136) (xy 344.869516 -237.037626) (xy 344.870532 -237.02772) (xy 344.870532 -236.792516)
			(xy 344.870022 -236.781734) (xy 344.861079 -236.762111) (xy 344.85326 -236.75467) (xy 344.829638 -236.73562)
			(xy 344.82913 -236.735112) (xy 344.78849 -236.702854) (xy 344.784546 -236.700106) (xy 344.77585 -236.696011)
			(xy 344.771218 -236.694726) (xy 344.761058 -236.69244) (xy 344.748866 -236.69498) (xy 344.735119 -236.697837)
			(xy 344.707264 -236.701398) (xy 344.69324 -236.702092) (xy 344.681048 -236.702092) (xy 344.656056 -236.701631)
			(xy 344.606685 -236.693819) (xy 344.559145 -236.678378) (xy 344.514606 -236.65569) (xy 344.474165 -236.626314)
			(xy 344.438818 -236.590972) (xy 344.409435 -236.550535) (xy 344.38674 -236.505999) (xy 344.371293 -236.458462)
			(xy 344.363473 -236.409092) (xy 344.363473 -236.359108) (xy 344.371293 -236.309738) (xy 344.38674 -236.262201)
			(xy 344.409435 -236.217665) (xy 344.438818 -236.177228) (xy 344.474165 -236.141886) (xy 344.514606 -236.11251)
			(xy 344.559145 -236.089822) (xy 344.606685 -236.074381) (xy 344.656056 -236.066569) (xy 344.681048 -236.066076)
			(xy 344.681048 -236.065822) (xy 344.698139 -236.066061) (xy 344.732122 -236.069752) (xy 344.748866 -236.073188)
			(xy 344.761058 -236.075728) (xy 344.770964 -236.073188) (xy 344.775794 -236.07196) (xy 344.78488 -236.067867)
			(xy 344.788998 -236.06506) (xy 344.854276 -236.012736) (xy 344.86158 -236.005321) (xy 344.869973 -235.986299)
			(xy 344.870532 -235.975906) (xy 344.870532 -235.740702) (xy 344.869516 -235.73105) (xy 344.866722 -235.718858)
			(xy 344.862912 -235.708444) (xy 344.862912 -235.70819) (xy 344.853884 -235.687907) (xy 344.84091 -235.64545)
			(xy 344.83397 -235.6016) (xy 344.833194 -235.579412) (xy 344.833194 -235.572808) (xy 344.83368 -235.549756)
			(xy 344.840478 -235.504154) (xy 344.853774 -235.460007) (xy 344.863166 -235.43895) (xy 344.865452 -235.434124)
			(xy 344.869516 -235.417614) (xy 344.870532 -235.407708) (xy 344.870532 -235.172504) (xy 344.87002 -235.161723)
			(xy 344.861073 -235.142104) (xy 344.85326 -235.134658) (xy 344.829638 -235.115608) (xy 344.82913 -235.1151)
			(xy 344.78849 -235.082842) (xy 344.784546 -235.080095) (xy 344.775849 -235.076001) (xy 344.771218 -235.074714)
			(xy 344.761058 -235.072428) (xy 344.748866 -235.074968) (xy 344.735119 -235.077825) (xy 344.707264 -235.081386)
			(xy 344.69324 -235.08208) (xy 344.681048 -235.08208) (xy 344.656057 -235.081619) (xy 344.606688 -235.073806)
			(xy 344.55915 -235.058367) (xy 344.514612 -235.03568) (xy 344.474173 -235.006304) (xy 344.438827 -234.970964)
			(xy 344.409445 -234.930529) (xy 344.386752 -234.885995) (xy 344.371305 -234.838459) (xy 344.363485 -234.789091)
			(xy 344.363485 -234.739109) (xy 344.371305 -234.689741) (xy 344.386752 -234.642205) (xy 344.409445 -234.597671)
			(xy 344.438827 -234.557236) (xy 344.474173 -234.521896) (xy 344.514612 -234.49252) (xy 344.55915 -234.469833)
			(xy 344.606688 -234.454394) (xy 344.656057 -234.446581) (xy 344.681048 -234.446064) (xy 344.681048 -234.44581)
			(xy 344.698139 -234.446049) (xy 344.732122 -234.449741) (xy 344.748866 -234.453176) (xy 344.761058 -234.455716)
			(xy 344.770964 -234.453176) (xy 344.775795 -234.45195) (xy 344.784885 -234.447863) (xy 344.788998 -234.445048)
			(xy 344.854276 -234.392724) (xy 344.861578 -234.385309) (xy 344.869967 -234.366287) (xy 344.870532 -234.355894)
			(xy 344.870532 -234.12069) (xy 344.869516 -234.111038) (xy 344.866722 -234.098846) (xy 344.862912 -234.088432)
			(xy 344.862912 -234.088178) (xy 344.853885 -234.067895) (xy 344.840912 -234.025437) (xy 344.833974 -233.981587)
			(xy 344.833194 -233.9594) (xy 344.833194 -233.952796) (xy 344.833681 -233.929745) (xy 344.84048 -233.884143)
			(xy 344.853778 -233.839996) (xy 344.863166 -233.818938) (xy 344.865452 -233.814112) (xy 344.869516 -233.797602)
			(xy 344.870532 -233.787696) (xy 344.870532 -233.552492) (xy 344.870017 -233.541712) (xy 344.861068 -233.522096)
			(xy 344.85326 -233.514646) (xy 344.829638 -233.495596) (xy 344.82913 -233.495088) (xy 344.78849 -233.46283)
			(xy 344.784545 -233.460083) (xy 344.775849 -233.45599) (xy 344.771218 -233.454702) (xy 344.761058 -233.452416)
			(xy 344.748866 -233.454956) (xy 344.735119 -233.457814) (xy 344.707264 -233.461374) (xy 344.69324 -233.462068)
			(xy 344.681048 -233.462068) (xy 344.656057 -233.461607) (xy 344.606691 -233.453795) (xy 344.559154 -233.438356)
			(xy 344.514619 -233.415669) (xy 344.474181 -233.386295) (xy 344.438836 -233.350956) (xy 344.409456 -233.310522)
			(xy 344.386763 -233.26599) (xy 344.371316 -233.218456) (xy 344.363497 -233.16909) (xy 344.363497 -233.11911)
			(xy 344.371316 -233.069744) (xy 344.386763 -233.02221) (xy 344.409456 -232.977678) (xy 344.438836 -232.937244)
			(xy 344.474181 -232.901905) (xy 344.514619 -232.872531) (xy 344.559154 -232.849844) (xy 344.606691 -232.834405)
			(xy 344.656057 -232.826593) (xy 344.681048 -232.826052) (xy 344.681048 -232.825798) (xy 344.698139 -232.826037)
			(xy 344.732122 -232.829729) (xy 344.748866 -232.833164) (xy 344.761058 -232.835704) (xy 344.770964 -232.833164)
			(xy 344.775795 -232.831938) (xy 344.784885 -232.82785) (xy 344.788998 -232.825036) (xy 344.854276 -232.772712)
			(xy 344.861576 -232.765296) (xy 344.869961 -232.746274) (xy 344.870532 -232.735882) (xy 344.870532 -232.500678)
			(xy 344.869516 -232.491026) (xy 344.866722 -232.478834) (xy 344.862912 -232.46842) (xy 344.862912 -232.468166)
			(xy 344.853886 -232.447883) (xy 344.840915 -232.405425) (xy 344.833978 -232.361575) (xy 344.833194 -232.339388)
			(xy 344.833194 -232.332784) (xy 344.833682 -232.309733) (xy 344.840483 -232.264132) (xy 344.853782 -232.219986)
			(xy 344.863166 -232.198926) (xy 344.865452 -232.1941) (xy 344.869516 -232.17759) (xy 344.870532 -232.167684)
			(xy 344.870532 -231.93248) (xy 344.870015 -231.921701) (xy 344.861062 -231.902089) (xy 344.85326 -231.894634)
			(xy 344.829638 -231.875584) (xy 344.82913 -231.875076) (xy 344.78849 -231.842818) (xy 344.784545 -231.840072)
			(xy 344.775849 -231.83598) (xy 344.771218 -231.83469) (xy 344.761058 -231.832404) (xy 344.748866 -231.834944)
			(xy 344.735119 -231.837802) (xy 344.707264 -231.841363) (xy 344.69324 -231.842056) (xy 344.681048 -231.842056)
			(xy 344.656051 -231.841595) (xy 344.60667 -231.833781) (xy 344.559121 -231.818337) (xy 344.514572 -231.795645)
			(xy 344.474123 -231.766262) (xy 344.438769 -231.730913) (xy 344.40938 -231.690469) (xy 344.386681 -231.645924)
			(xy 344.37123 -231.598377) (xy 344.363409 -231.548997) (xy 344.363409 -231.499003) (xy 344.37123 -231.449623)
			(xy 344.386681 -231.402076) (xy 344.40938 -231.357531) (xy 344.438769 -231.317087) (xy 344.474123 -231.281738)
			(xy 344.514572 -231.252355) (xy 344.559121 -231.229663) (xy 344.60667 -231.214219) (xy 344.656051 -231.206405)
			(xy 344.681048 -231.20604) (xy 344.681048 -231.205786) (xy 344.698139 -231.206025) (xy 344.732122 -231.209717)
			(xy 344.748866 -231.213152) (xy 344.761058 -231.215692) (xy 344.770964 -231.213152) (xy 344.775795 -231.211926)
			(xy 344.784884 -231.207837) (xy 344.788998 -231.205024) (xy 344.854276 -231.1527) (xy 344.861575 -231.145283)
			(xy 344.869954 -231.126261) (xy 344.870532 -231.11587) (xy 344.870532 -230.88092) (xy 344.869516 -230.871268)
			(xy 344.866722 -230.859076) (xy 344.862912 -230.848662) (xy 344.862912 -230.848408) (xy 344.853883 -230.828125)
			(xy 344.840906 -230.785668) (xy 344.833964 -230.741818) (xy 344.833194 -230.71963) (xy 344.833194 -230.713026)
			(xy 344.833679 -230.689974) (xy 344.840474 -230.644371) (xy 344.853768 -230.600222) (xy 344.863166 -230.579168)
			(xy 344.865452 -230.574342) (xy 344.869516 -230.557832) (xy 344.870532 -230.547926) (xy 344.870532 -230.312468)
			(xy 344.870013 -230.30169) (xy 344.861057 -230.282082) (xy 344.85326 -230.274622) (xy 344.829638 -230.255572)
			(xy 344.82913 -230.255064) (xy 344.78849 -230.222806) (xy 344.784547 -230.220056) (xy 344.775852 -230.215957)
			(xy 344.771218 -230.214678) (xy 344.761058 -230.212392) (xy 344.748866 -230.214932) (xy 344.735118 -230.217789)
			(xy 344.707264 -230.221349) (xy 344.69324 -230.222044) (xy 344.681048 -230.222044) (xy 344.656051 -230.221583)
			(xy 344.606673 -230.213769) (xy 344.559125 -230.198326) (xy 344.514579 -230.175635) (xy 344.474131 -230.146253)
			(xy 344.438778 -230.110906) (xy 344.40939 -230.070462) (xy 344.386692 -230.025919) (xy 344.371242 -229.978374)
			(xy 344.363421 -229.928996) (xy 344.363421 -229.879004) (xy 344.371242 -229.829626) (xy 344.386692 -229.782081)
			(xy 344.40939 -229.737538) (xy 344.438778 -229.697094) (xy 344.474131 -229.661747) (xy 344.514579 -229.632365)
			(xy 344.559125 -229.609674) (xy 344.606673 -229.594231) (xy 344.656051 -229.586417) (xy 344.681048 -229.586028)
			(xy 344.681048 -229.585774) (xy 344.698139 -229.586013) (xy 344.732122 -229.589704) (xy 344.748866 -229.59314)
			(xy 344.761058 -229.59568) (xy 344.770964 -229.59314) (xy 344.775795 -229.591913) (xy 344.784883 -229.587824)
			(xy 344.788998 -229.585012) (xy 344.854276 -229.532688) (xy 344.861588 -229.525276) (xy 344.870001 -229.506255)
			(xy 344.870532 -229.495858) (xy 344.870532 -229.260908) (xy 344.869516 -229.251256) (xy 344.866722 -229.239064)
			(xy 344.862912 -229.22865) (xy 344.862912 -229.228396) (xy 344.853884 -229.208113) (xy 344.840909 -229.165656)
			(xy 344.833968 -229.121806) (xy 344.833194 -229.099618) (xy 344.833194 -229.093014) (xy 344.833679 -229.069962)
			(xy 344.840477 -229.02436) (xy 344.853772 -228.980212) (xy 344.863166 -228.959156) (xy 344.865452 -228.95433)
			(xy 344.869516 -228.93782) (xy 344.870532 -228.927914) (xy 344.870532 -228.69271) (xy 344.870021 -228.681928)
			(xy 344.861076 -228.662307) (xy 344.85326 -228.654864) (xy 344.829638 -228.635814) (xy 344.82913 -228.635306)
			(xy 344.78849 -228.603048) (xy 344.784546 -228.6003) (xy 344.77585 -228.596206) (xy 344.771218 -228.59492)
			(xy 344.761058 -228.592634) (xy 344.748866 -228.595174) (xy 344.735119 -228.598031) (xy 344.707264 -228.601592)
			(xy 344.69324 -228.602286) (xy 344.681048 -228.602286) (xy 344.656056 -228.601825) (xy 344.606687 -228.594012)
			(xy 344.559147 -228.578572) (xy 344.514609 -228.555885) (xy 344.474169 -228.526509) (xy 344.438822 -228.491168)
			(xy 344.40944 -228.450732) (xy 344.386746 -228.406197) (xy 344.371299 -228.35866) (xy 344.363479 -228.309292)
			(xy 344.363479 -228.259308) (xy 344.371299 -228.20994) (xy 344.386746 -228.162403) (xy 344.40944 -228.117868)
			(xy 344.438822 -228.077432) (xy 344.474169 -228.042091) (xy 344.514609 -228.012715) (xy 344.559147 -227.990028)
			(xy 344.606687 -227.974588) (xy 344.656056 -227.966775) (xy 344.681048 -227.96627) (xy 344.681048 -227.966016)
			(xy 344.698139 -227.966255) (xy 344.732122 -227.969946) (xy 344.748866 -227.973382) (xy 344.761058 -227.975922)
			(xy 344.770964 -227.973382) (xy 344.775794 -227.972154) (xy 344.78488 -227.968061) (xy 344.788998 -227.965254)
			(xy 344.854276 -227.91293) (xy 344.861579 -227.905515) (xy 344.86997 -227.886493) (xy 344.870532 -227.8761)
			(xy 344.870532 -227.798884) (xy 344.870025 -227.78913) (xy 344.862587 -227.77109) (xy 344.856054 -227.763832)
			(xy 344.664284 -227.572062) (xy 344.655538 -227.564257) (xy 344.633284 -227.556988) (xy 344.621612 -227.558092)
			(xy 344.551254 -227.5713) (xy 344.545174 -227.572584) (xy 344.533862 -227.577717) (xy 344.528902 -227.58146)
			(xy 344.502486 -227.602288) (xy 344.499946 -227.607368) (xy 344.488647 -227.630662) (xy 344.459644 -227.673545)
			(xy 344.42408 -227.711165) (xy 344.382892 -227.742528) (xy 344.337169 -227.766808) (xy 344.288118 -227.783362)
			(xy 344.237033 -227.791753) (xy 344.211148 -227.79228) (xy 344.186289 -227.791796) (xy 344.137178 -227.78405)
			(xy 344.089871 -227.768754) (xy 344.045521 -227.746283) (xy 344.005209 -227.717183) (xy 343.969918 -227.682163)
			(xy 343.940507 -227.642077) (xy 343.917693 -227.597902) (xy 343.902032 -227.550715) (xy 343.893906 -227.501666)
			(xy 343.89314 -227.476812) (xy 343.89314 -227.473764) (xy 343.89346 -227.453929) (xy 343.898427 -227.41457)
			(xy 343.903046 -227.395278) (xy 343.903046 -227.395024) (xy 343.905184 -227.384058) (xy 343.900841 -227.362169)
			(xy 343.894664 -227.35286) (xy 343.870026 -227.32111) (xy 343.870026 -227.320602) (xy 343.845642 -227.289614)
			(xy 343.838178 -227.280964) (xy 343.817681 -227.270921) (xy 343.806272 -227.27031) (xy 343.67597 -227.27031)
			(xy 343.664548 -227.270865) (xy 343.644044 -227.280932) (xy 343.6366 -227.289614) (xy 343.588086 -227.352098)
			(xy 343.585071 -227.356241) (xy 343.580591 -227.365455) (xy 343.579196 -227.370386) (xy 343.579196 -227.389944)
			(xy 343.580466 -227.400866) (xy 343.584273 -227.417892) (xy 343.588598 -227.452514) (xy 343.589102 -227.469954)
			(xy 343.589102 -227.476812) (xy 343.588423 -227.501671) (xy 343.580291 -227.550727) (xy 343.564623 -227.597921)
			(xy 343.5418 -227.6421) (xy 343.51238 -227.682189) (xy 343.477078 -227.717211) (xy 343.436755 -227.74631)
			(xy 343.392395 -227.768779) (xy 343.345077 -227.78407) (xy 343.295957 -227.79181) (xy 343.246231 -227.79181)
			(xy 343.197111 -227.78407) (xy 343.149793 -227.768779) (xy 343.105433 -227.74631) (xy 343.06511 -227.717211)
			(xy 343.029808 -227.682189) (xy 343.000388 -227.6421) (xy 342.977565 -227.597921) (xy 342.961897 -227.550727)
			(xy 342.953765 -227.501671) (xy 342.953086 -227.476812) (xy 342.953086 -227.473764) (xy 342.953406 -227.453929)
			(xy 342.958374 -227.414571) (xy 342.962992 -227.395278) (xy 342.962992 -227.395024) (xy 342.965129 -227.384057)
			(xy 342.960789 -227.362168) (xy 342.95461 -227.35286) (xy 342.929972 -227.32111) (xy 342.929972 -227.320602)
			(xy 342.905588 -227.289614) (xy 342.898127 -227.280957) (xy 342.877631 -227.270895) (xy 342.866218 -227.27031)
			(xy 342.735916 -227.27031) (xy 342.724489 -227.270855) (xy 342.70397 -227.280911) (xy 342.696546 -227.289614)
			(xy 342.648032 -227.352098) (xy 342.645014 -227.35624) (xy 342.640531 -227.365453) (xy 342.639142 -227.370386)
			(xy 342.639142 -227.389944) (xy 342.640412 -227.400866) (xy 342.644219 -227.417893) (xy 342.648542 -227.452514)
			(xy 342.649048 -227.469954) (xy 342.649048 -227.476812) (xy 342.648369 -227.501671) (xy 342.640237 -227.550727)
			(xy 342.624569 -227.597921) (xy 342.601746 -227.6421) (xy 342.572326 -227.682189) (xy 342.537024 -227.717211)
			(xy 342.496701 -227.74631) (xy 342.452341 -227.768779) (xy 342.405023 -227.78407) (xy 342.355903 -227.79181)
			(xy 342.306177 -227.79181) (xy 342.257057 -227.78407) (xy 342.209739 -227.768779) (xy 342.165379 -227.74631)
			(xy 342.125056 -227.717211) (xy 342.089754 -227.682189) (xy 342.060334 -227.6421) (xy 342.037511 -227.597921)
			(xy 342.021843 -227.550727) (xy 342.013711 -227.501671) (xy 342.013032 -227.476812) (xy 342.013032 -227.473764)
			(xy 342.013352 -227.453929) (xy 342.018319 -227.41457) (xy 342.022938 -227.395278) (xy 342.022938 -227.395024)
			(xy 342.025077 -227.384058) (xy 342.020732 -227.36217) (xy 342.014556 -227.35286) (xy 341.989918 -227.32111)
			(xy 341.989918 -227.320602) (xy 341.965534 -227.289614) (xy 341.958069 -227.280966) (xy 341.937573 -227.270926)
			(xy 341.926164 -227.27031) (xy 340.856062 -227.27031) (xy 340.844641 -227.270866) (xy 340.82414 -227.280935)
			(xy 340.816692 -227.289614) (xy 340.768178 -227.352098) (xy 340.765163 -227.356241) (xy 340.760684 -227.365456)
			(xy 340.759288 -227.370386) (xy 340.759288 -227.389944) (xy 340.760558 -227.400866) (xy 340.764366 -227.417892)
			(xy 340.76869 -227.452514) (xy 340.769194 -227.469954) (xy 340.769194 -227.476812) (xy 340.768515 -227.501671)
			(xy 340.760383 -227.550727) (xy 340.744715 -227.597921) (xy 340.721892 -227.6421) (xy 340.692472 -227.682189)
			(xy 340.65717 -227.717211) (xy 340.616847 -227.74631) (xy 340.572487 -227.768779) (xy 340.525169 -227.78407)
			(xy 340.476049 -227.79181) (xy 340.426323 -227.79181) (xy 340.377203 -227.78407) (xy 340.329885 -227.768779)
			(xy 340.285525 -227.74631) (xy 340.245202 -227.717211) (xy 340.2099 -227.682189) (xy 340.18048 -227.6421)
			(xy 340.157657 -227.597921) (xy 340.141989 -227.550727) (xy 340.133857 -227.501671) (xy 340.133178 -227.476812)
			(xy 340.133178 -227.473764) (xy 340.133498 -227.453929) (xy 340.138466 -227.414571) (xy 340.143084 -227.395278)
			(xy 340.143084 -227.395024) (xy 340.145222 -227.384057) (xy 340.140881 -227.362168) (xy 340.134702 -227.35286)
			(xy 340.110064 -227.32111) (xy 340.110064 -227.320602) (xy 340.08568 -227.289614) (xy 340.078219 -227.280958)
			(xy 340.057722 -227.2709) (xy 340.04631 -227.27031) (xy 339.916008 -227.27031) (xy 339.904582 -227.270857)
			(xy 339.884065 -227.280914) (xy 339.876638 -227.289614) (xy 339.828124 -227.352098) (xy 339.825107 -227.35624)
			(xy 339.820624 -227.365454) (xy 339.819234 -227.370386) (xy 339.819234 -227.389944) (xy 339.820504 -227.400866)
			(xy 339.8266 -227.434394) (xy 339.8266 -227.434902) (xy 339.827616 -227.442776) (xy 339.827616 -227.443284)
			(xy 339.82914 -227.469954) (xy 339.82914 -227.476812) (xy 339.828461 -227.501671) (xy 339.820329 -227.550727)
			(xy 339.804661 -227.597921) (xy 339.781838 -227.6421) (xy 339.752418 -227.682189) (xy 339.717116 -227.717211)
			(xy 339.676793 -227.74631) (xy 339.632433 -227.768779) (xy 339.585115 -227.78407) (xy 339.535995 -227.79181)
			(xy 339.486269 -227.79181) (xy 339.437149 -227.78407) (xy 339.389831 -227.768779) (xy 339.345471 -227.74631)
			(xy 339.305148 -227.717211) (xy 339.269846 -227.682189) (xy 339.240426 -227.6421) (xy 339.217603 -227.597921)
			(xy 339.201935 -227.550727) (xy 339.193803 -227.501671) (xy 339.193124 -227.476812) (xy 339.193124 -227.473764)
			(xy 339.193444 -227.453929) (xy 339.198411 -227.41457) (xy 339.20303 -227.395278) (xy 339.20303 -227.395024)
			(xy 339.205168 -227.384058) (xy 339.200824 -227.36217) (xy 339.194648 -227.35286) (xy 339.17001 -227.32111)
			(xy 339.17001 -227.320602) (xy 339.145626 -227.289614) (xy 339.138161 -227.280967) (xy 339.117664 -227.270931)
			(xy 339.106256 -227.27031) (xy 338.975954 -227.27031) (xy 338.964534 -227.270868) (xy 338.944035 -227.280939)
			(xy 338.936584 -227.289614) (xy 338.88807 -227.352098) (xy 338.885055 -227.356241) (xy 338.880578 -227.365456)
			(xy 338.87918 -227.370386) (xy 338.87918 -227.389944) (xy 338.88045 -227.400866) (xy 338.884258 -227.417892)
			(xy 338.888582 -227.452514) (xy 338.889086 -227.469954) (xy 338.889086 -227.476812) (xy 338.888409 -227.501671)
			(xy 338.880281 -227.55073) (xy 338.864615 -227.597926) (xy 338.841793 -227.642108) (xy 338.812372 -227.682199)
			(xy 338.77707 -227.717221) (xy 338.736746 -227.746322) (xy 338.692383 -227.76879) (xy 338.645064 -227.78408)
			(xy 338.595942 -227.791817) (xy 338.571078 -227.79228) (xy 338.547169 -227.791848) (xy 338.499889 -227.784686)
			(xy 338.454214 -227.770529) (xy 338.411174 -227.749693) (xy 338.371737 -227.722649) (xy 338.336792 -227.690007)
			(xy 338.307128 -227.652502) (xy 338.283412 -227.610978) (xy 338.274406 -227.588826) (xy 338.27212 -227.583238)
			(xy 338.266856 -227.574348) (xy 338.250723 -227.561475) (xy 338.240878 -227.558346) (xy 338.219542 -227.55352)
			(xy 338.219034 -227.55352) (xy 338.153248 -227.53955) (xy 338.141512 -227.538378) (xy 338.119108 -227.545653)
			(xy 338.110322 -227.55352) (xy 338.027264 -227.636578) (xy 338.020548 -227.643815) (xy 338.012945 -227.66202)
			(xy 338.012532 -227.671884) (xy 338.012532 -227.866448) (xy 338.013026 -227.876111) (xy 338.020336 -227.894008)
			(xy 338.026756 -227.901246) (xy 338.068412 -227.943918) (xy 338.071908 -227.947374) (xy 338.079967 -227.953)
			(xy 338.084414 -227.955094) (xy 338.10956 -227.966016) (xy 338.118704 -227.966524) (xy 338.144042 -227.968417)
			(xy 338.193685 -227.979236) (xy 338.240978 -227.997805) (xy 338.284721 -228.023651) (xy 338.323801 -228.056119)
			(xy 338.357227 -228.094384) (xy 338.384148 -228.137473) (xy 338.403882 -228.184293) (xy 338.415926 -228.233652)
			(xy 338.419973 -228.284278) (xy 338.724743 -228.284278) (xy 338.728838 -228.23355) (xy 338.741017 -228.184136)
			(xy 338.760965 -228.137316) (xy 338.788166 -228.094302) (xy 338.821914 -228.056208) (xy 338.861336 -228.024021)
			(xy 338.90541 -227.998575) (xy 338.952996 -227.980528) (xy 339.00286 -227.970348) (xy 339.053712 -227.968299)
			(xy 339.104233 -227.974433) (xy 339.153117 -227.988593) (xy 339.199096 -228.01041) (xy 339.24098 -228.03932)
			(xy 339.277684 -228.074575) (xy 339.308257 -228.115261) (xy 339.331908 -228.160324) (xy 339.348024 -228.208598)
			(xy 339.356188 -228.258832) (xy 339.3567 -228.284278) (xy 339.664797 -228.284278) (xy 339.668892 -228.23355)
			(xy 339.681071 -228.184136) (xy 339.701019 -228.137316) (xy 339.72822 -228.094302) (xy 339.761968 -228.056208)
			(xy 339.80139 -228.024021) (xy 339.845464 -227.998575) (xy 339.89305 -227.980528) (xy 339.942914 -227.970348)
			(xy 339.993766 -227.968299) (xy 340.044287 -227.974433) (xy 340.093171 -227.988593) (xy 340.13915 -228.01041)
			(xy 340.181034 -228.03932) (xy 340.217738 -228.074575) (xy 340.248311 -228.115261) (xy 340.271962 -228.160324)
			(xy 340.288078 -228.208598) (xy 340.296242 -228.258832) (xy 340.296754 -228.284278) (xy 340.296251 -228.309267)
			(xy 340.603568 -228.309267) (xy 340.603568 -228.259289) (xy 340.611387 -228.209926) (xy 340.626831 -228.162394)
			(xy 340.649521 -228.117862) (xy 340.678897 -228.077429) (xy 340.714237 -228.042089) (xy 340.75467 -228.012713)
			(xy 340.799202 -227.990023) (xy 340.846734 -227.974579) (xy 340.896097 -227.96676) (xy 340.946075 -227.96676)
			(xy 340.995438 -227.974579) (xy 341.04297 -227.990023) (xy 341.087502 -228.012713) (xy 341.127935 -228.042089)
			(xy 341.163275 -228.077429) (xy 341.192651 -228.117862) (xy 341.215341 -228.162394) (xy 341.230785 -228.209926)
			(xy 341.238604 -228.259289) (xy 341.239094 -228.284278) (xy 341.544905 -228.284278) (xy 341.549 -228.23355)
			(xy 341.561179 -228.184136) (xy 341.581127 -228.137316) (xy 341.608328 -228.094302) (xy 341.642076 -228.056208)
			(xy 341.681498 -228.024021) (xy 341.725572 -227.998575) (xy 341.773158 -227.980528) (xy 341.823022 -227.970348)
			(xy 341.873874 -227.968299) (xy 341.924395 -227.974433) (xy 341.973279 -227.988593) (xy 342.019258 -228.01041)
			(xy 342.061142 -228.03932) (xy 342.097846 -228.074575) (xy 342.128419 -228.115261) (xy 342.15207 -228.160324)
			(xy 342.168186 -228.208598) (xy 342.17635 -228.258832) (xy 342.176862 -228.284278) (xy 342.176359 -228.309267)
			(xy 342.483676 -228.309267) (xy 342.483676 -228.259289) (xy 342.491495 -228.209926) (xy 342.506939 -228.162394)
			(xy 342.529629 -228.117862) (xy 342.559005 -228.077429) (xy 342.594345 -228.042089) (xy 342.634778 -228.012713)
			(xy 342.67931 -227.990023) (xy 342.726842 -227.974579) (xy 342.776205 -227.96676) (xy 342.826183 -227.96676)
			(xy 342.875546 -227.974579) (xy 342.923078 -227.990023) (xy 342.96761 -228.012713) (xy 343.008043 -228.042089)
			(xy 343.043383 -228.077429) (xy 343.072759 -228.117862) (xy 343.095449 -228.162394) (xy 343.110893 -228.209926)
			(xy 343.118712 -228.259289) (xy 343.119202 -228.284278) (xy 343.424759 -228.284278) (xy 343.428854 -228.23355)
			(xy 343.441033 -228.184136) (xy 343.460981 -228.137316) (xy 343.488182 -228.094302) (xy 343.52193 -228.056208)
			(xy 343.561352 -228.024021) (xy 343.605426 -227.998575) (xy 343.653012 -227.980528) (xy 343.702876 -227.970348)
			(xy 343.753728 -227.968299) (xy 343.804249 -227.974433) (xy 343.853133 -227.988593) (xy 343.899112 -228.01041)
			(xy 343.940996 -228.03932) (xy 343.9777 -228.074575) (xy 344.008273 -228.115261) (xy 344.031924 -228.160324)
			(xy 344.04804 -228.208598) (xy 344.056204 -228.258832) (xy 344.056716 -228.284278) (xy 344.056204 -228.309724)
			(xy 344.04804 -228.359958) (xy 344.031924 -228.408232) (xy 344.008273 -228.453295) (xy 343.9777 -228.493981)
			(xy 343.940996 -228.529236) (xy 343.899112 -228.558146) (xy 343.853133 -228.579963) (xy 343.804249 -228.594123)
			(xy 343.753728 -228.600257) (xy 343.702876 -228.598208) (xy 343.653012 -228.588028) (xy 343.605426 -228.569981)
			(xy 343.561352 -228.544535) (xy 343.52193 -228.512348) (xy 343.488182 -228.474254) (xy 343.460981 -228.43124)
			(xy 343.441033 -228.38442) (xy 343.428854 -228.335006) (xy 343.424759 -228.284278) (xy 343.119202 -228.284278)
			(xy 343.118712 -228.309267) (xy 343.110893 -228.35863) (xy 343.095449 -228.406162) (xy 343.072759 -228.450694)
			(xy 343.043383 -228.491127) (xy 343.008043 -228.526467) (xy 342.96761 -228.555843) (xy 342.923078 -228.578533)
			(xy 342.875546 -228.593977) (xy 342.826183 -228.601796) (xy 342.776205 -228.601796) (xy 342.726842 -228.593977)
			(xy 342.67931 -228.578533) (xy 342.634778 -228.555843) (xy 342.594345 -228.526467) (xy 342.559005 -228.491127)
			(xy 342.529629 -228.450694) (xy 342.506939 -228.406162) (xy 342.491495 -228.35863) (xy 342.483676 -228.309267)
			(xy 342.176359 -228.309267) (xy 342.17635 -228.309724) (xy 342.168186 -228.359958) (xy 342.15207 -228.408232)
			(xy 342.128419 -228.453295) (xy 342.097846 -228.493981) (xy 342.061142 -228.529236) (xy 342.019258 -228.558146)
			(xy 341.973279 -228.579963) (xy 341.924395 -228.594123) (xy 341.873874 -228.600257) (xy 341.823022 -228.598208)
			(xy 341.773158 -228.588028) (xy 341.725572 -228.569981) (xy 341.681498 -228.544535) (xy 341.642076 -228.512348)
			(xy 341.608328 -228.474254) (xy 341.581127 -228.43124) (xy 341.561179 -228.38442) (xy 341.549 -228.335006)
			(xy 341.544905 -228.284278) (xy 341.239094 -228.284278) (xy 341.238604 -228.309267) (xy 341.230785 -228.35863)
			(xy 341.215341 -228.406162) (xy 341.192651 -228.450694) (xy 341.163275 -228.491127) (xy 341.127935 -228.526467)
			(xy 341.087502 -228.555843) (xy 341.04297 -228.578533) (xy 340.995438 -228.593977) (xy 340.946075 -228.601796)
			(xy 340.896097 -228.601796) (xy 340.846734 -228.593977) (xy 340.799202 -228.578533) (xy 340.75467 -228.555843)
			(xy 340.714237 -228.526467) (xy 340.678897 -228.491127) (xy 340.649521 -228.450694) (xy 340.626831 -228.406162)
			(xy 340.611387 -228.35863) (xy 340.603568 -228.309267) (xy 340.296251 -228.309267) (xy 340.296242 -228.309724)
			(xy 340.288078 -228.359958) (xy 340.271962 -228.408232) (xy 340.248311 -228.453295) (xy 340.217738 -228.493981)
			(xy 340.181034 -228.529236) (xy 340.13915 -228.558146) (xy 340.093171 -228.579963) (xy 340.044287 -228.594123)
			(xy 339.993766 -228.600257) (xy 339.942914 -228.598208) (xy 339.89305 -228.588028) (xy 339.845464 -228.569981)
			(xy 339.80139 -228.544535) (xy 339.761968 -228.512348) (xy 339.72822 -228.474254) (xy 339.701019 -228.43124)
			(xy 339.681071 -228.38442) (xy 339.668892 -228.335006) (xy 339.664797 -228.284278) (xy 339.3567 -228.284278)
			(xy 339.356188 -228.309724) (xy 339.348024 -228.359958) (xy 339.331908 -228.408232) (xy 339.308257 -228.453295)
			(xy 339.277684 -228.493981) (xy 339.24098 -228.529236) (xy 339.199096 -228.558146) (xy 339.153117 -228.579963)
			(xy 339.104233 -228.594123) (xy 339.053712 -228.600257) (xy 339.00286 -228.598208) (xy 338.952996 -228.588028)
			(xy 338.90541 -228.569981) (xy 338.861336 -228.544535) (xy 338.821914 -228.512348) (xy 338.788166 -228.474254)
			(xy 338.760965 -228.43124) (xy 338.741017 -228.38442) (xy 338.728838 -228.335006) (xy 338.724743 -228.284278)
			(xy 338.419973 -228.284278) (xy 338.419975 -228.284299) (xy 338.415926 -228.334945) (xy 338.403882 -228.384305)
			(xy 338.384149 -228.431124) (xy 338.357228 -228.474214) (xy 338.323803 -228.512479) (xy 338.284723 -228.544947)
			(xy 338.24098 -228.570794) (xy 338.193687 -228.589363) (xy 338.144045 -228.600183) (xy 338.118704 -228.602032)
			(xy 338.10956 -228.60254) (xy 338.084414 -228.613462) (xy 338.079966 -228.615555) (xy 338.071907 -228.621181)
			(xy 338.068412 -228.624638) (xy 338.026756 -228.66731) (xy 338.020295 -228.674526) (xy 338.012962 -228.692433)
			(xy 338.012532 -228.702108) (xy 338.012532 -229.094284) (xy 338.254843 -229.094284) (xy 338.258938 -229.043556)
			(xy 338.271117 -228.994142) (xy 338.291065 -228.947322) (xy 338.318266 -228.904308) (xy 338.352014 -228.866214)
			(xy 338.391436 -228.834027) (xy 338.43551 -228.808581) (xy 338.483096 -228.790534) (xy 338.53296 -228.780354)
			(xy 338.583812 -228.778305) (xy 338.634333 -228.784439) (xy 338.683217 -228.798599) (xy 338.729196 -228.820416)
			(xy 338.77108 -228.849326) (xy 338.807784 -228.884581) (xy 338.838357 -228.925267) (xy 338.862008 -228.97033)
			(xy 338.878124 -229.018604) (xy 338.886288 -229.068838) (xy 338.8868 -229.094284) (xy 338.886297 -229.119273)
			(xy 339.193614 -229.119273) (xy 339.193614 -229.069295) (xy 339.201433 -229.019932) (xy 339.216877 -228.9724)
			(xy 339.239567 -228.927868) (xy 339.268943 -228.887435) (xy 339.304283 -228.852095) (xy 339.344716 -228.822719)
			(xy 339.389248 -228.800029) (xy 339.43678 -228.784585) (xy 339.486143 -228.776766) (xy 339.536121 -228.776766)
			(xy 339.585484 -228.784585) (xy 339.633016 -228.800029) (xy 339.677548 -228.822719) (xy 339.717981 -228.852095)
			(xy 339.753321 -228.887435) (xy 339.782697 -228.927868) (xy 339.805387 -228.9724) (xy 339.820831 -229.019932)
			(xy 339.82865 -229.069295) (xy 339.82914 -229.094284) (xy 340.134951 -229.094284) (xy 340.139046 -229.043556)
			(xy 340.151225 -228.994142) (xy 340.171173 -228.947322) (xy 340.198374 -228.904308) (xy 340.232122 -228.866214)
			(xy 340.271544 -228.834027) (xy 340.315618 -228.808581) (xy 340.363204 -228.790534) (xy 340.413068 -228.780354)
			(xy 340.46392 -228.778305) (xy 340.514441 -228.784439) (xy 340.563325 -228.798599) (xy 340.609304 -228.820416)
			(xy 340.651188 -228.849326) (xy 340.687892 -228.884581) (xy 340.718465 -228.925267) (xy 340.742116 -228.97033)
			(xy 340.758232 -229.018604) (xy 340.766396 -229.068838) (xy 340.766908 -229.094284) (xy 340.766405 -229.119273)
			(xy 341.073468 -229.119273) (xy 341.073468 -229.069295) (xy 341.081287 -229.019932) (xy 341.096731 -228.9724)
			(xy 341.119421 -228.927868) (xy 341.148797 -228.887435) (xy 341.184137 -228.852095) (xy 341.22457 -228.822719)
			(xy 341.269102 -228.800029) (xy 341.316634 -228.784585) (xy 341.365997 -228.776766) (xy 341.415975 -228.776766)
			(xy 341.465338 -228.784585) (xy 341.51287 -228.800029) (xy 341.557402 -228.822719) (xy 341.597835 -228.852095)
			(xy 341.633175 -228.887435) (xy 341.662551 -228.927868) (xy 341.685241 -228.9724) (xy 341.700685 -229.019932)
			(xy 341.708504 -229.069295) (xy 341.708994 -229.094284) (xy 342.014805 -229.094284) (xy 342.0189 -229.043556)
			(xy 342.031079 -228.994142) (xy 342.051027 -228.947322) (xy 342.078228 -228.904308) (xy 342.111976 -228.866214)
			(xy 342.151398 -228.834027) (xy 342.195472 -228.808581) (xy 342.243058 -228.790534) (xy 342.292922 -228.780354)
			(xy 342.343774 -228.778305) (xy 342.394295 -228.784439) (xy 342.443179 -228.798599) (xy 342.489158 -228.820416)
			(xy 342.531042 -228.849326) (xy 342.567746 -228.884581) (xy 342.598319 -228.925267) (xy 342.62197 -228.97033)
			(xy 342.638086 -229.018604) (xy 342.64625 -229.068838) (xy 342.646762 -229.094284) (xy 342.954859 -229.094284)
			(xy 342.958954 -229.043556) (xy 342.971133 -228.994142) (xy 342.991081 -228.947322) (xy 343.018282 -228.904308)
			(xy 343.05203 -228.866214) (xy 343.091452 -228.834027) (xy 343.135526 -228.808581) (xy 343.183112 -228.790534)
			(xy 343.232976 -228.780354) (xy 343.283828 -228.778305) (xy 343.334349 -228.784439) (xy 343.383233 -228.798599)
			(xy 343.429212 -228.820416) (xy 343.471096 -228.849326) (xy 343.5078 -228.884581) (xy 343.538373 -228.925267)
			(xy 343.562024 -228.97033) (xy 343.57814 -229.018604) (xy 343.586304 -229.068838) (xy 343.586816 -229.094284)
			(xy 343.586304 -229.11973) (xy 343.57814 -229.169964) (xy 343.562024 -229.218238) (xy 343.538373 -229.263301)
			(xy 343.5078 -229.303987) (xy 343.471096 -229.339242) (xy 343.429212 -229.368152) (xy 343.383233 -229.389969)
			(xy 343.334349 -229.404129) (xy 343.283828 -229.410263) (xy 343.232976 -229.408214) (xy 343.183112 -229.398034)
			(xy 343.135526 -229.379987) (xy 343.091452 -229.354541) (xy 343.05203 -229.322354) (xy 343.018282 -229.28426)
			(xy 342.991081 -229.241246) (xy 342.971133 -229.194426) (xy 342.958954 -229.145012) (xy 342.954859 -229.094284)
			(xy 342.646762 -229.094284) (xy 342.64625 -229.11973) (xy 342.638086 -229.169964) (xy 342.62197 -229.218238)
			(xy 342.598319 -229.263301) (xy 342.567746 -229.303987) (xy 342.531042 -229.339242) (xy 342.489158 -229.368152)
			(xy 342.443179 -229.389969) (xy 342.394295 -229.404129) (xy 342.343774 -229.410263) (xy 342.292922 -229.408214)
			(xy 342.243058 -229.398034) (xy 342.195472 -229.379987) (xy 342.151398 -229.354541) (xy 342.111976 -229.322354)
			(xy 342.078228 -229.28426) (xy 342.051027 -229.241246) (xy 342.031079 -229.194426) (xy 342.0189 -229.145012)
			(xy 342.014805 -229.094284) (xy 341.708994 -229.094284) (xy 341.708504 -229.119273) (xy 341.700685 -229.168636)
			(xy 341.685241 -229.216168) (xy 341.662551 -229.2607) (xy 341.633175 -229.301133) (xy 341.597835 -229.336473)
			(xy 341.557402 -229.365849) (xy 341.51287 -229.388539) (xy 341.465338 -229.403983) (xy 341.415975 -229.411802)
			(xy 341.365997 -229.411802) (xy 341.316634 -229.403983) (xy 341.269102 -229.388539) (xy 341.22457 -229.365849)
			(xy 341.184137 -229.336473) (xy 341.148797 -229.301133) (xy 341.119421 -229.2607) (xy 341.096731 -229.216168)
			(xy 341.081287 -229.168636) (xy 341.073468 -229.119273) (xy 340.766405 -229.119273) (xy 340.766396 -229.11973)
			(xy 340.758232 -229.169964) (xy 340.742116 -229.218238) (xy 340.718465 -229.263301) (xy 340.687892 -229.303987)
			(xy 340.651188 -229.339242) (xy 340.609304 -229.368152) (xy 340.563325 -229.389969) (xy 340.514441 -229.404129)
			(xy 340.46392 -229.410263) (xy 340.413068 -229.408214) (xy 340.363204 -229.398034) (xy 340.315618 -229.379987)
			(xy 340.271544 -229.354541) (xy 340.232122 -229.322354) (xy 340.198374 -229.28426) (xy 340.171173 -229.241246)
			(xy 340.151225 -229.194426) (xy 340.139046 -229.145012) (xy 340.134951 -229.094284) (xy 339.82914 -229.094284)
			(xy 339.82865 -229.119273) (xy 339.820831 -229.168636) (xy 339.805387 -229.216168) (xy 339.782697 -229.2607)
			(xy 339.753321 -229.301133) (xy 339.717981 -229.336473) (xy 339.677548 -229.365849) (xy 339.633016 -229.388539)
			(xy 339.585484 -229.403983) (xy 339.536121 -229.411802) (xy 339.486143 -229.411802) (xy 339.43678 -229.403983)
			(xy 339.389248 -229.388539) (xy 339.344716 -229.365849) (xy 339.304283 -229.336473) (xy 339.268943 -229.301133)
			(xy 339.239567 -229.2607) (xy 339.216877 -229.216168) (xy 339.201433 -229.168636) (xy 339.193614 -229.119273)
			(xy 338.886297 -229.119273) (xy 338.886288 -229.11973) (xy 338.878124 -229.169964) (xy 338.862008 -229.218238)
			(xy 338.838357 -229.263301) (xy 338.807784 -229.303987) (xy 338.77108 -229.339242) (xy 338.729196 -229.368152)
			(xy 338.683217 -229.389969) (xy 338.634333 -229.404129) (xy 338.583812 -229.410263) (xy 338.53296 -229.408214)
			(xy 338.483096 -229.398034) (xy 338.43551 -229.379987) (xy 338.391436 -229.354541) (xy 338.352014 -229.322354)
			(xy 338.318266 -229.28426) (xy 338.291065 -229.241246) (xy 338.271117 -229.194426) (xy 338.258938 -229.145012)
			(xy 338.254843 -229.094284) (xy 338.012532 -229.094284) (xy 338.012532 -229.486206) (xy 338.013019 -229.495872)
			(xy 338.020318 -229.51378) (xy 338.026756 -229.521004) (xy 338.068412 -229.563676) (xy 338.071906 -229.567134)
			(xy 338.079963 -229.572764) (xy 338.084414 -229.574852) (xy 338.10956 -229.585774) (xy 338.118704 -229.586282)
			(xy 338.144038 -229.588175) (xy 338.193671 -229.598992) (xy 338.240956 -229.617558) (xy 338.28469 -229.6434)
			(xy 338.323763 -229.675863) (xy 338.357182 -229.714121) (xy 338.384098 -229.757203) (xy 338.403828 -229.804014)
			(xy 338.415869 -229.853365) (xy 338.419917 -229.904002) (xy 338.419914 -229.904036) (xy 338.724743 -229.904036)
			(xy 338.728838 -229.853308) (xy 338.741017 -229.803894) (xy 338.760965 -229.757074) (xy 338.788166 -229.71406)
			(xy 338.821914 -229.675966) (xy 338.861336 -229.643779) (xy 338.90541 -229.618333) (xy 338.952996 -229.600286)
			(xy 339.00286 -229.590106) (xy 339.053712 -229.588057) (xy 339.104233 -229.594191) (xy 339.153117 -229.608351)
			(xy 339.199096 -229.630168) (xy 339.24098 -229.659078) (xy 339.277684 -229.694333) (xy 339.308257 -229.735019)
			(xy 339.331908 -229.780082) (xy 339.348024 -229.828356) (xy 339.356188 -229.87859) (xy 339.3567 -229.904036)
			(xy 339.664797 -229.904036) (xy 339.668892 -229.853308) (xy 339.681071 -229.803894) (xy 339.701019 -229.757074)
			(xy 339.72822 -229.71406) (xy 339.761968 -229.675966) (xy 339.80139 -229.643779) (xy 339.845464 -229.618333)
			(xy 339.89305 -229.600286) (xy 339.942914 -229.590106) (xy 339.993766 -229.588057) (xy 340.044287 -229.594191)
			(xy 340.093171 -229.608351) (xy 340.13915 -229.630168) (xy 340.181034 -229.659078) (xy 340.217738 -229.694333)
			(xy 340.248311 -229.735019) (xy 340.271962 -229.780082) (xy 340.288078 -229.828356) (xy 340.296242 -229.87859)
			(xy 340.296754 -229.904036) (xy 341.544905 -229.904036) (xy 341.549 -229.853308) (xy 341.561179 -229.803894)
			(xy 341.581127 -229.757074) (xy 341.608328 -229.71406) (xy 341.642076 -229.675966) (xy 341.681498 -229.643779)
			(xy 341.725572 -229.618333) (xy 341.773158 -229.600286) (xy 341.823022 -229.590106) (xy 341.873874 -229.588057)
			(xy 341.924395 -229.594191) (xy 341.973279 -229.608351) (xy 342.019258 -229.630168) (xy 342.061142 -229.659078)
			(xy 342.097846 -229.694333) (xy 342.128419 -229.735019) (xy 342.15207 -229.780082) (xy 342.168186 -229.828356)
			(xy 342.17635 -229.87859) (xy 342.176862 -229.904036) (xy 342.176359 -229.929025) (xy 342.483676 -229.929025)
			(xy 342.483676 -229.879047) (xy 342.491495 -229.829684) (xy 342.506939 -229.782152) (xy 342.529629 -229.73762)
			(xy 342.559005 -229.697187) (xy 342.594345 -229.661847) (xy 342.634778 -229.632471) (xy 342.67931 -229.609781)
			(xy 342.726842 -229.594337) (xy 342.776205 -229.586518) (xy 342.826183 -229.586518) (xy 342.875546 -229.594337)
			(xy 342.923078 -229.609781) (xy 342.96761 -229.632471) (xy 343.008043 -229.661847) (xy 343.043383 -229.697187)
			(xy 343.072759 -229.73762) (xy 343.095449 -229.782152) (xy 343.110893 -229.829684) (xy 343.118712 -229.879047)
			(xy 343.119202 -229.904036) (xy 343.424759 -229.904036) (xy 343.428854 -229.853308) (xy 343.441033 -229.803894)
			(xy 343.460981 -229.757074) (xy 343.488182 -229.71406) (xy 343.52193 -229.675966) (xy 343.561352 -229.643779)
			(xy 343.605426 -229.618333) (xy 343.653012 -229.600286) (xy 343.702876 -229.590106) (xy 343.753728 -229.588057)
			(xy 343.804249 -229.594191) (xy 343.853133 -229.608351) (xy 343.899112 -229.630168) (xy 343.940996 -229.659078)
			(xy 343.9777 -229.694333) (xy 344.008273 -229.735019) (xy 344.031924 -229.780082) (xy 344.04804 -229.828356)
			(xy 344.056204 -229.87859) (xy 344.056716 -229.904036) (xy 344.056204 -229.929482) (xy 344.04804 -229.979716)
			(xy 344.031924 -230.02799) (xy 344.008273 -230.073053) (xy 343.9777 -230.113739) (xy 343.940996 -230.148994)
			(xy 343.899112 -230.177904) (xy 343.853133 -230.199721) (xy 343.804249 -230.213881) (xy 343.753728 -230.220015)
			(xy 343.702876 -230.217966) (xy 343.653012 -230.207786) (xy 343.605426 -230.189739) (xy 343.561352 -230.164293)
			(xy 343.52193 -230.132106) (xy 343.488182 -230.094012) (xy 343.460981 -230.050998) (xy 343.441033 -230.004178)
			(xy 343.428854 -229.954764) (xy 343.424759 -229.904036) (xy 343.119202 -229.904036) (xy 343.118712 -229.929025)
			(xy 343.110893 -229.978388) (xy 343.095449 -230.02592) (xy 343.072759 -230.070452) (xy 343.043383 -230.110885)
			(xy 343.008043 -230.146225) (xy 342.96761 -230.175601) (xy 342.923078 -230.198291) (xy 342.875546 -230.213735)
			(xy 342.826183 -230.221554) (xy 342.776205 -230.221554) (xy 342.726842 -230.213735) (xy 342.67931 -230.198291)
			(xy 342.634778 -230.175601) (xy 342.594345 -230.146225) (xy 342.559005 -230.110885) (xy 342.529629 -230.070452)
			(xy 342.506939 -230.02592) (xy 342.491495 -229.978388) (xy 342.483676 -229.929025) (xy 342.176359 -229.929025)
			(xy 342.17635 -229.929482) (xy 342.168186 -229.979716) (xy 342.15207 -230.02799) (xy 342.128419 -230.073053)
			(xy 342.097846 -230.113739) (xy 342.061142 -230.148994) (xy 342.019258 -230.177904) (xy 341.973279 -230.199721)
			(xy 341.924395 -230.213881) (xy 341.873874 -230.220015) (xy 341.823022 -230.217966) (xy 341.773158 -230.207786)
			(xy 341.725572 -230.189739) (xy 341.681498 -230.164293) (xy 341.642076 -230.132106) (xy 341.608328 -230.094012)
			(xy 341.581127 -230.050998) (xy 341.561179 -230.004178) (xy 341.549 -229.954764) (xy 341.544905 -229.904036)
			(xy 340.296754 -229.904036) (xy 340.296242 -229.929482) (xy 340.288078 -229.979716) (xy 340.271962 -230.02799)
			(xy 340.248311 -230.073053) (xy 340.217738 -230.113739) (xy 340.181034 -230.148994) (xy 340.13915 -230.177904)
			(xy 340.093171 -230.199721) (xy 340.044287 -230.213881) (xy 339.993766 -230.220015) (xy 339.942914 -230.217966)
			(xy 339.89305 -230.207786) (xy 339.845464 -230.189739) (xy 339.80139 -230.164293) (xy 339.761968 -230.132106)
			(xy 339.72822 -230.094012) (xy 339.701019 -230.050998) (xy 339.681071 -230.004178) (xy 339.668892 -229.954764)
			(xy 339.664797 -229.904036) (xy 339.3567 -229.904036) (xy 339.356188 -229.929482) (xy 339.348024 -229.979716)
			(xy 339.331908 -230.02799) (xy 339.308257 -230.073053) (xy 339.277684 -230.113739) (xy 339.24098 -230.148994)
			(xy 339.199096 -230.177904) (xy 339.153117 -230.199721) (xy 339.104233 -230.213881) (xy 339.053712 -230.220015)
			(xy 339.00286 -230.217966) (xy 338.952996 -230.207786) (xy 338.90541 -230.189739) (xy 338.861336 -230.164293)
			(xy 338.821914 -230.132106) (xy 338.788166 -230.094012) (xy 338.760965 -230.050998) (xy 338.741017 -230.004178)
			(xy 338.728838 -229.954764) (xy 338.724743 -229.904036) (xy 338.419914 -229.904036) (xy 338.415869 -229.954639)
			(xy 338.403826 -230.00399) (xy 338.384096 -230.050801) (xy 338.35718 -230.093882) (xy 338.32376 -230.13214)
			(xy 338.284687 -230.164602) (xy 338.240952 -230.190444) (xy 338.193667 -230.209009) (xy 338.144034 -230.219826)
			(xy 338.118704 -230.22179) (xy 338.10956 -230.222298) (xy 338.084414 -230.23322) (xy 338.079965 -230.235311)
			(xy 338.071902 -230.240934) (xy 338.068412 -230.244396) (xy 338.026756 -230.287068) (xy 338.020304 -230.294287)
			(xy 338.012992 -230.312194) (xy 338.012532 -230.321866) (xy 338.012532 -230.714296) (xy 338.254843 -230.714296)
			(xy 338.258938 -230.663568) (xy 338.271117 -230.614154) (xy 338.291065 -230.567334) (xy 338.318266 -230.52432)
			(xy 338.352014 -230.486226) (xy 338.391436 -230.454039) (xy 338.43551 -230.428593) (xy 338.483096 -230.410546)
			(xy 338.53296 -230.400366) (xy 338.583812 -230.398317) (xy 338.634333 -230.404451) (xy 338.683217 -230.418611)
			(xy 338.729196 -230.440428) (xy 338.77108 -230.469338) (xy 338.807784 -230.504593) (xy 338.838357 -230.545279)
			(xy 338.862008 -230.590342) (xy 338.878124 -230.638616) (xy 338.886288 -230.68885) (xy 338.8868 -230.714296)
			(xy 338.886297 -230.739285) (xy 339.193614 -230.739285) (xy 339.193614 -230.689307) (xy 339.201433 -230.639944)
			(xy 339.216877 -230.592412) (xy 339.239567 -230.54788) (xy 339.268943 -230.507447) (xy 339.304283 -230.472107)
			(xy 339.344716 -230.442731) (xy 339.389248 -230.420041) (xy 339.43678 -230.404597) (xy 339.486143 -230.396778)
			(xy 339.536121 -230.396778) (xy 339.585484 -230.404597) (xy 339.633016 -230.420041) (xy 339.677548 -230.442731)
			(xy 339.717981 -230.472107) (xy 339.753321 -230.507447) (xy 339.782697 -230.54788) (xy 339.805387 -230.592412)
			(xy 339.820831 -230.639944) (xy 339.82865 -230.689307) (xy 339.82914 -230.714296) (xy 340.134951 -230.714296)
			(xy 340.139046 -230.663568) (xy 340.151225 -230.614154) (xy 340.171173 -230.567334) (xy 340.198374 -230.52432)
			(xy 340.232122 -230.486226) (xy 340.271544 -230.454039) (xy 340.315618 -230.428593) (xy 340.363204 -230.410546)
			(xy 340.413068 -230.400366) (xy 340.46392 -230.398317) (xy 340.514441 -230.404451) (xy 340.563325 -230.418611)
			(xy 340.609304 -230.440428) (xy 340.651188 -230.469338) (xy 340.687892 -230.504593) (xy 340.718465 -230.545279)
			(xy 340.742116 -230.590342) (xy 340.758232 -230.638616) (xy 340.766396 -230.68885) (xy 340.766908 -230.714296)
			(xy 340.76641 -230.739031) (xy 341.073468 -230.739031) (xy 341.073468 -230.689053) (xy 341.081287 -230.63969)
			(xy 341.096731 -230.592158) (xy 341.119421 -230.547626) (xy 341.148797 -230.507193) (xy 341.184137 -230.471853)
			(xy 341.22457 -230.442477) (xy 341.269102 -230.419787) (xy 341.316634 -230.404343) (xy 341.365997 -230.396524)
			(xy 341.415975 -230.396524) (xy 341.465338 -230.404343) (xy 341.51287 -230.419787) (xy 341.557402 -230.442477)
			(xy 341.597835 -230.471853) (xy 341.633175 -230.507193) (xy 341.662551 -230.547626) (xy 341.685241 -230.592158)
			(xy 341.700685 -230.63969) (xy 341.708504 -230.689053) (xy 341.708994 -230.714042) (xy 341.708989 -230.714296)
			(xy 342.014805 -230.714296) (xy 342.0189 -230.663568) (xy 342.031079 -230.614154) (xy 342.051027 -230.567334)
			(xy 342.078228 -230.52432) (xy 342.111976 -230.486226) (xy 342.151398 -230.454039) (xy 342.195472 -230.428593)
			(xy 342.243058 -230.410546) (xy 342.292922 -230.400366) (xy 342.343774 -230.398317) (xy 342.394295 -230.404451)
			(xy 342.443179 -230.418611) (xy 342.489158 -230.440428) (xy 342.531042 -230.469338) (xy 342.567746 -230.504593)
			(xy 342.598319 -230.545279) (xy 342.62197 -230.590342) (xy 342.638086 -230.638616) (xy 342.64625 -230.68885)
			(xy 342.646762 -230.714296) (xy 342.954859 -230.714296) (xy 342.958954 -230.663568) (xy 342.971133 -230.614154)
			(xy 342.991081 -230.567334) (xy 343.018282 -230.52432) (xy 343.05203 -230.486226) (xy 343.091452 -230.454039)
			(xy 343.135526 -230.428593) (xy 343.183112 -230.410546) (xy 343.232976 -230.400366) (xy 343.283828 -230.398317)
			(xy 343.334349 -230.404451) (xy 343.383233 -230.418611) (xy 343.429212 -230.440428) (xy 343.471096 -230.469338)
			(xy 343.5078 -230.504593) (xy 343.538373 -230.545279) (xy 343.562024 -230.590342) (xy 343.57814 -230.638616)
			(xy 343.586304 -230.68885) (xy 343.586816 -230.714296) (xy 343.586313 -230.739285) (xy 343.89363 -230.739285)
			(xy 343.89363 -230.689307) (xy 343.901449 -230.639944) (xy 343.916893 -230.592412) (xy 343.939583 -230.54788)
			(xy 343.968959 -230.507447) (xy 344.004299 -230.472107) (xy 344.044732 -230.442731) (xy 344.089264 -230.420041)
			(xy 344.136796 -230.404597) (xy 344.186159 -230.396778) (xy 344.236137 -230.396778) (xy 344.2855 -230.404597)
			(xy 344.333032 -230.420041) (xy 344.377564 -230.442731) (xy 344.417997 -230.472107) (xy 344.453337 -230.507447)
			(xy 344.482713 -230.54788) (xy 344.505403 -230.592412) (xy 344.520847 -230.639944) (xy 344.528666 -230.689307)
			(xy 344.529156 -230.714296) (xy 344.528666 -230.739285) (xy 344.520847 -230.788648) (xy 344.505403 -230.83618)
			(xy 344.482713 -230.880712) (xy 344.453337 -230.921145) (xy 344.417997 -230.956485) (xy 344.377564 -230.985861)
			(xy 344.333032 -231.008551) (xy 344.2855 -231.023995) (xy 344.236137 -231.031814) (xy 344.186159 -231.031814)
			(xy 344.136796 -231.023995) (xy 344.089264 -231.008551) (xy 344.044732 -230.985861) (xy 344.004299 -230.956485)
			(xy 343.968959 -230.921145) (xy 343.939583 -230.880712) (xy 343.916893 -230.83618) (xy 343.901449 -230.788648)
			(xy 343.89363 -230.739285) (xy 343.586313 -230.739285) (xy 343.586304 -230.739742) (xy 343.57814 -230.789976)
			(xy 343.562024 -230.83825) (xy 343.538373 -230.883313) (xy 343.5078 -230.923999) (xy 343.471096 -230.959254)
			(xy 343.429212 -230.988164) (xy 343.383233 -231.009981) (xy 343.334349 -231.024141) (xy 343.283828 -231.030275)
			(xy 343.232976 -231.028226) (xy 343.183112 -231.018046) (xy 343.135526 -230.999999) (xy 343.091452 -230.974553)
			(xy 343.05203 -230.942366) (xy 343.018282 -230.904272) (xy 342.991081 -230.861258) (xy 342.971133 -230.814438)
			(xy 342.958954 -230.765024) (xy 342.954859 -230.714296) (xy 342.646762 -230.714296) (xy 342.64625 -230.739742)
			(xy 342.638086 -230.789976) (xy 342.62197 -230.83825) (xy 342.598319 -230.883313) (xy 342.567746 -230.923999)
			(xy 342.531042 -230.959254) (xy 342.489158 -230.988164) (xy 342.443179 -231.009981) (xy 342.394295 -231.024141)
			(xy 342.343774 -231.030275) (xy 342.292922 -231.028226) (xy 342.243058 -231.018046) (xy 342.195472 -230.999999)
			(xy 342.151398 -230.974553) (xy 342.111976 -230.942366) (xy 342.078228 -230.904272) (xy 342.051027 -230.861258)
			(xy 342.031079 -230.814438) (xy 342.0189 -230.765024) (xy 342.014805 -230.714296) (xy 341.708989 -230.714296)
			(xy 341.708504 -230.739031) (xy 341.700685 -230.788394) (xy 341.685241 -230.835926) (xy 341.662551 -230.880458)
			(xy 341.633175 -230.920891) (xy 341.597835 -230.956231) (xy 341.557402 -230.985607) (xy 341.51287 -231.008297)
			(xy 341.465338 -231.023741) (xy 341.415975 -231.03156) (xy 341.365997 -231.03156) (xy 341.316634 -231.023741)
			(xy 341.269102 -231.008297) (xy 341.22457 -230.985607) (xy 341.184137 -230.956231) (xy 341.148797 -230.920891)
			(xy 341.119421 -230.880458) (xy 341.096731 -230.835926) (xy 341.081287 -230.788394) (xy 341.073468 -230.739031)
			(xy 340.76641 -230.739031) (xy 340.766396 -230.739742) (xy 340.758232 -230.789976) (xy 340.742116 -230.83825)
			(xy 340.718465 -230.883313) (xy 340.687892 -230.923999) (xy 340.651188 -230.959254) (xy 340.609304 -230.988164)
			(xy 340.563325 -231.009981) (xy 340.514441 -231.024141) (xy 340.46392 -231.030275) (xy 340.413068 -231.028226)
			(xy 340.363204 -231.018046) (xy 340.315618 -230.999999) (xy 340.271544 -230.974553) (xy 340.232122 -230.942366)
			(xy 340.198374 -230.904272) (xy 340.171173 -230.861258) (xy 340.151225 -230.814438) (xy 340.139046 -230.765024)
			(xy 340.134951 -230.714296) (xy 339.82914 -230.714296) (xy 339.82865 -230.739285) (xy 339.820831 -230.788648)
			(xy 339.805387 -230.83618) (xy 339.782697 -230.880712) (xy 339.753321 -230.921145) (xy 339.717981 -230.956485)
			(xy 339.677548 -230.985861) (xy 339.633016 -231.008551) (xy 339.585484 -231.023995) (xy 339.536121 -231.031814)
			(xy 339.486143 -231.031814) (xy 339.43678 -231.023995) (xy 339.389248 -231.008551) (xy 339.344716 -230.985861)
			(xy 339.304283 -230.956485) (xy 339.268943 -230.921145) (xy 339.239567 -230.880712) (xy 339.216877 -230.83618)
			(xy 339.201433 -230.788648) (xy 339.193614 -230.739285) (xy 338.886297 -230.739285) (xy 338.886288 -230.739742)
			(xy 338.878124 -230.789976) (xy 338.862008 -230.83825) (xy 338.838357 -230.883313) (xy 338.807784 -230.923999)
			(xy 338.77108 -230.959254) (xy 338.729196 -230.988164) (xy 338.683217 -231.009981) (xy 338.634333 -231.024141)
			(xy 338.583812 -231.030275) (xy 338.53296 -231.028226) (xy 338.483096 -231.018046) (xy 338.43551 -230.999999)
			(xy 338.391436 -230.974553) (xy 338.352014 -230.942366) (xy 338.318266 -230.904272) (xy 338.291065 -230.861258)
			(xy 338.271117 -230.814438) (xy 338.258938 -230.765024) (xy 338.254843 -230.714296) (xy 338.012532 -230.714296)
			(xy 338.012532 -231.106218) (xy 338.013021 -231.115883) (xy 338.020323 -231.133788) (xy 338.026756 -231.141016)
			(xy 338.068412 -231.183688) (xy 338.071907 -231.187145) (xy 338.079964 -231.192774) (xy 338.084414 -231.194864)
			(xy 338.10956 -231.205786) (xy 338.118704 -231.206294) (xy 338.144037 -231.208187) (xy 338.193668 -231.219004)
			(xy 338.240951 -231.237569) (xy 338.284684 -231.263411) (xy 338.323755 -231.295872) (xy 338.357173 -231.334129)
			(xy 338.384088 -231.377209) (xy 338.403816 -231.424018) (xy 338.415858 -231.473367) (xy 338.419905 -231.524003)
			(xy 338.419901 -231.524048) (xy 338.724743 -231.524048) (xy 338.728838 -231.47332) (xy 338.741017 -231.423906)
			(xy 338.760965 -231.377086) (xy 338.788166 -231.334072) (xy 338.821914 -231.295978) (xy 338.861336 -231.263791)
			(xy 338.90541 -231.238345) (xy 338.952996 -231.220298) (xy 339.00286 -231.210118) (xy 339.053712 -231.208069)
			(xy 339.104233 -231.214203) (xy 339.153117 -231.228363) (xy 339.199096 -231.25018) (xy 339.24098 -231.27909)
			(xy 339.277684 -231.314345) (xy 339.308257 -231.355031) (xy 339.331908 -231.400094) (xy 339.348024 -231.448368)
			(xy 339.356188 -231.498602) (xy 339.3567 -231.524048) (xy 339.664797 -231.524048) (xy 339.668892 -231.47332)
			(xy 339.681071 -231.423906) (xy 339.701019 -231.377086) (xy 339.72822 -231.334072) (xy 339.761968 -231.295978)
			(xy 339.80139 -231.263791) (xy 339.845464 -231.238345) (xy 339.89305 -231.220298) (xy 339.942914 -231.210118)
			(xy 339.993766 -231.208069) (xy 340.044287 -231.214203) (xy 340.093171 -231.228363) (xy 340.13915 -231.25018)
			(xy 340.181034 -231.27909) (xy 340.217738 -231.314345) (xy 340.248311 -231.355031) (xy 340.271962 -231.400094)
			(xy 340.288078 -231.448368) (xy 340.296242 -231.498602) (xy 340.296754 -231.524048) (xy 340.296251 -231.549037)
			(xy 340.603568 -231.549037) (xy 340.603568 -231.499059) (xy 340.611387 -231.449696) (xy 340.626831 -231.402164)
			(xy 340.649521 -231.357632) (xy 340.678897 -231.317199) (xy 340.714237 -231.281859) (xy 340.75467 -231.252483)
			(xy 340.799202 -231.229793) (xy 340.846734 -231.214349) (xy 340.896097 -231.20653) (xy 340.946075 -231.20653)
			(xy 340.995438 -231.214349) (xy 341.04297 -231.229793) (xy 341.087502 -231.252483) (xy 341.127935 -231.281859)
			(xy 341.163275 -231.317199) (xy 341.192651 -231.357632) (xy 341.215341 -231.402164) (xy 341.230785 -231.449696)
			(xy 341.238604 -231.499059) (xy 341.239094 -231.524048) (xy 341.544905 -231.524048) (xy 341.549 -231.47332)
			(xy 341.561179 -231.423906) (xy 341.581127 -231.377086) (xy 341.608328 -231.334072) (xy 341.642076 -231.295978)
			(xy 341.681498 -231.263791) (xy 341.725572 -231.238345) (xy 341.773158 -231.220298) (xy 341.823022 -231.210118)
			(xy 341.873874 -231.208069) (xy 341.924395 -231.214203) (xy 341.973279 -231.228363) (xy 342.019258 -231.25018)
			(xy 342.061142 -231.27909) (xy 342.097846 -231.314345) (xy 342.128419 -231.355031) (xy 342.15207 -231.400094)
			(xy 342.168186 -231.448368) (xy 342.17635 -231.498602) (xy 342.176862 -231.524048) (xy 342.176359 -231.549037)
			(xy 342.483676 -231.549037) (xy 342.483676 -231.499059) (xy 342.491495 -231.449696) (xy 342.506939 -231.402164)
			(xy 342.529629 -231.357632) (xy 342.559005 -231.317199) (xy 342.594345 -231.281859) (xy 342.634778 -231.252483)
			(xy 342.67931 -231.229793) (xy 342.726842 -231.214349) (xy 342.776205 -231.20653) (xy 342.826183 -231.20653)
			(xy 342.875546 -231.214349) (xy 342.923078 -231.229793) (xy 342.96761 -231.252483) (xy 343.008043 -231.281859)
			(xy 343.043383 -231.317199) (xy 343.072759 -231.357632) (xy 343.095449 -231.402164) (xy 343.110893 -231.449696)
			(xy 343.118712 -231.499059) (xy 343.119202 -231.524048) (xy 343.424759 -231.524048) (xy 343.428854 -231.47332)
			(xy 343.441033 -231.423906) (xy 343.460981 -231.377086) (xy 343.488182 -231.334072) (xy 343.52193 -231.295978)
			(xy 343.561352 -231.263791) (xy 343.605426 -231.238345) (xy 343.653012 -231.220298) (xy 343.702876 -231.210118)
			(xy 343.753728 -231.208069) (xy 343.804249 -231.214203) (xy 343.853133 -231.228363) (xy 343.899112 -231.25018)
			(xy 343.940996 -231.27909) (xy 343.9777 -231.314345) (xy 344.008273 -231.355031) (xy 344.031924 -231.400094)
			(xy 344.04804 -231.448368) (xy 344.056204 -231.498602) (xy 344.056716 -231.524048) (xy 344.056204 -231.549494)
			(xy 344.04804 -231.599728) (xy 344.031924 -231.648002) (xy 344.008273 -231.693065) (xy 343.9777 -231.733751)
			(xy 343.940996 -231.769006) (xy 343.899112 -231.797916) (xy 343.853133 -231.819733) (xy 343.804249 -231.833893)
			(xy 343.753728 -231.840027) (xy 343.702876 -231.837978) (xy 343.653012 -231.827798) (xy 343.605426 -231.809751)
			(xy 343.561352 -231.784305) (xy 343.52193 -231.752118) (xy 343.488182 -231.714024) (xy 343.460981 -231.67101)
			(xy 343.441033 -231.62419) (xy 343.428854 -231.574776) (xy 343.424759 -231.524048) (xy 343.119202 -231.524048)
			(xy 343.118712 -231.549037) (xy 343.110893 -231.5984) (xy 343.095449 -231.645932) (xy 343.072759 -231.690464)
			(xy 343.043383 -231.730897) (xy 343.008043 -231.766237) (xy 342.96761 -231.795613) (xy 342.923078 -231.818303)
			(xy 342.875546 -231.833747) (xy 342.826183 -231.841566) (xy 342.776205 -231.841566) (xy 342.726842 -231.833747)
			(xy 342.67931 -231.818303) (xy 342.634778 -231.795613) (xy 342.594345 -231.766237) (xy 342.559005 -231.730897)
			(xy 342.529629 -231.690464) (xy 342.506939 -231.645932) (xy 342.491495 -231.5984) (xy 342.483676 -231.549037)
			(xy 342.176359 -231.549037) (xy 342.17635 -231.549494) (xy 342.168186 -231.599728) (xy 342.15207 -231.648002)
			(xy 342.128419 -231.693065) (xy 342.097846 -231.733751) (xy 342.061142 -231.769006) (xy 342.019258 -231.797916)
			(xy 341.973279 -231.819733) (xy 341.924395 -231.833893) (xy 341.873874 -231.840027) (xy 341.823022 -231.837978)
			(xy 341.773158 -231.827798) (xy 341.725572 -231.809751) (xy 341.681498 -231.784305) (xy 341.642076 -231.752118)
			(xy 341.608328 -231.714024) (xy 341.581127 -231.67101) (xy 341.561179 -231.62419) (xy 341.549 -231.574776)
			(xy 341.544905 -231.524048) (xy 341.239094 -231.524048) (xy 341.238604 -231.549037) (xy 341.230785 -231.5984)
			(xy 341.215341 -231.645932) (xy 341.192651 -231.690464) (xy 341.163275 -231.730897) (xy 341.127935 -231.766237)
			(xy 341.087502 -231.795613) (xy 341.04297 -231.818303) (xy 340.995438 -231.833747) (xy 340.946075 -231.841566)
			(xy 340.896097 -231.841566) (xy 340.846734 -231.833747) (xy 340.799202 -231.818303) (xy 340.75467 -231.795613)
			(xy 340.714237 -231.766237) (xy 340.678897 -231.730897) (xy 340.649521 -231.690464) (xy 340.626831 -231.645932)
			(xy 340.611387 -231.5984) (xy 340.603568 -231.549037) (xy 340.296251 -231.549037) (xy 340.296242 -231.549494)
			(xy 340.288078 -231.599728) (xy 340.271962 -231.648002) (xy 340.248311 -231.693065) (xy 340.217738 -231.733751)
			(xy 340.181034 -231.769006) (xy 340.13915 -231.797916) (xy 340.093171 -231.819733) (xy 340.044287 -231.833893)
			(xy 339.993766 -231.840027) (xy 339.942914 -231.837978) (xy 339.89305 -231.827798) (xy 339.845464 -231.809751)
			(xy 339.80139 -231.784305) (xy 339.761968 -231.752118) (xy 339.72822 -231.714024) (xy 339.701019 -231.67101)
			(xy 339.681071 -231.62419) (xy 339.668892 -231.574776) (xy 339.664797 -231.524048) (xy 339.3567 -231.524048)
			(xy 339.356188 -231.549494) (xy 339.348024 -231.599728) (xy 339.331908 -231.648002) (xy 339.308257 -231.693065)
			(xy 339.277684 -231.733751) (xy 339.24098 -231.769006) (xy 339.199096 -231.797916) (xy 339.153117 -231.819733)
			(xy 339.104233 -231.833893) (xy 339.053712 -231.840027) (xy 339.00286 -231.837978) (xy 338.952996 -231.827798)
			(xy 338.90541 -231.809751) (xy 338.861336 -231.784305) (xy 338.821914 -231.752118) (xy 338.788166 -231.714024)
			(xy 338.760965 -231.67101) (xy 338.741017 -231.62419) (xy 338.728838 -231.574776) (xy 338.724743 -231.524048)
			(xy 338.419901 -231.524048) (xy 338.415857 -231.574638) (xy 338.403815 -231.623987) (xy 338.384085 -231.670796)
			(xy 338.35717 -231.713875) (xy 338.323751 -231.752132) (xy 338.284679 -231.784592) (xy 338.240946 -231.810433)
			(xy 338.193663 -231.828998) (xy 338.144031 -231.839814) (xy 338.118704 -231.841802) (xy 338.10956 -231.84231)
			(xy 338.084414 -231.853232) (xy 338.079965 -231.855324) (xy 338.071903 -231.860947) (xy 338.068412 -231.864408)
			(xy 338.026756 -231.90708) (xy 338.020291 -231.914295) (xy 338.012947 -231.932201) (xy 338.012532 -231.941878)
			(xy 338.012532 -232.334054) (xy 338.254843 -232.334054) (xy 338.258938 -232.283326) (xy 338.271117 -232.233912)
			(xy 338.291065 -232.187092) (xy 338.318266 -232.144078) (xy 338.352014 -232.105984) (xy 338.391436 -232.073797)
			(xy 338.43551 -232.048351) (xy 338.483096 -232.030304) (xy 338.53296 -232.020124) (xy 338.583812 -232.018075)
			(xy 338.634333 -232.024209) (xy 338.683217 -232.038369) (xy 338.729196 -232.060186) (xy 338.77108 -232.089096)
			(xy 338.807784 -232.124351) (xy 338.838357 -232.165037) (xy 338.862008 -232.2101) (xy 338.878124 -232.258374)
			(xy 338.886288 -232.308608) (xy 338.8868 -232.334054) (xy 338.886297 -232.359043) (xy 339.193614 -232.359043)
			(xy 339.193614 -232.309065) (xy 339.201433 -232.259702) (xy 339.216877 -232.21217) (xy 339.239567 -232.167638)
			(xy 339.268943 -232.127205) (xy 339.304283 -232.091865) (xy 339.344716 -232.062489) (xy 339.389248 -232.039799)
			(xy 339.43678 -232.024355) (xy 339.486143 -232.016536) (xy 339.536121 -232.016536) (xy 339.585484 -232.024355)
			(xy 339.633016 -232.039799) (xy 339.677548 -232.062489) (xy 339.717981 -232.091865) (xy 339.753321 -232.127205)
			(xy 339.782697 -232.167638) (xy 339.805387 -232.21217) (xy 339.820831 -232.259702) (xy 339.82865 -232.309065)
			(xy 339.82914 -232.334054) (xy 340.134951 -232.334054) (xy 340.139046 -232.283326) (xy 340.151225 -232.233912)
			(xy 340.171173 -232.187092) (xy 340.198374 -232.144078) (xy 340.232122 -232.105984) (xy 340.271544 -232.073797)
			(xy 340.315618 -232.048351) (xy 340.363204 -232.030304) (xy 340.413068 -232.020124) (xy 340.46392 -232.018075)
			(xy 340.514441 -232.024209) (xy 340.563325 -232.038369) (xy 340.609304 -232.060186) (xy 340.651188 -232.089096)
			(xy 340.687892 -232.124351) (xy 340.718465 -232.165037) (xy 340.742116 -232.2101) (xy 340.758232 -232.258374)
			(xy 340.766396 -232.308608) (xy 340.766908 -232.334054) (xy 342.014805 -232.334054) (xy 342.0189 -232.283326)
			(xy 342.031079 -232.233912) (xy 342.051027 -232.187092) (xy 342.078228 -232.144078) (xy 342.111976 -232.105984)
			(xy 342.151398 -232.073797) (xy 342.195472 -232.048351) (xy 342.243058 -232.030304) (xy 342.292922 -232.020124)
			(xy 342.343774 -232.018075) (xy 342.394295 -232.024209) (xy 342.443179 -232.038369) (xy 342.489158 -232.060186)
			(xy 342.531042 -232.089096) (xy 342.567746 -232.124351) (xy 342.598319 -232.165037) (xy 342.62197 -232.2101)
			(xy 342.638086 -232.258374) (xy 342.64625 -232.308608) (xy 342.646762 -232.334054) (xy 342.954859 -232.334054)
			(xy 342.958954 -232.283326) (xy 342.971133 -232.233912) (xy 342.991081 -232.187092) (xy 343.018282 -232.144078)
			(xy 343.05203 -232.105984) (xy 343.091452 -232.073797) (xy 343.135526 -232.048351) (xy 343.183112 -232.030304)
			(xy 343.232976 -232.020124) (xy 343.283828 -232.018075) (xy 343.334349 -232.024209) (xy 343.383233 -232.038369)
			(xy 343.429212 -232.060186) (xy 343.471096 -232.089096) (xy 343.5078 -232.124351) (xy 343.538373 -232.165037)
			(xy 343.562024 -232.2101) (xy 343.57814 -232.258374) (xy 343.586304 -232.308608) (xy 343.586816 -232.334054)
			(xy 343.586304 -232.3595) (xy 343.57814 -232.409734) (xy 343.562024 -232.458008) (xy 343.538373 -232.503071)
			(xy 343.5078 -232.543757) (xy 343.471096 -232.579012) (xy 343.429212 -232.607922) (xy 343.383233 -232.629739)
			(xy 343.334349 -232.643899) (xy 343.283828 -232.650033) (xy 343.232976 -232.647984) (xy 343.183112 -232.637804)
			(xy 343.135526 -232.619757) (xy 343.091452 -232.594311) (xy 343.05203 -232.562124) (xy 343.018282 -232.52403)
			(xy 342.991081 -232.481016) (xy 342.971133 -232.434196) (xy 342.958954 -232.384782) (xy 342.954859 -232.334054)
			(xy 342.646762 -232.334054) (xy 342.64625 -232.3595) (xy 342.638086 -232.409734) (xy 342.62197 -232.458008)
			(xy 342.598319 -232.503071) (xy 342.567746 -232.543757) (xy 342.531042 -232.579012) (xy 342.489158 -232.607922)
			(xy 342.443179 -232.629739) (xy 342.394295 -232.643899) (xy 342.343774 -232.650033) (xy 342.292922 -232.647984)
			(xy 342.243058 -232.637804) (xy 342.195472 -232.619757) (xy 342.151398 -232.594311) (xy 342.111976 -232.562124)
			(xy 342.078228 -232.52403) (xy 342.051027 -232.481016) (xy 342.031079 -232.434196) (xy 342.0189 -232.384782)
			(xy 342.014805 -232.334054) (xy 340.766908 -232.334054) (xy 340.766396 -232.3595) (xy 340.758232 -232.409734)
			(xy 340.742116 -232.458008) (xy 340.718465 -232.503071) (xy 340.687892 -232.543757) (xy 340.651188 -232.579012)
			(xy 340.609304 -232.607922) (xy 340.563325 -232.629739) (xy 340.514441 -232.643899) (xy 340.46392 -232.650033)
			(xy 340.413068 -232.647984) (xy 340.363204 -232.637804) (xy 340.315618 -232.619757) (xy 340.271544 -232.594311)
			(xy 340.232122 -232.562124) (xy 340.198374 -232.52403) (xy 340.171173 -232.481016) (xy 340.151225 -232.434196)
			(xy 340.139046 -232.384782) (xy 340.134951 -232.334054) (xy 339.82914 -232.334054) (xy 339.82865 -232.359043)
			(xy 339.820831 -232.408406) (xy 339.805387 -232.455938) (xy 339.782697 -232.50047) (xy 339.753321 -232.540903)
			(xy 339.717981 -232.576243) (xy 339.677548 -232.605619) (xy 339.633016 -232.628309) (xy 339.585484 -232.643753)
			(xy 339.536121 -232.651572) (xy 339.486143 -232.651572) (xy 339.43678 -232.643753) (xy 339.389248 -232.628309)
			(xy 339.344716 -232.605619) (xy 339.304283 -232.576243) (xy 339.268943 -232.540903) (xy 339.239567 -232.50047)
			(xy 339.216877 -232.455938) (xy 339.201433 -232.408406) (xy 339.193614 -232.359043) (xy 338.886297 -232.359043)
			(xy 338.886288 -232.3595) (xy 338.878124 -232.409734) (xy 338.862008 -232.458008) (xy 338.838357 -232.503071)
			(xy 338.807784 -232.543757) (xy 338.77108 -232.579012) (xy 338.729196 -232.607922) (xy 338.683217 -232.629739)
			(xy 338.634333 -232.643899) (xy 338.583812 -232.650033) (xy 338.53296 -232.647984) (xy 338.483096 -232.637804)
			(xy 338.43551 -232.619757) (xy 338.391436 -232.594311) (xy 338.352014 -232.562124) (xy 338.318266 -232.52403)
			(xy 338.291065 -232.481016) (xy 338.271117 -232.434196) (xy 338.258938 -232.384782) (xy 338.254843 -232.334054)
			(xy 338.012532 -232.334054) (xy 338.012532 -232.72623) (xy 338.013023 -232.735894) (xy 338.020328 -232.753796)
			(xy 338.026756 -232.761028) (xy 338.068412 -232.8037) (xy 338.071907 -232.807157) (xy 338.079965 -232.812784)
			(xy 338.084414 -232.814876) (xy 338.10956 -232.825798) (xy 338.118704 -232.826306) (xy 338.144044 -232.828199)
			(xy 338.193689 -232.839018) (xy 338.240985 -232.857588) (xy 338.28473 -232.883436) (xy 338.323813 -232.915906)
			(xy 338.35724 -232.954173) (xy 338.384164 -232.997264) (xy 338.403898 -233.044086) (xy 338.415944 -233.093449)
			(xy 338.41999 -233.14406) (xy 338.724743 -233.14406) (xy 338.728838 -233.093332) (xy 338.741017 -233.043918)
			(xy 338.760965 -232.997098) (xy 338.788166 -232.954084) (xy 338.821914 -232.91599) (xy 338.861336 -232.883803)
			(xy 338.90541 -232.858357) (xy 338.952996 -232.84031) (xy 339.00286 -232.83013) (xy 339.053712 -232.828081)
			(xy 339.104233 -232.834215) (xy 339.153117 -232.848375) (xy 339.199096 -232.870192) (xy 339.24098 -232.899102)
			(xy 339.277684 -232.934357) (xy 339.308257 -232.975043) (xy 339.331908 -233.020106) (xy 339.348024 -233.06838)
			(xy 339.356188 -233.118614) (xy 339.3567 -233.14406) (xy 339.664797 -233.14406) (xy 339.668892 -233.093332)
			(xy 339.681071 -233.043918) (xy 339.701019 -232.997098) (xy 339.72822 -232.954084) (xy 339.761968 -232.91599)
			(xy 339.80139 -232.883803) (xy 339.845464 -232.858357) (xy 339.89305 -232.84031) (xy 339.942914 -232.83013)
			(xy 339.993766 -232.828081) (xy 340.044287 -232.834215) (xy 340.093171 -232.848375) (xy 340.13915 -232.870192)
			(xy 340.181034 -232.899102) (xy 340.217738 -232.934357) (xy 340.248311 -232.975043) (xy 340.271962 -233.020106)
			(xy 340.288078 -233.06838) (xy 340.296242 -233.118614) (xy 340.296754 -233.14406) (xy 340.296251 -233.169049)
			(xy 340.603568 -233.169049) (xy 340.603568 -233.119071) (xy 340.611387 -233.069708) (xy 340.626831 -233.022176)
			(xy 340.649521 -232.977644) (xy 340.678897 -232.937211) (xy 340.714237 -232.901871) (xy 340.75467 -232.872495)
			(xy 340.799202 -232.849805) (xy 340.846734 -232.834361) (xy 340.896097 -232.826542) (xy 340.946075 -232.826542)
			(xy 340.995438 -232.834361) (xy 341.04297 -232.849805) (xy 341.087502 -232.872495) (xy 341.127935 -232.901871)
			(xy 341.163275 -232.937211) (xy 341.192651 -232.977644) (xy 341.215341 -233.022176) (xy 341.230785 -233.069708)
			(xy 341.238604 -233.119071) (xy 341.239094 -233.14406) (xy 341.544905 -233.14406) (xy 341.549 -233.093332)
			(xy 341.561179 -233.043918) (xy 341.581127 -232.997098) (xy 341.608328 -232.954084) (xy 341.642076 -232.91599)
			(xy 341.681498 -232.883803) (xy 341.725572 -232.858357) (xy 341.773158 -232.84031) (xy 341.823022 -232.83013)
			(xy 341.873874 -232.828081) (xy 341.924395 -232.834215) (xy 341.973279 -232.848375) (xy 342.019258 -232.870192)
			(xy 342.061142 -232.899102) (xy 342.097846 -232.934357) (xy 342.128419 -232.975043) (xy 342.15207 -233.020106)
			(xy 342.168186 -233.06838) (xy 342.17635 -233.118614) (xy 342.176862 -233.14406) (xy 342.176359 -233.169049)
			(xy 342.483676 -233.169049) (xy 342.483676 -233.119071) (xy 342.491495 -233.069708) (xy 342.506939 -233.022176)
			(xy 342.529629 -232.977644) (xy 342.559005 -232.937211) (xy 342.594345 -232.901871) (xy 342.634778 -232.872495)
			(xy 342.67931 -232.849805) (xy 342.726842 -232.834361) (xy 342.776205 -232.826542) (xy 342.826183 -232.826542)
			(xy 342.875546 -232.834361) (xy 342.923078 -232.849805) (xy 342.96761 -232.872495) (xy 343.008043 -232.901871)
			(xy 343.043383 -232.937211) (xy 343.072759 -232.977644) (xy 343.095449 -233.022176) (xy 343.110893 -233.069708)
			(xy 343.118712 -233.119071) (xy 343.119202 -233.14406) (xy 343.424759 -233.14406) (xy 343.428854 -233.093332)
			(xy 343.441033 -233.043918) (xy 343.460981 -232.997098) (xy 343.488182 -232.954084) (xy 343.52193 -232.91599)
			(xy 343.561352 -232.883803) (xy 343.605426 -232.858357) (xy 343.653012 -232.84031) (xy 343.702876 -232.83013)
			(xy 343.753728 -232.828081) (xy 343.804249 -232.834215) (xy 343.853133 -232.848375) (xy 343.899112 -232.870192)
			(xy 343.940996 -232.899102) (xy 343.9777 -232.934357) (xy 344.008273 -232.975043) (xy 344.031924 -233.020106)
			(xy 344.04804 -233.06838) (xy 344.056204 -233.118614) (xy 344.056716 -233.14406) (xy 344.056204 -233.169506)
			(xy 344.04804 -233.21974) (xy 344.031924 -233.268014) (xy 344.008273 -233.313077) (xy 343.9777 -233.353763)
			(xy 343.940996 -233.389018) (xy 343.899112 -233.417928) (xy 343.853133 -233.439745) (xy 343.804249 -233.453905)
			(xy 343.753728 -233.460039) (xy 343.702876 -233.45799) (xy 343.653012 -233.44781) (xy 343.605426 -233.429763)
			(xy 343.561352 -233.404317) (xy 343.52193 -233.37213) (xy 343.488182 -233.334036) (xy 343.460981 -233.291022)
			(xy 343.441033 -233.244202) (xy 343.428854 -233.194788) (xy 343.424759 -233.14406) (xy 343.119202 -233.14406)
			(xy 343.118712 -233.169049) (xy 343.110893 -233.218412) (xy 343.095449 -233.265944) (xy 343.072759 -233.310476)
			(xy 343.043383 -233.350909) (xy 343.008043 -233.386249) (xy 342.96761 -233.415625) (xy 342.923078 -233.438315)
			(xy 342.875546 -233.453759) (xy 342.826183 -233.461578) (xy 342.776205 -233.461578) (xy 342.726842 -233.453759)
			(xy 342.67931 -233.438315) (xy 342.634778 -233.415625) (xy 342.594345 -233.386249) (xy 342.559005 -233.350909)
			(xy 342.529629 -233.310476) (xy 342.506939 -233.265944) (xy 342.491495 -233.218412) (xy 342.483676 -233.169049)
			(xy 342.176359 -233.169049) (xy 342.17635 -233.169506) (xy 342.168186 -233.21974) (xy 342.15207 -233.268014)
			(xy 342.128419 -233.313077) (xy 342.097846 -233.353763) (xy 342.061142 -233.389018) (xy 342.019258 -233.417928)
			(xy 341.973279 -233.439745) (xy 341.924395 -233.453905) (xy 341.873874 -233.460039) (xy 341.823022 -233.45799)
			(xy 341.773158 -233.44781) (xy 341.725572 -233.429763) (xy 341.681498 -233.404317) (xy 341.642076 -233.37213)
			(xy 341.608328 -233.334036) (xy 341.581127 -233.291022) (xy 341.561179 -233.244202) (xy 341.549 -233.194788)
			(xy 341.544905 -233.14406) (xy 341.239094 -233.14406) (xy 341.238604 -233.169049) (xy 341.230785 -233.218412)
			(xy 341.215341 -233.265944) (xy 341.192651 -233.310476) (xy 341.163275 -233.350909) (xy 341.127935 -233.386249)
			(xy 341.087502 -233.415625) (xy 341.04297 -233.438315) (xy 340.995438 -233.453759) (xy 340.946075 -233.461578)
			(xy 340.896097 -233.461578) (xy 340.846734 -233.453759) (xy 340.799202 -233.438315) (xy 340.75467 -233.415625)
			(xy 340.714237 -233.386249) (xy 340.678897 -233.350909) (xy 340.649521 -233.310476) (xy 340.626831 -233.265944)
			(xy 340.611387 -233.218412) (xy 340.603568 -233.169049) (xy 340.296251 -233.169049) (xy 340.296242 -233.169506)
			(xy 340.288078 -233.21974) (xy 340.271962 -233.268014) (xy 340.248311 -233.313077) (xy 340.217738 -233.353763)
			(xy 340.181034 -233.389018) (xy 340.13915 -233.417928) (xy 340.093171 -233.439745) (xy 340.044287 -233.453905)
			(xy 339.993766 -233.460039) (xy 339.942914 -233.45799) (xy 339.89305 -233.44781) (xy 339.845464 -233.429763)
			(xy 339.80139 -233.404317) (xy 339.761968 -233.37213) (xy 339.72822 -233.334036) (xy 339.701019 -233.291022)
			(xy 339.681071 -233.244202) (xy 339.668892 -233.194788) (xy 339.664797 -233.14406) (xy 339.3567 -233.14406)
			(xy 339.356188 -233.169506) (xy 339.348024 -233.21974) (xy 339.331908 -233.268014) (xy 339.308257 -233.313077)
			(xy 339.277684 -233.353763) (xy 339.24098 -233.389018) (xy 339.199096 -233.417928) (xy 339.153117 -233.439745)
			(xy 339.104233 -233.453905) (xy 339.053712 -233.460039) (xy 339.00286 -233.45799) (xy 338.952996 -233.44781)
			(xy 338.90541 -233.429763) (xy 338.861336 -233.404317) (xy 338.821914 -233.37213) (xy 338.788166 -233.334036)
			(xy 338.760965 -233.291022) (xy 338.741017 -233.244202) (xy 338.728838 -233.194788) (xy 338.724743 -233.14406)
			(xy 338.41999 -233.14406) (xy 338.419993 -233.144098) (xy 338.415944 -233.194747) (xy 338.4039 -233.24411)
			(xy 338.384166 -233.290932) (xy 338.357243 -233.334024) (xy 338.323816 -233.372291) (xy 338.284734 -233.404761)
			(xy 338.240989 -233.43061) (xy 338.193693 -233.44918) (xy 338.144048 -233.460001) (xy 338.118704 -233.461814)
			(xy 338.10956 -233.462322) (xy 338.084414 -233.473244) (xy 338.079965 -233.475336) (xy 338.071905 -233.480961)
			(xy 338.068412 -233.48442) (xy 338.026756 -233.527092) (xy 338.020292 -233.534307) (xy 338.012953 -233.552214)
			(xy 338.012532 -233.56189) (xy 338.012532 -233.954066) (xy 338.254843 -233.954066) (xy 338.258938 -233.903338)
			(xy 338.271117 -233.853924) (xy 338.291065 -233.807104) (xy 338.318266 -233.76409) (xy 338.352014 -233.725996)
			(xy 338.391436 -233.693809) (xy 338.43551 -233.668363) (xy 338.483096 -233.650316) (xy 338.53296 -233.640136)
			(xy 338.583812 -233.638087) (xy 338.634333 -233.644221) (xy 338.683217 -233.658381) (xy 338.729196 -233.680198)
			(xy 338.77108 -233.709108) (xy 338.807784 -233.744363) (xy 338.838357 -233.785049) (xy 338.862008 -233.830112)
			(xy 338.878124 -233.878386) (xy 338.886288 -233.92862) (xy 338.8868 -233.954066) (xy 338.886297 -233.979055)
			(xy 339.193614 -233.979055) (xy 339.193614 -233.929077) (xy 339.201433 -233.879714) (xy 339.216877 -233.832182)
			(xy 339.239567 -233.78765) (xy 339.268943 -233.747217) (xy 339.304283 -233.711877) (xy 339.344716 -233.682501)
			(xy 339.389248 -233.659811) (xy 339.43678 -233.644367) (xy 339.486143 -233.636548) (xy 339.536121 -233.636548)
			(xy 339.585484 -233.644367) (xy 339.633016 -233.659811) (xy 339.677548 -233.682501) (xy 339.717981 -233.711877)
			(xy 339.753321 -233.747217) (xy 339.782697 -233.78765) (xy 339.805387 -233.832182) (xy 339.820831 -233.879714)
			(xy 339.82865 -233.929077) (xy 339.82914 -233.954066) (xy 340.134951 -233.954066) (xy 340.139046 -233.903338)
			(xy 340.151225 -233.853924) (xy 340.171173 -233.807104) (xy 340.198374 -233.76409) (xy 340.232122 -233.725996)
			(xy 340.271544 -233.693809) (xy 340.315618 -233.668363) (xy 340.363204 -233.650316) (xy 340.413068 -233.640136)
			(xy 340.46392 -233.638087) (xy 340.514441 -233.644221) (xy 340.563325 -233.658381) (xy 340.609304 -233.680198)
			(xy 340.651188 -233.709108) (xy 340.687892 -233.744363) (xy 340.718465 -233.785049) (xy 340.742116 -233.830112)
			(xy 340.758232 -233.878386) (xy 340.766396 -233.92862) (xy 340.766908 -233.954066) (xy 340.766405 -233.979055)
			(xy 341.073468 -233.979055) (xy 341.073468 -233.929077) (xy 341.081287 -233.879714) (xy 341.096731 -233.832182)
			(xy 341.119421 -233.78765) (xy 341.148797 -233.747217) (xy 341.184137 -233.711877) (xy 341.22457 -233.682501)
			(xy 341.269102 -233.659811) (xy 341.316634 -233.644367) (xy 341.365997 -233.636548) (xy 341.415975 -233.636548)
			(xy 341.465338 -233.644367) (xy 341.51287 -233.659811) (xy 341.557402 -233.682501) (xy 341.597835 -233.711877)
			(xy 341.633175 -233.747217) (xy 341.662551 -233.78765) (xy 341.685241 -233.832182) (xy 341.700685 -233.879714)
			(xy 341.708504 -233.929077) (xy 341.708994 -233.954066) (xy 342.014805 -233.954066) (xy 342.0189 -233.903338)
			(xy 342.031079 -233.853924) (xy 342.051027 -233.807104) (xy 342.078228 -233.76409) (xy 342.111976 -233.725996)
			(xy 342.151398 -233.693809) (xy 342.195472 -233.668363) (xy 342.243058 -233.650316) (xy 342.292922 -233.640136)
			(xy 342.343774 -233.638087) (xy 342.394295 -233.644221) (xy 342.443179 -233.658381) (xy 342.489158 -233.680198)
			(xy 342.531042 -233.709108) (xy 342.567746 -233.744363) (xy 342.598319 -233.785049) (xy 342.62197 -233.830112)
			(xy 342.638086 -233.878386) (xy 342.64625 -233.92862) (xy 342.646762 -233.954066) (xy 342.954859 -233.954066)
			(xy 342.958954 -233.903338) (xy 342.971133 -233.853924) (xy 342.991081 -233.807104) (xy 343.018282 -233.76409)
			(xy 343.05203 -233.725996) (xy 343.091452 -233.693809) (xy 343.135526 -233.668363) (xy 343.183112 -233.650316)
			(xy 343.232976 -233.640136) (xy 343.283828 -233.638087) (xy 343.334349 -233.644221) (xy 343.383233 -233.658381)
			(xy 343.429212 -233.680198) (xy 343.471096 -233.709108) (xy 343.5078 -233.744363) (xy 343.538373 -233.785049)
			(xy 343.562024 -233.830112) (xy 343.57814 -233.878386) (xy 343.586304 -233.92862) (xy 343.586816 -233.954066)
			(xy 343.586313 -233.979055) (xy 343.89363 -233.979055) (xy 343.89363 -233.929077) (xy 343.901449 -233.879714)
			(xy 343.916893 -233.832182) (xy 343.939583 -233.78765) (xy 343.968959 -233.747217) (xy 344.004299 -233.711877)
			(xy 344.044732 -233.682501) (xy 344.089264 -233.659811) (xy 344.136796 -233.644367) (xy 344.186159 -233.636548)
			(xy 344.236137 -233.636548) (xy 344.2855 -233.644367) (xy 344.333032 -233.659811) (xy 344.377564 -233.682501)
			(xy 344.417997 -233.711877) (xy 344.453337 -233.747217) (xy 344.482713 -233.78765) (xy 344.505403 -233.832182)
			(xy 344.520847 -233.879714) (xy 344.528666 -233.929077) (xy 344.529156 -233.954066) (xy 344.528666 -233.979055)
			(xy 344.520847 -234.028418) (xy 344.505403 -234.07595) (xy 344.482713 -234.120482) (xy 344.453337 -234.160915)
			(xy 344.417997 -234.196255) (xy 344.377564 -234.225631) (xy 344.333032 -234.248321) (xy 344.2855 -234.263765)
			(xy 344.236137 -234.271584) (xy 344.186159 -234.271584) (xy 344.136796 -234.263765) (xy 344.089264 -234.248321)
			(xy 344.044732 -234.225631) (xy 344.004299 -234.196255) (xy 343.968959 -234.160915) (xy 343.939583 -234.120482)
			(xy 343.916893 -234.07595) (xy 343.901449 -234.028418) (xy 343.89363 -233.979055) (xy 343.586313 -233.979055)
			(xy 343.586304 -233.979512) (xy 343.57814 -234.029746) (xy 343.562024 -234.07802) (xy 343.538373 -234.123083)
			(xy 343.5078 -234.163769) (xy 343.471096 -234.199024) (xy 343.429212 -234.227934) (xy 343.383233 -234.249751)
			(xy 343.334349 -234.263911) (xy 343.283828 -234.270045) (xy 343.232976 -234.267996) (xy 343.183112 -234.257816)
			(xy 343.135526 -234.239769) (xy 343.091452 -234.214323) (xy 343.05203 -234.182136) (xy 343.018282 -234.144042)
			(xy 342.991081 -234.101028) (xy 342.971133 -234.054208) (xy 342.958954 -234.004794) (xy 342.954859 -233.954066)
			(xy 342.646762 -233.954066) (xy 342.64625 -233.979512) (xy 342.638086 -234.029746) (xy 342.62197 -234.07802)
			(xy 342.598319 -234.123083) (xy 342.567746 -234.163769) (xy 342.531042 -234.199024) (xy 342.489158 -234.227934)
			(xy 342.443179 -234.249751) (xy 342.394295 -234.263911) (xy 342.343774 -234.270045) (xy 342.292922 -234.267996)
			(xy 342.243058 -234.257816) (xy 342.195472 -234.239769) (xy 342.151398 -234.214323) (xy 342.111976 -234.182136)
			(xy 342.078228 -234.144042) (xy 342.051027 -234.101028) (xy 342.031079 -234.054208) (xy 342.0189 -234.004794)
			(xy 342.014805 -233.954066) (xy 341.708994 -233.954066) (xy 341.708504 -233.979055) (xy 341.700685 -234.028418)
			(xy 341.685241 -234.07595) (xy 341.662551 -234.120482) (xy 341.633175 -234.160915) (xy 341.597835 -234.196255)
			(xy 341.557402 -234.225631) (xy 341.51287 -234.248321) (xy 341.465338 -234.263765) (xy 341.415975 -234.271584)
			(xy 341.365997 -234.271584) (xy 341.316634 -234.263765) (xy 341.269102 -234.248321) (xy 341.22457 -234.225631)
			(xy 341.184137 -234.196255) (xy 341.148797 -234.160915) (xy 341.119421 -234.120482) (xy 341.096731 -234.07595)
			(xy 341.081287 -234.028418) (xy 341.073468 -233.979055) (xy 340.766405 -233.979055) (xy 340.766396 -233.979512)
			(xy 340.758232 -234.029746) (xy 340.742116 -234.07802) (xy 340.718465 -234.123083) (xy 340.687892 -234.163769)
			(xy 340.651188 -234.199024) (xy 340.609304 -234.227934) (xy 340.563325 -234.249751) (xy 340.514441 -234.263911)
			(xy 340.46392 -234.270045) (xy 340.413068 -234.267996) (xy 340.363204 -234.257816) (xy 340.315618 -234.239769)
			(xy 340.271544 -234.214323) (xy 340.232122 -234.182136) (xy 340.198374 -234.144042) (xy 340.171173 -234.101028)
			(xy 340.151225 -234.054208) (xy 340.139046 -234.004794) (xy 340.134951 -233.954066) (xy 339.82914 -233.954066)
			(xy 339.82865 -233.979055) (xy 339.820831 -234.028418) (xy 339.805387 -234.07595) (xy 339.782697 -234.120482)
			(xy 339.753321 -234.160915) (xy 339.717981 -234.196255) (xy 339.677548 -234.225631) (xy 339.633016 -234.248321)
			(xy 339.585484 -234.263765) (xy 339.536121 -234.271584) (xy 339.486143 -234.271584) (xy 339.43678 -234.263765)
			(xy 339.389248 -234.248321) (xy 339.344716 -234.225631) (xy 339.304283 -234.196255) (xy 339.268943 -234.160915)
			(xy 339.239567 -234.120482) (xy 339.216877 -234.07595) (xy 339.201433 -234.028418) (xy 339.193614 -233.979055)
			(xy 338.886297 -233.979055) (xy 338.886288 -233.979512) (xy 338.878124 -234.029746) (xy 338.862008 -234.07802)
			(xy 338.838357 -234.123083) (xy 338.807784 -234.163769) (xy 338.77108 -234.199024) (xy 338.729196 -234.227934)
			(xy 338.683217 -234.249751) (xy 338.634333 -234.263911) (xy 338.583812 -234.270045) (xy 338.53296 -234.267996)
			(xy 338.483096 -234.257816) (xy 338.43551 -234.239769) (xy 338.391436 -234.214323) (xy 338.352014 -234.182136)
			(xy 338.318266 -234.144042) (xy 338.291065 -234.101028) (xy 338.271117 -234.054208) (xy 338.258938 -234.004794)
			(xy 338.254843 -233.954066) (xy 338.012532 -233.954066) (xy 338.012532 -234.346242) (xy 338.013025 -234.355905)
			(xy 338.020333 -234.373804) (xy 338.026756 -234.38104) (xy 338.068412 -234.423712) (xy 338.071908 -234.427168)
			(xy 338.079966 -234.432795) (xy 338.084414 -234.434888) (xy 338.10956 -234.44581) (xy 338.118704 -234.446318)
			(xy 338.144043 -234.448211) (xy 338.193686 -234.45903) (xy 338.240981 -234.477599) (xy 338.284724 -234.503446)
			(xy 338.323805 -234.535915) (xy 338.357231 -234.57418) (xy 338.384153 -234.61727) (xy 338.403887 -234.66409)
			(xy 338.415932 -234.713451) (xy 338.419979 -234.764072) (xy 338.724743 -234.764072) (xy 338.728838 -234.713344)
			(xy 338.741017 -234.66393) (xy 338.760965 -234.61711) (xy 338.788166 -234.574096) (xy 338.821914 -234.536002)
			(xy 338.861336 -234.503815) (xy 338.90541 -234.478369) (xy 338.952996 -234.460322) (xy 339.00286 -234.450142)
			(xy 339.053712 -234.448093) (xy 339.104233 -234.454227) (xy 339.153117 -234.468387) (xy 339.199096 -234.490204)
			(xy 339.24098 -234.519114) (xy 339.277684 -234.554369) (xy 339.308257 -234.595055) (xy 339.331908 -234.640118)
			(xy 339.348024 -234.688392) (xy 339.356188 -234.738626) (xy 339.3567 -234.764072) (xy 339.664797 -234.764072)
			(xy 339.668892 -234.713344) (xy 339.681071 -234.66393) (xy 339.701019 -234.61711) (xy 339.72822 -234.574096)
			(xy 339.761968 -234.536002) (xy 339.80139 -234.503815) (xy 339.845464 -234.478369) (xy 339.89305 -234.460322)
			(xy 339.942914 -234.450142) (xy 339.993766 -234.448093) (xy 340.044287 -234.454227) (xy 340.093171 -234.468387)
			(xy 340.13915 -234.490204) (xy 340.181034 -234.519114) (xy 340.217738 -234.554369) (xy 340.248311 -234.595055)
			(xy 340.271962 -234.640118) (xy 340.288078 -234.688392) (xy 340.296242 -234.738626) (xy 340.296754 -234.764072)
			(xy 341.544905 -234.764072) (xy 341.549 -234.713344) (xy 341.561179 -234.66393) (xy 341.581127 -234.61711)
			(xy 341.608328 -234.574096) (xy 341.642076 -234.536002) (xy 341.681498 -234.503815) (xy 341.725572 -234.478369)
			(xy 341.773158 -234.460322) (xy 341.823022 -234.450142) (xy 341.873874 -234.448093) (xy 341.924395 -234.454227)
			(xy 341.973279 -234.468387) (xy 342.019258 -234.490204) (xy 342.061142 -234.519114) (xy 342.097846 -234.554369)
			(xy 342.128419 -234.595055) (xy 342.15207 -234.640118) (xy 342.168186 -234.688392) (xy 342.17635 -234.738626)
			(xy 342.176862 -234.764072) (xy 342.176359 -234.789061) (xy 342.483676 -234.789061) (xy 342.483676 -234.739083)
			(xy 342.491495 -234.68972) (xy 342.506939 -234.642188) (xy 342.529629 -234.597656) (xy 342.559005 -234.557223)
			(xy 342.594345 -234.521883) (xy 342.634778 -234.492507) (xy 342.67931 -234.469817) (xy 342.726842 -234.454373)
			(xy 342.776205 -234.446554) (xy 342.826183 -234.446554) (xy 342.875546 -234.454373) (xy 342.923078 -234.469817)
			(xy 342.96761 -234.492507) (xy 343.008043 -234.521883) (xy 343.043383 -234.557223) (xy 343.072759 -234.597656)
			(xy 343.095449 -234.642188) (xy 343.110893 -234.68972) (xy 343.118712 -234.739083) (xy 343.119202 -234.764072)
			(xy 343.424759 -234.764072) (xy 343.428854 -234.713344) (xy 343.441033 -234.66393) (xy 343.460981 -234.61711)
			(xy 343.488182 -234.574096) (xy 343.52193 -234.536002) (xy 343.561352 -234.503815) (xy 343.605426 -234.478369)
			(xy 343.653012 -234.460322) (xy 343.702876 -234.450142) (xy 343.753728 -234.448093) (xy 343.804249 -234.454227)
			(xy 343.853133 -234.468387) (xy 343.899112 -234.490204) (xy 343.940996 -234.519114) (xy 343.9777 -234.554369)
			(xy 344.008273 -234.595055) (xy 344.031924 -234.640118) (xy 344.04804 -234.688392) (xy 344.056204 -234.738626)
			(xy 344.056716 -234.764072) (xy 344.056204 -234.789518) (xy 344.04804 -234.839752) (xy 344.031924 -234.888026)
			(xy 344.008273 -234.933089) (xy 343.9777 -234.973775) (xy 343.940996 -235.00903) (xy 343.899112 -235.03794)
			(xy 343.853133 -235.059757) (xy 343.804249 -235.073917) (xy 343.753728 -235.080051) (xy 343.702876 -235.078002)
			(xy 343.653012 -235.067822) (xy 343.605426 -235.049775) (xy 343.561352 -235.024329) (xy 343.52193 -234.992142)
			(xy 343.488182 -234.954048) (xy 343.460981 -234.911034) (xy 343.441033 -234.864214) (xy 343.428854 -234.8148)
			(xy 343.424759 -234.764072) (xy 343.119202 -234.764072) (xy 343.118712 -234.789061) (xy 343.110893 -234.838424)
			(xy 343.095449 -234.885956) (xy 343.072759 -234.930488) (xy 343.043383 -234.970921) (xy 343.008043 -235.006261)
			(xy 342.96761 -235.035637) (xy 342.923078 -235.058327) (xy 342.875546 -235.073771) (xy 342.826183 -235.08159)
			(xy 342.776205 -235.08159) (xy 342.726842 -235.073771) (xy 342.67931 -235.058327) (xy 342.634778 -235.035637)
			(xy 342.594345 -235.006261) (xy 342.559005 -234.970921) (xy 342.529629 -234.930488) (xy 342.506939 -234.885956)
			(xy 342.491495 -234.838424) (xy 342.483676 -234.789061) (xy 342.176359 -234.789061) (xy 342.17635 -234.789518)
			(xy 342.168186 -234.839752) (xy 342.15207 -234.888026) (xy 342.128419 -234.933089) (xy 342.097846 -234.973775)
			(xy 342.061142 -235.00903) (xy 342.019258 -235.03794) (xy 341.973279 -235.059757) (xy 341.924395 -235.073917)
			(xy 341.873874 -235.080051) (xy 341.823022 -235.078002) (xy 341.773158 -235.067822) (xy 341.725572 -235.049775)
			(xy 341.681498 -235.024329) (xy 341.642076 -234.992142) (xy 341.608328 -234.954048) (xy 341.581127 -234.911034)
			(xy 341.561179 -234.864214) (xy 341.549 -234.8148) (xy 341.544905 -234.764072) (xy 340.296754 -234.764072)
			(xy 340.296242 -234.789518) (xy 340.288078 -234.839752) (xy 340.271962 -234.888026) (xy 340.248311 -234.933089)
			(xy 340.217738 -234.973775) (xy 340.181034 -235.00903) (xy 340.13915 -235.03794) (xy 340.093171 -235.059757)
			(xy 340.044287 -235.073917) (xy 339.993766 -235.080051) (xy 339.942914 -235.078002) (xy 339.89305 -235.067822)
			(xy 339.845464 -235.049775) (xy 339.80139 -235.024329) (xy 339.761968 -234.992142) (xy 339.72822 -234.954048)
			(xy 339.701019 -234.911034) (xy 339.681071 -234.864214) (xy 339.668892 -234.8148) (xy 339.664797 -234.764072)
			(xy 339.3567 -234.764072) (xy 339.356188 -234.789518) (xy 339.348024 -234.839752) (xy 339.331908 -234.888026)
			(xy 339.308257 -234.933089) (xy 339.277684 -234.973775) (xy 339.24098 -235.00903) (xy 339.199096 -235.03794)
			(xy 339.153117 -235.059757) (xy 339.104233 -235.073917) (xy 339.053712 -235.080051) (xy 339.00286 -235.078002)
			(xy 338.952996 -235.067822) (xy 338.90541 -235.049775) (xy 338.861336 -235.024329) (xy 338.821914 -234.992142)
			(xy 338.788166 -234.954048) (xy 338.760965 -234.911034) (xy 338.741017 -234.864214) (xy 338.728838 -234.8148)
			(xy 338.724743 -234.764072) (xy 338.419979 -234.764072) (xy 338.419981 -234.764098) (xy 338.415932 -234.814746)
			(xy 338.403888 -234.864107) (xy 338.384155 -234.910927) (xy 338.357233 -234.954017) (xy 338.323807 -234.992283)
			(xy 338.284726 -235.024752) (xy 338.240983 -235.0506) (xy 338.193689 -235.069169) (xy 338.144046 -235.079989)
			(xy 338.118704 -235.081826) (xy 338.10956 -235.082334) (xy 338.084414 -235.093256) (xy 338.079966 -235.095348)
			(xy 338.071906 -235.100974) (xy 338.068412 -235.104432) (xy 338.026756 -235.147104) (xy 338.020294 -235.15432)
			(xy 338.012959 -235.172227) (xy 338.012532 -235.181902) (xy 338.012532 -235.574078) (xy 338.254843 -235.574078)
			(xy 338.258938 -235.52335) (xy 338.271117 -235.473936) (xy 338.291065 -235.427116) (xy 338.318266 -235.384102)
			(xy 338.352014 -235.346008) (xy 338.391436 -235.313821) (xy 338.43551 -235.288375) (xy 338.483096 -235.270328)
			(xy 338.53296 -235.260148) (xy 338.583812 -235.258099) (xy 338.634333 -235.264233) (xy 338.683217 -235.278393)
			(xy 338.729196 -235.30021) (xy 338.77108 -235.32912) (xy 338.807784 -235.364375) (xy 338.838357 -235.405061)
			(xy 338.862008 -235.450124) (xy 338.878124 -235.498398) (xy 338.886288 -235.548632) (xy 338.8868 -235.574078)
			(xy 338.886297 -235.599067) (xy 339.193614 -235.599067) (xy 339.193614 -235.549089) (xy 339.201433 -235.499726)
			(xy 339.216877 -235.452194) (xy 339.239567 -235.407662) (xy 339.268943 -235.367229) (xy 339.304283 -235.331889)
			(xy 339.344716 -235.302513) (xy 339.389248 -235.279823) (xy 339.43678 -235.264379) (xy 339.486143 -235.25656)
			(xy 339.536121 -235.25656) (xy 339.585484 -235.264379) (xy 339.633016 -235.279823) (xy 339.677548 -235.302513)
			(xy 339.717981 -235.331889) (xy 339.753321 -235.367229) (xy 339.782697 -235.407662) (xy 339.805387 -235.452194)
			(xy 339.820831 -235.499726) (xy 339.82865 -235.549089) (xy 339.82914 -235.574078) (xy 340.134951 -235.574078)
			(xy 340.139046 -235.52335) (xy 340.151225 -235.473936) (xy 340.171173 -235.427116) (xy 340.198374 -235.384102)
			(xy 340.232122 -235.346008) (xy 340.271544 -235.313821) (xy 340.315618 -235.288375) (xy 340.363204 -235.270328)
			(xy 340.413068 -235.260148) (xy 340.46392 -235.258099) (xy 340.514441 -235.264233) (xy 340.563325 -235.278393)
			(xy 340.609304 -235.30021) (xy 340.651188 -235.32912) (xy 340.687892 -235.364375) (xy 340.718465 -235.405061)
			(xy 340.742116 -235.450124) (xy 340.758232 -235.498398) (xy 340.766396 -235.548632) (xy 340.766908 -235.574078)
			(xy 340.766405 -235.599067) (xy 341.073468 -235.599067) (xy 341.073468 -235.549089) (xy 341.081287 -235.499726)
			(xy 341.096731 -235.452194) (xy 341.119421 -235.407662) (xy 341.148797 -235.367229) (xy 341.184137 -235.331889)
			(xy 341.22457 -235.302513) (xy 341.269102 -235.279823) (xy 341.316634 -235.264379) (xy 341.365997 -235.25656)
			(xy 341.415975 -235.25656) (xy 341.465338 -235.264379) (xy 341.51287 -235.279823) (xy 341.557402 -235.302513)
			(xy 341.597835 -235.331889) (xy 341.633175 -235.367229) (xy 341.662551 -235.407662) (xy 341.685241 -235.452194)
			(xy 341.700685 -235.499726) (xy 341.708504 -235.549089) (xy 341.708994 -235.574078) (xy 342.014805 -235.574078)
			(xy 342.0189 -235.52335) (xy 342.031079 -235.473936) (xy 342.051027 -235.427116) (xy 342.078228 -235.384102)
			(xy 342.111976 -235.346008) (xy 342.151398 -235.313821) (xy 342.195472 -235.288375) (xy 342.243058 -235.270328)
			(xy 342.292922 -235.260148) (xy 342.343774 -235.258099) (xy 342.394295 -235.264233) (xy 342.443179 -235.278393)
			(xy 342.489158 -235.30021) (xy 342.531042 -235.32912) (xy 342.567746 -235.364375) (xy 342.598319 -235.405061)
			(xy 342.62197 -235.450124) (xy 342.638086 -235.498398) (xy 342.64625 -235.548632) (xy 342.646762 -235.574078)
			(xy 342.954859 -235.574078) (xy 342.958954 -235.52335) (xy 342.971133 -235.473936) (xy 342.991081 -235.427116)
			(xy 343.018282 -235.384102) (xy 343.05203 -235.346008) (xy 343.091452 -235.313821) (xy 343.135526 -235.288375)
			(xy 343.183112 -235.270328) (xy 343.232976 -235.260148) (xy 343.283828 -235.258099) (xy 343.334349 -235.264233)
			(xy 343.383233 -235.278393) (xy 343.429212 -235.30021) (xy 343.471096 -235.32912) (xy 343.5078 -235.364375)
			(xy 343.538373 -235.405061) (xy 343.562024 -235.450124) (xy 343.57814 -235.498398) (xy 343.586304 -235.548632)
			(xy 343.586816 -235.574078) (xy 343.586304 -235.599524) (xy 343.57814 -235.649758) (xy 343.562024 -235.698032)
			(xy 343.538373 -235.743095) (xy 343.5078 -235.783781) (xy 343.471096 -235.819036) (xy 343.429212 -235.847946)
			(xy 343.383233 -235.869763) (xy 343.334349 -235.883923) (xy 343.283828 -235.890057) (xy 343.232976 -235.888008)
			(xy 343.183112 -235.877828) (xy 343.135526 -235.859781) (xy 343.091452 -235.834335) (xy 343.05203 -235.802148)
			(xy 343.018282 -235.764054) (xy 342.991081 -235.72104) (xy 342.971133 -235.67422) (xy 342.958954 -235.624806)
			(xy 342.954859 -235.574078) (xy 342.646762 -235.574078) (xy 342.64625 -235.599524) (xy 342.638086 -235.649758)
			(xy 342.62197 -235.698032) (xy 342.598319 -235.743095) (xy 342.567746 -235.783781) (xy 342.531042 -235.819036)
			(xy 342.489158 -235.847946) (xy 342.443179 -235.869763) (xy 342.394295 -235.883923) (xy 342.343774 -235.890057)
			(xy 342.292922 -235.888008) (xy 342.243058 -235.877828) (xy 342.195472 -235.859781) (xy 342.151398 -235.834335)
			(xy 342.111976 -235.802148) (xy 342.078228 -235.764054) (xy 342.051027 -235.72104) (xy 342.031079 -235.67422)
			(xy 342.0189 -235.624806) (xy 342.014805 -235.574078) (xy 341.708994 -235.574078) (xy 341.708504 -235.599067)
			(xy 341.700685 -235.64843) (xy 341.685241 -235.695962) (xy 341.662551 -235.740494) (xy 341.633175 -235.780927)
			(xy 341.597835 -235.816267) (xy 341.557402 -235.845643) (xy 341.51287 -235.868333) (xy 341.465338 -235.883777)
			(xy 341.415975 -235.891596) (xy 341.365997 -235.891596) (xy 341.316634 -235.883777) (xy 341.269102 -235.868333)
			(xy 341.22457 -235.845643) (xy 341.184137 -235.816267) (xy 341.148797 -235.780927) (xy 341.119421 -235.740494)
			(xy 341.096731 -235.695962) (xy 341.081287 -235.64843) (xy 341.073468 -235.599067) (xy 340.766405 -235.599067)
			(xy 340.766396 -235.599524) (xy 340.758232 -235.649758) (xy 340.742116 -235.698032) (xy 340.718465 -235.743095)
			(xy 340.687892 -235.783781) (xy 340.651188 -235.819036) (xy 340.609304 -235.847946) (xy 340.563325 -235.869763)
			(xy 340.514441 -235.883923) (xy 340.46392 -235.890057) (xy 340.413068 -235.888008) (xy 340.363204 -235.877828)
			(xy 340.315618 -235.859781) (xy 340.271544 -235.834335) (xy 340.232122 -235.802148) (xy 340.198374 -235.764054)
			(xy 340.171173 -235.72104) (xy 340.151225 -235.67422) (xy 340.139046 -235.624806) (xy 340.134951 -235.574078)
			(xy 339.82914 -235.574078) (xy 339.82865 -235.599067) (xy 339.820831 -235.64843) (xy 339.805387 -235.695962)
			(xy 339.782697 -235.740494) (xy 339.753321 -235.780927) (xy 339.717981 -235.816267) (xy 339.677548 -235.845643)
			(xy 339.633016 -235.868333) (xy 339.585484 -235.883777) (xy 339.536121 -235.891596) (xy 339.486143 -235.891596)
			(xy 339.43678 -235.883777) (xy 339.389248 -235.868333) (xy 339.344716 -235.845643) (xy 339.304283 -235.816267)
			(xy 339.268943 -235.780927) (xy 339.239567 -235.740494) (xy 339.216877 -235.695962) (xy 339.201433 -235.64843)
			(xy 339.193614 -235.599067) (xy 338.886297 -235.599067) (xy 338.886288 -235.599524) (xy 338.878124 -235.649758)
			(xy 338.862008 -235.698032) (xy 338.838357 -235.743095) (xy 338.807784 -235.783781) (xy 338.77108 -235.819036)
			(xy 338.729196 -235.847946) (xy 338.683217 -235.869763) (xy 338.634333 -235.883923) (xy 338.583812 -235.890057)
			(xy 338.53296 -235.888008) (xy 338.483096 -235.877828) (xy 338.43551 -235.859781) (xy 338.391436 -235.834335)
			(xy 338.352014 -235.802148) (xy 338.318266 -235.764054) (xy 338.291065 -235.72104) (xy 338.271117 -235.67422)
			(xy 338.258938 -235.624806) (xy 338.254843 -235.574078) (xy 338.012532 -235.574078) (xy 338.012532 -235.966254)
			(xy 338.013027 -235.975916) (xy 338.020339 -235.993812) (xy 338.026756 -236.001052) (xy 338.068412 -236.043724)
			(xy 338.071908 -236.047179) (xy 338.079967 -236.052805) (xy 338.084414 -236.0549) (xy 338.10956 -236.065822)
			(xy 338.118704 -236.06633) (xy 338.144042 -236.068223) (xy 338.193684 -236.079042) (xy 338.240976 -236.09761)
			(xy 338.284718 -236.123456) (xy 338.323797 -236.155924) (xy 338.357222 -236.194188) (xy 338.384143 -236.237276)
			(xy 338.403876 -236.284095) (xy 338.41592 -236.333454) (xy 338.419968 -236.384084) (xy 338.724743 -236.384084)
			(xy 338.728838 -236.333356) (xy 338.741017 -236.283942) (xy 338.760965 -236.237122) (xy 338.788166 -236.194108)
			(xy 338.821914 -236.156014) (xy 338.861336 -236.123827) (xy 338.90541 -236.098381) (xy 338.952996 -236.080334)
			(xy 339.00286 -236.070154) (xy 339.053712 -236.068105) (xy 339.104233 -236.074239) (xy 339.153117 -236.088399)
			(xy 339.199096 -236.110216) (xy 339.24098 -236.139126) (xy 339.277684 -236.174381) (xy 339.308257 -236.215067)
			(xy 339.331908 -236.26013) (xy 339.348024 -236.308404) (xy 339.356188 -236.358638) (xy 339.3567 -236.384084)
			(xy 339.664797 -236.384084) (xy 339.668892 -236.333356) (xy 339.681071 -236.283942) (xy 339.701019 -236.237122)
			(xy 339.72822 -236.194108) (xy 339.761968 -236.156014) (xy 339.80139 -236.123827) (xy 339.845464 -236.098381)
			(xy 339.89305 -236.080334) (xy 339.942914 -236.070154) (xy 339.993766 -236.068105) (xy 340.044287 -236.074239)
			(xy 340.093171 -236.088399) (xy 340.13915 -236.110216) (xy 340.181034 -236.139126) (xy 340.217738 -236.174381)
			(xy 340.248311 -236.215067) (xy 340.271962 -236.26013) (xy 340.288078 -236.308404) (xy 340.296242 -236.358638)
			(xy 340.296754 -236.384084) (xy 340.296251 -236.409073) (xy 340.603568 -236.409073) (xy 340.603568 -236.359095)
			(xy 340.611387 -236.309732) (xy 340.626831 -236.2622) (xy 340.649521 -236.217668) (xy 340.678897 -236.177235)
			(xy 340.714237 -236.141895) (xy 340.75467 -236.112519) (xy 340.799202 -236.089829) (xy 340.846734 -236.074385)
			(xy 340.896097 -236.066566) (xy 340.946075 -236.066566) (xy 340.995438 -236.074385) (xy 341.04297 -236.089829)
			(xy 341.087502 -236.112519) (xy 341.127935 -236.141895) (xy 341.163275 -236.177235) (xy 341.192651 -236.217668)
			(xy 341.215341 -236.2622) (xy 341.230785 -236.309732) (xy 341.238604 -236.359095) (xy 341.239094 -236.384084)
			(xy 341.544905 -236.384084) (xy 341.549 -236.333356) (xy 341.561179 -236.283942) (xy 341.581127 -236.237122)
			(xy 341.608328 -236.194108) (xy 341.642076 -236.156014) (xy 341.681498 -236.123827) (xy 341.725572 -236.098381)
			(xy 341.773158 -236.080334) (xy 341.823022 -236.070154) (xy 341.873874 -236.068105) (xy 341.924395 -236.074239)
			(xy 341.973279 -236.088399) (xy 342.019258 -236.110216) (xy 342.061142 -236.139126) (xy 342.097846 -236.174381)
			(xy 342.128419 -236.215067) (xy 342.15207 -236.26013) (xy 342.168186 -236.308404) (xy 342.17635 -236.358638)
			(xy 342.176862 -236.384084) (xy 342.176359 -236.409073) (xy 342.483676 -236.409073) (xy 342.483676 -236.359095)
			(xy 342.491495 -236.309732) (xy 342.506939 -236.2622) (xy 342.529629 -236.217668) (xy 342.559005 -236.177235)
			(xy 342.594345 -236.141895) (xy 342.634778 -236.112519) (xy 342.67931 -236.089829) (xy 342.726842 -236.074385)
			(xy 342.776205 -236.066566) (xy 342.826183 -236.066566) (xy 342.875546 -236.074385) (xy 342.923078 -236.089829)
			(xy 342.96761 -236.112519) (xy 343.008043 -236.141895) (xy 343.043383 -236.177235) (xy 343.072759 -236.217668)
			(xy 343.095449 -236.2622) (xy 343.110893 -236.309732) (xy 343.118712 -236.359095) (xy 343.119202 -236.384084)
			(xy 343.424759 -236.384084) (xy 343.428854 -236.333356) (xy 343.441033 -236.283942) (xy 343.460981 -236.237122)
			(xy 343.488182 -236.194108) (xy 343.52193 -236.156014) (xy 343.561352 -236.123827) (xy 343.605426 -236.098381)
			(xy 343.653012 -236.080334) (xy 343.702876 -236.070154) (xy 343.753728 -236.068105) (xy 343.804249 -236.074239)
			(xy 343.853133 -236.088399) (xy 343.899112 -236.110216) (xy 343.940996 -236.139126) (xy 343.9777 -236.174381)
			(xy 344.008273 -236.215067) (xy 344.031924 -236.26013) (xy 344.04804 -236.308404) (xy 344.056204 -236.358638)
			(xy 344.056716 -236.384084) (xy 344.056204 -236.40953) (xy 344.04804 -236.459764) (xy 344.031924 -236.508038)
			(xy 344.008273 -236.553101) (xy 343.9777 -236.593787) (xy 343.940996 -236.629042) (xy 343.899112 -236.657952)
			(xy 343.853133 -236.679769) (xy 343.804249 -236.693929) (xy 343.753728 -236.700063) (xy 343.702876 -236.698014)
			(xy 343.653012 -236.687834) (xy 343.605426 -236.669787) (xy 343.561352 -236.644341) (xy 343.52193 -236.612154)
			(xy 343.488182 -236.57406) (xy 343.460981 -236.531046) (xy 343.441033 -236.484226) (xy 343.428854 -236.434812)
			(xy 343.424759 -236.384084) (xy 343.119202 -236.384084) (xy 343.118712 -236.409073) (xy 343.110893 -236.458436)
			(xy 343.095449 -236.505968) (xy 343.072759 -236.5505) (xy 343.043383 -236.590933) (xy 343.008043 -236.626273)
			(xy 342.96761 -236.655649) (xy 342.923078 -236.678339) (xy 342.875546 -236.693783) (xy 342.826183 -236.701602)
			(xy 342.776205 -236.701602) (xy 342.726842 -236.693783) (xy 342.67931 -236.678339) (xy 342.634778 -236.655649)
			(xy 342.594345 -236.626273) (xy 342.559005 -236.590933) (xy 342.529629 -236.5505) (xy 342.506939 -236.505968)
			(xy 342.491495 -236.458436) (xy 342.483676 -236.409073) (xy 342.176359 -236.409073) (xy 342.17635 -236.40953)
			(xy 342.168186 -236.459764) (xy 342.15207 -236.508038) (xy 342.128419 -236.553101) (xy 342.097846 -236.593787)
			(xy 342.061142 -236.629042) (xy 342.019258 -236.657952) (xy 341.973279 -236.679769) (xy 341.924395 -236.693929)
			(xy 341.873874 -236.700063) (xy 341.823022 -236.698014) (xy 341.773158 -236.687834) (xy 341.725572 -236.669787)
			(xy 341.681498 -236.644341) (xy 341.642076 -236.612154) (xy 341.608328 -236.57406) (xy 341.581127 -236.531046)
			(xy 341.561179 -236.484226) (xy 341.549 -236.434812) (xy 341.544905 -236.384084) (xy 341.239094 -236.384084)
			(xy 341.238604 -236.409073) (xy 341.230785 -236.458436) (xy 341.215341 -236.505968) (xy 341.192651 -236.5505)
			(xy 341.163275 -236.590933) (xy 341.127935 -236.626273) (xy 341.087502 -236.655649) (xy 341.04297 -236.678339)
			(xy 340.995438 -236.693783) (xy 340.946075 -236.701602) (xy 340.896097 -236.701602) (xy 340.846734 -236.693783)
			(xy 340.799202 -236.678339) (xy 340.75467 -236.655649) (xy 340.714237 -236.626273) (xy 340.678897 -236.590933)
			(xy 340.649521 -236.5505) (xy 340.626831 -236.505968) (xy 340.611387 -236.458436) (xy 340.603568 -236.409073)
			(xy 340.296251 -236.409073) (xy 340.296242 -236.40953) (xy 340.288078 -236.459764) (xy 340.271962 -236.508038)
			(xy 340.248311 -236.553101) (xy 340.217738 -236.593787) (xy 340.181034 -236.629042) (xy 340.13915 -236.657952)
			(xy 340.093171 -236.679769) (xy 340.044287 -236.693929) (xy 339.993766 -236.700063) (xy 339.942914 -236.698014)
			(xy 339.89305 -236.687834) (xy 339.845464 -236.669787) (xy 339.80139 -236.644341) (xy 339.761968 -236.612154)
			(xy 339.72822 -236.57406) (xy 339.701019 -236.531046) (xy 339.681071 -236.484226) (xy 339.668892 -236.434812)
			(xy 339.664797 -236.384084) (xy 339.3567 -236.384084) (xy 339.356188 -236.40953) (xy 339.348024 -236.459764)
			(xy 339.331908 -236.508038) (xy 339.308257 -236.553101) (xy 339.277684 -236.593787) (xy 339.24098 -236.629042)
			(xy 339.199096 -236.657952) (xy 339.153117 -236.679769) (xy 339.104233 -236.693929) (xy 339.053712 -236.700063)
			(xy 339.00286 -236.698014) (xy 338.952996 -236.687834) (xy 338.90541 -236.669787) (xy 338.861336 -236.644341)
			(xy 338.821914 -236.612154) (xy 338.788166 -236.57406) (xy 338.760965 -236.531046) (xy 338.741017 -236.484226)
			(xy 338.728838 -236.434812) (xy 338.724743 -236.384084) (xy 338.419968 -236.384084) (xy 338.419969 -236.384099)
			(xy 338.41592 -236.434745) (xy 338.403877 -236.484104) (xy 338.384144 -236.530922) (xy 338.357223 -236.574011)
			(xy 338.323798 -236.612275) (xy 338.284719 -236.644743) (xy 338.240978 -236.670589) (xy 338.193685 -236.689158)
			(xy 338.144044 -236.699977) (xy 338.118704 -236.701838) (xy 338.10956 -236.702346) (xy 338.084414 -236.713268)
			(xy 338.079966 -236.715361) (xy 338.071907 -236.720988) (xy 338.068412 -236.724444) (xy 338.026756 -236.767116)
			(xy 338.020296 -236.774332) (xy 338.012965 -236.792239) (xy 338.012532 -236.801914) (xy 338.012532 -237.19409)
			(xy 338.254843 -237.19409) (xy 338.258938 -237.143362) (xy 338.271117 -237.093948) (xy 338.291065 -237.047128)
			(xy 338.318266 -237.004114) (xy 338.352014 -236.96602) (xy 338.391436 -236.933833) (xy 338.43551 -236.908387)
			(xy 338.483096 -236.89034) (xy 338.53296 -236.88016) (xy 338.583812 -236.878111) (xy 338.634333 -236.884245)
			(xy 338.683217 -236.898405) (xy 338.729196 -236.920222) (xy 338.77108 -236.949132) (xy 338.807784 -236.984387)
			(xy 338.838357 -237.025073) (xy 338.862008 -237.070136) (xy 338.878124 -237.11841) (xy 338.886288 -237.168644)
			(xy 338.8868 -237.19409) (xy 338.886297 -237.219079) (xy 339.193614 -237.219079) (xy 339.193614 -237.169101)
			(xy 339.201433 -237.119738) (xy 339.216877 -237.072206) (xy 339.239567 -237.027674) (xy 339.268943 -236.987241)
			(xy 339.304283 -236.951901) (xy 339.344716 -236.922525) (xy 339.389248 -236.899835) (xy 339.43678 -236.884391)
			(xy 339.486143 -236.876572) (xy 339.536121 -236.876572) (xy 339.585484 -236.884391) (xy 339.633016 -236.899835)
			(xy 339.677548 -236.922525) (xy 339.717981 -236.951901) (xy 339.753321 -236.987241) (xy 339.782697 -237.027674)
			(xy 339.805387 -237.072206) (xy 339.820831 -237.119738) (xy 339.82865 -237.169101) (xy 339.82914 -237.19409)
			(xy 340.134951 -237.19409) (xy 340.139046 -237.143362) (xy 340.151225 -237.093948) (xy 340.171173 -237.047128)
			(xy 340.198374 -237.004114) (xy 340.232122 -236.96602) (xy 340.271544 -236.933833) (xy 340.315618 -236.908387)
			(xy 340.363204 -236.89034) (xy 340.413068 -236.88016) (xy 340.46392 -236.878111) (xy 340.514441 -236.884245)
			(xy 340.563325 -236.898405) (xy 340.609304 -236.920222) (xy 340.651188 -236.949132) (xy 340.687892 -236.984387)
			(xy 340.718465 -237.025073) (xy 340.742116 -237.070136) (xy 340.758232 -237.11841) (xy 340.766396 -237.168644)
			(xy 340.766908 -237.19409) (xy 342.014805 -237.19409) (xy 342.0189 -237.143362) (xy 342.031079 -237.093948)
			(xy 342.051027 -237.047128) (xy 342.078228 -237.004114) (xy 342.111976 -236.96602) (xy 342.151398 -236.933833)
			(xy 342.195472 -236.908387) (xy 342.243058 -236.89034) (xy 342.292922 -236.88016) (xy 342.343774 -236.878111)
			(xy 342.394295 -236.884245) (xy 342.443179 -236.898405) (xy 342.489158 -236.920222) (xy 342.531042 -236.949132)
			(xy 342.567746 -236.984387) (xy 342.598319 -237.025073) (xy 342.62197 -237.070136) (xy 342.638086 -237.11841)
			(xy 342.64625 -237.168644) (xy 342.646762 -237.19409) (xy 342.954859 -237.19409) (xy 342.958954 -237.143362)
			(xy 342.971133 -237.093948) (xy 342.991081 -237.047128) (xy 343.018282 -237.004114) (xy 343.05203 -236.96602)
			(xy 343.091452 -236.933833) (xy 343.135526 -236.908387) (xy 343.183112 -236.89034) (xy 343.232976 -236.88016)
			(xy 343.283828 -236.878111) (xy 343.334349 -236.884245) (xy 343.383233 -236.898405) (xy 343.429212 -236.920222)
			(xy 343.471096 -236.949132) (xy 343.5078 -236.984387) (xy 343.538373 -237.025073) (xy 343.562024 -237.070136)
			(xy 343.57814 -237.11841) (xy 343.586304 -237.168644) (xy 343.586816 -237.19409) (xy 343.586313 -237.219079)
			(xy 343.89363 -237.219079) (xy 343.89363 -237.169101) (xy 343.901449 -237.119738) (xy 343.916893 -237.072206)
			(xy 343.939583 -237.027674) (xy 343.968959 -236.987241) (xy 344.004299 -236.951901) (xy 344.044732 -236.922525)
			(xy 344.089264 -236.899835) (xy 344.136796 -236.884391) (xy 344.186159 -236.876572) (xy 344.236137 -236.876572)
			(xy 344.2855 -236.884391) (xy 344.333032 -236.899835) (xy 344.377564 -236.922525) (xy 344.417997 -236.951901)
			(xy 344.453337 -236.987241) (xy 344.482713 -237.027674) (xy 344.505403 -237.072206) (xy 344.520847 -237.119738)
			(xy 344.528666 -237.169101) (xy 344.529156 -237.19409) (xy 344.528666 -237.219079) (xy 344.520847 -237.268442)
			(xy 344.505403 -237.315974) (xy 344.482713 -237.360506) (xy 344.453337 -237.400939) (xy 344.417997 -237.436279)
			(xy 344.377564 -237.465655) (xy 344.333032 -237.488345) (xy 344.2855 -237.503789) (xy 344.236137 -237.511608)
			(xy 344.186159 -237.511608) (xy 344.136796 -237.503789) (xy 344.089264 -237.488345) (xy 344.044732 -237.465655)
			(xy 344.004299 -237.436279) (xy 343.968959 -237.400939) (xy 343.939583 -237.360506) (xy 343.916893 -237.315974)
			(xy 343.901449 -237.268442) (xy 343.89363 -237.219079) (xy 343.586313 -237.219079) (xy 343.586304 -237.219536)
			(xy 343.57814 -237.26977) (xy 343.562024 -237.318044) (xy 343.538373 -237.363107) (xy 343.5078 -237.403793)
			(xy 343.471096 -237.439048) (xy 343.429212 -237.467958) (xy 343.383233 -237.489775) (xy 343.334349 -237.503935)
			(xy 343.283828 -237.510069) (xy 343.232976 -237.50802) (xy 343.183112 -237.49784) (xy 343.135526 -237.479793)
			(xy 343.091452 -237.454347) (xy 343.05203 -237.42216) (xy 343.018282 -237.384066) (xy 342.991081 -237.341052)
			(xy 342.971133 -237.294232) (xy 342.958954 -237.244818) (xy 342.954859 -237.19409) (xy 342.646762 -237.19409)
			(xy 342.64625 -237.219536) (xy 342.638086 -237.26977) (xy 342.62197 -237.318044) (xy 342.598319 -237.363107)
			(xy 342.567746 -237.403793) (xy 342.531042 -237.439048) (xy 342.489158 -237.467958) (xy 342.443179 -237.489775)
			(xy 342.394295 -237.503935) (xy 342.343774 -237.510069) (xy 342.292922 -237.50802) (xy 342.243058 -237.49784)
			(xy 342.195472 -237.479793) (xy 342.151398 -237.454347) (xy 342.111976 -237.42216) (xy 342.078228 -237.384066)
			(xy 342.051027 -237.341052) (xy 342.031079 -237.294232) (xy 342.0189 -237.244818) (xy 342.014805 -237.19409)
			(xy 340.766908 -237.19409) (xy 340.766396 -237.219536) (xy 340.758232 -237.26977) (xy 340.742116 -237.318044)
			(xy 340.718465 -237.363107) (xy 340.687892 -237.403793) (xy 340.651188 -237.439048) (xy 340.609304 -237.467958)
			(xy 340.563325 -237.489775) (xy 340.514441 -237.503935) (xy 340.46392 -237.510069) (xy 340.413068 -237.50802)
			(xy 340.363204 -237.49784) (xy 340.315618 -237.479793) (xy 340.271544 -237.454347) (xy 340.232122 -237.42216)
			(xy 340.198374 -237.384066) (xy 340.171173 -237.341052) (xy 340.151225 -237.294232) (xy 340.139046 -237.244818)
			(xy 340.134951 -237.19409) (xy 339.82914 -237.19409) (xy 339.82865 -237.219079) (xy 339.820831 -237.268442)
			(xy 339.805387 -237.315974) (xy 339.782697 -237.360506) (xy 339.753321 -237.400939) (xy 339.717981 -237.436279)
			(xy 339.677548 -237.465655) (xy 339.633016 -237.488345) (xy 339.585484 -237.503789) (xy 339.536121 -237.511608)
			(xy 339.486143 -237.511608) (xy 339.43678 -237.503789) (xy 339.389248 -237.488345) (xy 339.344716 -237.465655)
			(xy 339.304283 -237.436279) (xy 339.268943 -237.400939) (xy 339.239567 -237.360506) (xy 339.216877 -237.315974)
			(xy 339.201433 -237.268442) (xy 339.193614 -237.219079) (xy 338.886297 -237.219079) (xy 338.886288 -237.219536)
			(xy 338.878124 -237.26977) (xy 338.862008 -237.318044) (xy 338.838357 -237.363107) (xy 338.807784 -237.403793)
			(xy 338.77108 -237.439048) (xy 338.729196 -237.467958) (xy 338.683217 -237.489775) (xy 338.634333 -237.503935)
			(xy 338.583812 -237.510069) (xy 338.53296 -237.50802) (xy 338.483096 -237.49784) (xy 338.43551 -237.479793)
			(xy 338.391436 -237.454347) (xy 338.352014 -237.42216) (xy 338.318266 -237.384066) (xy 338.291065 -237.341052)
			(xy 338.271117 -237.294232) (xy 338.258938 -237.244818) (xy 338.254843 -237.19409) (xy 338.012532 -237.19409)
			(xy 338.012532 -237.586266) (xy 338.013029 -237.595928) (xy 338.020344 -237.61382) (xy 338.026756 -237.621064)
			(xy 338.068412 -237.663736) (xy 338.071909 -237.667191) (xy 338.079968 -237.672815) (xy 338.084414 -237.674912)
			(xy 338.10956 -237.685834) (xy 338.118704 -237.686342) (xy 338.144041 -237.688235) (xy 338.193681 -237.699053)
			(xy 338.240971 -237.717621) (xy 338.284711 -237.743467) (xy 338.323789 -237.775933) (xy 338.357213 -237.814196)
			(xy 338.384133 -237.857283) (xy 338.403865 -237.904099) (xy 338.415908 -237.953456) (xy 338.419957 -238.004096)
			(xy 338.724743 -238.004096) (xy 338.728838 -237.953368) (xy 338.741017 -237.903954) (xy 338.760965 -237.857134)
			(xy 338.788166 -237.81412) (xy 338.821914 -237.776026) (xy 338.861336 -237.743839) (xy 338.90541 -237.718393)
			(xy 338.952996 -237.700346) (xy 339.00286 -237.690166) (xy 339.053712 -237.688117) (xy 339.104233 -237.694251)
			(xy 339.153117 -237.708411) (xy 339.199096 -237.730228) (xy 339.24098 -237.759138) (xy 339.277684 -237.794393)
			(xy 339.308257 -237.835079) (xy 339.331908 -237.880142) (xy 339.348024 -237.928416) (xy 339.356188 -237.97865)
			(xy 339.3567 -238.004096) (xy 339.664797 -238.004096) (xy 339.668892 -237.953368) (xy 339.681071 -237.903954)
			(xy 339.701019 -237.857134) (xy 339.72822 -237.81412) (xy 339.761968 -237.776026) (xy 339.80139 -237.743839)
			(xy 339.845464 -237.718393) (xy 339.89305 -237.700346) (xy 339.942914 -237.690166) (xy 339.993766 -237.688117)
			(xy 340.044287 -237.694251) (xy 340.093171 -237.708411) (xy 340.13915 -237.730228) (xy 340.181034 -237.759138)
			(xy 340.217738 -237.794393) (xy 340.248311 -237.835079) (xy 340.271962 -237.880142) (xy 340.288078 -237.928416)
			(xy 340.296242 -237.97865) (xy 340.296754 -238.004096) (xy 340.296251 -238.029085) (xy 340.603568 -238.029085)
			(xy 340.603568 -237.979107) (xy 340.611387 -237.929744) (xy 340.626831 -237.882212) (xy 340.649521 -237.83768)
			(xy 340.678897 -237.797247) (xy 340.714237 -237.761907) (xy 340.75467 -237.732531) (xy 340.799202 -237.709841)
			(xy 340.846734 -237.694397) (xy 340.896097 -237.686578) (xy 340.946075 -237.686578) (xy 340.995438 -237.694397)
			(xy 341.04297 -237.709841) (xy 341.087502 -237.732531) (xy 341.127935 -237.761907) (xy 341.163275 -237.797247)
			(xy 341.192651 -237.83768) (xy 341.215341 -237.882212) (xy 341.230785 -237.929744) (xy 341.238604 -237.979107)
			(xy 341.239094 -238.004096) (xy 341.544905 -238.004096) (xy 341.549 -237.953368) (xy 341.561179 -237.903954)
			(xy 341.581127 -237.857134) (xy 341.608328 -237.81412) (xy 341.642076 -237.776026) (xy 341.681498 -237.743839)
			(xy 341.725572 -237.718393) (xy 341.773158 -237.700346) (xy 341.823022 -237.690166) (xy 341.873874 -237.688117)
			(xy 341.924395 -237.694251) (xy 341.973279 -237.708411) (xy 342.019258 -237.730228) (xy 342.061142 -237.759138)
			(xy 342.097846 -237.794393) (xy 342.128419 -237.835079) (xy 342.15207 -237.880142) (xy 342.168186 -237.928416)
			(xy 342.17635 -237.97865) (xy 342.176862 -238.004096) (xy 342.176359 -238.029085) (xy 342.483676 -238.029085)
			(xy 342.483676 -237.979107) (xy 342.491495 -237.929744) (xy 342.506939 -237.882212) (xy 342.529629 -237.83768)
			(xy 342.559005 -237.797247) (xy 342.594345 -237.761907) (xy 342.634778 -237.732531) (xy 342.67931 -237.709841)
			(xy 342.726842 -237.694397) (xy 342.776205 -237.686578) (xy 342.826183 -237.686578) (xy 342.875546 -237.694397)
			(xy 342.923078 -237.709841) (xy 342.96761 -237.732531) (xy 343.008043 -237.761907) (xy 343.043383 -237.797247)
			(xy 343.072759 -237.83768) (xy 343.095449 -237.882212) (xy 343.110893 -237.929744) (xy 343.118712 -237.979107)
			(xy 343.119202 -238.004096) (xy 343.424759 -238.004096) (xy 343.428854 -237.953368) (xy 343.441033 -237.903954)
			(xy 343.460981 -237.857134) (xy 343.488182 -237.81412) (xy 343.52193 -237.776026) (xy 343.561352 -237.743839)
			(xy 343.605426 -237.718393) (xy 343.653012 -237.700346) (xy 343.702876 -237.690166) (xy 343.753728 -237.688117)
			(xy 343.804249 -237.694251) (xy 343.853133 -237.708411) (xy 343.899112 -237.730228) (xy 343.940996 -237.759138)
			(xy 343.9777 -237.794393) (xy 344.008273 -237.835079) (xy 344.031924 -237.880142) (xy 344.04804 -237.928416)
			(xy 344.056204 -237.97865) (xy 344.056716 -238.004096) (xy 344.056204 -238.029542) (xy 344.04804 -238.079776)
			(xy 344.031924 -238.12805) (xy 344.008273 -238.173113) (xy 343.9777 -238.213799) (xy 343.940996 -238.249054)
			(xy 343.899112 -238.277964) (xy 343.853133 -238.299781) (xy 343.804249 -238.313941) (xy 343.753728 -238.320075)
			(xy 343.702876 -238.318026) (xy 343.653012 -238.307846) (xy 343.605426 -238.289799) (xy 343.561352 -238.264353)
			(xy 343.52193 -238.232166) (xy 343.488182 -238.194072) (xy 343.460981 -238.151058) (xy 343.441033 -238.104238)
			(xy 343.428854 -238.054824) (xy 343.424759 -238.004096) (xy 343.119202 -238.004096) (xy 343.118712 -238.029085)
			(xy 343.110893 -238.078448) (xy 343.095449 -238.12598) (xy 343.072759 -238.170512) (xy 343.043383 -238.210945)
			(xy 343.008043 -238.246285) (xy 342.96761 -238.275661) (xy 342.923078 -238.298351) (xy 342.875546 -238.313795)
			(xy 342.826183 -238.321614) (xy 342.776205 -238.321614) (xy 342.726842 -238.313795) (xy 342.67931 -238.298351)
			(xy 342.634778 -238.275661) (xy 342.594345 -238.246285) (xy 342.559005 -238.210945) (xy 342.529629 -238.170512)
			(xy 342.506939 -238.12598) (xy 342.491495 -238.078448) (xy 342.483676 -238.029085) (xy 342.176359 -238.029085)
			(xy 342.17635 -238.029542) (xy 342.168186 -238.079776) (xy 342.15207 -238.12805) (xy 342.128419 -238.173113)
			(xy 342.097846 -238.213799) (xy 342.061142 -238.249054) (xy 342.019258 -238.277964) (xy 341.973279 -238.299781)
			(xy 341.924395 -238.313941) (xy 341.873874 -238.320075) (xy 341.823022 -238.318026) (xy 341.773158 -238.307846)
			(xy 341.725572 -238.289799) (xy 341.681498 -238.264353) (xy 341.642076 -238.232166) (xy 341.608328 -238.194072)
			(xy 341.581127 -238.151058) (xy 341.561179 -238.104238) (xy 341.549 -238.054824) (xy 341.544905 -238.004096)
			(xy 341.239094 -238.004096) (xy 341.238604 -238.029085) (xy 341.230785 -238.078448) (xy 341.215341 -238.12598)
			(xy 341.192651 -238.170512) (xy 341.163275 -238.210945) (xy 341.127935 -238.246285) (xy 341.087502 -238.275661)
			(xy 341.04297 -238.298351) (xy 340.995438 -238.313795) (xy 340.946075 -238.321614) (xy 340.896097 -238.321614)
			(xy 340.846734 -238.313795) (xy 340.799202 -238.298351) (xy 340.75467 -238.275661) (xy 340.714237 -238.246285)
			(xy 340.678897 -238.210945) (xy 340.649521 -238.170512) (xy 340.626831 -238.12598) (xy 340.611387 -238.078448)
			(xy 340.603568 -238.029085) (xy 340.296251 -238.029085) (xy 340.296242 -238.029542) (xy 340.288078 -238.079776)
			(xy 340.271962 -238.12805) (xy 340.248311 -238.173113) (xy 340.217738 -238.213799) (xy 340.181034 -238.249054)
			(xy 340.13915 -238.277964) (xy 340.093171 -238.299781) (xy 340.044287 -238.313941) (xy 339.993766 -238.320075)
			(xy 339.942914 -238.318026) (xy 339.89305 -238.307846) (xy 339.845464 -238.289799) (xy 339.80139 -238.264353)
			(xy 339.761968 -238.232166) (xy 339.72822 -238.194072) (xy 339.701019 -238.151058) (xy 339.681071 -238.104238)
			(xy 339.668892 -238.054824) (xy 339.664797 -238.004096) (xy 339.3567 -238.004096) (xy 339.356188 -238.029542)
			(xy 339.348024 -238.079776) (xy 339.331908 -238.12805) (xy 339.308257 -238.173113) (xy 339.277684 -238.213799)
			(xy 339.24098 -238.249054) (xy 339.199096 -238.277964) (xy 339.153117 -238.299781) (xy 339.104233 -238.313941)
			(xy 339.053712 -238.320075) (xy 339.00286 -238.318026) (xy 338.952996 -238.307846) (xy 338.90541 -238.289799)
			(xy 338.861336 -238.264353) (xy 338.821914 -238.232166) (xy 338.788166 -238.194072) (xy 338.760965 -238.151058)
			(xy 338.741017 -238.104238) (xy 338.728838 -238.054824) (xy 338.724743 -238.004096) (xy 338.419957 -238.004096)
			(xy 338.419957 -238.0041) (xy 338.415908 -238.054743) (xy 338.403865 -238.1041) (xy 338.384133 -238.150917)
			(xy 338.357213 -238.194004) (xy 338.32379 -238.232267) (xy 338.284712 -238.264733) (xy 338.240972 -238.290579)
			(xy 338.193681 -238.309147) (xy 338.144041 -238.319965) (xy 338.118704 -238.32185) (xy 338.10956 -238.322358)
			(xy 338.084414 -238.33328) (xy 338.079966 -238.335373) (xy 338.071908 -238.341001) (xy 338.068412 -238.344456)
			(xy 338.026756 -238.387128) (xy 338.020298 -238.394345) (xy 338.012972 -238.412252) (xy 338.012532 -238.421926)
			(xy 338.012532 -238.814102) (xy 338.254843 -238.814102) (xy 338.258938 -238.763374) (xy 338.271117 -238.71396)
			(xy 338.291065 -238.66714) (xy 338.318266 -238.624126) (xy 338.352014 -238.586032) (xy 338.391436 -238.553845)
			(xy 338.43551 -238.528399) (xy 338.483096 -238.510352) (xy 338.53296 -238.500172) (xy 338.583812 -238.498123)
			(xy 338.634333 -238.504257) (xy 338.683217 -238.518417) (xy 338.729196 -238.540234) (xy 338.77108 -238.569144)
			(xy 338.807784 -238.604399) (xy 338.838357 -238.645085) (xy 338.862008 -238.690148) (xy 338.878124 -238.738422)
			(xy 338.886288 -238.788656) (xy 338.8868 -238.814102) (xy 338.886297 -238.839091) (xy 339.193614 -238.839091)
			(xy 339.193614 -238.789113) (xy 339.201433 -238.73975) (xy 339.216877 -238.692218) (xy 339.239567 -238.647686)
			(xy 339.268943 -238.607253) (xy 339.304283 -238.571913) (xy 339.344716 -238.542537) (xy 339.389248 -238.519847)
			(xy 339.43678 -238.504403) (xy 339.486143 -238.496584) (xy 339.536121 -238.496584) (xy 339.585484 -238.504403)
			(xy 339.633016 -238.519847) (xy 339.677548 -238.542537) (xy 339.717981 -238.571913) (xy 339.753321 -238.607253)
			(xy 339.782697 -238.647686) (xy 339.805387 -238.692218) (xy 339.820831 -238.73975) (xy 339.82865 -238.789113)
			(xy 339.82914 -238.814102) (xy 340.134951 -238.814102) (xy 340.139046 -238.763374) (xy 340.151225 -238.71396)
			(xy 340.171173 -238.66714) (xy 340.198374 -238.624126) (xy 340.232122 -238.586032) (xy 340.271544 -238.553845)
			(xy 340.315618 -238.528399) (xy 340.363204 -238.510352) (xy 340.413068 -238.500172) (xy 340.46392 -238.498123)
			(xy 340.514441 -238.504257) (xy 340.563325 -238.518417) (xy 340.609304 -238.540234) (xy 340.651188 -238.569144)
			(xy 340.687892 -238.604399) (xy 340.718465 -238.645085) (xy 340.742116 -238.690148) (xy 340.758232 -238.738422)
			(xy 340.766396 -238.788656) (xy 340.766908 -238.814102) (xy 340.766405 -238.839091) (xy 341.073468 -238.839091)
			(xy 341.073468 -238.789113) (xy 341.081287 -238.73975) (xy 341.096731 -238.692218) (xy 341.119421 -238.647686)
			(xy 341.148797 -238.607253) (xy 341.184137 -238.571913) (xy 341.22457 -238.542537) (xy 341.269102 -238.519847)
			(xy 341.316634 -238.504403) (xy 341.365997 -238.496584) (xy 341.415975 -238.496584) (xy 341.465338 -238.504403)
			(xy 341.51287 -238.519847) (xy 341.557402 -238.542537) (xy 341.597835 -238.571913) (xy 341.633175 -238.607253)
			(xy 341.662551 -238.647686) (xy 341.685241 -238.692218) (xy 341.700685 -238.73975) (xy 341.708504 -238.789113)
			(xy 341.708994 -238.814102) (xy 342.014805 -238.814102) (xy 342.0189 -238.763374) (xy 342.031079 -238.71396)
			(xy 342.051027 -238.66714) (xy 342.078228 -238.624126) (xy 342.111976 -238.586032) (xy 342.151398 -238.553845)
			(xy 342.195472 -238.528399) (xy 342.243058 -238.510352) (xy 342.292922 -238.500172) (xy 342.343774 -238.498123)
			(xy 342.394295 -238.504257) (xy 342.443179 -238.518417) (xy 342.489158 -238.540234) (xy 342.531042 -238.569144)
			(xy 342.567746 -238.604399) (xy 342.598319 -238.645085) (xy 342.62197 -238.690148) (xy 342.638086 -238.738422)
			(xy 342.64625 -238.788656) (xy 342.646762 -238.814102) (xy 342.954859 -238.814102) (xy 342.958954 -238.763374)
			(xy 342.971133 -238.71396) (xy 342.991081 -238.66714) (xy 343.018282 -238.624126) (xy 343.05203 -238.586032)
			(xy 343.091452 -238.553845) (xy 343.135526 -238.528399) (xy 343.183112 -238.510352) (xy 343.232976 -238.500172)
			(xy 343.283828 -238.498123) (xy 343.334349 -238.504257) (xy 343.383233 -238.518417) (xy 343.429212 -238.540234)
			(xy 343.471096 -238.569144) (xy 343.5078 -238.604399) (xy 343.538373 -238.645085) (xy 343.562024 -238.690148)
			(xy 343.57814 -238.738422) (xy 343.586304 -238.788656) (xy 343.586816 -238.814102) (xy 343.586313 -238.839091)
			(xy 343.89363 -238.839091) (xy 343.89363 -238.789113) (xy 343.901449 -238.73975) (xy 343.916893 -238.692218)
			(xy 343.939583 -238.647686) (xy 343.968959 -238.607253) (xy 344.004299 -238.571913) (xy 344.044732 -238.542537)
			(xy 344.089264 -238.519847) (xy 344.136796 -238.504403) (xy 344.186159 -238.496584) (xy 344.236137 -238.496584)
			(xy 344.2855 -238.504403) (xy 344.333032 -238.519847) (xy 344.377564 -238.542537) (xy 344.417997 -238.571913)
			(xy 344.453337 -238.607253) (xy 344.482713 -238.647686) (xy 344.505403 -238.692218) (xy 344.520847 -238.73975)
			(xy 344.528666 -238.789113) (xy 344.529156 -238.814102) (xy 344.528666 -238.839091) (xy 344.520847 -238.888454)
			(xy 344.505403 -238.935986) (xy 344.482713 -238.980518) (xy 344.453337 -239.020951) (xy 344.417997 -239.056291)
			(xy 344.377564 -239.085667) (xy 344.333032 -239.108357) (xy 344.2855 -239.123801) (xy 344.236137 -239.13162)
			(xy 344.186159 -239.13162) (xy 344.136796 -239.123801) (xy 344.089264 -239.108357) (xy 344.044732 -239.085667)
			(xy 344.004299 -239.056291) (xy 343.968959 -239.020951) (xy 343.939583 -238.980518) (xy 343.916893 -238.935986)
			(xy 343.901449 -238.888454) (xy 343.89363 -238.839091) (xy 343.586313 -238.839091) (xy 343.586304 -238.839548)
			(xy 343.57814 -238.889782) (xy 343.562024 -238.938056) (xy 343.538373 -238.983119) (xy 343.5078 -239.023805)
			(xy 343.471096 -239.05906) (xy 343.429212 -239.08797) (xy 343.383233 -239.109787) (xy 343.334349 -239.123947)
			(xy 343.283828 -239.130081) (xy 343.232976 -239.128032) (xy 343.183112 -239.117852) (xy 343.135526 -239.099805)
			(xy 343.091452 -239.074359) (xy 343.05203 -239.042172) (xy 343.018282 -239.004078) (xy 342.991081 -238.961064)
			(xy 342.971133 -238.914244) (xy 342.958954 -238.86483) (xy 342.954859 -238.814102) (xy 342.646762 -238.814102)
			(xy 342.64625 -238.839548) (xy 342.638086 -238.889782) (xy 342.62197 -238.938056) (xy 342.598319 -238.983119)
			(xy 342.567746 -239.023805) (xy 342.531042 -239.05906) (xy 342.489158 -239.08797) (xy 342.443179 -239.109787)
			(xy 342.394295 -239.123947) (xy 342.343774 -239.130081) (xy 342.292922 -239.128032) (xy 342.243058 -239.117852)
			(xy 342.195472 -239.099805) (xy 342.151398 -239.074359) (xy 342.111976 -239.042172) (xy 342.078228 -239.004078)
			(xy 342.051027 -238.961064) (xy 342.031079 -238.914244) (xy 342.0189 -238.86483) (xy 342.014805 -238.814102)
			(xy 341.708994 -238.814102) (xy 341.708504 -238.839091) (xy 341.700685 -238.888454) (xy 341.685241 -238.935986)
			(xy 341.662551 -238.980518) (xy 341.633175 -239.020951) (xy 341.597835 -239.056291) (xy 341.557402 -239.085667)
			(xy 341.51287 -239.108357) (xy 341.465338 -239.123801) (xy 341.415975 -239.13162) (xy 341.365997 -239.13162)
			(xy 341.316634 -239.123801) (xy 341.269102 -239.108357) (xy 341.22457 -239.085667) (xy 341.184137 -239.056291)
			(xy 341.148797 -239.020951) (xy 341.119421 -238.980518) (xy 341.096731 -238.935986) (xy 341.081287 -238.888454)
			(xy 341.073468 -238.839091) (xy 340.766405 -238.839091) (xy 340.766396 -238.839548) (xy 340.758232 -238.889782)
			(xy 340.742116 -238.938056) (xy 340.718465 -238.983119) (xy 340.687892 -239.023805) (xy 340.651188 -239.05906)
			(xy 340.609304 -239.08797) (xy 340.563325 -239.109787) (xy 340.514441 -239.123947) (xy 340.46392 -239.130081)
			(xy 340.413068 -239.128032) (xy 340.363204 -239.117852) (xy 340.315618 -239.099805) (xy 340.271544 -239.074359)
			(xy 340.232122 -239.042172) (xy 340.198374 -239.004078) (xy 340.171173 -238.961064) (xy 340.151225 -238.914244)
			(xy 340.139046 -238.86483) (xy 340.134951 -238.814102) (xy 339.82914 -238.814102) (xy 339.82865 -238.839091)
			(xy 339.820831 -238.888454) (xy 339.805387 -238.935986) (xy 339.782697 -238.980518) (xy 339.753321 -239.020951)
			(xy 339.717981 -239.056291) (xy 339.677548 -239.085667) (xy 339.633016 -239.108357) (xy 339.585484 -239.123801)
			(xy 339.536121 -239.13162) (xy 339.486143 -239.13162) (xy 339.43678 -239.123801) (xy 339.389248 -239.108357)
			(xy 339.344716 -239.085667) (xy 339.304283 -239.056291) (xy 339.268943 -239.020951) (xy 339.239567 -238.980518)
			(xy 339.216877 -238.935986) (xy 339.201433 -238.888454) (xy 339.193614 -238.839091) (xy 338.886297 -238.839091)
			(xy 338.886288 -238.839548) (xy 338.878124 -238.889782) (xy 338.862008 -238.938056) (xy 338.838357 -238.983119)
			(xy 338.807784 -239.023805) (xy 338.77108 -239.05906) (xy 338.729196 -239.08797) (xy 338.683217 -239.109787)
			(xy 338.634333 -239.123947) (xy 338.583812 -239.130081) (xy 338.53296 -239.128032) (xy 338.483096 -239.117852)
			(xy 338.43551 -239.099805) (xy 338.391436 -239.074359) (xy 338.352014 -239.042172) (xy 338.318266 -239.004078)
			(xy 338.291065 -238.961064) (xy 338.271117 -238.914244) (xy 338.258938 -238.86483) (xy 338.254843 -238.814102)
			(xy 338.012532 -238.814102) (xy 338.012532 -239.206278) (xy 338.013032 -239.215939) (xy 338.020349 -239.233828)
			(xy 338.026756 -239.241076) (xy 338.068412 -239.283748) (xy 338.071909 -239.287202) (xy 338.079969 -239.292825)
			(xy 338.084414 -239.294924) (xy 338.10956 -239.305846) (xy 338.118704 -239.306354) (xy 338.14404 -239.308247)
			(xy 338.193678 -239.319065) (xy 338.240967 -239.337632) (xy 338.284705 -239.363477) (xy 338.323781 -239.395942)
			(xy 338.357203 -239.434203) (xy 338.384122 -239.477289) (xy 338.403854 -239.524104) (xy 338.415897 -239.573459)
			(xy 338.419945 -239.6241) (xy 338.419944 -239.624108) (xy 338.724743 -239.624108) (xy 338.728838 -239.57338)
			(xy 338.741017 -239.523966) (xy 338.760965 -239.477146) (xy 338.788166 -239.434132) (xy 338.821914 -239.396038)
			(xy 338.861336 -239.363851) (xy 338.90541 -239.338405) (xy 338.952996 -239.320358) (xy 339.00286 -239.310178)
			(xy 339.053712 -239.308129) (xy 339.104233 -239.314263) (xy 339.153117 -239.328423) (xy 339.199096 -239.35024)
			(xy 339.24098 -239.37915) (xy 339.277684 -239.414405) (xy 339.308257 -239.455091) (xy 339.331908 -239.500154)
			(xy 339.348024 -239.548428) (xy 339.356188 -239.598662) (xy 339.3567 -239.624108) (xy 339.664797 -239.624108)
			(xy 339.668892 -239.57338) (xy 339.681071 -239.523966) (xy 339.701019 -239.477146) (xy 339.72822 -239.434132)
			(xy 339.761968 -239.396038) (xy 339.80139 -239.363851) (xy 339.845464 -239.338405) (xy 339.89305 -239.320358)
			(xy 339.942914 -239.310178) (xy 339.993766 -239.308129) (xy 340.044287 -239.314263) (xy 340.093171 -239.328423)
			(xy 340.13915 -239.35024) (xy 340.181034 -239.37915) (xy 340.217738 -239.414405) (xy 340.248311 -239.455091)
			(xy 340.271962 -239.500154) (xy 340.288078 -239.548428) (xy 340.296242 -239.598662) (xy 340.296754 -239.624108)
			(xy 341.544905 -239.624108) (xy 341.549 -239.57338) (xy 341.561179 -239.523966) (xy 341.581127 -239.477146)
			(xy 341.608328 -239.434132) (xy 341.642076 -239.396038) (xy 341.681498 -239.363851) (xy 341.725572 -239.338405)
			(xy 341.773158 -239.320358) (xy 341.823022 -239.310178) (xy 341.873874 -239.308129) (xy 341.924395 -239.314263)
			(xy 341.973279 -239.328423) (xy 342.019258 -239.35024) (xy 342.061142 -239.37915) (xy 342.097846 -239.414405)
			(xy 342.128419 -239.455091) (xy 342.15207 -239.500154) (xy 342.168186 -239.548428) (xy 342.17635 -239.598662)
			(xy 342.176862 -239.624108) (xy 342.176359 -239.649097) (xy 342.483676 -239.649097) (xy 342.483676 -239.599119)
			(xy 342.491495 -239.549756) (xy 342.506939 -239.502224) (xy 342.529629 -239.457692) (xy 342.559005 -239.417259)
			(xy 342.594345 -239.381919) (xy 342.634778 -239.352543) (xy 342.67931 -239.329853) (xy 342.726842 -239.314409)
			(xy 342.776205 -239.30659) (xy 342.826183 -239.30659) (xy 342.875546 -239.314409) (xy 342.923078 -239.329853)
			(xy 342.96761 -239.352543) (xy 343.008043 -239.381919) (xy 343.043383 -239.417259) (xy 343.072759 -239.457692)
			(xy 343.095449 -239.502224) (xy 343.110893 -239.549756) (xy 343.118712 -239.599119) (xy 343.119202 -239.624108)
			(xy 343.424759 -239.624108) (xy 343.428854 -239.57338) (xy 343.441033 -239.523966) (xy 343.460981 -239.477146)
			(xy 343.488182 -239.434132) (xy 343.52193 -239.396038) (xy 343.561352 -239.363851) (xy 343.605426 -239.338405)
			(xy 343.653012 -239.320358) (xy 343.702876 -239.310178) (xy 343.753728 -239.308129) (xy 343.804249 -239.314263)
			(xy 343.853133 -239.328423) (xy 343.899112 -239.35024) (xy 343.940996 -239.37915) (xy 343.9777 -239.414405)
			(xy 344.008273 -239.455091) (xy 344.031924 -239.500154) (xy 344.04804 -239.548428) (xy 344.056204 -239.598662)
			(xy 344.056716 -239.624108) (xy 344.056204 -239.649554) (xy 344.04804 -239.699788) (xy 344.031924 -239.748062)
			(xy 344.008273 -239.793125) (xy 343.9777 -239.833811) (xy 343.940996 -239.869066) (xy 343.899112 -239.897976)
			(xy 343.853133 -239.919793) (xy 343.804249 -239.933953) (xy 343.753728 -239.940087) (xy 343.702876 -239.938038)
			(xy 343.653012 -239.927858) (xy 343.605426 -239.909811) (xy 343.561352 -239.884365) (xy 343.52193 -239.852178)
			(xy 343.488182 -239.814084) (xy 343.460981 -239.77107) (xy 343.441033 -239.72425) (xy 343.428854 -239.674836)
			(xy 343.424759 -239.624108) (xy 343.119202 -239.624108) (xy 343.118712 -239.649097) (xy 343.110893 -239.69846)
			(xy 343.095449 -239.745992) (xy 343.072759 -239.790524) (xy 343.043383 -239.830957) (xy 343.008043 -239.866297)
			(xy 342.96761 -239.895673) (xy 342.923078 -239.918363) (xy 342.875546 -239.933807) (xy 342.826183 -239.941626)
			(xy 342.776205 -239.941626) (xy 342.726842 -239.933807) (xy 342.67931 -239.918363) (xy 342.634778 -239.895673)
			(xy 342.594345 -239.866297) (xy 342.559005 -239.830957) (xy 342.529629 -239.790524) (xy 342.506939 -239.745992)
			(xy 342.491495 -239.69846) (xy 342.483676 -239.649097) (xy 342.176359 -239.649097) (xy 342.17635 -239.649554)
			(xy 342.168186 -239.699788) (xy 342.15207 -239.748062) (xy 342.128419 -239.793125) (xy 342.097846 -239.833811)
			(xy 342.061142 -239.869066) (xy 342.019258 -239.897976) (xy 341.973279 -239.919793) (xy 341.924395 -239.933953)
			(xy 341.873874 -239.940087) (xy 341.823022 -239.938038) (xy 341.773158 -239.927858) (xy 341.725572 -239.909811)
			(xy 341.681498 -239.884365) (xy 341.642076 -239.852178) (xy 341.608328 -239.814084) (xy 341.581127 -239.77107)
			(xy 341.561179 -239.72425) (xy 341.549 -239.674836) (xy 341.544905 -239.624108) (xy 340.296754 -239.624108)
			(xy 340.296242 -239.649554) (xy 340.288078 -239.699788) (xy 340.271962 -239.748062) (xy 340.248311 -239.793125)
			(xy 340.217738 -239.833811) (xy 340.181034 -239.869066) (xy 340.13915 -239.897976) (xy 340.093171 -239.919793)
			(xy 340.044287 -239.933953) (xy 339.993766 -239.940087) (xy 339.942914 -239.938038) (xy 339.89305 -239.927858)
			(xy 339.845464 -239.909811) (xy 339.80139 -239.884365) (xy 339.761968 -239.852178) (xy 339.72822 -239.814084)
			(xy 339.701019 -239.77107) (xy 339.681071 -239.72425) (xy 339.668892 -239.674836) (xy 339.664797 -239.624108)
			(xy 339.3567 -239.624108) (xy 339.356188 -239.649554) (xy 339.348024 -239.699788) (xy 339.331908 -239.748062)
			(xy 339.308257 -239.793125) (xy 339.277684 -239.833811) (xy 339.24098 -239.869066) (xy 339.199096 -239.897976)
			(xy 339.153117 -239.919793) (xy 339.104233 -239.933953) (xy 339.053712 -239.940087) (xy 339.00286 -239.938038)
			(xy 338.952996 -239.927858) (xy 338.90541 -239.909811) (xy 338.861336 -239.884365) (xy 338.821914 -239.852178)
			(xy 338.788166 -239.814084) (xy 338.760965 -239.77107) (xy 338.741017 -239.72425) (xy 338.728838 -239.674836)
			(xy 338.724743 -239.624108) (xy 338.419944 -239.624108) (xy 338.415897 -239.674742) (xy 338.403853 -239.724097)
			(xy 338.384122 -239.770912) (xy 338.357203 -239.813997) (xy 338.323781 -239.852259) (xy 338.284704 -239.884724)
			(xy 338.240966 -239.910568) (xy 338.193677 -239.929135) (xy 338.144039 -239.939953) (xy 338.118704 -239.941862)
			(xy 338.10956 -239.94237) (xy 338.084414 -239.953292) (xy 338.079964 -239.955382) (xy 338.071899 -239.961003)
			(xy 338.068412 -239.964468) (xy 338.026756 -240.00714) (xy 338.0203 -240.014358) (xy 338.012978 -240.032265)
			(xy 338.012532 -240.041938) (xy 338.012532 -240.434114) (xy 338.254843 -240.434114) (xy 338.258938 -240.383386)
			(xy 338.271117 -240.333972) (xy 338.291065 -240.287152) (xy 338.318266 -240.244138) (xy 338.352014 -240.206044)
			(xy 338.391436 -240.173857) (xy 338.43551 -240.148411) (xy 338.483096 -240.130364) (xy 338.53296 -240.120184)
			(xy 338.583812 -240.118135) (xy 338.634333 -240.124269) (xy 338.683217 -240.138429) (xy 338.729196 -240.160246)
			(xy 338.77108 -240.189156) (xy 338.807784 -240.224411) (xy 338.838357 -240.265097) (xy 338.862008 -240.31016)
			(xy 338.878124 -240.358434) (xy 338.886288 -240.408668) (xy 338.8868 -240.434114) (xy 338.886297 -240.459103)
			(xy 339.193614 -240.459103) (xy 339.193614 -240.409125) (xy 339.201433 -240.359762) (xy 339.216877 -240.31223)
			(xy 339.239567 -240.267698) (xy 339.268943 -240.227265) (xy 339.304283 -240.191925) (xy 339.344716 -240.162549)
			(xy 339.389248 -240.139859) (xy 339.43678 -240.124415) (xy 339.486143 -240.116596) (xy 339.536121 -240.116596)
			(xy 339.585484 -240.124415) (xy 339.633016 -240.139859) (xy 339.677548 -240.162549) (xy 339.717981 -240.191925)
			(xy 339.753321 -240.227265) (xy 339.782697 -240.267698) (xy 339.805387 -240.31223) (xy 339.820831 -240.359762)
			(xy 339.82865 -240.409125) (xy 339.82914 -240.434114) (xy 340.134951 -240.434114) (xy 340.139046 -240.383386)
			(xy 340.151225 -240.333972) (xy 340.171173 -240.287152) (xy 340.198374 -240.244138) (xy 340.232122 -240.206044)
			(xy 340.271544 -240.173857) (xy 340.315618 -240.148411) (xy 340.363204 -240.130364) (xy 340.413068 -240.120184)
			(xy 340.46392 -240.118135) (xy 340.514441 -240.124269) (xy 340.563325 -240.138429) (xy 340.609304 -240.160246)
			(xy 340.651188 -240.189156) (xy 340.687892 -240.224411) (xy 340.718465 -240.265097) (xy 340.742116 -240.31016)
			(xy 340.758232 -240.358434) (xy 340.766396 -240.408668) (xy 340.766908 -240.434114) (xy 340.766405 -240.459103)
			(xy 341.073468 -240.459103) (xy 341.073468 -240.409125) (xy 341.081287 -240.359762) (xy 341.096731 -240.31223)
			(xy 341.119421 -240.267698) (xy 341.148797 -240.227265) (xy 341.184137 -240.191925) (xy 341.22457 -240.162549)
			(xy 341.269102 -240.139859) (xy 341.316634 -240.124415) (xy 341.365997 -240.116596) (xy 341.415975 -240.116596)
			(xy 341.465338 -240.124415) (xy 341.51287 -240.139859) (xy 341.557402 -240.162549) (xy 341.597835 -240.191925)
			(xy 341.633175 -240.227265) (xy 341.662551 -240.267698) (xy 341.685241 -240.31223) (xy 341.700685 -240.359762)
			(xy 341.708504 -240.409125) (xy 341.708994 -240.434114) (xy 342.014805 -240.434114) (xy 342.0189 -240.383386)
			(xy 342.031079 -240.333972) (xy 342.051027 -240.287152) (xy 342.078228 -240.244138) (xy 342.111976 -240.206044)
			(xy 342.151398 -240.173857) (xy 342.195472 -240.148411) (xy 342.243058 -240.130364) (xy 342.292922 -240.120184)
			(xy 342.343774 -240.118135) (xy 342.394295 -240.124269) (xy 342.443179 -240.138429) (xy 342.489158 -240.160246)
			(xy 342.531042 -240.189156) (xy 342.567746 -240.224411) (xy 342.598319 -240.265097) (xy 342.62197 -240.31016)
			(xy 342.638086 -240.358434) (xy 342.64625 -240.408668) (xy 342.646762 -240.434114) (xy 342.954859 -240.434114)
			(xy 342.958954 -240.383386) (xy 342.971133 -240.333972) (xy 342.991081 -240.287152) (xy 343.018282 -240.244138)
			(xy 343.05203 -240.206044) (xy 343.091452 -240.173857) (xy 343.135526 -240.148411) (xy 343.183112 -240.130364)
			(xy 343.232976 -240.120184) (xy 343.283828 -240.118135) (xy 343.334349 -240.124269) (xy 343.383233 -240.138429)
			(xy 343.429212 -240.160246) (xy 343.471096 -240.189156) (xy 343.5078 -240.224411) (xy 343.538373 -240.265097)
			(xy 343.562024 -240.31016) (xy 343.57814 -240.358434) (xy 343.586304 -240.408668) (xy 343.586816 -240.434114)
			(xy 343.586304 -240.45956) (xy 343.57814 -240.509794) (xy 343.562024 -240.558068) (xy 343.538373 -240.603131)
			(xy 343.5078 -240.643817) (xy 343.471096 -240.679072) (xy 343.429212 -240.707982) (xy 343.383233 -240.729799)
			(xy 343.334349 -240.743959) (xy 343.283828 -240.750093) (xy 343.232976 -240.748044) (xy 343.183112 -240.737864)
			(xy 343.135526 -240.719817) (xy 343.091452 -240.694371) (xy 343.05203 -240.662184) (xy 343.018282 -240.62409)
			(xy 342.991081 -240.581076) (xy 342.971133 -240.534256) (xy 342.958954 -240.484842) (xy 342.954859 -240.434114)
			(xy 342.646762 -240.434114) (xy 342.64625 -240.45956) (xy 342.638086 -240.509794) (xy 342.62197 -240.558068)
			(xy 342.598319 -240.603131) (xy 342.567746 -240.643817) (xy 342.531042 -240.679072) (xy 342.489158 -240.707982)
			(xy 342.443179 -240.729799) (xy 342.394295 -240.743959) (xy 342.343774 -240.750093) (xy 342.292922 -240.748044)
			(xy 342.243058 -240.737864) (xy 342.195472 -240.719817) (xy 342.151398 -240.694371) (xy 342.111976 -240.662184)
			(xy 342.078228 -240.62409) (xy 342.051027 -240.581076) (xy 342.031079 -240.534256) (xy 342.0189 -240.484842)
			(xy 342.014805 -240.434114) (xy 341.708994 -240.434114) (xy 341.708504 -240.459103) (xy 341.700685 -240.508466)
			(xy 341.685241 -240.555998) (xy 341.662551 -240.60053) (xy 341.633175 -240.640963) (xy 341.597835 -240.676303)
			(xy 341.557402 -240.705679) (xy 341.51287 -240.728369) (xy 341.465338 -240.743813) (xy 341.415975 -240.751632)
			(xy 341.365997 -240.751632) (xy 341.316634 -240.743813) (xy 341.269102 -240.728369) (xy 341.22457 -240.705679)
			(xy 341.184137 -240.676303) (xy 341.148797 -240.640963) (xy 341.119421 -240.60053) (xy 341.096731 -240.555998)
			(xy 341.081287 -240.508466) (xy 341.073468 -240.459103) (xy 340.766405 -240.459103) (xy 340.766396 -240.45956)
			(xy 340.758232 -240.509794) (xy 340.742116 -240.558068) (xy 340.718465 -240.603131) (xy 340.687892 -240.643817)
			(xy 340.651188 -240.679072) (xy 340.609304 -240.707982) (xy 340.563325 -240.729799) (xy 340.514441 -240.743959)
			(xy 340.46392 -240.750093) (xy 340.413068 -240.748044) (xy 340.363204 -240.737864) (xy 340.315618 -240.719817)
			(xy 340.271544 -240.694371) (xy 340.232122 -240.662184) (xy 340.198374 -240.62409) (xy 340.171173 -240.581076)
			(xy 340.151225 -240.534256) (xy 340.139046 -240.484842) (xy 340.134951 -240.434114) (xy 339.82914 -240.434114)
			(xy 339.82865 -240.459103) (xy 339.820831 -240.508466) (xy 339.805387 -240.555998) (xy 339.782697 -240.60053)
			(xy 339.753321 -240.640963) (xy 339.717981 -240.676303) (xy 339.677548 -240.705679) (xy 339.633016 -240.728369)
			(xy 339.585484 -240.743813) (xy 339.536121 -240.751632) (xy 339.486143 -240.751632) (xy 339.43678 -240.743813)
			(xy 339.389248 -240.728369) (xy 339.344716 -240.705679) (xy 339.304283 -240.676303) (xy 339.268943 -240.640963)
			(xy 339.239567 -240.60053) (xy 339.216877 -240.555998) (xy 339.201433 -240.508466) (xy 339.193614 -240.459103)
			(xy 338.886297 -240.459103) (xy 338.886288 -240.45956) (xy 338.878124 -240.509794) (xy 338.862008 -240.558068)
			(xy 338.838357 -240.603131) (xy 338.807784 -240.643817) (xy 338.77108 -240.679072) (xy 338.729196 -240.707982)
			(xy 338.683217 -240.729799) (xy 338.634333 -240.743959) (xy 338.583812 -240.750093) (xy 338.53296 -240.748044)
			(xy 338.483096 -240.737864) (xy 338.43551 -240.719817) (xy 338.391436 -240.694371) (xy 338.352014 -240.662184)
			(xy 338.318266 -240.62409) (xy 338.291065 -240.581076) (xy 338.271117 -240.534256) (xy 338.258938 -240.484842)
			(xy 338.254843 -240.434114) (xy 338.012532 -240.434114) (xy 338.012532 -240.82629) (xy 338.013034 -240.83595)
			(xy 338.020354 -240.853836) (xy 338.026756 -240.861088) (xy 338.068412 -240.90376) (xy 338.071906 -240.907219)
			(xy 338.079962 -240.912851) (xy 338.084414 -240.914936) (xy 338.10956 -240.925858) (xy 338.118704 -240.926366)
			(xy 338.144039 -240.928259) (xy 338.193675 -240.939077) (xy 338.240962 -240.957643) (xy 338.284698 -240.983487)
			(xy 338.323773 -241.015951) (xy 338.357194 -241.054211) (xy 338.384112 -241.097295) (xy 338.403843 -241.144108)
			(xy 338.415885 -241.193461) (xy 338.419933 -241.244101) (xy 338.419931 -241.24412) (xy 338.724743 -241.24412)
			(xy 338.728838 -241.193392) (xy 338.741017 -241.143978) (xy 338.760965 -241.097158) (xy 338.788166 -241.054144)
			(xy 338.821914 -241.01605) (xy 338.861336 -240.983863) (xy 338.90541 -240.958417) (xy 338.952996 -240.94037)
			(xy 339.00286 -240.93019) (xy 339.053712 -240.928141) (xy 339.104233 -240.934275) (xy 339.153117 -240.948435)
			(xy 339.199096 -240.970252) (xy 339.24098 -240.999162) (xy 339.277684 -241.034417) (xy 339.308257 -241.075103)
			(xy 339.331908 -241.120166) (xy 339.348024 -241.16844) (xy 339.356188 -241.218674) (xy 339.3567 -241.24412)
			(xy 339.664797 -241.24412) (xy 339.668892 -241.193392) (xy 339.681071 -241.143978) (xy 339.701019 -241.097158)
			(xy 339.72822 -241.054144) (xy 339.761968 -241.01605) (xy 339.80139 -240.983863) (xy 339.845464 -240.958417)
			(xy 339.89305 -240.94037) (xy 339.942914 -240.93019) (xy 339.993766 -240.928141) (xy 340.044287 -240.934275)
			(xy 340.093171 -240.948435) (xy 340.13915 -240.970252) (xy 340.181034 -240.999162) (xy 340.217738 -241.034417)
			(xy 340.248311 -241.075103) (xy 340.271962 -241.120166) (xy 340.288078 -241.16844) (xy 340.296242 -241.218674)
			(xy 340.296754 -241.24412) (xy 340.296251 -241.269109) (xy 340.603568 -241.269109) (xy 340.603568 -241.219131)
			(xy 340.611387 -241.169768) (xy 340.626831 -241.122236) (xy 340.649521 -241.077704) (xy 340.678897 -241.037271)
			(xy 340.714237 -241.001931) (xy 340.75467 -240.972555) (xy 340.799202 -240.949865) (xy 340.846734 -240.934421)
			(xy 340.896097 -240.926602) (xy 340.946075 -240.926602) (xy 340.995438 -240.934421) (xy 341.04297 -240.949865)
			(xy 341.087502 -240.972555) (xy 341.127935 -241.001931) (xy 341.163275 -241.037271) (xy 341.192651 -241.077704)
			(xy 341.215341 -241.122236) (xy 341.230785 -241.169768) (xy 341.238604 -241.219131) (xy 341.239094 -241.24412)
			(xy 341.544905 -241.24412) (xy 341.549 -241.193392) (xy 341.561179 -241.143978) (xy 341.581127 -241.097158)
			(xy 341.608328 -241.054144) (xy 341.642076 -241.01605) (xy 341.681498 -240.983863) (xy 341.725572 -240.958417)
			(xy 341.773158 -240.94037) (xy 341.823022 -240.93019) (xy 341.873874 -240.928141) (xy 341.924395 -240.934275)
			(xy 341.973279 -240.948435) (xy 342.019258 -240.970252) (xy 342.061142 -240.999162) (xy 342.097846 -241.034417)
			(xy 342.128419 -241.075103) (xy 342.15207 -241.120166) (xy 342.168186 -241.16844) (xy 342.17635 -241.218674)
			(xy 342.176862 -241.24412) (xy 342.176359 -241.269109) (xy 342.483676 -241.269109) (xy 342.483676 -241.219131)
			(xy 342.491495 -241.169768) (xy 342.506939 -241.122236) (xy 342.529629 -241.077704) (xy 342.559005 -241.037271)
			(xy 342.594345 -241.001931) (xy 342.634778 -240.972555) (xy 342.67931 -240.949865) (xy 342.726842 -240.934421)
			(xy 342.776205 -240.926602) (xy 342.826183 -240.926602) (xy 342.875546 -240.934421) (xy 342.923078 -240.949865)
			(xy 342.96761 -240.972555) (xy 343.008043 -241.001931) (xy 343.043383 -241.037271) (xy 343.072759 -241.077704)
			(xy 343.095449 -241.122236) (xy 343.110893 -241.169768) (xy 343.118712 -241.219131) (xy 343.119202 -241.24412)
			(xy 343.424759 -241.24412) (xy 343.428854 -241.193392) (xy 343.441033 -241.143978) (xy 343.460981 -241.097158)
			(xy 343.488182 -241.054144) (xy 343.52193 -241.01605) (xy 343.561352 -240.983863) (xy 343.605426 -240.958417)
			(xy 343.653012 -240.94037) (xy 343.702876 -240.93019) (xy 343.753728 -240.928141) (xy 343.804249 -240.934275)
			(xy 343.853133 -240.948435) (xy 343.899112 -240.970252) (xy 343.940996 -240.999162) (xy 343.9777 -241.034417)
			(xy 344.008273 -241.075103) (xy 344.031924 -241.120166) (xy 344.04804 -241.16844) (xy 344.056204 -241.218674)
			(xy 344.056716 -241.24412) (xy 344.056204 -241.269566) (xy 344.04804 -241.3198) (xy 344.031924 -241.368074)
			(xy 344.008273 -241.413137) (xy 343.9777 -241.453823) (xy 343.940996 -241.489078) (xy 343.899112 -241.517988)
			(xy 343.853133 -241.539805) (xy 343.804249 -241.553965) (xy 343.753728 -241.560099) (xy 343.702876 -241.55805)
			(xy 343.653012 -241.54787) (xy 343.605426 -241.529823) (xy 343.561352 -241.504377) (xy 343.52193 -241.47219)
			(xy 343.488182 -241.434096) (xy 343.460981 -241.391082) (xy 343.441033 -241.344262) (xy 343.428854 -241.294848)
			(xy 343.424759 -241.24412) (xy 343.119202 -241.24412) (xy 343.118712 -241.269109) (xy 343.110893 -241.318472)
			(xy 343.095449 -241.366004) (xy 343.072759 -241.410536) (xy 343.043383 -241.450969) (xy 343.008043 -241.486309)
			(xy 342.96761 -241.515685) (xy 342.923078 -241.538375) (xy 342.875546 -241.553819) (xy 342.826183 -241.561638)
			(xy 342.776205 -241.561638) (xy 342.726842 -241.553819) (xy 342.67931 -241.538375) (xy 342.634778 -241.515685)
			(xy 342.594345 -241.486309) (xy 342.559005 -241.450969) (xy 342.529629 -241.410536) (xy 342.506939 -241.366004)
			(xy 342.491495 -241.318472) (xy 342.483676 -241.269109) (xy 342.176359 -241.269109) (xy 342.17635 -241.269566)
			(xy 342.168186 -241.3198) (xy 342.15207 -241.368074) (xy 342.128419 -241.413137) (xy 342.097846 -241.453823)
			(xy 342.061142 -241.489078) (xy 342.019258 -241.517988) (xy 341.973279 -241.539805) (xy 341.924395 -241.553965)
			(xy 341.873874 -241.560099) (xy 341.823022 -241.55805) (xy 341.773158 -241.54787) (xy 341.725572 -241.529823)
			(xy 341.681498 -241.504377) (xy 341.642076 -241.47219) (xy 341.608328 -241.434096) (xy 341.581127 -241.391082)
			(xy 341.561179 -241.344262) (xy 341.549 -241.294848) (xy 341.544905 -241.24412) (xy 341.239094 -241.24412)
			(xy 341.238604 -241.269109) (xy 341.230785 -241.318472) (xy 341.215341 -241.366004) (xy 341.192651 -241.410536)
			(xy 341.163275 -241.450969) (xy 341.127935 -241.486309) (xy 341.087502 -241.515685) (xy 341.04297 -241.538375)
			(xy 340.995438 -241.553819) (xy 340.946075 -241.561638) (xy 340.896097 -241.561638) (xy 340.846734 -241.553819)
			(xy 340.799202 -241.538375) (xy 340.75467 -241.515685) (xy 340.714237 -241.486309) (xy 340.678897 -241.450969)
			(xy 340.649521 -241.410536) (xy 340.626831 -241.366004) (xy 340.611387 -241.318472) (xy 340.603568 -241.269109)
			(xy 340.296251 -241.269109) (xy 340.296242 -241.269566) (xy 340.288078 -241.3198) (xy 340.271962 -241.368074)
			(xy 340.248311 -241.413137) (xy 340.217738 -241.453823) (xy 340.181034 -241.489078) (xy 340.13915 -241.517988)
			(xy 340.093171 -241.539805) (xy 340.044287 -241.553965) (xy 339.993766 -241.560099) (xy 339.942914 -241.55805)
			(xy 339.89305 -241.54787) (xy 339.845464 -241.529823) (xy 339.80139 -241.504377) (xy 339.761968 -241.47219)
			(xy 339.72822 -241.434096) (xy 339.701019 -241.391082) (xy 339.681071 -241.344262) (xy 339.668892 -241.294848)
			(xy 339.664797 -241.24412) (xy 339.3567 -241.24412) (xy 339.356188 -241.269566) (xy 339.348024 -241.3198)
			(xy 339.331908 -241.368074) (xy 339.308257 -241.413137) (xy 339.277684 -241.453823) (xy 339.24098 -241.489078)
			(xy 339.199096 -241.517988) (xy 339.153117 -241.539805) (xy 339.104233 -241.553965) (xy 339.053712 -241.560099)
			(xy 339.00286 -241.55805) (xy 338.952996 -241.54787) (xy 338.90541 -241.529823) (xy 338.861336 -241.504377)
			(xy 338.821914 -241.47219) (xy 338.788166 -241.434096) (xy 338.760965 -241.391082) (xy 338.741017 -241.344262)
			(xy 338.728838 -241.294848) (xy 338.724743 -241.24412) (xy 338.419931 -241.24412) (xy 338.415885 -241.294741)
			(xy 338.403842 -241.344094) (xy 338.384111 -241.390907) (xy 338.357193 -241.433991) (xy 338.323772 -241.472251)
			(xy 338.284697 -241.504714) (xy 338.24096 -241.530558) (xy 338.193673 -241.549124) (xy 338.144037 -241.559942)
			(xy 338.118704 -241.561874) (xy 338.10956 -241.562382) (xy 338.084414 -241.573304) (xy 338.079964 -241.575395)
			(xy 338.071901 -241.581016) (xy 338.068412 -241.58448) (xy 338.026756 -241.627152) (xy 338.020302 -241.63437)
			(xy 338.012984 -241.652277) (xy 338.012532 -241.66195) (xy 338.012532 -242.054126) (xy 338.254843 -242.054126)
			(xy 338.258938 -242.003398) (xy 338.271117 -241.953984) (xy 338.291065 -241.907164) (xy 338.318266 -241.86415)
			(xy 338.352014 -241.826056) (xy 338.391436 -241.793869) (xy 338.43551 -241.768423) (xy 338.483096 -241.750376)
			(xy 338.53296 -241.740196) (xy 338.583812 -241.738147) (xy 338.634333 -241.744281) (xy 338.683217 -241.758441)
			(xy 338.729196 -241.780258) (xy 338.77108 -241.809168) (xy 338.807784 -241.844423) (xy 338.838357 -241.885109)
			(xy 338.862008 -241.930172) (xy 338.878124 -241.978446) (xy 338.886288 -242.02868) (xy 338.8868 -242.054126)
			(xy 338.886297 -242.079115) (xy 339.193614 -242.079115) (xy 339.193614 -242.029137) (xy 339.201433 -241.979774)
			(xy 339.216877 -241.932242) (xy 339.239567 -241.88771) (xy 339.268943 -241.847277) (xy 339.304283 -241.811937)
			(xy 339.344716 -241.782561) (xy 339.389248 -241.759871) (xy 339.43678 -241.744427) (xy 339.486143 -241.736608)
			(xy 339.536121 -241.736608) (xy 339.585484 -241.744427) (xy 339.633016 -241.759871) (xy 339.677548 -241.782561)
			(xy 339.717981 -241.811937) (xy 339.753321 -241.847277) (xy 339.782697 -241.88771) (xy 339.805387 -241.932242)
			(xy 339.820831 -241.979774) (xy 339.82865 -242.029137) (xy 339.82914 -242.054126) (xy 340.134951 -242.054126)
			(xy 340.139046 -242.003398) (xy 340.151225 -241.953984) (xy 340.171173 -241.907164) (xy 340.198374 -241.86415)
			(xy 340.232122 -241.826056) (xy 340.271544 -241.793869) (xy 340.315618 -241.768423) (xy 340.363204 -241.750376)
			(xy 340.413068 -241.740196) (xy 340.46392 -241.738147) (xy 340.514441 -241.744281) (xy 340.563325 -241.758441)
			(xy 340.609304 -241.780258) (xy 340.651188 -241.809168) (xy 340.687892 -241.844423) (xy 340.718465 -241.885109)
			(xy 340.742116 -241.930172) (xy 340.758232 -241.978446) (xy 340.766396 -242.02868) (xy 340.766908 -242.054126)
			(xy 342.014805 -242.054126) (xy 342.0189 -242.003398) (xy 342.031079 -241.953984) (xy 342.051027 -241.907164)
			(xy 342.078228 -241.86415) (xy 342.111976 -241.826056) (xy 342.151398 -241.793869) (xy 342.195472 -241.768423)
			(xy 342.243058 -241.750376) (xy 342.292922 -241.740196) (xy 342.343774 -241.738147) (xy 342.394295 -241.744281)
			(xy 342.443179 -241.758441) (xy 342.489158 -241.780258) (xy 342.531042 -241.809168) (xy 342.567746 -241.844423)
			(xy 342.598319 -241.885109) (xy 342.62197 -241.930172) (xy 342.638086 -241.978446) (xy 342.64625 -242.02868)
			(xy 342.646762 -242.054126) (xy 342.954859 -242.054126) (xy 342.958954 -242.003398) (xy 342.971133 -241.953984)
			(xy 342.991081 -241.907164) (xy 343.018282 -241.86415) (xy 343.05203 -241.826056) (xy 343.091452 -241.793869)
			(xy 343.135526 -241.768423) (xy 343.183112 -241.750376) (xy 343.232976 -241.740196) (xy 343.283828 -241.738147)
			(xy 343.334349 -241.744281) (xy 343.383233 -241.758441) (xy 343.429212 -241.780258) (xy 343.471096 -241.809168)
			(xy 343.5078 -241.844423) (xy 343.538373 -241.885109) (xy 343.562024 -241.930172) (xy 343.57814 -241.978446)
			(xy 343.586304 -242.02868) (xy 343.586816 -242.054126) (xy 343.586313 -242.079115) (xy 343.89363 -242.079115)
			(xy 343.89363 -242.029137) (xy 343.901449 -241.979774) (xy 343.916893 -241.932242) (xy 343.939583 -241.88771)
			(xy 343.968959 -241.847277) (xy 344.004299 -241.811937) (xy 344.044732 -241.782561) (xy 344.089264 -241.759871)
			(xy 344.136796 -241.744427) (xy 344.186159 -241.736608) (xy 344.236137 -241.736608) (xy 344.2855 -241.744427)
			(xy 344.333032 -241.759871) (xy 344.377564 -241.782561) (xy 344.417997 -241.811937) (xy 344.453337 -241.847277)
			(xy 344.482713 -241.88771) (xy 344.505403 -241.932242) (xy 344.520847 -241.979774) (xy 344.528666 -242.029137)
			(xy 344.529156 -242.054126) (xy 344.528666 -242.079115) (xy 344.520847 -242.128478) (xy 344.505403 -242.17601)
			(xy 344.482713 -242.220542) (xy 344.453337 -242.260975) (xy 344.417997 -242.296315) (xy 344.377564 -242.325691)
			(xy 344.333032 -242.348381) (xy 344.2855 -242.363825) (xy 344.236137 -242.371644) (xy 344.186159 -242.371644)
			(xy 344.136796 -242.363825) (xy 344.089264 -242.348381) (xy 344.044732 -242.325691) (xy 344.004299 -242.296315)
			(xy 343.968959 -242.260975) (xy 343.939583 -242.220542) (xy 343.916893 -242.17601) (xy 343.901449 -242.128478)
			(xy 343.89363 -242.079115) (xy 343.586313 -242.079115) (xy 343.586304 -242.079572) (xy 343.57814 -242.129806)
			(xy 343.562024 -242.17808) (xy 343.538373 -242.223143) (xy 343.5078 -242.263829) (xy 343.471096 -242.299084)
			(xy 343.429212 -242.327994) (xy 343.383233 -242.349811) (xy 343.334349 -242.363971) (xy 343.283828 -242.370105)
			(xy 343.232976 -242.368056) (xy 343.183112 -242.357876) (xy 343.135526 -242.339829) (xy 343.091452 -242.314383)
			(xy 343.05203 -242.282196) (xy 343.018282 -242.244102) (xy 342.991081 -242.201088) (xy 342.971133 -242.154268)
			(xy 342.958954 -242.104854) (xy 342.954859 -242.054126) (xy 342.646762 -242.054126) (xy 342.64625 -242.079572)
			(xy 342.638086 -242.129806) (xy 342.62197 -242.17808) (xy 342.598319 -242.223143) (xy 342.567746 -242.263829)
			(xy 342.531042 -242.299084) (xy 342.489158 -242.327994) (xy 342.443179 -242.349811) (xy 342.394295 -242.363971)
			(xy 342.343774 -242.370105) (xy 342.292922 -242.368056) (xy 342.243058 -242.357876) (xy 342.195472 -242.339829)
			(xy 342.151398 -242.314383) (xy 342.111976 -242.282196) (xy 342.078228 -242.244102) (xy 342.051027 -242.201088)
			(xy 342.031079 -242.154268) (xy 342.0189 -242.104854) (xy 342.014805 -242.054126) (xy 340.766908 -242.054126)
			(xy 340.766396 -242.079572) (xy 340.758232 -242.129806) (xy 340.742116 -242.17808) (xy 340.718465 -242.223143)
			(xy 340.687892 -242.263829) (xy 340.651188 -242.299084) (xy 340.609304 -242.327994) (xy 340.563325 -242.349811)
			(xy 340.514441 -242.363971) (xy 340.46392 -242.370105) (xy 340.413068 -242.368056) (xy 340.363204 -242.357876)
			(xy 340.315618 -242.339829) (xy 340.271544 -242.314383) (xy 340.232122 -242.282196) (xy 340.198374 -242.244102)
			(xy 340.171173 -242.201088) (xy 340.151225 -242.154268) (xy 340.139046 -242.104854) (xy 340.134951 -242.054126)
			(xy 339.82914 -242.054126) (xy 339.82865 -242.079115) (xy 339.820831 -242.128478) (xy 339.805387 -242.17601)
			(xy 339.782697 -242.220542) (xy 339.753321 -242.260975) (xy 339.717981 -242.296315) (xy 339.677548 -242.325691)
			(xy 339.633016 -242.348381) (xy 339.585484 -242.363825) (xy 339.536121 -242.371644) (xy 339.486143 -242.371644)
			(xy 339.43678 -242.363825) (xy 339.389248 -242.348381) (xy 339.344716 -242.325691) (xy 339.304283 -242.296315)
			(xy 339.268943 -242.260975) (xy 339.239567 -242.220542) (xy 339.216877 -242.17601) (xy 339.201433 -242.128478)
			(xy 339.193614 -242.079115) (xy 338.886297 -242.079115) (xy 338.886288 -242.079572) (xy 338.878124 -242.129806)
			(xy 338.862008 -242.17808) (xy 338.838357 -242.223143) (xy 338.807784 -242.263829) (xy 338.77108 -242.299084)
			(xy 338.729196 -242.327994) (xy 338.683217 -242.349811) (xy 338.634333 -242.363971) (xy 338.583812 -242.370105)
			(xy 338.53296 -242.368056) (xy 338.483096 -242.357876) (xy 338.43551 -242.339829) (xy 338.391436 -242.314383)
			(xy 338.352014 -242.282196) (xy 338.318266 -242.244102) (xy 338.291065 -242.201088) (xy 338.271117 -242.154268)
			(xy 338.258938 -242.104854) (xy 338.254843 -242.054126) (xy 338.012532 -242.054126) (xy 338.012532 -242.446302)
			(xy 338.013036 -242.455961) (xy 338.020359 -242.473844) (xy 338.026756 -242.4811) (xy 338.068412 -242.523772)
			(xy 338.071906 -242.52723) (xy 338.079963 -242.532861) (xy 338.084414 -242.534948) (xy 338.10956 -242.54587)
			(xy 338.118704 -242.546378) (xy 338.144038 -242.548271) (xy 338.193672 -242.559088) (xy 338.240957 -242.577654)
			(xy 338.284692 -242.603497) (xy 338.323766 -242.63596) (xy 338.357185 -242.674219) (xy 338.384102 -242.717301)
			(xy 338.403831 -242.764112) (xy 338.415873 -242.813464) (xy 338.419921 -242.864102) (xy 338.419919 -242.864132)
			(xy 338.724743 -242.864132) (xy 338.728838 -242.813404) (xy 338.741017 -242.76399) (xy 338.760965 -242.71717)
			(xy 338.788166 -242.674156) (xy 338.821914 -242.636062) (xy 338.861336 -242.603875) (xy 338.90541 -242.578429)
			(xy 338.952996 -242.560382) (xy 339.00286 -242.550202) (xy 339.053712 -242.548153) (xy 339.104233 -242.554287)
			(xy 339.153117 -242.568447) (xy 339.199096 -242.590264) (xy 339.24098 -242.619174) (xy 339.277684 -242.654429)
			(xy 339.308257 -242.695115) (xy 339.331908 -242.740178) (xy 339.348024 -242.788452) (xy 339.356188 -242.838686)
			(xy 339.3567 -242.864132) (xy 339.664797 -242.864132) (xy 339.668892 -242.813404) (xy 339.681071 -242.76399)
			(xy 339.701019 -242.71717) (xy 339.72822 -242.674156) (xy 339.761968 -242.636062) (xy 339.80139 -242.603875)
			(xy 339.845464 -242.578429) (xy 339.89305 -242.560382) (xy 339.942914 -242.550202) (xy 339.993766 -242.548153)
			(xy 340.044287 -242.554287) (xy 340.093171 -242.568447) (xy 340.13915 -242.590264) (xy 340.181034 -242.619174)
			(xy 340.217738 -242.654429) (xy 340.248311 -242.695115) (xy 340.271962 -242.740178) (xy 340.288078 -242.788452)
			(xy 340.296242 -242.838686) (xy 340.296754 -242.864132) (xy 340.296251 -242.889121) (xy 340.603568 -242.889121)
			(xy 340.603568 -242.839143) (xy 340.611387 -242.78978) (xy 340.626831 -242.742248) (xy 340.649521 -242.697716)
			(xy 340.678897 -242.657283) (xy 340.714237 -242.621943) (xy 340.75467 -242.592567) (xy 340.799202 -242.569877)
			(xy 340.846734 -242.554433) (xy 340.896097 -242.546614) (xy 340.946075 -242.546614) (xy 340.995438 -242.554433)
			(xy 341.04297 -242.569877) (xy 341.087502 -242.592567) (xy 341.127935 -242.621943) (xy 341.163275 -242.657283)
			(xy 341.192651 -242.697716) (xy 341.215341 -242.742248) (xy 341.230785 -242.78978) (xy 341.238604 -242.839143)
			(xy 341.239094 -242.864132) (xy 341.544905 -242.864132) (xy 341.549 -242.813404) (xy 341.561179 -242.76399)
			(xy 341.581127 -242.71717) (xy 341.608328 -242.674156) (xy 341.642076 -242.636062) (xy 341.681498 -242.603875)
			(xy 341.725572 -242.578429) (xy 341.773158 -242.560382) (xy 341.823022 -242.550202) (xy 341.873874 -242.548153)
			(xy 341.924395 -242.554287) (xy 341.973279 -242.568447) (xy 342.019258 -242.590264) (xy 342.061142 -242.619174)
			(xy 342.097846 -242.654429) (xy 342.128419 -242.695115) (xy 342.15207 -242.740178) (xy 342.168186 -242.788452)
			(xy 342.17635 -242.838686) (xy 342.176862 -242.864132) (xy 342.176359 -242.889121) (xy 342.483676 -242.889121)
			(xy 342.483676 -242.839143) (xy 342.491495 -242.78978) (xy 342.506939 -242.742248) (xy 342.529629 -242.697716)
			(xy 342.559005 -242.657283) (xy 342.594345 -242.621943) (xy 342.634778 -242.592567) (xy 342.67931 -242.569877)
			(xy 342.726842 -242.554433) (xy 342.776205 -242.546614) (xy 342.826183 -242.546614) (xy 342.875546 -242.554433)
			(xy 342.923078 -242.569877) (xy 342.96761 -242.592567) (xy 343.008043 -242.621943) (xy 343.043383 -242.657283)
			(xy 343.072759 -242.697716) (xy 343.095449 -242.742248) (xy 343.110893 -242.78978) (xy 343.118712 -242.839143)
			(xy 343.119202 -242.864132) (xy 343.424759 -242.864132) (xy 343.428854 -242.813404) (xy 343.441033 -242.76399)
			(xy 343.460981 -242.71717) (xy 343.488182 -242.674156) (xy 343.52193 -242.636062) (xy 343.561352 -242.603875)
			(xy 343.605426 -242.578429) (xy 343.653012 -242.560382) (xy 343.702876 -242.550202) (xy 343.753728 -242.548153)
			(xy 343.804249 -242.554287) (xy 343.853133 -242.568447) (xy 343.899112 -242.590264) (xy 343.940996 -242.619174)
			(xy 343.9777 -242.654429) (xy 344.008273 -242.695115) (xy 344.031924 -242.740178) (xy 344.04804 -242.788452)
			(xy 344.056204 -242.838686) (xy 344.056716 -242.864132) (xy 344.056204 -242.889578) (xy 344.04804 -242.939812)
			(xy 344.031924 -242.988086) (xy 344.008273 -243.033149) (xy 343.9777 -243.073835) (xy 343.940996 -243.10909)
			(xy 343.899112 -243.138) (xy 343.853133 -243.159817) (xy 343.804249 -243.173977) (xy 343.753728 -243.180111)
			(xy 343.702876 -243.178062) (xy 343.653012 -243.167882) (xy 343.605426 -243.149835) (xy 343.561352 -243.124389)
			(xy 343.52193 -243.092202) (xy 343.488182 -243.054108) (xy 343.460981 -243.011094) (xy 343.441033 -242.964274)
			(xy 343.428854 -242.91486) (xy 343.424759 -242.864132) (xy 343.119202 -242.864132) (xy 343.118712 -242.889121)
			(xy 343.110893 -242.938484) (xy 343.095449 -242.986016) (xy 343.072759 -243.030548) (xy 343.043383 -243.070981)
			(xy 343.008043 -243.106321) (xy 342.96761 -243.135697) (xy 342.923078 -243.158387) (xy 342.875546 -243.173831)
			(xy 342.826183 -243.18165) (xy 342.776205 -243.18165) (xy 342.726842 -243.173831) (xy 342.67931 -243.158387)
			(xy 342.634778 -243.135697) (xy 342.594345 -243.106321) (xy 342.559005 -243.070981) (xy 342.529629 -243.030548)
			(xy 342.506939 -242.986016) (xy 342.491495 -242.938484) (xy 342.483676 -242.889121) (xy 342.176359 -242.889121)
			(xy 342.17635 -242.889578) (xy 342.168186 -242.939812) (xy 342.15207 -242.988086) (xy 342.128419 -243.033149)
			(xy 342.097846 -243.073835) (xy 342.061142 -243.10909) (xy 342.019258 -243.138) (xy 341.973279 -243.159817)
			(xy 341.924395 -243.173977) (xy 341.873874 -243.180111) (xy 341.823022 -243.178062) (xy 341.773158 -243.167882)
			(xy 341.725572 -243.149835) (xy 341.681498 -243.124389) (xy 341.642076 -243.092202) (xy 341.608328 -243.054108)
			(xy 341.581127 -243.011094) (xy 341.561179 -242.964274) (xy 341.549 -242.91486) (xy 341.544905 -242.864132)
			(xy 341.239094 -242.864132) (xy 341.238604 -242.889121) (xy 341.230785 -242.938484) (xy 341.215341 -242.986016)
			(xy 341.192651 -243.030548) (xy 341.163275 -243.070981) (xy 341.127935 -243.106321) (xy 341.087502 -243.135697)
			(xy 341.04297 -243.158387) (xy 340.995438 -243.173831) (xy 340.946075 -243.18165) (xy 340.896097 -243.18165)
			(xy 340.846734 -243.173831) (xy 340.799202 -243.158387) (xy 340.75467 -243.135697) (xy 340.714237 -243.106321)
			(xy 340.678897 -243.070981) (xy 340.649521 -243.030548) (xy 340.626831 -242.986016) (xy 340.611387 -242.938484)
			(xy 340.603568 -242.889121) (xy 340.296251 -242.889121) (xy 340.296242 -242.889578) (xy 340.288078 -242.939812)
			(xy 340.271962 -242.988086) (xy 340.248311 -243.033149) (xy 340.217738 -243.073835) (xy 340.181034 -243.10909)
			(xy 340.13915 -243.138) (xy 340.093171 -243.159817) (xy 340.044287 -243.173977) (xy 339.993766 -243.180111)
			(xy 339.942914 -243.178062) (xy 339.89305 -243.167882) (xy 339.845464 -243.149835) (xy 339.80139 -243.124389)
			(xy 339.761968 -243.092202) (xy 339.72822 -243.054108) (xy 339.701019 -243.011094) (xy 339.681071 -242.964274)
			(xy 339.668892 -242.91486) (xy 339.664797 -242.864132) (xy 339.3567 -242.864132) (xy 339.356188 -242.889578)
			(xy 339.348024 -242.939812) (xy 339.331908 -242.988086) (xy 339.308257 -243.033149) (xy 339.277684 -243.073835)
			(xy 339.24098 -243.10909) (xy 339.199096 -243.138) (xy 339.153117 -243.159817) (xy 339.104233 -243.173977)
			(xy 339.053712 -243.180111) (xy 339.00286 -243.178062) (xy 338.952996 -243.167882) (xy 338.90541 -243.149835)
			(xy 338.861336 -243.124389) (xy 338.821914 -243.092202) (xy 338.788166 -243.054108) (xy 338.760965 -243.011094)
			(xy 338.741017 -242.964274) (xy 338.728838 -242.91486) (xy 338.724743 -242.864132) (xy 338.419919 -242.864132)
			(xy 338.415873 -242.91474) (xy 338.40383 -242.964091) (xy 338.3841 -243.010902) (xy 338.357183 -243.053984)
			(xy 338.323763 -243.092242) (xy 338.284689 -243.124705) (xy 338.240954 -243.150547) (xy 338.193669 -243.169113)
			(xy 338.144034 -243.17993) (xy 338.118704 -243.181886) (xy 338.10956 -243.182394) (xy 338.084414 -243.193316)
			(xy 338.079965 -243.195407) (xy 338.071902 -243.20103) (xy 338.068412 -243.204492) (xy 338.026756 -243.247164)
			(xy 338.020303 -243.254383) (xy 338.01299 -243.27229) (xy 338.012532 -243.281962) (xy 338.012532 -243.674138)
			(xy 338.254843 -243.674138) (xy 338.258938 -243.62341) (xy 338.271117 -243.573996) (xy 338.291065 -243.527176)
			(xy 338.318266 -243.484162) (xy 338.352014 -243.446068) (xy 338.391436 -243.413881) (xy 338.43551 -243.388435)
			(xy 338.483096 -243.370388) (xy 338.53296 -243.360208) (xy 338.583812 -243.358159) (xy 338.634333 -243.364293)
			(xy 338.683217 -243.378453) (xy 338.729196 -243.40027) (xy 338.77108 -243.42918) (xy 338.807784 -243.464435)
			(xy 338.838357 -243.505121) (xy 338.862008 -243.550184) (xy 338.878124 -243.598458) (xy 338.886288 -243.648692)
			(xy 338.8868 -243.674138) (xy 338.886297 -243.699127) (xy 339.193614 -243.699127) (xy 339.193614 -243.649149)
			(xy 339.201433 -243.599786) (xy 339.216877 -243.552254) (xy 339.239567 -243.507722) (xy 339.268943 -243.467289)
			(xy 339.304283 -243.431949) (xy 339.344716 -243.402573) (xy 339.389248 -243.379883) (xy 339.43678 -243.364439)
			(xy 339.486143 -243.35662) (xy 339.536121 -243.35662) (xy 339.585484 -243.364439) (xy 339.633016 -243.379883)
			(xy 339.677548 -243.402573) (xy 339.717981 -243.431949) (xy 339.753321 -243.467289) (xy 339.782697 -243.507722)
			(xy 339.805387 -243.552254) (xy 339.820831 -243.599786) (xy 339.82865 -243.649149) (xy 339.82914 -243.674138)
			(xy 340.134951 -243.674138) (xy 340.139046 -243.62341) (xy 340.151225 -243.573996) (xy 340.171173 -243.527176)
			(xy 340.198374 -243.484162) (xy 340.232122 -243.446068) (xy 340.271544 -243.413881) (xy 340.315618 -243.388435)
			(xy 340.363204 -243.370388) (xy 340.413068 -243.360208) (xy 340.46392 -243.358159) (xy 340.514441 -243.364293)
			(xy 340.563325 -243.378453) (xy 340.609304 -243.40027) (xy 340.651188 -243.42918) (xy 340.687892 -243.464435)
			(xy 340.718465 -243.505121) (xy 340.742116 -243.550184) (xy 340.758232 -243.598458) (xy 340.766396 -243.648692)
			(xy 340.766908 -243.674138) (xy 340.766405 -243.699127) (xy 341.073468 -243.699127) (xy 341.073468 -243.649149)
			(xy 341.081287 -243.599786) (xy 341.096731 -243.552254) (xy 341.119421 -243.507722) (xy 341.148797 -243.467289)
			(xy 341.184137 -243.431949) (xy 341.22457 -243.402573) (xy 341.269102 -243.379883) (xy 341.316634 -243.364439)
			(xy 341.365997 -243.35662) (xy 341.415975 -243.35662) (xy 341.465338 -243.364439) (xy 341.51287 -243.379883)
			(xy 341.557402 -243.402573) (xy 341.597835 -243.431949) (xy 341.633175 -243.467289) (xy 341.662551 -243.507722)
			(xy 341.685241 -243.552254) (xy 341.700685 -243.599786) (xy 341.708504 -243.649149) (xy 341.708994 -243.674138)
			(xy 342.014805 -243.674138) (xy 342.0189 -243.62341) (xy 342.031079 -243.573996) (xy 342.051027 -243.527176)
			(xy 342.078228 -243.484162) (xy 342.111976 -243.446068) (xy 342.151398 -243.413881) (xy 342.195472 -243.388435)
			(xy 342.243058 -243.370388) (xy 342.292922 -243.360208) (xy 342.343774 -243.358159) (xy 342.394295 -243.364293)
			(xy 342.443179 -243.378453) (xy 342.489158 -243.40027) (xy 342.531042 -243.42918) (xy 342.567746 -243.464435)
			(xy 342.598319 -243.505121) (xy 342.62197 -243.550184) (xy 342.638086 -243.598458) (xy 342.64625 -243.648692)
			(xy 342.646762 -243.674138) (xy 342.954859 -243.674138) (xy 342.958954 -243.62341) (xy 342.971133 -243.573996)
			(xy 342.991081 -243.527176) (xy 343.018282 -243.484162) (xy 343.05203 -243.446068) (xy 343.091452 -243.413881)
			(xy 343.135526 -243.388435) (xy 343.183112 -243.370388) (xy 343.232976 -243.360208) (xy 343.283828 -243.358159)
			(xy 343.334349 -243.364293) (xy 343.383233 -243.378453) (xy 343.429212 -243.40027) (xy 343.471096 -243.42918)
			(xy 343.5078 -243.464435) (xy 343.538373 -243.505121) (xy 343.562024 -243.550184) (xy 343.57814 -243.598458)
			(xy 343.586304 -243.648692) (xy 343.586816 -243.674138) (xy 343.586304 -243.699584) (xy 343.57814 -243.749818)
			(xy 343.562024 -243.798092) (xy 343.538373 -243.843155) (xy 343.5078 -243.883841) (xy 343.471096 -243.919096)
			(xy 343.429212 -243.948006) (xy 343.383233 -243.969823) (xy 343.334349 -243.983983) (xy 343.283828 -243.990117)
			(xy 343.232976 -243.988068) (xy 343.183112 -243.977888) (xy 343.135526 -243.959841) (xy 343.091452 -243.934395)
			(xy 343.05203 -243.902208) (xy 343.018282 -243.864114) (xy 342.991081 -243.8211) (xy 342.971133 -243.77428)
			(xy 342.958954 -243.724866) (xy 342.954859 -243.674138) (xy 342.646762 -243.674138) (xy 342.64625 -243.699584)
			(xy 342.638086 -243.749818) (xy 342.62197 -243.798092) (xy 342.598319 -243.843155) (xy 342.567746 -243.883841)
			(xy 342.531042 -243.919096) (xy 342.489158 -243.948006) (xy 342.443179 -243.969823) (xy 342.394295 -243.983983)
			(xy 342.343774 -243.990117) (xy 342.292922 -243.988068) (xy 342.243058 -243.977888) (xy 342.195472 -243.959841)
			(xy 342.151398 -243.934395) (xy 342.111976 -243.902208) (xy 342.078228 -243.864114) (xy 342.051027 -243.8211)
			(xy 342.031079 -243.77428) (xy 342.0189 -243.724866) (xy 342.014805 -243.674138) (xy 341.708994 -243.674138)
			(xy 341.708504 -243.699127) (xy 341.700685 -243.74849) (xy 341.685241 -243.796022) (xy 341.662551 -243.840554)
			(xy 341.633175 -243.880987) (xy 341.597835 -243.916327) (xy 341.557402 -243.945703) (xy 341.51287 -243.968393)
			(xy 341.465338 -243.983837) (xy 341.415975 -243.991656) (xy 341.365997 -243.991656) (xy 341.316634 -243.983837)
			(xy 341.269102 -243.968393) (xy 341.22457 -243.945703) (xy 341.184137 -243.916327) (xy 341.148797 -243.880987)
			(xy 341.119421 -243.840554) (xy 341.096731 -243.796022) (xy 341.081287 -243.74849) (xy 341.073468 -243.699127)
			(xy 340.766405 -243.699127) (xy 340.766396 -243.699584) (xy 340.758232 -243.749818) (xy 340.742116 -243.798092)
			(xy 340.718465 -243.843155) (xy 340.687892 -243.883841) (xy 340.651188 -243.919096) (xy 340.609304 -243.948006)
			(xy 340.563325 -243.969823) (xy 340.514441 -243.983983) (xy 340.46392 -243.990117) (xy 340.413068 -243.988068)
			(xy 340.363204 -243.977888) (xy 340.315618 -243.959841) (xy 340.271544 -243.934395) (xy 340.232122 -243.902208)
			(xy 340.198374 -243.864114) (xy 340.171173 -243.8211) (xy 340.151225 -243.77428) (xy 340.139046 -243.724866)
			(xy 340.134951 -243.674138) (xy 339.82914 -243.674138) (xy 339.82865 -243.699127) (xy 339.820831 -243.74849)
			(xy 339.805387 -243.796022) (xy 339.782697 -243.840554) (xy 339.753321 -243.880987) (xy 339.717981 -243.916327)
			(xy 339.677548 -243.945703) (xy 339.633016 -243.968393) (xy 339.585484 -243.983837) (xy 339.536121 -243.991656)
			(xy 339.486143 -243.991656) (xy 339.43678 -243.983837) (xy 339.389248 -243.968393) (xy 339.344716 -243.945703)
			(xy 339.304283 -243.916327) (xy 339.268943 -243.880987) (xy 339.239567 -243.840554) (xy 339.216877 -243.796022)
			(xy 339.201433 -243.74849) (xy 339.193614 -243.699127) (xy 338.886297 -243.699127) (xy 338.886288 -243.699584)
			(xy 338.878124 -243.749818) (xy 338.862008 -243.798092) (xy 338.838357 -243.843155) (xy 338.807784 -243.883841)
			(xy 338.77108 -243.919096) (xy 338.729196 -243.948006) (xy 338.683217 -243.969823) (xy 338.634333 -243.983983)
			(xy 338.583812 -243.990117) (xy 338.53296 -243.988068) (xy 338.483096 -243.977888) (xy 338.43551 -243.959841)
			(xy 338.391436 -243.934395) (xy 338.352014 -243.902208) (xy 338.318266 -243.864114) (xy 338.291065 -243.8211)
			(xy 338.271117 -243.77428) (xy 338.258938 -243.724866) (xy 338.254843 -243.674138) (xy 338.012532 -243.674138)
			(xy 338.012532 -244.066314) (xy 338.01302 -244.07598) (xy 338.020321 -244.093885) (xy 338.026756 -244.101112)
			(xy 338.068412 -244.143784) (xy 338.071907 -244.147241) (xy 338.079964 -244.152871) (xy 338.084414 -244.15496)
			(xy 338.10956 -244.165882) (xy 338.118704 -244.16639) (xy 338.144037 -244.168283) (xy 338.193669 -244.1791)
			(xy 338.240953 -244.197665) (xy 338.284686 -244.223507) (xy 338.323758 -244.255969) (xy 338.357176 -244.294226)
			(xy 338.384091 -244.337307) (xy 338.40382 -244.384117) (xy 338.415862 -244.433466) (xy 338.419909 -244.484102)
			(xy 338.419906 -244.484144) (xy 338.724743 -244.484144) (xy 338.728838 -244.433416) (xy 338.741017 -244.384002)
			(xy 338.760965 -244.337182) (xy 338.788166 -244.294168) (xy 338.821914 -244.256074) (xy 338.861336 -244.223887)
			(xy 338.90541 -244.198441) (xy 338.952996 -244.180394) (xy 339.00286 -244.170214) (xy 339.053712 -244.168165)
			(xy 339.104233 -244.174299) (xy 339.153117 -244.188459) (xy 339.199096 -244.210276) (xy 339.24098 -244.239186)
			(xy 339.277684 -244.274441) (xy 339.308257 -244.315127) (xy 339.331908 -244.36019) (xy 339.348024 -244.408464)
			(xy 339.356188 -244.458698) (xy 339.3567 -244.484144) (xy 339.664797 -244.484144) (xy 339.668892 -244.433416)
			(xy 339.681071 -244.384002) (xy 339.701019 -244.337182) (xy 339.72822 -244.294168) (xy 339.761968 -244.256074)
			(xy 339.80139 -244.223887) (xy 339.845464 -244.198441) (xy 339.89305 -244.180394) (xy 339.942914 -244.170214)
			(xy 339.993766 -244.168165) (xy 340.044287 -244.174299) (xy 340.093171 -244.188459) (xy 340.13915 -244.210276)
			(xy 340.181034 -244.239186) (xy 340.217738 -244.274441) (xy 340.248311 -244.315127) (xy 340.271962 -244.36019)
			(xy 340.288078 -244.408464) (xy 340.296242 -244.458698) (xy 340.296754 -244.484144) (xy 341.544905 -244.484144)
			(xy 341.549 -244.433416) (xy 341.561179 -244.384002) (xy 341.581127 -244.337182) (xy 341.608328 -244.294168)
			(xy 341.642076 -244.256074) (xy 341.681498 -244.223887) (xy 341.725572 -244.198441) (xy 341.773158 -244.180394)
			(xy 341.823022 -244.170214) (xy 341.873874 -244.168165) (xy 341.924395 -244.174299) (xy 341.973279 -244.188459)
			(xy 342.019258 -244.210276) (xy 342.061142 -244.239186) (xy 342.097846 -244.274441) (xy 342.128419 -244.315127)
			(xy 342.15207 -244.36019) (xy 342.168186 -244.408464) (xy 342.17635 -244.458698) (xy 342.176862 -244.484144)
			(xy 342.176359 -244.509133) (xy 342.483676 -244.509133) (xy 342.483676 -244.459155) (xy 342.491495 -244.409792)
			(xy 342.506939 -244.36226) (xy 342.529629 -244.317728) (xy 342.559005 -244.277295) (xy 342.594345 -244.241955)
			(xy 342.634778 -244.212579) (xy 342.67931 -244.189889) (xy 342.726842 -244.174445) (xy 342.776205 -244.166626)
			(xy 342.826183 -244.166626) (xy 342.875546 -244.174445) (xy 342.923078 -244.189889) (xy 342.96761 -244.212579)
			(xy 343.008043 -244.241955) (xy 343.043383 -244.277295) (xy 343.072759 -244.317728) (xy 343.095449 -244.36226)
			(xy 343.110893 -244.409792) (xy 343.118712 -244.459155) (xy 343.119202 -244.484144) (xy 343.424759 -244.484144)
			(xy 343.428854 -244.433416) (xy 343.441033 -244.384002) (xy 343.460981 -244.337182) (xy 343.488182 -244.294168)
			(xy 343.52193 -244.256074) (xy 343.561352 -244.223887) (xy 343.605426 -244.198441) (xy 343.653012 -244.180394)
			(xy 343.702876 -244.170214) (xy 343.753728 -244.168165) (xy 343.804249 -244.174299) (xy 343.853133 -244.188459)
			(xy 343.899112 -244.210276) (xy 343.940996 -244.239186) (xy 343.9777 -244.274441) (xy 344.008273 -244.315127)
			(xy 344.031924 -244.36019) (xy 344.04804 -244.408464) (xy 344.056204 -244.458698) (xy 344.056716 -244.484144)
			(xy 344.056204 -244.50959) (xy 344.04804 -244.559824) (xy 344.031924 -244.608098) (xy 344.008273 -244.653161)
			(xy 343.9777 -244.693847) (xy 343.940996 -244.729102) (xy 343.899112 -244.758012) (xy 343.853133 -244.779829)
			(xy 343.804249 -244.793989) (xy 343.753728 -244.800123) (xy 343.702876 -244.798074) (xy 343.653012 -244.787894)
			(xy 343.605426 -244.769847) (xy 343.561352 -244.744401) (xy 343.52193 -244.712214) (xy 343.488182 -244.67412)
			(xy 343.460981 -244.631106) (xy 343.441033 -244.584286) (xy 343.428854 -244.534872) (xy 343.424759 -244.484144)
			(xy 343.119202 -244.484144) (xy 343.118712 -244.509133) (xy 343.110893 -244.558496) (xy 343.095449 -244.606028)
			(xy 343.072759 -244.65056) (xy 343.043383 -244.690993) (xy 343.008043 -244.726333) (xy 342.96761 -244.755709)
			(xy 342.923078 -244.778399) (xy 342.875546 -244.793843) (xy 342.826183 -244.801662) (xy 342.776205 -244.801662)
			(xy 342.726842 -244.793843) (xy 342.67931 -244.778399) (xy 342.634778 -244.755709) (xy 342.594345 -244.726333)
			(xy 342.559005 -244.690993) (xy 342.529629 -244.65056) (xy 342.506939 -244.606028) (xy 342.491495 -244.558496)
			(xy 342.483676 -244.509133) (xy 342.176359 -244.509133) (xy 342.17635 -244.50959) (xy 342.168186 -244.559824)
			(xy 342.15207 -244.608098) (xy 342.128419 -244.653161) (xy 342.097846 -244.693847) (xy 342.061142 -244.729102)
			(xy 342.019258 -244.758012) (xy 341.973279 -244.779829) (xy 341.924395 -244.793989) (xy 341.873874 -244.800123)
			(xy 341.823022 -244.798074) (xy 341.773158 -244.787894) (xy 341.725572 -244.769847) (xy 341.681498 -244.744401)
			(xy 341.642076 -244.712214) (xy 341.608328 -244.67412) (xy 341.581127 -244.631106) (xy 341.561179 -244.584286)
			(xy 341.549 -244.534872) (xy 341.544905 -244.484144) (xy 340.296754 -244.484144) (xy 340.296242 -244.50959)
			(xy 340.288078 -244.559824) (xy 340.271962 -244.608098) (xy 340.248311 -244.653161) (xy 340.217738 -244.693847)
			(xy 340.181034 -244.729102) (xy 340.13915 -244.758012) (xy 340.093171 -244.779829) (xy 340.044287 -244.793989)
			(xy 339.993766 -244.800123) (xy 339.942914 -244.798074) (xy 339.89305 -244.787894) (xy 339.845464 -244.769847)
			(xy 339.80139 -244.744401) (xy 339.761968 -244.712214) (xy 339.72822 -244.67412) (xy 339.701019 -244.631106)
			(xy 339.681071 -244.584286) (xy 339.668892 -244.534872) (xy 339.664797 -244.484144) (xy 339.3567 -244.484144)
			(xy 339.356188 -244.50959) (xy 339.348024 -244.559824) (xy 339.331908 -244.608098) (xy 339.308257 -244.653161)
			(xy 339.277684 -244.693847) (xy 339.24098 -244.729102) (xy 339.199096 -244.758012) (xy 339.153117 -244.779829)
			(xy 339.104233 -244.793989) (xy 339.053712 -244.800123) (xy 339.00286 -244.798074) (xy 338.952996 -244.787894)
			(xy 338.90541 -244.769847) (xy 338.861336 -244.744401) (xy 338.821914 -244.712214) (xy 338.788166 -244.67412)
			(xy 338.760965 -244.631106) (xy 338.741017 -244.584286) (xy 338.728838 -244.534872) (xy 338.724743 -244.484144)
			(xy 338.419906 -244.484144) (xy 338.415861 -244.534738) (xy 338.403819 -244.584088) (xy 338.384089 -244.630897)
			(xy 338.357173 -244.673978) (xy 338.323754 -244.712234) (xy 338.284682 -244.744696) (xy 338.240948 -244.770537)
			(xy 338.193665 -244.789101) (xy 338.144032 -244.799918) (xy 338.118704 -244.801898) (xy 338.10956 -244.802406)
			(xy 338.084414 -244.813328) (xy 338.079965 -244.815419) (xy 338.071903 -244.821043) (xy 338.068412 -244.824504)
			(xy 338.026756 -244.867176) (xy 338.020305 -244.874395) (xy 338.012996 -244.892303) (xy 338.012532 -244.901974)
			(xy 338.012532 -245.29415) (xy 338.254843 -245.29415) (xy 338.258938 -245.243422) (xy 338.271117 -245.194008)
			(xy 338.291065 -245.147188) (xy 338.318266 -245.104174) (xy 338.352014 -245.06608) (xy 338.391436 -245.033893)
			(xy 338.43551 -245.008447) (xy 338.483096 -244.9904) (xy 338.53296 -244.98022) (xy 338.583812 -244.978171)
			(xy 338.634333 -244.984305) (xy 338.683217 -244.998465) (xy 338.729196 -245.020282) (xy 338.77108 -245.049192)
			(xy 338.807784 -245.084447) (xy 338.838357 -245.125133) (xy 338.862008 -245.170196) (xy 338.878124 -245.21847)
			(xy 338.886288 -245.268704) (xy 338.8868 -245.29415) (xy 338.886297 -245.319139) (xy 339.193614 -245.319139)
			(xy 339.193614 -245.269161) (xy 339.201433 -245.219798) (xy 339.216877 -245.172266) (xy 339.239567 -245.127734)
			(xy 339.268943 -245.087301) (xy 339.304283 -245.051961) (xy 339.344716 -245.022585) (xy 339.389248 -244.999895)
			(xy 339.43678 -244.984451) (xy 339.486143 -244.976632) (xy 339.536121 -244.976632) (xy 339.585484 -244.984451)
			(xy 339.633016 -244.999895) (xy 339.677548 -245.022585) (xy 339.717981 -245.051961) (xy 339.753321 -245.087301)
			(xy 339.782697 -245.127734) (xy 339.805387 -245.172266) (xy 339.820831 -245.219798) (xy 339.82865 -245.269161)
			(xy 339.82914 -245.29415) (xy 340.134951 -245.29415) (xy 340.139046 -245.243422) (xy 340.151225 -245.194008)
			(xy 340.171173 -245.147188) (xy 340.198374 -245.104174) (xy 340.232122 -245.06608) (xy 340.271544 -245.033893)
			(xy 340.315618 -245.008447) (xy 340.363204 -244.9904) (xy 340.413068 -244.98022) (xy 340.46392 -244.978171)
			(xy 340.514441 -244.984305) (xy 340.563325 -244.998465) (xy 340.609304 -245.020282) (xy 340.651188 -245.049192)
			(xy 340.687892 -245.084447) (xy 340.718465 -245.125133) (xy 340.742116 -245.170196) (xy 340.758232 -245.21847)
			(xy 340.766396 -245.268704) (xy 340.766908 -245.29415) (xy 340.766405 -245.319139) (xy 341.073468 -245.319139)
			(xy 341.073468 -245.269161) (xy 341.081287 -245.219798) (xy 341.096731 -245.172266) (xy 341.119421 -245.127734)
			(xy 341.148797 -245.087301) (xy 341.184137 -245.051961) (xy 341.22457 -245.022585) (xy 341.269102 -244.999895)
			(xy 341.316634 -244.984451) (xy 341.365997 -244.976632) (xy 341.415975 -244.976632) (xy 341.465338 -244.984451)
			(xy 341.51287 -244.999895) (xy 341.557402 -245.022585) (xy 341.597835 -245.051961) (xy 341.633175 -245.087301)
			(xy 341.662551 -245.127734) (xy 341.685241 -245.172266) (xy 341.700685 -245.219798) (xy 341.708504 -245.269161)
			(xy 341.708994 -245.29415) (xy 342.014805 -245.29415) (xy 342.0189 -245.243422) (xy 342.031079 -245.194008)
			(xy 342.051027 -245.147188) (xy 342.078228 -245.104174) (xy 342.111976 -245.06608) (xy 342.151398 -245.033893)
			(xy 342.195472 -245.008447) (xy 342.243058 -244.9904) (xy 342.292922 -244.98022) (xy 342.343774 -244.978171)
			(xy 342.394295 -244.984305) (xy 342.443179 -244.998465) (xy 342.489158 -245.020282) (xy 342.531042 -245.049192)
			(xy 342.567746 -245.084447) (xy 342.598319 -245.125133) (xy 342.62197 -245.170196) (xy 342.638086 -245.21847)
			(xy 342.64625 -245.268704) (xy 342.646762 -245.29415) (xy 342.954859 -245.29415) (xy 342.958954 -245.243422)
			(xy 342.971133 -245.194008) (xy 342.991081 -245.147188) (xy 343.018282 -245.104174) (xy 343.05203 -245.06608)
			(xy 343.091452 -245.033893) (xy 343.135526 -245.008447) (xy 343.183112 -244.9904) (xy 343.232976 -244.98022)
			(xy 343.283828 -244.978171) (xy 343.334349 -244.984305) (xy 343.383233 -244.998465) (xy 343.429212 -245.020282)
			(xy 343.471096 -245.049192) (xy 343.5078 -245.084447) (xy 343.538373 -245.125133) (xy 343.562024 -245.170196)
			(xy 343.57814 -245.21847) (xy 343.586304 -245.268704) (xy 343.586816 -245.29415) (xy 343.586313 -245.319139)
			(xy 343.89363 -245.319139) (xy 343.89363 -245.269161) (xy 343.901449 -245.219798) (xy 343.916893 -245.172266)
			(xy 343.939583 -245.127734) (xy 343.968959 -245.087301) (xy 344.004299 -245.051961) (xy 344.044732 -245.022585)
			(xy 344.089264 -244.999895) (xy 344.136796 -244.984451) (xy 344.186159 -244.976632) (xy 344.236137 -244.976632)
			(xy 344.2855 -244.984451) (xy 344.333032 -244.999895) (xy 344.377564 -245.022585) (xy 344.417997 -245.051961)
			(xy 344.453337 -245.087301) (xy 344.482713 -245.127734) (xy 344.505403 -245.172266) (xy 344.520847 -245.219798)
			(xy 344.528666 -245.269161) (xy 344.529156 -245.29415) (xy 344.528666 -245.319139) (xy 344.520847 -245.368502)
			(xy 344.505403 -245.416034) (xy 344.482713 -245.460566) (xy 344.453337 -245.500999) (xy 344.417997 -245.536339)
			(xy 344.377564 -245.565715) (xy 344.333032 -245.588405) (xy 344.2855 -245.603849) (xy 344.236137 -245.611668)
			(xy 344.186159 -245.611668) (xy 344.136796 -245.603849) (xy 344.089264 -245.588405) (xy 344.044732 -245.565715)
			(xy 344.004299 -245.536339) (xy 343.968959 -245.500999) (xy 343.939583 -245.460566) (xy 343.916893 -245.416034)
			(xy 343.901449 -245.368502) (xy 343.89363 -245.319139) (xy 343.586313 -245.319139) (xy 343.586304 -245.319596)
			(xy 343.57814 -245.36983) (xy 343.562024 -245.418104) (xy 343.538373 -245.463167) (xy 343.5078 -245.503853)
			(xy 343.471096 -245.539108) (xy 343.429212 -245.568018) (xy 343.383233 -245.589835) (xy 343.334349 -245.603995)
			(xy 343.283828 -245.610129) (xy 343.232976 -245.60808) (xy 343.183112 -245.5979) (xy 343.135526 -245.579853)
			(xy 343.091452 -245.554407) (xy 343.05203 -245.52222) (xy 343.018282 -245.484126) (xy 342.991081 -245.441112)
			(xy 342.971133 -245.394292) (xy 342.958954 -245.344878) (xy 342.954859 -245.29415) (xy 342.646762 -245.29415)
			(xy 342.64625 -245.319596) (xy 342.638086 -245.36983) (xy 342.62197 -245.418104) (xy 342.598319 -245.463167)
			(xy 342.567746 -245.503853) (xy 342.531042 -245.539108) (xy 342.489158 -245.568018) (xy 342.443179 -245.589835)
			(xy 342.394295 -245.603995) (xy 342.343774 -245.610129) (xy 342.292922 -245.60808) (xy 342.243058 -245.5979)
			(xy 342.195472 -245.579853) (xy 342.151398 -245.554407) (xy 342.111976 -245.52222) (xy 342.078228 -245.484126)
			(xy 342.051027 -245.441112) (xy 342.031079 -245.394292) (xy 342.0189 -245.344878) (xy 342.014805 -245.29415)
			(xy 341.708994 -245.29415) (xy 341.708504 -245.319139) (xy 341.700685 -245.368502) (xy 341.685241 -245.416034)
			(xy 341.662551 -245.460566) (xy 341.633175 -245.500999) (xy 341.597835 -245.536339) (xy 341.557402 -245.565715)
			(xy 341.51287 -245.588405) (xy 341.465338 -245.603849) (xy 341.415975 -245.611668) (xy 341.365997 -245.611668)
			(xy 341.316634 -245.603849) (xy 341.269102 -245.588405) (xy 341.22457 -245.565715) (xy 341.184137 -245.536339)
			(xy 341.148797 -245.500999) (xy 341.119421 -245.460566) (xy 341.096731 -245.416034) (xy 341.081287 -245.368502)
			(xy 341.073468 -245.319139) (xy 340.766405 -245.319139) (xy 340.766396 -245.319596) (xy 340.758232 -245.36983)
			(xy 340.742116 -245.418104) (xy 340.718465 -245.463167) (xy 340.687892 -245.503853) (xy 340.651188 -245.539108)
			(xy 340.609304 -245.568018) (xy 340.563325 -245.589835) (xy 340.514441 -245.603995) (xy 340.46392 -245.610129)
			(xy 340.413068 -245.60808) (xy 340.363204 -245.5979) (xy 340.315618 -245.579853) (xy 340.271544 -245.554407)
			(xy 340.232122 -245.52222) (xy 340.198374 -245.484126) (xy 340.171173 -245.441112) (xy 340.151225 -245.394292)
			(xy 340.139046 -245.344878) (xy 340.134951 -245.29415) (xy 339.82914 -245.29415) (xy 339.82865 -245.319139)
			(xy 339.820831 -245.368502) (xy 339.805387 -245.416034) (xy 339.782697 -245.460566) (xy 339.753321 -245.500999)
			(xy 339.717981 -245.536339) (xy 339.677548 -245.565715) (xy 339.633016 -245.588405) (xy 339.585484 -245.603849)
			(xy 339.536121 -245.611668) (xy 339.486143 -245.611668) (xy 339.43678 -245.603849) (xy 339.389248 -245.588405)
			(xy 339.344716 -245.565715) (xy 339.304283 -245.536339) (xy 339.268943 -245.500999) (xy 339.239567 -245.460566)
			(xy 339.216877 -245.416034) (xy 339.201433 -245.368502) (xy 339.193614 -245.319139) (xy 338.886297 -245.319139)
			(xy 338.886288 -245.319596) (xy 338.878124 -245.36983) (xy 338.862008 -245.418104) (xy 338.838357 -245.463167)
			(xy 338.807784 -245.503853) (xy 338.77108 -245.539108) (xy 338.729196 -245.568018) (xy 338.683217 -245.589835)
			(xy 338.634333 -245.603995) (xy 338.583812 -245.610129) (xy 338.53296 -245.60808) (xy 338.483096 -245.5979)
			(xy 338.43551 -245.579853) (xy 338.391436 -245.554407) (xy 338.352014 -245.52222) (xy 338.318266 -245.484126)
			(xy 338.291065 -245.441112) (xy 338.271117 -245.394292) (xy 338.258938 -245.344878) (xy 338.254843 -245.29415)
			(xy 338.012532 -245.29415) (xy 338.012532 -245.686326) (xy 338.013022 -245.695991) (xy 338.020327 -245.713893)
			(xy 338.026756 -245.721124) (xy 338.068412 -245.763796) (xy 338.071907 -245.767253) (xy 338.079965 -245.772881)
			(xy 338.084414 -245.774972) (xy 338.10956 -245.785894) (xy 338.118704 -245.786402) (xy 338.144044 -245.788295)
			(xy 338.19369 -245.799114) (xy 338.240987 -245.817684) (xy 338.284732 -245.843533) (xy 338.323816 -245.876003)
			(xy 338.357243 -245.91427) (xy 338.384167 -245.957362) (xy 338.403902 -246.004185) (xy 338.415948 -246.053548)
			(xy 338.419994 -246.104156) (xy 338.724743 -246.104156) (xy 338.728838 -246.053428) (xy 338.741017 -246.004014)
			(xy 338.760965 -245.957194) (xy 338.788166 -245.91418) (xy 338.821914 -245.876086) (xy 338.861336 -245.843899)
			(xy 338.90541 -245.818453) (xy 338.952996 -245.800406) (xy 339.00286 -245.790226) (xy 339.053712 -245.788177)
			(xy 339.104233 -245.794311) (xy 339.153117 -245.808471) (xy 339.199096 -245.830288) (xy 339.24098 -245.859198)
			(xy 339.277684 -245.894453) (xy 339.308257 -245.935139) (xy 339.331908 -245.980202) (xy 339.348024 -246.028476)
			(xy 339.356188 -246.07871) (xy 339.3567 -246.104156) (xy 339.664797 -246.104156) (xy 339.668892 -246.053428)
			(xy 339.681071 -246.004014) (xy 339.701019 -245.957194) (xy 339.72822 -245.91418) (xy 339.761968 -245.876086)
			(xy 339.80139 -245.843899) (xy 339.845464 -245.818453) (xy 339.89305 -245.800406) (xy 339.942914 -245.790226)
			(xy 339.993766 -245.788177) (xy 340.044287 -245.794311) (xy 340.093171 -245.808471) (xy 340.13915 -245.830288)
			(xy 340.181034 -245.859198) (xy 340.217738 -245.894453) (xy 340.248311 -245.935139) (xy 340.271962 -245.980202)
			(xy 340.288078 -246.028476) (xy 340.296242 -246.07871) (xy 340.296754 -246.104156) (xy 340.296251 -246.129145)
			(xy 340.603568 -246.129145) (xy 340.603568 -246.079167) (xy 340.611387 -246.029804) (xy 340.626831 -245.982272)
			(xy 340.649521 -245.93774) (xy 340.678897 -245.897307) (xy 340.714237 -245.861967) (xy 340.75467 -245.832591)
			(xy 340.799202 -245.809901) (xy 340.846734 -245.794457) (xy 340.896097 -245.786638) (xy 340.946075 -245.786638)
			(xy 340.995438 -245.794457) (xy 341.04297 -245.809901) (xy 341.087502 -245.832591) (xy 341.127935 -245.861967)
			(xy 341.163275 -245.897307) (xy 341.192651 -245.93774) (xy 341.215341 -245.982272) (xy 341.230785 -246.029804)
			(xy 341.238604 -246.079167) (xy 341.239094 -246.104156) (xy 341.544905 -246.104156) (xy 341.549 -246.053428)
			(xy 341.561179 -246.004014) (xy 341.581127 -245.957194) (xy 341.608328 -245.91418) (xy 341.642076 -245.876086)
			(xy 341.681498 -245.843899) (xy 341.725572 -245.818453) (xy 341.773158 -245.800406) (xy 341.823022 -245.790226)
			(xy 341.873874 -245.788177) (xy 341.924395 -245.794311) (xy 341.973279 -245.808471) (xy 342.019258 -245.830288)
			(xy 342.061142 -245.859198) (xy 342.097846 -245.894453) (xy 342.128419 -245.935139) (xy 342.15207 -245.980202)
			(xy 342.168186 -246.028476) (xy 342.17635 -246.07871) (xy 342.176862 -246.104156) (xy 342.176359 -246.129145)
			(xy 342.483676 -246.129145) (xy 342.483676 -246.079167) (xy 342.491495 -246.029804) (xy 342.506939 -245.982272)
			(xy 342.529629 -245.93774) (xy 342.559005 -245.897307) (xy 342.594345 -245.861967) (xy 342.634778 -245.832591)
			(xy 342.67931 -245.809901) (xy 342.726842 -245.794457) (xy 342.776205 -245.786638) (xy 342.826183 -245.786638)
			(xy 342.875546 -245.794457) (xy 342.923078 -245.809901) (xy 342.96761 -245.832591) (xy 343.008043 -245.861967)
			(xy 343.043383 -245.897307) (xy 343.072759 -245.93774) (xy 343.095449 -245.982272) (xy 343.110893 -246.029804)
			(xy 343.118712 -246.079167) (xy 343.119202 -246.104156) (xy 343.424759 -246.104156) (xy 343.428854 -246.053428)
			(xy 343.441033 -246.004014) (xy 343.460981 -245.957194) (xy 343.488182 -245.91418) (xy 343.52193 -245.876086)
			(xy 343.561352 -245.843899) (xy 343.605426 -245.818453) (xy 343.653012 -245.800406) (xy 343.702876 -245.790226)
			(xy 343.753728 -245.788177) (xy 343.804249 -245.794311) (xy 343.853133 -245.808471) (xy 343.899112 -245.830288)
			(xy 343.940996 -245.859198) (xy 343.9777 -245.894453) (xy 344.008273 -245.935139) (xy 344.031924 -245.980202)
			(xy 344.04804 -246.028476) (xy 344.056204 -246.07871) (xy 344.056716 -246.104156) (xy 344.056204 -246.129602)
			(xy 344.04804 -246.179836) (xy 344.031924 -246.22811) (xy 344.008273 -246.273173) (xy 343.9777 -246.313859)
			(xy 343.940996 -246.349114) (xy 343.899112 -246.378024) (xy 343.853133 -246.399841) (xy 343.804249 -246.414001)
			(xy 343.753728 -246.420135) (xy 343.702876 -246.418086) (xy 343.653012 -246.407906) (xy 343.605426 -246.389859)
			(xy 343.561352 -246.364413) (xy 343.52193 -246.332226) (xy 343.488182 -246.294132) (xy 343.460981 -246.251118)
			(xy 343.441033 -246.204298) (xy 343.428854 -246.154884) (xy 343.424759 -246.104156) (xy 343.119202 -246.104156)
			(xy 343.118712 -246.129145) (xy 343.110893 -246.178508) (xy 343.095449 -246.22604) (xy 343.072759 -246.270572)
			(xy 343.043383 -246.311005) (xy 343.008043 -246.346345) (xy 342.96761 -246.375721) (xy 342.923078 -246.398411)
			(xy 342.875546 -246.413855) (xy 342.826183 -246.421674) (xy 342.776205 -246.421674) (xy 342.726842 -246.413855)
			(xy 342.67931 -246.398411) (xy 342.634778 -246.375721) (xy 342.594345 -246.346345) (xy 342.559005 -246.311005)
			(xy 342.529629 -246.270572) (xy 342.506939 -246.22604) (xy 342.491495 -246.178508) (xy 342.483676 -246.129145)
			(xy 342.176359 -246.129145) (xy 342.17635 -246.129602) (xy 342.168186 -246.179836) (xy 342.15207 -246.22811)
			(xy 342.128419 -246.273173) (xy 342.097846 -246.313859) (xy 342.061142 -246.349114) (xy 342.019258 -246.378024)
			(xy 341.973279 -246.399841) (xy 341.924395 -246.414001) (xy 341.873874 -246.420135) (xy 341.823022 -246.418086)
			(xy 341.773158 -246.407906) (xy 341.725572 -246.389859) (xy 341.681498 -246.364413) (xy 341.642076 -246.332226)
			(xy 341.608328 -246.294132) (xy 341.581127 -246.251118) (xy 341.561179 -246.204298) (xy 341.549 -246.154884)
			(xy 341.544905 -246.104156) (xy 341.239094 -246.104156) (xy 341.238604 -246.129145) (xy 341.230785 -246.178508)
			(xy 341.215341 -246.22604) (xy 341.192651 -246.270572) (xy 341.163275 -246.311005) (xy 341.127935 -246.346345)
			(xy 341.087502 -246.375721) (xy 341.04297 -246.398411) (xy 340.995438 -246.413855) (xy 340.946075 -246.421674)
			(xy 340.896097 -246.421674) (xy 340.846734 -246.413855) (xy 340.799202 -246.398411) (xy 340.75467 -246.375721)
			(xy 340.714237 -246.346345) (xy 340.678897 -246.311005) (xy 340.649521 -246.270572) (xy 340.626831 -246.22604)
			(xy 340.611387 -246.178508) (xy 340.603568 -246.129145) (xy 340.296251 -246.129145) (xy 340.296242 -246.129602)
			(xy 340.288078 -246.179836) (xy 340.271962 -246.22811) (xy 340.248311 -246.273173) (xy 340.217738 -246.313859)
			(xy 340.181034 -246.349114) (xy 340.13915 -246.378024) (xy 340.093171 -246.399841) (xy 340.044287 -246.414001)
			(xy 339.993766 -246.420135) (xy 339.942914 -246.418086) (xy 339.89305 -246.407906) (xy 339.845464 -246.389859)
			(xy 339.80139 -246.364413) (xy 339.761968 -246.332226) (xy 339.72822 -246.294132) (xy 339.701019 -246.251118)
			(xy 339.681071 -246.204298) (xy 339.668892 -246.154884) (xy 339.664797 -246.104156) (xy 339.3567 -246.104156)
			(xy 339.356188 -246.129602) (xy 339.348024 -246.179836) (xy 339.331908 -246.22811) (xy 339.308257 -246.273173)
			(xy 339.277684 -246.313859) (xy 339.24098 -246.349114) (xy 339.199096 -246.378024) (xy 339.153117 -246.399841)
			(xy 339.104233 -246.414001) (xy 339.053712 -246.420135) (xy 339.00286 -246.418086) (xy 338.952996 -246.407906)
			(xy 338.90541 -246.389859) (xy 338.861336 -246.364413) (xy 338.821914 -246.332226) (xy 338.788166 -246.294132)
			(xy 338.760965 -246.251118) (xy 338.741017 -246.204298) (xy 338.728838 -246.154884) (xy 338.724743 -246.104156)
			(xy 338.419994 -246.104156) (xy 338.419997 -246.104198) (xy 338.415948 -246.154848) (xy 338.403904 -246.204211)
			(xy 338.384169 -246.251033) (xy 338.357246 -246.294126) (xy 338.323819 -246.332394) (xy 338.284736 -246.364865)
			(xy 338.240991 -246.390714) (xy 338.193695 -246.409284) (xy 338.144049 -246.420104) (xy 338.118704 -246.42191)
			(xy 338.10956 -246.422418) (xy 338.084414 -246.43334) (xy 338.079965 -246.435432) (xy 338.071904 -246.441056)
			(xy 338.068412 -246.444516) (xy 338.026756 -246.487188) (xy 338.020292 -246.494403) (xy 338.012951 -246.51231)
			(xy 338.012532 -246.521986) (xy 338.012532 -246.914162) (xy 338.254843 -246.914162) (xy 338.258938 -246.863434)
			(xy 338.271117 -246.81402) (xy 338.291065 -246.7672) (xy 338.318266 -246.724186) (xy 338.352014 -246.686092)
			(xy 338.391436 -246.653905) (xy 338.43551 -246.628459) (xy 338.483096 -246.610412) (xy 338.53296 -246.600232)
			(xy 338.583812 -246.598183) (xy 338.634333 -246.604317) (xy 338.683217 -246.618477) (xy 338.729196 -246.640294)
			(xy 338.77108 -246.669204) (xy 338.807784 -246.704459) (xy 338.838357 -246.745145) (xy 338.862008 -246.790208)
			(xy 338.878124 -246.838482) (xy 338.886288 -246.888716) (xy 338.8868 -246.914162) (xy 338.886297 -246.939151)
			(xy 339.193614 -246.939151) (xy 339.193614 -246.889173) (xy 339.201433 -246.83981) (xy 339.216877 -246.792278)
			(xy 339.239567 -246.747746) (xy 339.268943 -246.707313) (xy 339.304283 -246.671973) (xy 339.344716 -246.642597)
			(xy 339.389248 -246.619907) (xy 339.43678 -246.604463) (xy 339.486143 -246.596644) (xy 339.536121 -246.596644)
			(xy 339.585484 -246.604463) (xy 339.633016 -246.619907) (xy 339.677548 -246.642597) (xy 339.717981 -246.671973)
			(xy 339.753321 -246.707313) (xy 339.782697 -246.747746) (xy 339.805387 -246.792278) (xy 339.820831 -246.83981)
			(xy 339.82865 -246.889173) (xy 339.82914 -246.914162) (xy 340.134951 -246.914162) (xy 340.139046 -246.863434)
			(xy 340.151225 -246.81402) (xy 340.171173 -246.7672) (xy 340.198374 -246.724186) (xy 340.232122 -246.686092)
			(xy 340.271544 -246.653905) (xy 340.315618 -246.628459) (xy 340.363204 -246.610412) (xy 340.413068 -246.600232)
			(xy 340.46392 -246.598183) (xy 340.514441 -246.604317) (xy 340.563325 -246.618477) (xy 340.609304 -246.640294)
			(xy 340.651188 -246.669204) (xy 340.687892 -246.704459) (xy 340.718465 -246.745145) (xy 340.742116 -246.790208)
			(xy 340.758232 -246.838482) (xy 340.766396 -246.888716) (xy 340.766908 -246.914162) (xy 342.014805 -246.914162)
			(xy 342.0189 -246.863434) (xy 342.031079 -246.81402) (xy 342.051027 -246.7672) (xy 342.078228 -246.724186)
			(xy 342.111976 -246.686092) (xy 342.151398 -246.653905) (xy 342.195472 -246.628459) (xy 342.243058 -246.610412)
			(xy 342.292922 -246.600232) (xy 342.343774 -246.598183) (xy 342.394295 -246.604317) (xy 342.443179 -246.618477)
			(xy 342.489158 -246.640294) (xy 342.531042 -246.669204) (xy 342.567746 -246.704459) (xy 342.598319 -246.745145)
			(xy 342.62197 -246.790208) (xy 342.638086 -246.838482) (xy 342.64625 -246.888716) (xy 342.646762 -246.914162)
			(xy 342.954859 -246.914162) (xy 342.958954 -246.863434) (xy 342.971133 -246.81402) (xy 342.991081 -246.7672)
			(xy 343.018282 -246.724186) (xy 343.05203 -246.686092) (xy 343.091452 -246.653905) (xy 343.135526 -246.628459)
			(xy 343.183112 -246.610412) (xy 343.232976 -246.600232) (xy 343.283828 -246.598183) (xy 343.334349 -246.604317)
			(xy 343.383233 -246.618477) (xy 343.429212 -246.640294) (xy 343.471096 -246.669204) (xy 343.5078 -246.704459)
			(xy 343.538373 -246.745145) (xy 343.562024 -246.790208) (xy 343.57814 -246.838482) (xy 343.586304 -246.888716)
			(xy 343.586816 -246.914162) (xy 343.586304 -246.939608) (xy 343.57814 -246.989842) (xy 343.562024 -247.038116)
			(xy 343.538373 -247.083179) (xy 343.5078 -247.123865) (xy 343.471096 -247.15912) (xy 343.429212 -247.18803)
			(xy 343.383233 -247.209847) (xy 343.334349 -247.224007) (xy 343.283828 -247.230141) (xy 343.232976 -247.228092)
			(xy 343.183112 -247.217912) (xy 343.135526 -247.199865) (xy 343.091452 -247.174419) (xy 343.05203 -247.142232)
			(xy 343.018282 -247.104138) (xy 342.991081 -247.061124) (xy 342.971133 -247.014304) (xy 342.958954 -246.96489)
			(xy 342.954859 -246.914162) (xy 342.646762 -246.914162) (xy 342.64625 -246.939608) (xy 342.638086 -246.989842)
			(xy 342.62197 -247.038116) (xy 342.598319 -247.083179) (xy 342.567746 -247.123865) (xy 342.531042 -247.15912)
			(xy 342.489158 -247.18803) (xy 342.443179 -247.209847) (xy 342.394295 -247.224007) (xy 342.343774 -247.230141)
			(xy 342.292922 -247.228092) (xy 342.243058 -247.217912) (xy 342.195472 -247.199865) (xy 342.151398 -247.174419)
			(xy 342.111976 -247.142232) (xy 342.078228 -247.104138) (xy 342.051027 -247.061124) (xy 342.031079 -247.014304)
			(xy 342.0189 -246.96489) (xy 342.014805 -246.914162) (xy 340.766908 -246.914162) (xy 340.766396 -246.939608)
			(xy 340.758232 -246.989842) (xy 340.742116 -247.038116) (xy 340.718465 -247.083179) (xy 340.687892 -247.123865)
			(xy 340.651188 -247.15912) (xy 340.609304 -247.18803) (xy 340.563325 -247.209847) (xy 340.514441 -247.224007)
			(xy 340.46392 -247.230141) (xy 340.413068 -247.228092) (xy 340.363204 -247.217912) (xy 340.315618 -247.199865)
			(xy 340.271544 -247.174419) (xy 340.232122 -247.142232) (xy 340.198374 -247.104138) (xy 340.171173 -247.061124)
			(xy 340.151225 -247.014304) (xy 340.139046 -246.96489) (xy 340.134951 -246.914162) (xy 339.82914 -246.914162)
			(xy 339.82865 -246.939151) (xy 339.820831 -246.988514) (xy 339.805387 -247.036046) (xy 339.782697 -247.080578)
			(xy 339.753321 -247.121011) (xy 339.717981 -247.156351) (xy 339.677548 -247.185727) (xy 339.633016 -247.208417)
			(xy 339.585484 -247.223861) (xy 339.536121 -247.23168) (xy 339.486143 -247.23168) (xy 339.43678 -247.223861)
			(xy 339.389248 -247.208417) (xy 339.344716 -247.185727) (xy 339.304283 -247.156351) (xy 339.268943 -247.121011)
			(xy 339.239567 -247.080578) (xy 339.216877 -247.036046) (xy 339.201433 -246.988514) (xy 339.193614 -246.939151)
			(xy 338.886297 -246.939151) (xy 338.886288 -246.939608) (xy 338.878124 -246.989842) (xy 338.862008 -247.038116)
			(xy 338.838357 -247.083179) (xy 338.807784 -247.123865) (xy 338.77108 -247.15912) (xy 338.729196 -247.18803)
			(xy 338.683217 -247.209847) (xy 338.634333 -247.224007) (xy 338.583812 -247.230141) (xy 338.53296 -247.228092)
			(xy 338.483096 -247.217912) (xy 338.43551 -247.199865) (xy 338.391436 -247.174419) (xy 338.352014 -247.142232)
			(xy 338.318266 -247.104138) (xy 338.291065 -247.061124) (xy 338.271117 -247.014304) (xy 338.258938 -246.96489)
			(xy 338.254843 -246.914162) (xy 338.012532 -246.914162) (xy 338.012532 -247.306338) (xy 338.013024 -247.316002)
			(xy 338.020332 -247.333901) (xy 338.026756 -247.341136) (xy 338.068412 -247.383808) (xy 338.071908 -247.387264)
			(xy 338.079966 -247.392891) (xy 338.084414 -247.394984) (xy 338.10956 -247.405906) (xy 338.118704 -247.406414)
			(xy 338.144043 -247.408307) (xy 338.193687 -247.419126) (xy 338.240982 -247.437695) (xy 338.284726 -247.463543)
			(xy 338.323808 -247.496012) (xy 338.357234 -247.534278) (xy 338.384157 -247.577368) (xy 338.403891 -247.624189)
			(xy 338.415936 -247.67355) (xy 338.419983 -247.724168) (xy 338.724743 -247.724168) (xy 338.728838 -247.67344)
			(xy 338.741017 -247.624026) (xy 338.760965 -247.577206) (xy 338.788166 -247.534192) (xy 338.821914 -247.496098)
			(xy 338.861336 -247.463911) (xy 338.90541 -247.438465) (xy 338.952996 -247.420418) (xy 339.00286 -247.410238)
			(xy 339.053712 -247.408189) (xy 339.104233 -247.414323) (xy 339.153117 -247.428483) (xy 339.199096 -247.4503)
			(xy 339.24098 -247.47921) (xy 339.277684 -247.514465) (xy 339.308257 -247.555151) (xy 339.331908 -247.600214)
			(xy 339.348024 -247.648488) (xy 339.356188 -247.698722) (xy 339.3567 -247.724168) (xy 339.664797 -247.724168)
			(xy 339.668892 -247.67344) (xy 339.681071 -247.624026) (xy 339.701019 -247.577206) (xy 339.72822 -247.534192)
			(xy 339.761968 -247.496098) (xy 339.80139 -247.463911) (xy 339.845464 -247.438465) (xy 339.89305 -247.420418)
			(xy 339.942914 -247.410238) (xy 339.993766 -247.408189) (xy 340.044287 -247.414323) (xy 340.093171 -247.428483)
			(xy 340.13915 -247.4503) (xy 340.181034 -247.47921) (xy 340.217738 -247.514465) (xy 340.248311 -247.555151)
			(xy 340.271962 -247.600214) (xy 340.288078 -247.648488) (xy 340.296242 -247.698722) (xy 340.296754 -247.724168)
			(xy 340.296251 -247.749157) (xy 340.603568 -247.749157) (xy 340.603568 -247.699179) (xy 340.611387 -247.649816)
			(xy 340.626831 -247.602284) (xy 340.649521 -247.557752) (xy 340.678897 -247.517319) (xy 340.714237 -247.481979)
			(xy 340.75467 -247.452603) (xy 340.799202 -247.429913) (xy 340.846734 -247.414469) (xy 340.896097 -247.40665)
			(xy 340.946075 -247.40665) (xy 340.995438 -247.414469) (xy 341.04297 -247.429913) (xy 341.087502 -247.452603)
			(xy 341.127935 -247.481979) (xy 341.163275 -247.517319) (xy 341.192651 -247.557752) (xy 341.215341 -247.602284)
			(xy 341.230785 -247.649816) (xy 341.238604 -247.699179) (xy 341.239094 -247.724168) (xy 341.544905 -247.724168)
			(xy 341.549 -247.67344) (xy 341.561179 -247.624026) (xy 341.581127 -247.577206) (xy 341.608328 -247.534192)
			(xy 341.642076 -247.496098) (xy 341.681498 -247.463911) (xy 341.725572 -247.438465) (xy 341.773158 -247.420418)
			(xy 341.823022 -247.410238) (xy 341.873874 -247.408189) (xy 341.924395 -247.414323) (xy 341.973279 -247.428483)
			(xy 342.019258 -247.4503) (xy 342.061142 -247.47921) (xy 342.097846 -247.514465) (xy 342.128419 -247.555151)
			(xy 342.15207 -247.600214) (xy 342.168186 -247.648488) (xy 342.17635 -247.698722) (xy 342.176862 -247.724168)
			(xy 342.176359 -247.749157) (xy 342.483676 -247.749157) (xy 342.483676 -247.699179) (xy 342.491495 -247.649816)
			(xy 342.506939 -247.602284) (xy 342.529629 -247.557752) (xy 342.559005 -247.517319) (xy 342.594345 -247.481979)
			(xy 342.634778 -247.452603) (xy 342.67931 -247.429913) (xy 342.726842 -247.414469) (xy 342.776205 -247.40665)
			(xy 342.826183 -247.40665) (xy 342.875546 -247.414469) (xy 342.923078 -247.429913) (xy 342.96761 -247.452603)
			(xy 343.008043 -247.481979) (xy 343.043383 -247.517319) (xy 343.072759 -247.557752) (xy 343.095449 -247.602284)
			(xy 343.110893 -247.649816) (xy 343.118712 -247.699179) (xy 343.119202 -247.724168) (xy 343.424759 -247.724168)
			(xy 343.428854 -247.67344) (xy 343.441033 -247.624026) (xy 343.460981 -247.577206) (xy 343.488182 -247.534192)
			(xy 343.52193 -247.496098) (xy 343.561352 -247.463911) (xy 343.605426 -247.438465) (xy 343.653012 -247.420418)
			(xy 343.702876 -247.410238) (xy 343.753728 -247.408189) (xy 343.804249 -247.414323) (xy 343.853133 -247.428483)
			(xy 343.899112 -247.4503) (xy 343.940996 -247.47921) (xy 343.9777 -247.514465) (xy 344.008273 -247.555151)
			(xy 344.031924 -247.600214) (xy 344.04804 -247.648488) (xy 344.056204 -247.698722) (xy 344.056716 -247.724168)
			(xy 344.056204 -247.749614) (xy 344.04804 -247.799848) (xy 344.031924 -247.848122) (xy 344.008273 -247.893185)
			(xy 343.9777 -247.933871) (xy 343.940996 -247.969126) (xy 343.899112 -247.998036) (xy 343.853133 -248.019853)
			(xy 343.804249 -248.034013) (xy 343.753728 -248.040147) (xy 343.702876 -248.038098) (xy 343.653012 -248.027918)
			(xy 343.605426 -248.009871) (xy 343.561352 -247.984425) (xy 343.52193 -247.952238) (xy 343.488182 -247.914144)
			(xy 343.460981 -247.87113) (xy 343.441033 -247.82431) (xy 343.428854 -247.774896) (xy 343.424759 -247.724168)
			(xy 343.119202 -247.724168) (xy 343.118712 -247.749157) (xy 343.110893 -247.79852) (xy 343.095449 -247.846052)
			(xy 343.072759 -247.890584) (xy 343.043383 -247.931017) (xy 343.008043 -247.966357) (xy 342.96761 -247.995733)
			(xy 342.923078 -248.018423) (xy 342.875546 -248.033867) (xy 342.826183 -248.041686) (xy 342.776205 -248.041686)
			(xy 342.726842 -248.033867) (xy 342.67931 -248.018423) (xy 342.634778 -247.995733) (xy 342.594345 -247.966357)
			(xy 342.559005 -247.931017) (xy 342.529629 -247.890584) (xy 342.506939 -247.846052) (xy 342.491495 -247.79852)
			(xy 342.483676 -247.749157) (xy 342.176359 -247.749157) (xy 342.17635 -247.749614) (xy 342.168186 -247.799848)
			(xy 342.15207 -247.848122) (xy 342.128419 -247.893185) (xy 342.097846 -247.933871) (xy 342.061142 -247.969126)
			(xy 342.019258 -247.998036) (xy 341.973279 -248.019853) (xy 341.924395 -248.034013) (xy 341.873874 -248.040147)
			(xy 341.823022 -248.038098) (xy 341.773158 -248.027918) (xy 341.725572 -248.009871) (xy 341.681498 -247.984425)
			(xy 341.642076 -247.952238) (xy 341.608328 -247.914144) (xy 341.581127 -247.87113) (xy 341.561179 -247.82431)
			(xy 341.549 -247.774896) (xy 341.544905 -247.724168) (xy 341.239094 -247.724168) (xy 341.238604 -247.749157)
			(xy 341.230785 -247.79852) (xy 341.215341 -247.846052) (xy 341.192651 -247.890584) (xy 341.163275 -247.931017)
			(xy 341.127935 -247.966357) (xy 341.087502 -247.995733) (xy 341.04297 -248.018423) (xy 340.995438 -248.033867)
			(xy 340.946075 -248.041686) (xy 340.896097 -248.041686) (xy 340.846734 -248.033867) (xy 340.799202 -248.018423)
			(xy 340.75467 -247.995733) (xy 340.714237 -247.966357) (xy 340.678897 -247.931017) (xy 340.649521 -247.890584)
			(xy 340.626831 -247.846052) (xy 340.611387 -247.79852) (xy 340.603568 -247.749157) (xy 340.296251 -247.749157)
			(xy 340.296242 -247.749614) (xy 340.288078 -247.799848) (xy 340.271962 -247.848122) (xy 340.248311 -247.893185)
			(xy 340.217738 -247.933871) (xy 340.181034 -247.969126) (xy 340.13915 -247.998036) (xy 340.093171 -248.019853)
			(xy 340.044287 -248.034013) (xy 339.993766 -248.040147) (xy 339.942914 -248.038098) (xy 339.89305 -248.027918)
			(xy 339.845464 -248.009871) (xy 339.80139 -247.984425) (xy 339.761968 -247.952238) (xy 339.72822 -247.914144)
			(xy 339.701019 -247.87113) (xy 339.681071 -247.82431) (xy 339.668892 -247.774896) (xy 339.664797 -247.724168)
			(xy 339.3567 -247.724168) (xy 339.356188 -247.749614) (xy 339.348024 -247.799848) (xy 339.331908 -247.848122)
			(xy 339.308257 -247.893185) (xy 339.277684 -247.933871) (xy 339.24098 -247.969126) (xy 339.199096 -247.998036)
			(xy 339.153117 -248.019853) (xy 339.104233 -248.034013) (xy 339.053712 -248.040147) (xy 339.00286 -248.038098)
			(xy 338.952996 -248.027918) (xy 338.90541 -248.009871) (xy 338.861336 -247.984425) (xy 338.821914 -247.952238)
			(xy 338.788166 -247.914144) (xy 338.760965 -247.87113) (xy 338.741017 -247.82431) (xy 338.728838 -247.774896)
			(xy 338.724743 -247.724168) (xy 338.419983 -247.724168) (xy 338.419985 -247.724198) (xy 338.415936 -247.774846)
			(xy 338.403892 -247.824208) (xy 338.384158 -247.871029) (xy 338.357236 -247.914119) (xy 338.32381 -247.952386)
			(xy 338.284729 -247.984855) (xy 338.240985 -248.010703) (xy 338.193691 -248.029273) (xy 338.144047 -248.040093)
			(xy 338.118704 -248.041922) (xy 338.10956 -248.04243) (xy 338.084414 -248.053352) (xy 338.079966 -248.055444)
			(xy 338.071906 -248.06107) (xy 338.068412 -248.064528) (xy 338.026756 -248.1072) (xy 338.020293 -248.114416)
			(xy 338.012957 -248.132322) (xy 338.012532 -248.141998) (xy 338.012532 -248.534174) (xy 338.254843 -248.534174)
			(xy 338.258938 -248.483446) (xy 338.271117 -248.434032) (xy 338.291065 -248.387212) (xy 338.318266 -248.344198)
			(xy 338.352014 -248.306104) (xy 338.391436 -248.273917) (xy 338.43551 -248.248471) (xy 338.483096 -248.230424)
			(xy 338.53296 -248.220244) (xy 338.583812 -248.218195) (xy 338.634333 -248.224329) (xy 338.683217 -248.238489)
			(xy 338.729196 -248.260306) (xy 338.77108 -248.289216) (xy 338.807784 -248.324471) (xy 338.838357 -248.365157)
			(xy 338.862008 -248.41022) (xy 338.878124 -248.458494) (xy 338.886288 -248.508728) (xy 338.8868 -248.534174)
			(xy 338.886297 -248.559163) (xy 339.193614 -248.559163) (xy 339.193614 -248.509185) (xy 339.201433 -248.459822)
			(xy 339.216877 -248.41229) (xy 339.239567 -248.367758) (xy 339.268943 -248.327325) (xy 339.304283 -248.291985)
			(xy 339.344716 -248.262609) (xy 339.389248 -248.239919) (xy 339.43678 -248.224475) (xy 339.486143 -248.216656)
			(xy 339.536121 -248.216656) (xy 339.585484 -248.224475) (xy 339.633016 -248.239919) (xy 339.677548 -248.262609)
			(xy 339.717981 -248.291985) (xy 339.753321 -248.327325) (xy 339.782697 -248.367758) (xy 339.805387 -248.41229)
			(xy 339.820831 -248.459822) (xy 339.82865 -248.509185) (xy 339.82914 -248.534174) (xy 340.134951 -248.534174)
			(xy 340.139046 -248.483446) (xy 340.151225 -248.434032) (xy 340.171173 -248.387212) (xy 340.198374 -248.344198)
			(xy 340.232122 -248.306104) (xy 340.271544 -248.273917) (xy 340.315618 -248.248471) (xy 340.363204 -248.230424)
			(xy 340.413068 -248.220244) (xy 340.46392 -248.218195) (xy 340.514441 -248.224329) (xy 340.563325 -248.238489)
			(xy 340.609304 -248.260306) (xy 340.651188 -248.289216) (xy 340.687892 -248.324471) (xy 340.718465 -248.365157)
			(xy 340.742116 -248.41022) (xy 340.758232 -248.458494) (xy 340.766396 -248.508728) (xy 340.766908 -248.534174)
			(xy 340.766405 -248.559163) (xy 341.073468 -248.559163) (xy 341.073468 -248.509185) (xy 341.081287 -248.459822)
			(xy 341.096731 -248.41229) (xy 341.119421 -248.367758) (xy 341.148797 -248.327325) (xy 341.184137 -248.291985)
			(xy 341.22457 -248.262609) (xy 341.269102 -248.239919) (xy 341.316634 -248.224475) (xy 341.365997 -248.216656)
			(xy 341.415975 -248.216656) (xy 341.465338 -248.224475) (xy 341.51287 -248.239919) (xy 341.557402 -248.262609)
			(xy 341.597835 -248.291985) (xy 341.633175 -248.327325) (xy 341.662551 -248.367758) (xy 341.685241 -248.41229)
			(xy 341.700685 -248.459822) (xy 341.708504 -248.509185) (xy 341.708994 -248.534174) (xy 342.014805 -248.534174)
			(xy 342.0189 -248.483446) (xy 342.031079 -248.434032) (xy 342.051027 -248.387212) (xy 342.078228 -248.344198)
			(xy 342.111976 -248.306104) (xy 342.151398 -248.273917) (xy 342.195472 -248.248471) (xy 342.243058 -248.230424)
			(xy 342.292922 -248.220244) (xy 342.343774 -248.218195) (xy 342.394295 -248.224329) (xy 342.443179 -248.238489)
			(xy 342.489158 -248.260306) (xy 342.531042 -248.289216) (xy 342.567746 -248.324471) (xy 342.598319 -248.365157)
			(xy 342.62197 -248.41022) (xy 342.638086 -248.458494) (xy 342.64625 -248.508728) (xy 342.646762 -248.534174)
			(xy 342.954859 -248.534174) (xy 342.958954 -248.483446) (xy 342.971133 -248.434032) (xy 342.991081 -248.387212)
			(xy 343.018282 -248.344198) (xy 343.05203 -248.306104) (xy 343.091452 -248.273917) (xy 343.135526 -248.248471)
			(xy 343.183112 -248.230424) (xy 343.232976 -248.220244) (xy 343.283828 -248.218195) (xy 343.334349 -248.224329)
			(xy 343.383233 -248.238489) (xy 343.429212 -248.260306) (xy 343.471096 -248.289216) (xy 343.5078 -248.324471)
			(xy 343.538373 -248.365157) (xy 343.562024 -248.41022) (xy 343.57814 -248.458494) (xy 343.586304 -248.508728)
			(xy 343.586816 -248.534174) (xy 343.586304 -248.55962) (xy 343.57814 -248.609854) (xy 343.562024 -248.658128)
			(xy 343.538373 -248.703191) (xy 343.5078 -248.743877) (xy 343.471096 -248.779132) (xy 343.429212 -248.808042)
			(xy 343.383233 -248.829859) (xy 343.334349 -248.844019) (xy 343.283828 -248.850153) (xy 343.232976 -248.848104)
			(xy 343.183112 -248.837924) (xy 343.135526 -248.819877) (xy 343.091452 -248.794431) (xy 343.05203 -248.762244)
			(xy 343.018282 -248.72415) (xy 342.991081 -248.681136) (xy 342.971133 -248.634316) (xy 342.958954 -248.584902)
			(xy 342.954859 -248.534174) (xy 342.646762 -248.534174) (xy 342.64625 -248.55962) (xy 342.638086 -248.609854)
			(xy 342.62197 -248.658128) (xy 342.598319 -248.703191) (xy 342.567746 -248.743877) (xy 342.531042 -248.779132)
			(xy 342.489158 -248.808042) (xy 342.443179 -248.829859) (xy 342.394295 -248.844019) (xy 342.343774 -248.850153)
			(xy 342.292922 -248.848104) (xy 342.243058 -248.837924) (xy 342.195472 -248.819877) (xy 342.151398 -248.794431)
			(xy 342.111976 -248.762244) (xy 342.078228 -248.72415) (xy 342.051027 -248.681136) (xy 342.031079 -248.634316)
			(xy 342.0189 -248.584902) (xy 342.014805 -248.534174) (xy 341.708994 -248.534174) (xy 341.708504 -248.559163)
			(xy 341.700685 -248.608526) (xy 341.685241 -248.656058) (xy 341.662551 -248.70059) (xy 341.633175 -248.741023)
			(xy 341.597835 -248.776363) (xy 341.557402 -248.805739) (xy 341.51287 -248.828429) (xy 341.465338 -248.843873)
			(xy 341.415975 -248.851692) (xy 341.365997 -248.851692) (xy 341.316634 -248.843873) (xy 341.269102 -248.828429)
			(xy 341.22457 -248.805739) (xy 341.184137 -248.776363) (xy 341.148797 -248.741023) (xy 341.119421 -248.70059)
			(xy 341.096731 -248.656058) (xy 341.081287 -248.608526) (xy 341.073468 -248.559163) (xy 340.766405 -248.559163)
			(xy 340.766396 -248.55962) (xy 340.758232 -248.609854) (xy 340.742116 -248.658128) (xy 340.718465 -248.703191)
			(xy 340.687892 -248.743877) (xy 340.651188 -248.779132) (xy 340.609304 -248.808042) (xy 340.563325 -248.829859)
			(xy 340.514441 -248.844019) (xy 340.46392 -248.850153) (xy 340.413068 -248.848104) (xy 340.363204 -248.837924)
			(xy 340.315618 -248.819877) (xy 340.271544 -248.794431) (xy 340.232122 -248.762244) (xy 340.198374 -248.72415)
			(xy 340.171173 -248.681136) (xy 340.151225 -248.634316) (xy 340.139046 -248.584902) (xy 340.134951 -248.534174)
			(xy 339.82914 -248.534174) (xy 339.82865 -248.559163) (xy 339.820831 -248.608526) (xy 339.805387 -248.656058)
			(xy 339.782697 -248.70059) (xy 339.753321 -248.741023) (xy 339.717981 -248.776363) (xy 339.677548 -248.805739)
			(xy 339.633016 -248.828429) (xy 339.585484 -248.843873) (xy 339.536121 -248.851692) (xy 339.486143 -248.851692)
			(xy 339.43678 -248.843873) (xy 339.389248 -248.828429) (xy 339.344716 -248.805739) (xy 339.304283 -248.776363)
			(xy 339.268943 -248.741023) (xy 339.239567 -248.70059) (xy 339.216877 -248.656058) (xy 339.201433 -248.608526)
			(xy 339.193614 -248.559163) (xy 338.886297 -248.559163) (xy 338.886288 -248.55962) (xy 338.878124 -248.609854)
			(xy 338.862008 -248.658128) (xy 338.838357 -248.703191) (xy 338.807784 -248.743877) (xy 338.77108 -248.779132)
			(xy 338.729196 -248.808042) (xy 338.683217 -248.829859) (xy 338.634333 -248.844019) (xy 338.583812 -248.850153)
			(xy 338.53296 -248.848104) (xy 338.483096 -248.837924) (xy 338.43551 -248.819877) (xy 338.391436 -248.794431)
			(xy 338.352014 -248.762244) (xy 338.318266 -248.72415) (xy 338.291065 -248.681136) (xy 338.271117 -248.634316)
			(xy 338.258938 -248.584902) (xy 338.254843 -248.534174) (xy 338.012532 -248.534174) (xy 338.012532 -248.92635)
			(xy 338.013027 -248.936013) (xy 338.020337 -248.953909) (xy 338.026756 -248.961148) (xy 338.068412 -249.00382)
			(xy 338.071908 -249.007275) (xy 338.079967 -249.012901) (xy 338.084414 -249.014996) (xy 338.10956 -249.025918)
			(xy 338.118704 -249.026426) (xy 338.144042 -249.028319) (xy 338.193685 -249.039138) (xy 338.240978 -249.057706)
			(xy 338.28472 -249.083553) (xy 338.3238 -249.116021) (xy 338.357225 -249.154285) (xy 338.384146 -249.197374)
			(xy 338.40388 -249.244193) (xy 338.415924 -249.293553) (xy 338.419973 -249.344199) (xy 338.417977 -249.369169)
			(xy 338.72346 -249.369169) (xy 338.72346 -249.319191) (xy 338.731279 -249.269828) (xy 338.746723 -249.222296)
			(xy 338.769413 -249.177764) (xy 338.798789 -249.137331) (xy 338.834129 -249.101991) (xy 338.874562 -249.072615)
			(xy 338.919094 -249.049925) (xy 338.966626 -249.034481) (xy 339.015989 -249.026662) (xy 339.065967 -249.026662)
			(xy 339.11533 -249.034481) (xy 339.162862 -249.049925) (xy 339.207394 -249.072615) (xy 339.247827 -249.101991)
			(xy 339.283167 -249.137331) (xy 339.312543 -249.177764) (xy 339.335233 -249.222296) (xy 339.350677 -249.269828)
			(xy 339.358496 -249.319191) (xy 339.358986 -249.34418) (xy 339.664797 -249.34418) (xy 339.668892 -249.293452)
			(xy 339.681071 -249.244038) (xy 339.701019 -249.197218) (xy 339.72822 -249.154204) (xy 339.761968 -249.11611)
			(xy 339.80139 -249.083923) (xy 339.845464 -249.058477) (xy 339.89305 -249.04043) (xy 339.942914 -249.03025)
			(xy 339.993766 -249.028201) (xy 340.044287 -249.034335) (xy 340.093171 -249.048495) (xy 340.13915 -249.070312)
			(xy 340.181034 -249.099222) (xy 340.217738 -249.134477) (xy 340.248311 -249.175163) (xy 340.271962 -249.220226)
			(xy 340.288078 -249.2685) (xy 340.296242 -249.318734) (xy 340.296754 -249.34418) (xy 340.296251 -249.369169)
			(xy 341.543622 -249.369169) (xy 341.543622 -249.319191) (xy 341.551441 -249.269828) (xy 341.566885 -249.222296)
			(xy 341.589575 -249.177764) (xy 341.618951 -249.137331) (xy 341.654291 -249.101991) (xy 341.694724 -249.072615)
			(xy 341.739256 -249.049925) (xy 341.786788 -249.034481) (xy 341.836151 -249.026662) (xy 341.886129 -249.026662)
			(xy 341.935492 -249.034481) (xy 341.983024 -249.049925) (xy 342.027556 -249.072615) (xy 342.067989 -249.101991)
			(xy 342.103329 -249.137331) (xy 342.132705 -249.177764) (xy 342.155395 -249.222296) (xy 342.170839 -249.269828)
			(xy 342.178658 -249.319191) (xy 342.179148 -249.34418) (xy 342.178658 -249.369169) (xy 342.483676 -249.369169)
			(xy 342.483676 -249.319191) (xy 342.491495 -249.269828) (xy 342.506939 -249.222296) (xy 342.529629 -249.177764)
			(xy 342.559005 -249.137331) (xy 342.594345 -249.101991) (xy 342.634778 -249.072615) (xy 342.67931 -249.049925)
			(xy 342.726842 -249.034481) (xy 342.776205 -249.026662) (xy 342.826183 -249.026662) (xy 342.875546 -249.034481)
			(xy 342.923078 -249.049925) (xy 342.96761 -249.072615) (xy 343.008043 -249.101991) (xy 343.043383 -249.137331)
			(xy 343.072759 -249.177764) (xy 343.095449 -249.222296) (xy 343.110893 -249.269828) (xy 343.118712 -249.319191)
			(xy 343.119202 -249.34418) (xy 343.118712 -249.369169) (xy 343.110893 -249.418532) (xy 343.095449 -249.466064)
			(xy 343.072759 -249.510596) (xy 343.043383 -249.551029) (xy 343.008043 -249.586369) (xy 342.96761 -249.615745)
			(xy 342.923078 -249.638435) (xy 342.875546 -249.653879) (xy 342.826183 -249.661698) (xy 342.776205 -249.661698)
			(xy 342.726842 -249.653879) (xy 342.67931 -249.638435) (xy 342.634778 -249.615745) (xy 342.594345 -249.586369)
			(xy 342.559005 -249.551029) (xy 342.529629 -249.510596) (xy 342.506939 -249.466064) (xy 342.491495 -249.418532)
			(xy 342.483676 -249.369169) (xy 342.178658 -249.369169) (xy 342.170839 -249.418532) (xy 342.155395 -249.466064)
			(xy 342.132705 -249.510596) (xy 342.103329 -249.551029) (xy 342.067989 -249.586369) (xy 342.027556 -249.615745)
			(xy 341.983024 -249.638435) (xy 341.935492 -249.653879) (xy 341.886129 -249.661698) (xy 341.836151 -249.661698)
			(xy 341.786788 -249.653879) (xy 341.739256 -249.638435) (xy 341.694724 -249.615745) (xy 341.654291 -249.586369)
			(xy 341.618951 -249.551029) (xy 341.589575 -249.510596) (xy 341.566885 -249.466064) (xy 341.551441 -249.418532)
			(xy 341.543622 -249.369169) (xy 340.296251 -249.369169) (xy 340.296242 -249.369626) (xy 340.288078 -249.41986)
			(xy 340.271962 -249.468134) (xy 340.248311 -249.513197) (xy 340.217738 -249.553883) (xy 340.181034 -249.589138)
			(xy 340.13915 -249.618048) (xy 340.093171 -249.639865) (xy 340.044287 -249.654025) (xy 339.993766 -249.660159)
			(xy 339.942914 -249.65811) (xy 339.89305 -249.64793) (xy 339.845464 -249.629883) (xy 339.80139 -249.604437)
			(xy 339.761968 -249.57225) (xy 339.72822 -249.534156) (xy 339.701019 -249.491142) (xy 339.681071 -249.444322)
			(xy 339.668892 -249.394908) (xy 339.664797 -249.34418) (xy 339.358986 -249.34418) (xy 339.358496 -249.369169)
			(xy 339.350677 -249.418532) (xy 339.335233 -249.466064) (xy 339.312543 -249.510596) (xy 339.283167 -249.551029)
			(xy 339.247827 -249.586369) (xy 339.207394 -249.615745) (xy 339.162862 -249.638435) (xy 339.11533 -249.653879)
			(xy 339.065967 -249.661698) (xy 339.015989 -249.661698) (xy 338.966626 -249.653879) (xy 338.919094 -249.638435)
			(xy 338.874562 -249.615745) (xy 338.834129 -249.586369) (xy 338.798789 -249.551029) (xy 338.769413 -249.510596)
			(xy 338.746723 -249.466064) (xy 338.731279 -249.418532) (xy 338.72346 -249.369169) (xy 338.417977 -249.369169)
			(xy 338.415924 -249.394845) (xy 338.40388 -249.444205) (xy 338.384147 -249.491024) (xy 338.357226 -249.534113)
			(xy 338.323801 -249.572378) (xy 338.284721 -249.604846) (xy 338.24098 -249.630693) (xy 338.193687 -249.649262)
			(xy 338.144044 -249.660081) (xy 338.118704 -249.661934) (xy 338.10956 -249.662442) (xy 338.084414 -249.673364)
			(xy 338.079966 -249.675457) (xy 338.071907 -249.681083) (xy 338.068412 -249.68454) (xy 338.026756 -249.727212)
			(xy 338.020295 -249.734428) (xy 338.012963 -249.752335) (xy 338.012532 -249.76201) (xy 338.012532 -250.179175)
			(xy 338.25356 -250.179175) (xy 338.25356 -250.129197) (xy 338.261379 -250.079834) (xy 338.276823 -250.032302)
			(xy 338.299513 -249.98777) (xy 338.328889 -249.947337) (xy 338.364229 -249.911997) (xy 338.404662 -249.882621)
			(xy 338.449194 -249.859931) (xy 338.496726 -249.844487) (xy 338.546089 -249.836668) (xy 338.596067 -249.836668)
			(xy 338.64543 -249.844487) (xy 338.692962 -249.859931) (xy 338.737494 -249.882621) (xy 338.777927 -249.911997)
			(xy 338.813267 -249.947337) (xy 338.842643 -249.98777) (xy 338.865333 -250.032302) (xy 338.880777 -250.079834)
			(xy 338.888596 -250.129197) (xy 338.889086 -250.154186) (xy 338.888596 -250.179175) (xy 339.193614 -250.179175)
			(xy 339.193614 -250.129197) (xy 339.201433 -250.079834) (xy 339.216877 -250.032302) (xy 339.239567 -249.98777)
			(xy 339.268943 -249.947337) (xy 339.304283 -249.911997) (xy 339.344716 -249.882621) (xy 339.389248 -249.859931)
			(xy 339.43678 -249.844487) (xy 339.486143 -249.836668) (xy 339.536121 -249.836668) (xy 339.585484 -249.844487)
			(xy 339.633016 -249.859931) (xy 339.677548 -249.882621) (xy 339.717981 -249.911997) (xy 339.753321 -249.947337)
			(xy 339.782697 -249.98777) (xy 339.805387 -250.032302) (xy 339.820831 -250.079834) (xy 339.82865 -250.129197)
			(xy 339.82914 -250.154186) (xy 340.134951 -250.154186) (xy 340.139046 -250.103458) (xy 340.151225 -250.054044)
			(xy 340.171173 -250.007224) (xy 340.198374 -249.96421) (xy 340.232122 -249.926116) (xy 340.271544 -249.893929)
			(xy 340.315618 -249.868483) (xy 340.363204 -249.850436) (xy 340.413068 -249.840256) (xy 340.46392 -249.838207)
			(xy 340.514441 -249.844341) (xy 340.563325 -249.858501) (xy 340.609304 -249.880318) (xy 340.651188 -249.909228)
			(xy 340.687892 -249.944483) (xy 340.718465 -249.985169) (xy 340.742116 -250.030232) (xy 340.758232 -250.078506)
			(xy 340.766396 -250.12874) (xy 340.766908 -250.154186) (xy 340.766405 -250.179175) (xy 341.073468 -250.179175)
			(xy 341.073468 -250.129197) (xy 341.081287 -250.079834) (xy 341.096731 -250.032302) (xy 341.119421 -249.98777)
			(xy 341.148797 -249.947337) (xy 341.184137 -249.911997) (xy 341.22457 -249.882621) (xy 341.269102 -249.859931)
			(xy 341.316634 -249.844487) (xy 341.365997 -249.836668) (xy 341.415975 -249.836668) (xy 341.465338 -249.844487)
			(xy 341.51287 -249.859931) (xy 341.557402 -249.882621) (xy 341.597835 -249.911997) (xy 341.633175 -249.947337)
			(xy 341.662551 -249.98777) (xy 341.685241 -250.032302) (xy 341.700685 -250.079834) (xy 341.708504 -250.129197)
			(xy 341.708994 -250.154186) (xy 341.708504 -250.179175) (xy 342.013522 -250.179175) (xy 342.013522 -250.129197)
			(xy 342.021341 -250.079834) (xy 342.036785 -250.032302) (xy 342.059475 -249.98777) (xy 342.088851 -249.947337)
			(xy 342.124191 -249.911997) (xy 342.164624 -249.882621) (xy 342.209156 -249.859931) (xy 342.256688 -249.844487)
			(xy 342.306051 -249.836668) (xy 342.356029 -249.836668) (xy 342.405392 -249.844487) (xy 342.452924 -249.859931)
			(xy 342.497456 -249.882621) (xy 342.537889 -249.911997) (xy 342.573229 -249.947337) (xy 342.602605 -249.98777)
			(xy 342.625295 -250.032302) (xy 342.640739 -250.079834) (xy 342.648558 -250.129197) (xy 342.649048 -250.154186)
			(xy 342.954859 -250.154186) (xy 342.958954 -250.103458) (xy 342.971133 -250.054044) (xy 342.991081 -250.007224)
			(xy 343.018282 -249.96421) (xy 343.05203 -249.926116) (xy 343.091452 -249.893929) (xy 343.135526 -249.868483)
			(xy 343.183112 -249.850436) (xy 343.232976 -249.840256) (xy 343.283828 -249.838207) (xy 343.334349 -249.844341)
			(xy 343.383233 -249.858501) (xy 343.429212 -249.880318) (xy 343.471096 -249.909228) (xy 343.5078 -249.944483)
			(xy 343.538373 -249.985169) (xy 343.562024 -250.030232) (xy 343.57814 -250.078506) (xy 343.586304 -250.12874)
			(xy 343.586816 -250.154186) (xy 343.586304 -250.179632) (xy 343.57814 -250.229866) (xy 343.562024 -250.27814)
			(xy 343.538373 -250.323203) (xy 343.5078 -250.363889) (xy 343.471096 -250.399144) (xy 343.429212 -250.428054)
			(xy 343.383233 -250.449871) (xy 343.334349 -250.464031) (xy 343.283828 -250.470165) (xy 343.232976 -250.468116)
			(xy 343.183112 -250.457936) (xy 343.135526 -250.439889) (xy 343.091452 -250.414443) (xy 343.05203 -250.382256)
			(xy 343.018282 -250.344162) (xy 342.991081 -250.301148) (xy 342.971133 -250.254328) (xy 342.958954 -250.204914)
			(xy 342.954859 -250.154186) (xy 342.649048 -250.154186) (xy 342.648558 -250.179175) (xy 342.640739 -250.228538)
			(xy 342.625295 -250.27607) (xy 342.602605 -250.320602) (xy 342.573229 -250.361035) (xy 342.537889 -250.396375)
			(xy 342.497456 -250.425751) (xy 342.452924 -250.448441) (xy 342.405392 -250.463885) (xy 342.356029 -250.471704)
			(xy 342.306051 -250.471704) (xy 342.256688 -250.463885) (xy 342.209156 -250.448441) (xy 342.164624 -250.425751)
			(xy 342.124191 -250.396375) (xy 342.088851 -250.361035) (xy 342.059475 -250.320602) (xy 342.036785 -250.27607)
			(xy 342.021341 -250.228538) (xy 342.013522 -250.179175) (xy 341.708504 -250.179175) (xy 341.700685 -250.228538)
			(xy 341.685241 -250.27607) (xy 341.662551 -250.320602) (xy 341.633175 -250.361035) (xy 341.597835 -250.396375)
			(xy 341.557402 -250.425751) (xy 341.51287 -250.448441) (xy 341.465338 -250.463885) (xy 341.415975 -250.471704)
			(xy 341.365997 -250.471704) (xy 341.316634 -250.463885) (xy 341.269102 -250.448441) (xy 341.22457 -250.425751)
			(xy 341.184137 -250.396375) (xy 341.148797 -250.361035) (xy 341.119421 -250.320602) (xy 341.096731 -250.27607)
			(xy 341.081287 -250.228538) (xy 341.073468 -250.179175) (xy 340.766405 -250.179175) (xy 340.766396 -250.179632)
			(xy 340.758232 -250.229866) (xy 340.742116 -250.27814) (xy 340.718465 -250.323203) (xy 340.687892 -250.363889)
			(xy 340.651188 -250.399144) (xy 340.609304 -250.428054) (xy 340.563325 -250.449871) (xy 340.514441 -250.464031)
			(xy 340.46392 -250.470165) (xy 340.413068 -250.468116) (xy 340.363204 -250.457936) (xy 340.315618 -250.439889)
			(xy 340.271544 -250.414443) (xy 340.232122 -250.382256) (xy 340.198374 -250.344162) (xy 340.171173 -250.301148)
			(xy 340.151225 -250.254328) (xy 340.139046 -250.204914) (xy 340.134951 -250.154186) (xy 339.82914 -250.154186)
			(xy 339.82865 -250.179175) (xy 339.820831 -250.228538) (xy 339.805387 -250.27607) (xy 339.782697 -250.320602)
			(xy 339.753321 -250.361035) (xy 339.717981 -250.396375) (xy 339.677548 -250.425751) (xy 339.633016 -250.448441)
			(xy 339.585484 -250.463885) (xy 339.536121 -250.471704) (xy 339.486143 -250.471704) (xy 339.43678 -250.463885)
			(xy 339.389248 -250.448441) (xy 339.344716 -250.425751) (xy 339.304283 -250.396375) (xy 339.268943 -250.361035)
			(xy 339.239567 -250.320602) (xy 339.216877 -250.27607) (xy 339.201433 -250.228538) (xy 339.193614 -250.179175)
			(xy 338.888596 -250.179175) (xy 338.880777 -250.228538) (xy 338.865333 -250.27607) (xy 338.842643 -250.320602)
			(xy 338.813267 -250.361035) (xy 338.777927 -250.396375) (xy 338.737494 -250.425751) (xy 338.692962 -250.448441)
			(xy 338.64543 -250.463885) (xy 338.596067 -250.471704) (xy 338.546089 -250.471704) (xy 338.496726 -250.463885)
			(xy 338.449194 -250.448441) (xy 338.404662 -250.425751) (xy 338.364229 -250.396375) (xy 338.328889 -250.361035)
			(xy 338.299513 -250.320602) (xy 338.276823 -250.27607) (xy 338.261379 -250.228538) (xy 338.25356 -250.179175)
			(xy 338.012532 -250.179175) (xy 338.012532 -250.546362) (xy 338.013029 -250.556024) (xy 338.020342 -250.573917)
			(xy 338.026756 -250.58116) (xy 338.068412 -250.623832) (xy 338.071908 -250.627287) (xy 338.079968 -250.632911)
			(xy 338.084414 -250.635008) (xy 338.10956 -250.64593) (xy 338.118704 -250.646438) (xy 338.144041 -250.648331)
			(xy 338.193682 -250.659149) (xy 338.240973 -250.677717) (xy 338.284713 -250.703563) (xy 338.323792 -250.73603)
			(xy 338.357216 -250.774293) (xy 338.384136 -250.817381) (xy 338.403869 -250.864198) (xy 338.415912 -250.913555)
			(xy 338.419961 -250.9642) (xy 338.417964 -250.989181) (xy 338.723714 -250.989181) (xy 338.723714 -250.939203)
			(xy 338.731533 -250.88984) (xy 338.746977 -250.842308) (xy 338.769667 -250.797776) (xy 338.799043 -250.757343)
			(xy 338.834383 -250.722003) (xy 338.874816 -250.692627) (xy 338.919348 -250.669937) (xy 338.96688 -250.654493)
			(xy 339.016243 -250.646674) (xy 339.066221 -250.646674) (xy 339.115584 -250.654493) (xy 339.163116 -250.669937)
			(xy 339.207648 -250.692627) (xy 339.248081 -250.722003) (xy 339.283421 -250.757343) (xy 339.312797 -250.797776)
			(xy 339.335487 -250.842308) (xy 339.350931 -250.88984) (xy 339.35875 -250.939203) (xy 339.35924 -250.964192)
			(xy 339.664797 -250.964192) (xy 339.668892 -250.913464) (xy 339.681071 -250.86405) (xy 339.701019 -250.81723)
			(xy 339.72822 -250.774216) (xy 339.761968 -250.736122) (xy 339.80139 -250.703935) (xy 339.845464 -250.678489)
			(xy 339.89305 -250.660442) (xy 339.942914 -250.650262) (xy 339.993766 -250.648213) (xy 340.044287 -250.654347)
			(xy 340.093171 -250.668507) (xy 340.13915 -250.690324) (xy 340.181034 -250.719234) (xy 340.217738 -250.754489)
			(xy 340.248311 -250.795175) (xy 340.271962 -250.840238) (xy 340.288078 -250.888512) (xy 340.296242 -250.938746)
			(xy 340.296754 -250.964192) (xy 340.296251 -250.989181) (xy 340.603568 -250.989181) (xy 340.603568 -250.939203)
			(xy 340.611387 -250.88984) (xy 340.626831 -250.842308) (xy 340.649521 -250.797776) (xy 340.678897 -250.757343)
			(xy 340.714237 -250.722003) (xy 340.75467 -250.692627) (xy 340.799202 -250.669937) (xy 340.846734 -250.654493)
			(xy 340.896097 -250.646674) (xy 340.946075 -250.646674) (xy 340.995438 -250.654493) (xy 341.04297 -250.669937)
			(xy 341.087502 -250.692627) (xy 341.127935 -250.722003) (xy 341.163275 -250.757343) (xy 341.192651 -250.797776)
			(xy 341.215341 -250.842308) (xy 341.230785 -250.88984) (xy 341.238604 -250.939203) (xy 341.239094 -250.964192)
			(xy 341.238604 -250.989181) (xy 341.543622 -250.989181) (xy 341.543622 -250.939203) (xy 341.551441 -250.88984)
			(xy 341.566885 -250.842308) (xy 341.589575 -250.797776) (xy 341.618951 -250.757343) (xy 341.654291 -250.722003)
			(xy 341.694724 -250.692627) (xy 341.739256 -250.669937) (xy 341.786788 -250.654493) (xy 341.836151 -250.646674)
			(xy 341.886129 -250.646674) (xy 341.935492 -250.654493) (xy 341.983024 -250.669937) (xy 342.027556 -250.692627)
			(xy 342.067989 -250.722003) (xy 342.103329 -250.757343) (xy 342.132705 -250.797776) (xy 342.155395 -250.842308)
			(xy 342.170839 -250.88984) (xy 342.178658 -250.939203) (xy 342.179148 -250.964192) (xy 342.178658 -250.989181)
			(xy 342.483676 -250.989181) (xy 342.483676 -250.939203) (xy 342.491495 -250.88984) (xy 342.506939 -250.842308)
			(xy 342.529629 -250.797776) (xy 342.559005 -250.757343) (xy 342.594345 -250.722003) (xy 342.634778 -250.692627)
			(xy 342.67931 -250.669937) (xy 342.726842 -250.654493) (xy 342.776205 -250.646674) (xy 342.826183 -250.646674)
			(xy 342.875546 -250.654493) (xy 342.923078 -250.669937) (xy 342.96761 -250.692627) (xy 343.008043 -250.722003)
			(xy 343.043383 -250.757343) (xy 343.072759 -250.797776) (xy 343.095449 -250.842308) (xy 343.110893 -250.88984)
			(xy 343.118712 -250.939203) (xy 343.119202 -250.964192) (xy 343.118712 -250.989181) (xy 343.110893 -251.038544)
			(xy 343.095449 -251.086076) (xy 343.072759 -251.130608) (xy 343.043383 -251.171041) (xy 343.008043 -251.206381)
			(xy 342.96761 -251.235757) (xy 342.923078 -251.258447) (xy 342.875546 -251.273891) (xy 342.826183 -251.28171)
			(xy 342.776205 -251.28171) (xy 342.726842 -251.273891) (xy 342.67931 -251.258447) (xy 342.634778 -251.235757)
			(xy 342.594345 -251.206381) (xy 342.559005 -251.171041) (xy 342.529629 -251.130608) (xy 342.506939 -251.086076)
			(xy 342.491495 -251.038544) (xy 342.483676 -250.989181) (xy 342.178658 -250.989181) (xy 342.170839 -251.038544)
			(xy 342.155395 -251.086076) (xy 342.132705 -251.130608) (xy 342.103329 -251.171041) (xy 342.067989 -251.206381)
			(xy 342.027556 -251.235757) (xy 341.983024 -251.258447) (xy 341.935492 -251.273891) (xy 341.886129 -251.28171)
			(xy 341.836151 -251.28171) (xy 341.786788 -251.273891) (xy 341.739256 -251.258447) (xy 341.694724 -251.235757)
			(xy 341.654291 -251.206381) (xy 341.618951 -251.171041) (xy 341.589575 -251.130608) (xy 341.566885 -251.086076)
			(xy 341.551441 -251.038544) (xy 341.543622 -250.989181) (xy 341.238604 -250.989181) (xy 341.230785 -251.038544)
			(xy 341.215341 -251.086076) (xy 341.192651 -251.130608) (xy 341.163275 -251.171041) (xy 341.127935 -251.206381)
			(xy 341.087502 -251.235757) (xy 341.04297 -251.258447) (xy 340.995438 -251.273891) (xy 340.946075 -251.28171)
			(xy 340.896097 -251.28171) (xy 340.846734 -251.273891) (xy 340.799202 -251.258447) (xy 340.75467 -251.235757)
			(xy 340.714237 -251.206381) (xy 340.678897 -251.171041) (xy 340.649521 -251.130608) (xy 340.626831 -251.086076)
			(xy 340.611387 -251.038544) (xy 340.603568 -250.989181) (xy 340.296251 -250.989181) (xy 340.296242 -250.989638)
			(xy 340.288078 -251.039872) (xy 340.271962 -251.088146) (xy 340.248311 -251.133209) (xy 340.217738 -251.173895)
			(xy 340.181034 -251.20915) (xy 340.13915 -251.23806) (xy 340.093171 -251.259877) (xy 340.044287 -251.274037)
			(xy 339.993766 -251.280171) (xy 339.942914 -251.278122) (xy 339.89305 -251.267942) (xy 339.845464 -251.249895)
			(xy 339.80139 -251.224449) (xy 339.761968 -251.192262) (xy 339.72822 -251.154168) (xy 339.701019 -251.111154)
			(xy 339.681071 -251.064334) (xy 339.668892 -251.01492) (xy 339.664797 -250.964192) (xy 339.35924 -250.964192)
			(xy 339.35875 -250.989181) (xy 339.350931 -251.038544) (xy 339.335487 -251.086076) (xy 339.312797 -251.130608)
			(xy 339.283421 -251.171041) (xy 339.248081 -251.206381) (xy 339.207648 -251.235757) (xy 339.163116 -251.258447)
			(xy 339.115584 -251.273891) (xy 339.066221 -251.28171) (xy 339.016243 -251.28171) (xy 338.96688 -251.273891)
			(xy 338.919348 -251.258447) (xy 338.874816 -251.235757) (xy 338.834383 -251.206381) (xy 338.799043 -251.171041)
			(xy 338.769667 -251.130608) (xy 338.746977 -251.086076) (xy 338.731533 -251.038544) (xy 338.723714 -250.989181)
			(xy 338.417964 -250.989181) (xy 338.415912 -251.014844) (xy 338.403869 -251.064201) (xy 338.384136 -251.111019)
			(xy 338.357216 -251.154106) (xy 338.323793 -251.192369) (xy 338.284714 -251.224836) (xy 338.240974 -251.250682)
			(xy 338.193683 -251.26925) (xy 338.144042 -251.280069) (xy 338.118704 -251.281946) (xy 338.10956 -251.282454)
			(xy 338.084414 -251.293376) (xy 338.079966 -251.295469) (xy 338.071908 -251.301096) (xy 338.068412 -251.304552)
			(xy 338.026756 -251.347224) (xy 338.020297 -251.354441) (xy 338.01297 -251.372348) (xy 338.012532 -251.382022)
			(xy 338.012532 -251.774198) (xy 338.254843 -251.774198) (xy 338.258938 -251.72347) (xy 338.271117 -251.674056)
			(xy 338.291065 -251.627236) (xy 338.318266 -251.584222) (xy 338.352014 -251.546128) (xy 338.391436 -251.513941)
			(xy 338.43551 -251.488495) (xy 338.483096 -251.470448) (xy 338.53296 -251.460268) (xy 338.583812 -251.458219)
			(xy 338.634333 -251.464353) (xy 338.683217 -251.478513) (xy 338.729196 -251.50033) (xy 338.77108 -251.52924)
			(xy 338.807784 -251.564495) (xy 338.838357 -251.605181) (xy 338.862008 -251.650244) (xy 338.878124 -251.698518)
			(xy 338.886288 -251.748752) (xy 338.8868 -251.774198) (xy 338.886297 -251.799187) (xy 339.193614 -251.799187)
			(xy 339.193614 -251.749209) (xy 339.201433 -251.699846) (xy 339.216877 -251.652314) (xy 339.239567 -251.607782)
			(xy 339.268943 -251.567349) (xy 339.304283 -251.532009) (xy 339.344716 -251.502633) (xy 339.389248 -251.479943)
			(xy 339.43678 -251.464499) (xy 339.486143 -251.45668) (xy 339.536121 -251.45668) (xy 339.585484 -251.464499)
			(xy 339.633016 -251.479943) (xy 339.677548 -251.502633) (xy 339.717981 -251.532009) (xy 339.753321 -251.567349)
			(xy 339.782697 -251.607782) (xy 339.805387 -251.652314) (xy 339.820831 -251.699846) (xy 339.82865 -251.749209)
			(xy 339.82914 -251.774198) (xy 339.82865 -251.799187) (xy 340.133668 -251.799187) (xy 340.133668 -251.749209)
			(xy 340.141487 -251.699846) (xy 340.156931 -251.652314) (xy 340.179621 -251.607782) (xy 340.208997 -251.567349)
			(xy 340.244337 -251.532009) (xy 340.28477 -251.502633) (xy 340.329302 -251.479943) (xy 340.376834 -251.464499)
			(xy 340.426197 -251.45668) (xy 340.476175 -251.45668) (xy 340.525538 -251.464499) (xy 340.57307 -251.479943)
			(xy 340.617602 -251.502633) (xy 340.658035 -251.532009) (xy 340.693375 -251.567349) (xy 340.722751 -251.607782)
			(xy 340.745441 -251.652314) (xy 340.760885 -251.699846) (xy 340.768704 -251.749209) (xy 340.769194 -251.774198)
			(xy 342.014805 -251.774198) (xy 342.0189 -251.72347) (xy 342.031079 -251.674056) (xy 342.051027 -251.627236)
			(xy 342.078228 -251.584222) (xy 342.111976 -251.546128) (xy 342.151398 -251.513941) (xy 342.195472 -251.488495)
			(xy 342.243058 -251.470448) (xy 342.292922 -251.460268) (xy 342.343774 -251.458219) (xy 342.394295 -251.464353)
			(xy 342.443179 -251.478513) (xy 342.489158 -251.50033) (xy 342.531042 -251.52924) (xy 342.567746 -251.564495)
			(xy 342.598319 -251.605181) (xy 342.62197 -251.650244) (xy 342.638086 -251.698518) (xy 342.64625 -251.748752)
			(xy 342.646762 -251.774198) (xy 342.646259 -251.799187) (xy 342.953576 -251.799187) (xy 342.953576 -251.749209)
			(xy 342.961395 -251.699846) (xy 342.976839 -251.652314) (xy 342.999529 -251.607782) (xy 343.028905 -251.567349)
			(xy 343.064245 -251.532009) (xy 343.104678 -251.502633) (xy 343.14921 -251.479943) (xy 343.196742 -251.464499)
			(xy 343.246105 -251.45668) (xy 343.296083 -251.45668) (xy 343.345446 -251.464499) (xy 343.392978 -251.479943)
			(xy 343.43751 -251.502633) (xy 343.477943 -251.532009) (xy 343.513283 -251.567349) (xy 343.542659 -251.607782)
			(xy 343.565349 -251.652314) (xy 343.580793 -251.699846) (xy 343.588612 -251.749209) (xy 343.589102 -251.774198)
			(xy 343.588612 -251.799187) (xy 343.580793 -251.84855) (xy 343.565349 -251.896082) (xy 343.542659 -251.940614)
			(xy 343.513283 -251.981047) (xy 343.477943 -252.016387) (xy 343.43751 -252.045763) (xy 343.392978 -252.068453)
			(xy 343.345446 -252.083897) (xy 343.296083 -252.091716) (xy 343.246105 -252.091716) (xy 343.196742 -252.083897)
			(xy 343.14921 -252.068453) (xy 343.104678 -252.045763) (xy 343.064245 -252.016387) (xy 343.028905 -251.981047)
			(xy 342.999529 -251.940614) (xy 342.976839 -251.896082) (xy 342.961395 -251.84855) (xy 342.953576 -251.799187)
			(xy 342.646259 -251.799187) (xy 342.64625 -251.799644) (xy 342.638086 -251.849878) (xy 342.62197 -251.898152)
			(xy 342.598319 -251.943215) (xy 342.567746 -251.983901) (xy 342.531042 -252.019156) (xy 342.489158 -252.048066)
			(xy 342.443179 -252.069883) (xy 342.394295 -252.084043) (xy 342.343774 -252.090177) (xy 342.292922 -252.088128)
			(xy 342.243058 -252.077948) (xy 342.195472 -252.059901) (xy 342.151398 -252.034455) (xy 342.111976 -252.002268)
			(xy 342.078228 -251.964174) (xy 342.051027 -251.92116) (xy 342.031079 -251.87434) (xy 342.0189 -251.824926)
			(xy 342.014805 -251.774198) (xy 340.769194 -251.774198) (xy 340.768704 -251.799187) (xy 340.760885 -251.84855)
			(xy 340.745441 -251.896082) (xy 340.722751 -251.940614) (xy 340.693375 -251.981047) (xy 340.658035 -252.016387)
			(xy 340.617602 -252.045763) (xy 340.57307 -252.068453) (xy 340.525538 -252.083897) (xy 340.476175 -252.091716)
			(xy 340.426197 -252.091716) (xy 340.376834 -252.083897) (xy 340.329302 -252.068453) (xy 340.28477 -252.045763)
			(xy 340.244337 -252.016387) (xy 340.208997 -251.981047) (xy 340.179621 -251.940614) (xy 340.156931 -251.896082)
			(xy 340.141487 -251.84855) (xy 340.133668 -251.799187) (xy 339.82865 -251.799187) (xy 339.820831 -251.84855)
			(xy 339.805387 -251.896082) (xy 339.782697 -251.940614) (xy 339.753321 -251.981047) (xy 339.717981 -252.016387)
			(xy 339.677548 -252.045763) (xy 339.633016 -252.068453) (xy 339.585484 -252.083897) (xy 339.536121 -252.091716)
			(xy 339.486143 -252.091716) (xy 339.43678 -252.083897) (xy 339.389248 -252.068453) (xy 339.344716 -252.045763)
			(xy 339.304283 -252.016387) (xy 339.268943 -251.981047) (xy 339.239567 -251.940614) (xy 339.216877 -251.896082)
			(xy 339.201433 -251.84855) (xy 339.193614 -251.799187) (xy 338.886297 -251.799187) (xy 338.886288 -251.799644)
			(xy 338.878124 -251.849878) (xy 338.862008 -251.898152) (xy 338.838357 -251.943215) (xy 338.807784 -251.983901)
			(xy 338.77108 -252.019156) (xy 338.729196 -252.048066) (xy 338.683217 -252.069883) (xy 338.634333 -252.084043)
			(xy 338.583812 -252.090177) (xy 338.53296 -252.088128) (xy 338.483096 -252.077948) (xy 338.43551 -252.059901)
			(xy 338.391436 -252.034455) (xy 338.352014 -252.002268) (xy 338.318266 -251.964174) (xy 338.291065 -251.92116)
			(xy 338.271117 -251.87434) (xy 338.258938 -251.824926) (xy 338.254843 -251.774198) (xy 338.012532 -251.774198)
			(xy 338.012532 -252.166374) (xy 338.013031 -252.176035) (xy 338.020347 -252.193925) (xy 338.026756 -252.201172)
			(xy 338.068412 -252.243844) (xy 338.071909 -252.247298) (xy 338.079969 -252.252922) (xy 338.084414 -252.25502)
			(xy 338.10956 -252.265942) (xy 338.118704 -252.26645) (xy 338.14404 -252.268343) (xy 338.193679 -252.279161)
			(xy 338.240968 -252.297728) (xy 338.284707 -252.323573) (xy 338.323784 -252.356039) (xy 338.357207 -252.394301)
			(xy 338.384126 -252.437387) (xy 338.403857 -252.484202) (xy 338.415901 -252.533558) (xy 338.419949 -252.5842)
			(xy 338.419949 -252.584204) (xy 338.724743 -252.584204) (xy 338.728838 -252.533476) (xy 338.741017 -252.484062)
			(xy 338.760965 -252.437242) (xy 338.788166 -252.394228) (xy 338.821914 -252.356134) (xy 338.861336 -252.323947)
			(xy 338.90541 -252.298501) (xy 338.952996 -252.280454) (xy 339.00286 -252.270274) (xy 339.053712 -252.268225)
			(xy 339.104233 -252.274359) (xy 339.153117 -252.288519) (xy 339.199096 -252.310336) (xy 339.24098 -252.339246)
			(xy 339.277684 -252.374501) (xy 339.308257 -252.415187) (xy 339.331908 -252.46025) (xy 339.348024 -252.508524)
			(xy 339.356188 -252.558758) (xy 339.3567 -252.584204) (xy 339.664797 -252.584204) (xy 339.668892 -252.533476)
			(xy 339.681071 -252.484062) (xy 339.701019 -252.437242) (xy 339.72822 -252.394228) (xy 339.761968 -252.356134)
			(xy 339.80139 -252.323947) (xy 339.845464 -252.298501) (xy 339.89305 -252.280454) (xy 339.942914 -252.270274)
			(xy 339.993766 -252.268225) (xy 340.044287 -252.274359) (xy 340.093171 -252.288519) (xy 340.13915 -252.310336)
			(xy 340.181034 -252.339246) (xy 340.217738 -252.374501) (xy 340.248311 -252.415187) (xy 340.271962 -252.46025)
			(xy 340.288078 -252.508524) (xy 340.296242 -252.558758) (xy 340.296754 -252.584204) (xy 340.296251 -252.609193)
			(xy 340.603568 -252.609193) (xy 340.603568 -252.559215) (xy 340.611387 -252.509852) (xy 340.626831 -252.46232)
			(xy 340.649521 -252.417788) (xy 340.678897 -252.377355) (xy 340.714237 -252.342015) (xy 340.75467 -252.312639)
			(xy 340.799202 -252.289949) (xy 340.846734 -252.274505) (xy 340.896097 -252.266686) (xy 340.946075 -252.266686)
			(xy 340.995438 -252.274505) (xy 341.04297 -252.289949) (xy 341.087502 -252.312639) (xy 341.127935 -252.342015)
			(xy 341.163275 -252.377355) (xy 341.192651 -252.417788) (xy 341.215341 -252.46232) (xy 341.230785 -252.509852)
			(xy 341.238604 -252.559215) (xy 341.239094 -252.584204) (xy 341.544905 -252.584204) (xy 341.549 -252.533476)
			(xy 341.561179 -252.484062) (xy 341.581127 -252.437242) (xy 341.608328 -252.394228) (xy 341.642076 -252.356134)
			(xy 341.681498 -252.323947) (xy 341.725572 -252.298501) (xy 341.773158 -252.280454) (xy 341.823022 -252.270274)
			(xy 341.873874 -252.268225) (xy 341.924395 -252.274359) (xy 341.973279 -252.288519) (xy 342.019258 -252.310336)
			(xy 342.061142 -252.339246) (xy 342.097846 -252.374501) (xy 342.128419 -252.415187) (xy 342.15207 -252.46025)
			(xy 342.168186 -252.508524) (xy 342.17635 -252.558758) (xy 342.176862 -252.584204) (xy 342.176359 -252.609193)
			(xy 342.483676 -252.609193) (xy 342.483676 -252.559215) (xy 342.491495 -252.509852) (xy 342.506939 -252.46232)
			(xy 342.529629 -252.417788) (xy 342.559005 -252.377355) (xy 342.594345 -252.342015) (xy 342.634778 -252.312639)
			(xy 342.67931 -252.289949) (xy 342.726842 -252.274505) (xy 342.776205 -252.266686) (xy 342.826183 -252.266686)
			(xy 342.875546 -252.274505) (xy 342.923078 -252.289949) (xy 342.96761 -252.312639) (xy 343.008043 -252.342015)
			(xy 343.043383 -252.377355) (xy 343.072759 -252.417788) (xy 343.095449 -252.46232) (xy 343.110893 -252.509852)
			(xy 343.118712 -252.559215) (xy 343.119202 -252.584204) (xy 343.118712 -252.609193) (xy 343.110893 -252.658556)
			(xy 343.095449 -252.706088) (xy 343.072759 -252.75062) (xy 343.043383 -252.791053) (xy 343.008043 -252.826393)
			(xy 342.96761 -252.855769) (xy 342.923078 -252.878459) (xy 342.875546 -252.893903) (xy 342.826183 -252.901722)
			(xy 342.776205 -252.901722) (xy 342.726842 -252.893903) (xy 342.67931 -252.878459) (xy 342.634778 -252.855769)
			(xy 342.594345 -252.826393) (xy 342.559005 -252.791053) (xy 342.529629 -252.75062) (xy 342.506939 -252.706088)
			(xy 342.491495 -252.658556) (xy 342.483676 -252.609193) (xy 342.176359 -252.609193) (xy 342.17635 -252.60965)
			(xy 342.168186 -252.659884) (xy 342.15207 -252.708158) (xy 342.128419 -252.753221) (xy 342.097846 -252.793907)
			(xy 342.061142 -252.829162) (xy 342.019258 -252.858072) (xy 341.973279 -252.879889) (xy 341.924395 -252.894049)
			(xy 341.873874 -252.900183) (xy 341.823022 -252.898134) (xy 341.773158 -252.887954) (xy 341.725572 -252.869907)
			(xy 341.681498 -252.844461) (xy 341.642076 -252.812274) (xy 341.608328 -252.77418) (xy 341.581127 -252.731166)
			(xy 341.561179 -252.684346) (xy 341.549 -252.634932) (xy 341.544905 -252.584204) (xy 341.239094 -252.584204)
			(xy 341.238604 -252.609193) (xy 341.230785 -252.658556) (xy 341.215341 -252.706088) (xy 341.192651 -252.75062)
			(xy 341.163275 -252.791053) (xy 341.127935 -252.826393) (xy 341.087502 -252.855769) (xy 341.04297 -252.878459)
			(xy 340.995438 -252.893903) (xy 340.946075 -252.901722) (xy 340.896097 -252.901722) (xy 340.846734 -252.893903)
			(xy 340.799202 -252.878459) (xy 340.75467 -252.855769) (xy 340.714237 -252.826393) (xy 340.678897 -252.791053)
			(xy 340.649521 -252.75062) (xy 340.626831 -252.706088) (xy 340.611387 -252.658556) (xy 340.603568 -252.609193)
			(xy 340.296251 -252.609193) (xy 340.296242 -252.60965) (xy 340.288078 -252.659884) (xy 340.271962 -252.708158)
			(xy 340.248311 -252.753221) (xy 340.217738 -252.793907) (xy 340.181034 -252.829162) (xy 340.13915 -252.858072)
			(xy 340.093171 -252.879889) (xy 340.044287 -252.894049) (xy 339.993766 -252.900183) (xy 339.942914 -252.898134)
			(xy 339.89305 -252.887954) (xy 339.845464 -252.869907) (xy 339.80139 -252.844461) (xy 339.761968 -252.812274)
			(xy 339.72822 -252.77418) (xy 339.701019 -252.731166) (xy 339.681071 -252.684346) (xy 339.668892 -252.634932)
			(xy 339.664797 -252.584204) (xy 339.3567 -252.584204) (xy 339.356188 -252.60965) (xy 339.348024 -252.659884)
			(xy 339.331908 -252.708158) (xy 339.308257 -252.753221) (xy 339.277684 -252.793907) (xy 339.24098 -252.829162)
			(xy 339.199096 -252.858072) (xy 339.153117 -252.879889) (xy 339.104233 -252.894049) (xy 339.053712 -252.900183)
			(xy 339.00286 -252.898134) (xy 338.952996 -252.887954) (xy 338.90541 -252.869907) (xy 338.861336 -252.844461)
			(xy 338.821914 -252.812274) (xy 338.788166 -252.77418) (xy 338.760965 -252.731166) (xy 338.741017 -252.684346)
			(xy 338.728838 -252.634932) (xy 338.724743 -252.584204) (xy 338.419949 -252.584204) (xy 338.415901 -252.634843)
			(xy 338.403857 -252.684198) (xy 338.384125 -252.731014) (xy 338.357206 -252.7741) (xy 338.323784 -252.812361)
			(xy 338.284707 -252.844827) (xy 338.240968 -252.870672) (xy 338.193678 -252.889239) (xy 338.14404 -252.900057)
			(xy 338.118704 -252.901958) (xy 338.10956 -252.902466) (xy 338.084414 -252.913388) (xy 338.079964 -252.915478)
			(xy 338.071899 -252.921098) (xy 338.068412 -252.924564) (xy 338.026756 -252.967236) (xy 338.020299 -252.974454)
			(xy 338.012976 -252.99236) (xy 338.012532 -253.002034) (xy 338.012532 -253.39421) (xy 338.254843 -253.39421)
			(xy 338.258938 -253.343482) (xy 338.271117 -253.294068) (xy 338.291065 -253.247248) (xy 338.318266 -253.204234)
			(xy 338.352014 -253.16614) (xy 338.391436 -253.133953) (xy 338.43551 -253.108507) (xy 338.483096 -253.09046)
			(xy 338.53296 -253.08028) (xy 338.583812 -253.078231) (xy 338.634333 -253.084365) (xy 338.683217 -253.098525)
			(xy 338.729196 -253.120342) (xy 338.77108 -253.149252) (xy 338.807784 -253.184507) (xy 338.838357 -253.225193)
			(xy 338.862008 -253.270256) (xy 338.878124 -253.31853) (xy 338.886288 -253.368764) (xy 338.8868 -253.39421)
			(xy 338.886297 -253.419199) (xy 339.193614 -253.419199) (xy 339.193614 -253.369221) (xy 339.201433 -253.319858)
			(xy 339.216877 -253.272326) (xy 339.239567 -253.227794) (xy 339.268943 -253.187361) (xy 339.304283 -253.152021)
			(xy 339.344716 -253.122645) (xy 339.389248 -253.099955) (xy 339.43678 -253.084511) (xy 339.486143 -253.076692)
			(xy 339.536121 -253.076692) (xy 339.585484 -253.084511) (xy 339.633016 -253.099955) (xy 339.677548 -253.122645)
			(xy 339.717981 -253.152021) (xy 339.753321 -253.187361) (xy 339.782697 -253.227794) (xy 339.805387 -253.272326)
			(xy 339.820831 -253.319858) (xy 339.82865 -253.369221) (xy 339.82914 -253.39421) (xy 340.134951 -253.39421)
			(xy 340.139046 -253.343482) (xy 340.151225 -253.294068) (xy 340.171173 -253.247248) (xy 340.198374 -253.204234)
			(xy 340.232122 -253.16614) (xy 340.271544 -253.133953) (xy 340.315618 -253.108507) (xy 340.363204 -253.09046)
			(xy 340.413068 -253.08028) (xy 340.46392 -253.078231) (xy 340.514441 -253.084365) (xy 340.563325 -253.098525)
			(xy 340.609304 -253.120342) (xy 340.651188 -253.149252) (xy 340.687892 -253.184507) (xy 340.718465 -253.225193)
			(xy 340.742116 -253.270256) (xy 340.758232 -253.31853) (xy 340.766396 -253.368764) (xy 340.766908 -253.39421)
			(xy 340.766405 -253.419199) (xy 341.073468 -253.419199) (xy 341.073468 -253.369221) (xy 341.081287 -253.319858)
			(xy 341.096731 -253.272326) (xy 341.119421 -253.227794) (xy 341.148797 -253.187361) (xy 341.184137 -253.152021)
			(xy 341.22457 -253.122645) (xy 341.269102 -253.099955) (xy 341.316634 -253.084511) (xy 341.365997 -253.076692)
			(xy 341.415975 -253.076692) (xy 341.465338 -253.084511) (xy 341.51287 -253.099955) (xy 341.557402 -253.122645)
			(xy 341.597835 -253.152021) (xy 341.633175 -253.187361) (xy 341.662551 -253.227794) (xy 341.685241 -253.272326)
			(xy 341.700685 -253.319858) (xy 341.708504 -253.369221) (xy 341.708994 -253.39421) (xy 342.014805 -253.39421)
			(xy 342.0189 -253.343482) (xy 342.031079 -253.294068) (xy 342.051027 -253.247248) (xy 342.078228 -253.204234)
			(xy 342.111976 -253.16614) (xy 342.151398 -253.133953) (xy 342.195472 -253.108507) (xy 342.243058 -253.09046)
			(xy 342.292922 -253.08028) (xy 342.343774 -253.078231) (xy 342.394295 -253.084365) (xy 342.443179 -253.098525)
			(xy 342.489158 -253.120342) (xy 342.531042 -253.149252) (xy 342.567746 -253.184507) (xy 342.598319 -253.225193)
			(xy 342.62197 -253.270256) (xy 342.638086 -253.31853) (xy 342.64625 -253.368764) (xy 342.646762 -253.39421)
			(xy 342.954859 -253.39421) (xy 342.958954 -253.343482) (xy 342.971133 -253.294068) (xy 342.991081 -253.247248)
			(xy 343.018282 -253.204234) (xy 343.05203 -253.16614) (xy 343.091452 -253.133953) (xy 343.135526 -253.108507)
			(xy 343.183112 -253.09046) (xy 343.232976 -253.08028) (xy 343.283828 -253.078231) (xy 343.334349 -253.084365)
			(xy 343.383233 -253.098525) (xy 343.429212 -253.120342) (xy 343.471096 -253.149252) (xy 343.5078 -253.184507)
			(xy 343.538373 -253.225193) (xy 343.562024 -253.270256) (xy 343.57814 -253.31853) (xy 343.586304 -253.368764)
			(xy 343.586816 -253.39421) (xy 343.586304 -253.419656) (xy 343.57814 -253.46989) (xy 343.562024 -253.518164)
			(xy 343.538373 -253.563227) (xy 343.5078 -253.603913) (xy 343.471096 -253.639168) (xy 343.429212 -253.668078)
			(xy 343.383233 -253.689895) (xy 343.334349 -253.704055) (xy 343.283828 -253.710189) (xy 343.232976 -253.70814)
			(xy 343.183112 -253.69796) (xy 343.135526 -253.679913) (xy 343.091452 -253.654467) (xy 343.05203 -253.62228)
			(xy 343.018282 -253.584186) (xy 342.991081 -253.541172) (xy 342.971133 -253.494352) (xy 342.958954 -253.444938)
			(xy 342.954859 -253.39421) (xy 342.646762 -253.39421) (xy 342.64625 -253.419656) (xy 342.638086 -253.46989)
			(xy 342.62197 -253.518164) (xy 342.598319 -253.563227) (xy 342.567746 -253.603913) (xy 342.531042 -253.639168)
			(xy 342.489158 -253.668078) (xy 342.443179 -253.689895) (xy 342.394295 -253.704055) (xy 342.343774 -253.710189)
			(xy 342.292922 -253.70814) (xy 342.243058 -253.69796) (xy 342.195472 -253.679913) (xy 342.151398 -253.654467)
			(xy 342.111976 -253.62228) (xy 342.078228 -253.584186) (xy 342.051027 -253.541172) (xy 342.031079 -253.494352)
			(xy 342.0189 -253.444938) (xy 342.014805 -253.39421) (xy 341.708994 -253.39421) (xy 341.708504 -253.419199)
			(xy 341.700685 -253.468562) (xy 341.685241 -253.516094) (xy 341.662551 -253.560626) (xy 341.633175 -253.601059)
			(xy 341.597835 -253.636399) (xy 341.557402 -253.665775) (xy 341.51287 -253.688465) (xy 341.465338 -253.703909)
			(xy 341.415975 -253.711728) (xy 341.365997 -253.711728) (xy 341.316634 -253.703909) (xy 341.269102 -253.688465)
			(xy 341.22457 -253.665775) (xy 341.184137 -253.636399) (xy 341.148797 -253.601059) (xy 341.119421 -253.560626)
			(xy 341.096731 -253.516094) (xy 341.081287 -253.468562) (xy 341.073468 -253.419199) (xy 340.766405 -253.419199)
			(xy 340.766396 -253.419656) (xy 340.758232 -253.46989) (xy 340.742116 -253.518164) (xy 340.718465 -253.563227)
			(xy 340.687892 -253.603913) (xy 340.651188 -253.639168) (xy 340.609304 -253.668078) (xy 340.563325 -253.689895)
			(xy 340.514441 -253.704055) (xy 340.46392 -253.710189) (xy 340.413068 -253.70814) (xy 340.363204 -253.69796)
			(xy 340.315618 -253.679913) (xy 340.271544 -253.654467) (xy 340.232122 -253.62228) (xy 340.198374 -253.584186)
			(xy 340.171173 -253.541172) (xy 340.151225 -253.494352) (xy 340.139046 -253.444938) (xy 340.134951 -253.39421)
			(xy 339.82914 -253.39421) (xy 339.82865 -253.419199) (xy 339.820831 -253.468562) (xy 339.805387 -253.516094)
			(xy 339.782697 -253.560626) (xy 339.753321 -253.601059) (xy 339.717981 -253.636399) (xy 339.677548 -253.665775)
			(xy 339.633016 -253.688465) (xy 339.585484 -253.703909) (xy 339.536121 -253.711728) (xy 339.486143 -253.711728)
			(xy 339.43678 -253.703909) (xy 339.389248 -253.688465) (xy 339.344716 -253.665775) (xy 339.304283 -253.636399)
			(xy 339.268943 -253.601059) (xy 339.239567 -253.560626) (xy 339.216877 -253.516094) (xy 339.201433 -253.468562)
			(xy 339.193614 -253.419199) (xy 338.886297 -253.419199) (xy 338.886288 -253.419656) (xy 338.878124 -253.46989)
			(xy 338.862008 -253.518164) (xy 338.838357 -253.563227) (xy 338.807784 -253.603913) (xy 338.77108 -253.639168)
			(xy 338.729196 -253.668078) (xy 338.683217 -253.689895) (xy 338.634333 -253.704055) (xy 338.583812 -253.710189)
			(xy 338.53296 -253.70814) (xy 338.483096 -253.69796) (xy 338.43551 -253.679913) (xy 338.391436 -253.654467)
			(xy 338.352014 -253.62228) (xy 338.318266 -253.584186) (xy 338.291065 -253.541172) (xy 338.271117 -253.494352)
			(xy 338.258938 -253.444938) (xy 338.254843 -253.39421) (xy 338.012532 -253.39421) (xy 338.012532 -253.786386)
			(xy 338.013033 -253.796046) (xy 338.020352 -253.813933) (xy 338.026756 -253.821184) (xy 338.068412 -253.863856)
			(xy 338.071909 -253.86731) (xy 338.07997 -253.872932) (xy 338.084414 -253.875032) (xy 338.10956 -253.885954)
			(xy 338.118704 -253.886462) (xy 338.144039 -253.888355) (xy 338.193676 -253.899173) (xy 338.240964 -253.91774)
			(xy 338.284701 -253.943583) (xy 338.323776 -253.976048) (xy 338.357197 -254.014308) (xy 338.384115 -254.057393)
			(xy 338.403846 -254.104207) (xy 338.415889 -254.15356) (xy 338.419937 -254.204201) (xy 338.419936 -254.204216)
			(xy 338.724743 -254.204216) (xy 338.728838 -254.153488) (xy 338.741017 -254.104074) (xy 338.760965 -254.057254)
			(xy 338.788166 -254.01424) (xy 338.821914 -253.976146) (xy 338.861336 -253.943959) (xy 338.90541 -253.918513)
			(xy 338.952996 -253.900466) (xy 339.00286 -253.890286) (xy 339.053712 -253.888237) (xy 339.104233 -253.894371)
			(xy 339.153117 -253.908531) (xy 339.199096 -253.930348) (xy 339.24098 -253.959258) (xy 339.277684 -253.994513)
			(xy 339.308257 -254.035199) (xy 339.331908 -254.080262) (xy 339.348024 -254.128536) (xy 339.356188 -254.17877)
			(xy 339.3567 -254.204216) (xy 339.664797 -254.204216) (xy 339.668892 -254.153488) (xy 339.681071 -254.104074)
			(xy 339.701019 -254.057254) (xy 339.72822 -254.01424) (xy 339.761968 -253.976146) (xy 339.80139 -253.943959)
			(xy 339.845464 -253.918513) (xy 339.89305 -253.900466) (xy 339.942914 -253.890286) (xy 339.993766 -253.888237)
			(xy 340.044287 -253.894371) (xy 340.093171 -253.908531) (xy 340.13915 -253.930348) (xy 340.181034 -253.959258)
			(xy 340.217738 -253.994513) (xy 340.248311 -254.035199) (xy 340.271962 -254.080262) (xy 340.288078 -254.128536)
			(xy 340.296242 -254.17877) (xy 340.296754 -254.204216) (xy 341.544905 -254.204216) (xy 341.549 -254.153488)
			(xy 341.561179 -254.104074) (xy 341.581127 -254.057254) (xy 341.608328 -254.01424) (xy 341.642076 -253.976146)
			(xy 341.681498 -253.943959) (xy 341.725572 -253.918513) (xy 341.773158 -253.900466) (xy 341.823022 -253.890286)
			(xy 341.873874 -253.888237) (xy 341.924395 -253.894371) (xy 341.973279 -253.908531) (xy 342.019258 -253.930348)
			(xy 342.061142 -253.959258) (xy 342.097846 -253.994513) (xy 342.128419 -254.035199) (xy 342.15207 -254.080262)
			(xy 342.168186 -254.128536) (xy 342.17635 -254.17877) (xy 342.176862 -254.204216) (xy 342.176359 -254.229205)
			(xy 342.483676 -254.229205) (xy 342.483676 -254.179227) (xy 342.491495 -254.129864) (xy 342.506939 -254.082332)
			(xy 342.529629 -254.0378) (xy 342.559005 -253.997367) (xy 342.594345 -253.962027) (xy 342.634778 -253.932651)
			(xy 342.67931 -253.909961) (xy 342.726842 -253.894517) (xy 342.776205 -253.886698) (xy 342.826183 -253.886698)
			(xy 342.875546 -253.894517) (xy 342.923078 -253.909961) (xy 342.96761 -253.932651) (xy 343.008043 -253.962027)
			(xy 343.043383 -253.997367) (xy 343.072759 -254.0378) (xy 343.095449 -254.082332) (xy 343.110893 -254.129864)
			(xy 343.118712 -254.179227) (xy 343.119202 -254.204216) (xy 343.118712 -254.229205) (xy 343.110893 -254.278568)
			(xy 343.095449 -254.3261) (xy 343.072759 -254.370632) (xy 343.043383 -254.411065) (xy 343.008043 -254.446405)
			(xy 342.96761 -254.475781) (xy 342.923078 -254.498471) (xy 342.875546 -254.513915) (xy 342.826183 -254.521734)
			(xy 342.776205 -254.521734) (xy 342.726842 -254.513915) (xy 342.67931 -254.498471) (xy 342.634778 -254.475781)
			(xy 342.594345 -254.446405) (xy 342.559005 -254.411065) (xy 342.529629 -254.370632) (xy 342.506939 -254.3261)
			(xy 342.491495 -254.278568) (xy 342.483676 -254.229205) (xy 342.176359 -254.229205) (xy 342.17635 -254.229662)
			(xy 342.168186 -254.279896) (xy 342.15207 -254.32817) (xy 342.128419 -254.373233) (xy 342.097846 -254.413919)
			(xy 342.061142 -254.449174) (xy 342.019258 -254.478084) (xy 341.973279 -254.499901) (xy 341.924395 -254.514061)
			(xy 341.873874 -254.520195) (xy 341.823022 -254.518146) (xy 341.773158 -254.507966) (xy 341.725572 -254.489919)
			(xy 341.681498 -254.464473) (xy 341.642076 -254.432286) (xy 341.608328 -254.394192) (xy 341.581127 -254.351178)
			(xy 341.561179 -254.304358) (xy 341.549 -254.254944) (xy 341.544905 -254.204216) (xy 340.296754 -254.204216)
			(xy 340.296242 -254.229662) (xy 340.288078 -254.279896) (xy 340.271962 -254.32817) (xy 340.248311 -254.373233)
			(xy 340.217738 -254.413919) (xy 340.181034 -254.449174) (xy 340.13915 -254.478084) (xy 340.093171 -254.499901)
			(xy 340.044287 -254.514061) (xy 339.993766 -254.520195) (xy 339.942914 -254.518146) (xy 339.89305 -254.507966)
			(xy 339.845464 -254.489919) (xy 339.80139 -254.464473) (xy 339.761968 -254.432286) (xy 339.72822 -254.394192)
			(xy 339.701019 -254.351178) (xy 339.681071 -254.304358) (xy 339.668892 -254.254944) (xy 339.664797 -254.204216)
			(xy 339.3567 -254.204216) (xy 339.356188 -254.229662) (xy 339.348024 -254.279896) (xy 339.331908 -254.32817)
			(xy 339.308257 -254.373233) (xy 339.277684 -254.413919) (xy 339.24098 -254.449174) (xy 339.199096 -254.478084)
			(xy 339.153117 -254.499901) (xy 339.104233 -254.514061) (xy 339.053712 -254.520195) (xy 339.00286 -254.518146)
			(xy 338.952996 -254.507966) (xy 338.90541 -254.489919) (xy 338.861336 -254.464473) (xy 338.821914 -254.432286)
			(xy 338.788166 -254.394192) (xy 338.760965 -254.351178) (xy 338.741017 -254.304358) (xy 338.728838 -254.254944)
			(xy 338.724743 -254.204216) (xy 338.419936 -254.204216) (xy 338.415889 -254.254841) (xy 338.403846 -254.304195)
			(xy 338.384115 -254.351009) (xy 338.357196 -254.394093) (xy 338.323775 -254.432353) (xy 338.284699 -254.464818)
			(xy 338.240962 -254.490661) (xy 338.193674 -254.509228) (xy 338.144037 -254.520046) (xy 338.118704 -254.52197)
			(xy 338.10956 -254.522478) (xy 338.084414 -254.5334) (xy 338.079964 -254.53549) (xy 338.0719 -254.541112)
			(xy 338.068412 -254.544576) (xy 338.026756 -254.587248) (xy 338.020301 -254.594466) (xy 338.012982 -254.612373)
			(xy 338.012532 -254.622046) (xy 338.012532 -255.014222) (xy 338.254843 -255.014222) (xy 338.258938 -254.963494)
			(xy 338.271117 -254.91408) (xy 338.291065 -254.86726) (xy 338.318266 -254.824246) (xy 338.352014 -254.786152)
			(xy 338.391436 -254.753965) (xy 338.43551 -254.728519) (xy 338.483096 -254.710472) (xy 338.53296 -254.700292)
			(xy 338.583812 -254.698243) (xy 338.634333 -254.704377) (xy 338.683217 -254.718537) (xy 338.729196 -254.740354)
			(xy 338.77108 -254.769264) (xy 338.807784 -254.804519) (xy 338.838357 -254.845205) (xy 338.862008 -254.890268)
			(xy 338.878124 -254.938542) (xy 338.886288 -254.988776) (xy 338.8868 -255.014222) (xy 338.886297 -255.039211)
			(xy 339.193614 -255.039211) (xy 339.193614 -254.989233) (xy 339.201433 -254.93987) (xy 339.216877 -254.892338)
			(xy 339.239567 -254.847806) (xy 339.268943 -254.807373) (xy 339.304283 -254.772033) (xy 339.344716 -254.742657)
			(xy 339.389248 -254.719967) (xy 339.43678 -254.704523) (xy 339.486143 -254.696704) (xy 339.536121 -254.696704)
			(xy 339.585484 -254.704523) (xy 339.633016 -254.719967) (xy 339.677548 -254.742657) (xy 339.717981 -254.772033)
			(xy 339.753321 -254.807373) (xy 339.782697 -254.847806) (xy 339.805387 -254.892338) (xy 339.820831 -254.93987)
			(xy 339.82865 -254.989233) (xy 339.82914 -255.014222) (xy 340.134951 -255.014222) (xy 340.139046 -254.963494)
			(xy 340.151225 -254.91408) (xy 340.171173 -254.86726) (xy 340.198374 -254.824246) (xy 340.232122 -254.786152)
			(xy 340.271544 -254.753965) (xy 340.315618 -254.728519) (xy 340.363204 -254.710472) (xy 340.413068 -254.700292)
			(xy 340.46392 -254.698243) (xy 340.514441 -254.704377) (xy 340.563325 -254.718537) (xy 340.609304 -254.740354)
			(xy 340.651188 -254.769264) (xy 340.687892 -254.804519) (xy 340.718465 -254.845205) (xy 340.742116 -254.890268)
			(xy 340.758232 -254.938542) (xy 340.766396 -254.988776) (xy 340.766908 -255.014222) (xy 340.766405 -255.039211)
			(xy 341.073468 -255.039211) (xy 341.073468 -254.989233) (xy 341.081287 -254.93987) (xy 341.096731 -254.892338)
			(xy 341.119421 -254.847806) (xy 341.148797 -254.807373) (xy 341.184137 -254.772033) (xy 341.22457 -254.742657)
			(xy 341.269102 -254.719967) (xy 341.316634 -254.704523) (xy 341.365997 -254.696704) (xy 341.415975 -254.696704)
			(xy 341.465338 -254.704523) (xy 341.51287 -254.719967) (xy 341.557402 -254.742657) (xy 341.597835 -254.772033)
			(xy 341.633175 -254.807373) (xy 341.662551 -254.847806) (xy 341.685241 -254.892338) (xy 341.700685 -254.93987)
			(xy 341.708504 -254.989233) (xy 341.708994 -255.014222) (xy 342.014805 -255.014222) (xy 342.0189 -254.963494)
			(xy 342.031079 -254.91408) (xy 342.051027 -254.86726) (xy 342.078228 -254.824246) (xy 342.111976 -254.786152)
			(xy 342.151398 -254.753965) (xy 342.195472 -254.728519) (xy 342.243058 -254.710472) (xy 342.292922 -254.700292)
			(xy 342.343774 -254.698243) (xy 342.394295 -254.704377) (xy 342.443179 -254.718537) (xy 342.489158 -254.740354)
			(xy 342.531042 -254.769264) (xy 342.567746 -254.804519) (xy 342.598319 -254.845205) (xy 342.62197 -254.890268)
			(xy 342.638086 -254.938542) (xy 342.64625 -254.988776) (xy 342.646762 -255.014222) (xy 342.954859 -255.014222)
			(xy 342.958954 -254.963494) (xy 342.971133 -254.91408) (xy 342.991081 -254.86726) (xy 343.018282 -254.824246)
			(xy 343.05203 -254.786152) (xy 343.091452 -254.753965) (xy 343.135526 -254.728519) (xy 343.183112 -254.710472)
			(xy 343.232976 -254.700292) (xy 343.283828 -254.698243) (xy 343.334349 -254.704377) (xy 343.383233 -254.718537)
			(xy 343.429212 -254.740354) (xy 343.471096 -254.769264) (xy 343.5078 -254.804519) (xy 343.538373 -254.845205)
			(xy 343.562024 -254.890268) (xy 343.57814 -254.938542) (xy 343.586304 -254.988776) (xy 343.586816 -255.014222)
			(xy 343.586304 -255.039668) (xy 343.57814 -255.089902) (xy 343.562024 -255.138176) (xy 343.538373 -255.183239)
			(xy 343.5078 -255.223925) (xy 343.471096 -255.25918) (xy 343.429212 -255.28809) (xy 343.383233 -255.309907)
			(xy 343.334349 -255.324067) (xy 343.283828 -255.330201) (xy 343.232976 -255.328152) (xy 343.183112 -255.317972)
			(xy 343.135526 -255.299925) (xy 343.091452 -255.274479) (xy 343.05203 -255.242292) (xy 343.018282 -255.204198)
			(xy 342.991081 -255.161184) (xy 342.971133 -255.114364) (xy 342.958954 -255.06495) (xy 342.954859 -255.014222)
			(xy 342.646762 -255.014222) (xy 342.64625 -255.039668) (xy 342.638086 -255.089902) (xy 342.62197 -255.138176)
			(xy 342.598319 -255.183239) (xy 342.567746 -255.223925) (xy 342.531042 -255.25918) (xy 342.489158 -255.28809)
			(xy 342.443179 -255.309907) (xy 342.394295 -255.324067) (xy 342.343774 -255.330201) (xy 342.292922 -255.328152)
			(xy 342.243058 -255.317972) (xy 342.195472 -255.299925) (xy 342.151398 -255.274479) (xy 342.111976 -255.242292)
			(xy 342.078228 -255.204198) (xy 342.051027 -255.161184) (xy 342.031079 -255.114364) (xy 342.0189 -255.06495)
			(xy 342.014805 -255.014222) (xy 341.708994 -255.014222) (xy 341.708504 -255.039211) (xy 341.700685 -255.088574)
			(xy 341.685241 -255.136106) (xy 341.662551 -255.180638) (xy 341.633175 -255.221071) (xy 341.597835 -255.256411)
			(xy 341.557402 -255.285787) (xy 341.51287 -255.308477) (xy 341.465338 -255.323921) (xy 341.415975 -255.33174)
			(xy 341.365997 -255.33174) (xy 341.316634 -255.323921) (xy 341.269102 -255.308477) (xy 341.22457 -255.285787)
			(xy 341.184137 -255.256411) (xy 341.148797 -255.221071) (xy 341.119421 -255.180638) (xy 341.096731 -255.136106)
			(xy 341.081287 -255.088574) (xy 341.073468 -255.039211) (xy 340.766405 -255.039211) (xy 340.766396 -255.039668)
			(xy 340.758232 -255.089902) (xy 340.742116 -255.138176) (xy 340.718465 -255.183239) (xy 340.687892 -255.223925)
			(xy 340.651188 -255.25918) (xy 340.609304 -255.28809) (xy 340.563325 -255.309907) (xy 340.514441 -255.324067)
			(xy 340.46392 -255.330201) (xy 340.413068 -255.328152) (xy 340.363204 -255.317972) (xy 340.315618 -255.299925)
			(xy 340.271544 -255.274479) (xy 340.232122 -255.242292) (xy 340.198374 -255.204198) (xy 340.171173 -255.161184)
			(xy 340.151225 -255.114364) (xy 340.139046 -255.06495) (xy 340.134951 -255.014222) (xy 339.82914 -255.014222)
			(xy 339.82865 -255.039211) (xy 339.820831 -255.088574) (xy 339.805387 -255.136106) (xy 339.782697 -255.180638)
			(xy 339.753321 -255.221071) (xy 339.717981 -255.256411) (xy 339.677548 -255.285787) (xy 339.633016 -255.308477)
			(xy 339.585484 -255.323921) (xy 339.536121 -255.33174) (xy 339.486143 -255.33174) (xy 339.43678 -255.323921)
			(xy 339.389248 -255.308477) (xy 339.344716 -255.285787) (xy 339.304283 -255.256411) (xy 339.268943 -255.221071)
			(xy 339.239567 -255.180638) (xy 339.216877 -255.136106) (xy 339.201433 -255.088574) (xy 339.193614 -255.039211)
			(xy 338.886297 -255.039211) (xy 338.886288 -255.039668) (xy 338.878124 -255.089902) (xy 338.862008 -255.138176)
			(xy 338.838357 -255.183239) (xy 338.807784 -255.223925) (xy 338.77108 -255.25918) (xy 338.729196 -255.28809)
			(xy 338.683217 -255.309907) (xy 338.634333 -255.324067) (xy 338.583812 -255.330201) (xy 338.53296 -255.328152)
			(xy 338.483096 -255.317972) (xy 338.43551 -255.299925) (xy 338.391436 -255.274479) (xy 338.352014 -255.242292)
			(xy 338.318266 -255.204198) (xy 338.291065 -255.161184) (xy 338.271117 -255.114364) (xy 338.258938 -255.06495)
			(xy 338.254843 -255.014222) (xy 338.012532 -255.014222) (xy 338.012532 -255.406398) (xy 338.013035 -255.416057)
			(xy 338.020358 -255.433941) (xy 338.026756 -255.441196) (xy 338.068412 -255.483868) (xy 338.071906 -255.487326)
			(xy 338.079963 -255.492958) (xy 338.084414 -255.495044) (xy 338.10956 -255.505966) (xy 338.118704 -255.506474)
			(xy 338.144038 -255.508367) (xy 338.193673 -255.519184) (xy 338.240959 -255.537751) (xy 338.284694 -255.563594)
			(xy 338.323768 -255.596057) (xy 338.357188 -255.634316) (xy 338.384105 -255.677399) (xy 338.403835 -255.724211)
			(xy 338.415877 -255.773563) (xy 338.419925 -255.824202) (xy 338.419923 -255.824228) (xy 338.724743 -255.824228)
			(xy 338.728838 -255.7735) (xy 338.741017 -255.724086) (xy 338.760965 -255.677266) (xy 338.788166 -255.634252)
			(xy 338.821914 -255.596158) (xy 338.861336 -255.563971) (xy 338.90541 -255.538525) (xy 338.952996 -255.520478)
			(xy 339.00286 -255.510298) (xy 339.053712 -255.508249) (xy 339.104233 -255.514383) (xy 339.153117 -255.528543)
			(xy 339.199096 -255.55036) (xy 339.24098 -255.57927) (xy 339.277684 -255.614525) (xy 339.308257 -255.655211)
			(xy 339.331908 -255.700274) (xy 339.348024 -255.748548) (xy 339.356188 -255.798782) (xy 339.3567 -255.824228)
			(xy 339.664797 -255.824228) (xy 339.668892 -255.7735) (xy 339.681071 -255.724086) (xy 339.701019 -255.677266)
			(xy 339.72822 -255.634252) (xy 339.761968 -255.596158) (xy 339.80139 -255.563971) (xy 339.845464 -255.538525)
			(xy 339.89305 -255.520478) (xy 339.942914 -255.510298) (xy 339.993766 -255.508249) (xy 340.044287 -255.514383)
			(xy 340.093171 -255.528543) (xy 340.13915 -255.55036) (xy 340.181034 -255.57927) (xy 340.217738 -255.614525)
			(xy 340.248311 -255.655211) (xy 340.271962 -255.700274) (xy 340.288078 -255.748548) (xy 340.296242 -255.798782)
			(xy 340.296754 -255.824228) (xy 340.296251 -255.849217) (xy 340.603568 -255.849217) (xy 340.603568 -255.799239)
			(xy 340.611387 -255.749876) (xy 340.626831 -255.702344) (xy 340.649521 -255.657812) (xy 340.678897 -255.617379)
			(xy 340.714237 -255.582039) (xy 340.75467 -255.552663) (xy 340.799202 -255.529973) (xy 340.846734 -255.514529)
			(xy 340.896097 -255.50671) (xy 340.946075 -255.50671) (xy 340.995438 -255.514529) (xy 341.04297 -255.529973)
			(xy 341.087502 -255.552663) (xy 341.127935 -255.582039) (xy 341.163275 -255.617379) (xy 341.192651 -255.657812)
			(xy 341.215341 -255.702344) (xy 341.230785 -255.749876) (xy 341.238604 -255.799239) (xy 341.239094 -255.824228)
			(xy 341.544905 -255.824228) (xy 341.549 -255.7735) (xy 341.561179 -255.724086) (xy 341.581127 -255.677266)
			(xy 341.608328 -255.634252) (xy 341.642076 -255.596158) (xy 341.681498 -255.563971) (xy 341.725572 -255.538525)
			(xy 341.773158 -255.520478) (xy 341.823022 -255.510298) (xy 341.873874 -255.508249) (xy 341.924395 -255.514383)
			(xy 341.973279 -255.528543) (xy 342.019258 -255.55036) (xy 342.061142 -255.57927) (xy 342.097846 -255.614525)
			(xy 342.128419 -255.655211) (xy 342.15207 -255.700274) (xy 342.168186 -255.748548) (xy 342.17635 -255.798782)
			(xy 342.176862 -255.824228) (xy 342.176359 -255.849217) (xy 342.483676 -255.849217) (xy 342.483676 -255.799239)
			(xy 342.491495 -255.749876) (xy 342.506939 -255.702344) (xy 342.529629 -255.657812) (xy 342.559005 -255.617379)
			(xy 342.594345 -255.582039) (xy 342.634778 -255.552663) (xy 342.67931 -255.529973) (xy 342.726842 -255.514529)
			(xy 342.776205 -255.50671) (xy 342.826183 -255.50671) (xy 342.875546 -255.514529) (xy 342.923078 -255.529973)
			(xy 342.96761 -255.552663) (xy 343.008043 -255.582039) (xy 343.043383 -255.617379) (xy 343.072759 -255.657812)
			(xy 343.095449 -255.702344) (xy 343.110893 -255.749876) (xy 343.118712 -255.799239) (xy 343.119202 -255.824228)
			(xy 343.118712 -255.849217) (xy 343.110893 -255.89858) (xy 343.095449 -255.946112) (xy 343.072759 -255.990644)
			(xy 343.043383 -256.031077) (xy 343.008043 -256.066417) (xy 342.96761 -256.095793) (xy 342.923078 -256.118483)
			(xy 342.875546 -256.133927) (xy 342.826183 -256.141746) (xy 342.776205 -256.141746) (xy 342.726842 -256.133927)
			(xy 342.67931 -256.118483) (xy 342.634778 -256.095793) (xy 342.594345 -256.066417) (xy 342.559005 -256.031077)
			(xy 342.529629 -255.990644) (xy 342.506939 -255.946112) (xy 342.491495 -255.89858) (xy 342.483676 -255.849217)
			(xy 342.176359 -255.849217) (xy 342.17635 -255.849674) (xy 342.168186 -255.899908) (xy 342.15207 -255.948182)
			(xy 342.128419 -255.993245) (xy 342.097846 -256.033931) (xy 342.061142 -256.069186) (xy 342.019258 -256.098096)
			(xy 341.973279 -256.119913) (xy 341.924395 -256.134073) (xy 341.873874 -256.140207) (xy 341.823022 -256.138158)
			(xy 341.773158 -256.127978) (xy 341.725572 -256.109931) (xy 341.681498 -256.084485) (xy 341.642076 -256.052298)
			(xy 341.608328 -256.014204) (xy 341.581127 -255.97119) (xy 341.561179 -255.92437) (xy 341.549 -255.874956)
			(xy 341.544905 -255.824228) (xy 341.239094 -255.824228) (xy 341.238604 -255.849217) (xy 341.230785 -255.89858)
			(xy 341.215341 -255.946112) (xy 341.192651 -255.990644) (xy 341.163275 -256.031077) (xy 341.127935 -256.066417)
			(xy 341.087502 -256.095793) (xy 341.04297 -256.118483) (xy 340.995438 -256.133927) (xy 340.946075 -256.141746)
			(xy 340.896097 -256.141746) (xy 340.846734 -256.133927) (xy 340.799202 -256.118483) (xy 340.75467 -256.095793)
			(xy 340.714237 -256.066417) (xy 340.678897 -256.031077) (xy 340.649521 -255.990644) (xy 340.626831 -255.946112)
			(xy 340.611387 -255.89858) (xy 340.603568 -255.849217) (xy 340.296251 -255.849217) (xy 340.296242 -255.849674)
			(xy 340.288078 -255.899908) (xy 340.271962 -255.948182) (xy 340.248311 -255.993245) (xy 340.217738 -256.033931)
			(xy 340.181034 -256.069186) (xy 340.13915 -256.098096) (xy 340.093171 -256.119913) (xy 340.044287 -256.134073)
			(xy 339.993766 -256.140207) (xy 339.942914 -256.138158) (xy 339.89305 -256.127978) (xy 339.845464 -256.109931)
			(xy 339.80139 -256.084485) (xy 339.761968 -256.052298) (xy 339.72822 -256.014204) (xy 339.701019 -255.97119)
			(xy 339.681071 -255.92437) (xy 339.668892 -255.874956) (xy 339.664797 -255.824228) (xy 339.3567 -255.824228)
			(xy 339.356188 -255.849674) (xy 339.348024 -255.899908) (xy 339.331908 -255.948182) (xy 339.308257 -255.993245)
			(xy 339.277684 -256.033931) (xy 339.24098 -256.069186) (xy 339.199096 -256.098096) (xy 339.153117 -256.119913)
			(xy 339.104233 -256.134073) (xy 339.053712 -256.140207) (xy 339.00286 -256.138158) (xy 338.952996 -256.127978)
			(xy 338.90541 -256.109931) (xy 338.861336 -256.084485) (xy 338.821914 -256.052298) (xy 338.788166 -256.014204)
			(xy 338.760965 -255.97119) (xy 338.741017 -255.92437) (xy 338.728838 -255.874956) (xy 338.724743 -255.824228)
			(xy 338.419923 -255.824228) (xy 338.415877 -255.87484) (xy 338.403834 -255.924192) (xy 338.384104 -255.971004)
			(xy 338.357186 -256.014086) (xy 338.323766 -256.052345) (xy 338.284692 -256.084808) (xy 338.240956 -256.110651)
			(xy 338.19367 -256.129217) (xy 338.144035 -256.140034) (xy 338.118704 -256.141982) (xy 338.10956 -256.14249)
			(xy 338.084414 -256.153412) (xy 338.079965 -256.155503) (xy 338.071901 -256.161125) (xy 338.068412 -256.164588)
			(xy 338.026756 -256.20726) (xy 338.020303 -256.214479) (xy 338.012988 -256.232386) (xy 338.012532 -256.242058)
			(xy 338.012532 -256.634234) (xy 338.254843 -256.634234) (xy 338.258938 -256.583506) (xy 338.271117 -256.534092)
			(xy 338.291065 -256.487272) (xy 338.318266 -256.444258) (xy 338.352014 -256.406164) (xy 338.391436 -256.373977)
			(xy 338.43551 -256.348531) (xy 338.483096 -256.330484) (xy 338.53296 -256.320304) (xy 338.583812 -256.318255)
			(xy 338.634333 -256.324389) (xy 338.683217 -256.338549) (xy 338.729196 -256.360366) (xy 338.77108 -256.389276)
			(xy 338.807784 -256.424531) (xy 338.838357 -256.465217) (xy 338.862008 -256.51028) (xy 338.878124 -256.558554)
			(xy 338.886288 -256.608788) (xy 338.8868 -256.634234) (xy 338.886297 -256.659223) (xy 339.193614 -256.659223)
			(xy 339.193614 -256.609245) (xy 339.201433 -256.559882) (xy 339.216877 -256.51235) (xy 339.239567 -256.467818)
			(xy 339.268943 -256.427385) (xy 339.304283 -256.392045) (xy 339.344716 -256.362669) (xy 339.389248 -256.339979)
			(xy 339.43678 -256.324535) (xy 339.486143 -256.316716) (xy 339.536121 -256.316716) (xy 339.585484 -256.324535)
			(xy 339.633016 -256.339979) (xy 339.677548 -256.362669) (xy 339.717981 -256.392045) (xy 339.753321 -256.427385)
			(xy 339.782697 -256.467818) (xy 339.805387 -256.51235) (xy 339.820831 -256.559882) (xy 339.82865 -256.609245)
			(xy 339.82914 -256.634234) (xy 339.82865 -256.659223) (xy 340.133668 -256.659223) (xy 340.133668 -256.609245)
			(xy 340.141487 -256.559882) (xy 340.156931 -256.51235) (xy 340.179621 -256.467818) (xy 340.208997 -256.427385)
			(xy 340.244337 -256.392045) (xy 340.28477 -256.362669) (xy 340.329302 -256.339979) (xy 340.376834 -256.324535)
			(xy 340.426197 -256.316716) (xy 340.476175 -256.316716) (xy 340.525538 -256.324535) (xy 340.57307 -256.339979)
			(xy 340.617602 -256.362669) (xy 340.658035 -256.392045) (xy 340.693375 -256.427385) (xy 340.722751 -256.467818)
			(xy 340.745441 -256.51235) (xy 340.760885 -256.559882) (xy 340.768704 -256.609245) (xy 340.769194 -256.634234)
			(xy 340.768704 -256.659223) (xy 341.073468 -256.659223) (xy 341.073468 -256.609245) (xy 341.081287 -256.559882)
			(xy 341.096731 -256.51235) (xy 341.119421 -256.467818) (xy 341.148797 -256.427385) (xy 341.184137 -256.392045)
			(xy 341.22457 -256.362669) (xy 341.269102 -256.339979) (xy 341.316634 -256.324535) (xy 341.365997 -256.316716)
			(xy 341.415975 -256.316716) (xy 341.465338 -256.324535) (xy 341.51287 -256.339979) (xy 341.557402 -256.362669)
			(xy 341.597835 -256.392045) (xy 341.633175 -256.427385) (xy 341.662551 -256.467818) (xy 341.685241 -256.51235)
			(xy 341.700685 -256.559882) (xy 341.708504 -256.609245) (xy 341.708994 -256.634234) (xy 342.014805 -256.634234)
			(xy 342.0189 -256.583506) (xy 342.031079 -256.534092) (xy 342.051027 -256.487272) (xy 342.078228 -256.444258)
			(xy 342.111976 -256.406164) (xy 342.151398 -256.373977) (xy 342.195472 -256.348531) (xy 342.243058 -256.330484)
			(xy 342.292922 -256.320304) (xy 342.343774 -256.318255) (xy 342.394295 -256.324389) (xy 342.443179 -256.338549)
			(xy 342.489158 -256.360366) (xy 342.531042 -256.389276) (xy 342.567746 -256.424531) (xy 342.598319 -256.465217)
			(xy 342.62197 -256.51028) (xy 342.638086 -256.558554) (xy 342.64625 -256.608788) (xy 342.646762 -256.634234)
			(xy 342.646259 -256.659223) (xy 342.953576 -256.659223) (xy 342.953576 -256.609245) (xy 342.961395 -256.559882)
			(xy 342.976839 -256.51235) (xy 342.999529 -256.467818) (xy 343.028905 -256.427385) (xy 343.064245 -256.392045)
			(xy 343.104678 -256.362669) (xy 343.14921 -256.339979) (xy 343.196742 -256.324535) (xy 343.246105 -256.316716)
			(xy 343.296083 -256.316716) (xy 343.345446 -256.324535) (xy 343.392978 -256.339979) (xy 343.43751 -256.362669)
			(xy 343.477943 -256.392045) (xy 343.513283 -256.427385) (xy 343.542659 -256.467818) (xy 343.565349 -256.51235)
			(xy 343.580793 -256.559882) (xy 343.588612 -256.609245) (xy 343.589102 -256.634234) (xy 343.588612 -256.659223)
			(xy 343.580793 -256.708586) (xy 343.565349 -256.756118) (xy 343.542659 -256.80065) (xy 343.513283 -256.841083)
			(xy 343.477943 -256.876423) (xy 343.43751 -256.905799) (xy 343.392978 -256.928489) (xy 343.345446 -256.943933)
			(xy 343.296083 -256.951752) (xy 343.246105 -256.951752) (xy 343.196742 -256.943933) (xy 343.14921 -256.928489)
			(xy 343.104678 -256.905799) (xy 343.064245 -256.876423) (xy 343.028905 -256.841083) (xy 342.999529 -256.80065)
			(xy 342.976839 -256.756118) (xy 342.961395 -256.708586) (xy 342.953576 -256.659223) (xy 342.646259 -256.659223)
			(xy 342.64625 -256.65968) (xy 342.638086 -256.709914) (xy 342.62197 -256.758188) (xy 342.598319 -256.803251)
			(xy 342.567746 -256.843937) (xy 342.531042 -256.879192) (xy 342.489158 -256.908102) (xy 342.443179 -256.929919)
			(xy 342.394295 -256.944079) (xy 342.343774 -256.950213) (xy 342.292922 -256.948164) (xy 342.243058 -256.937984)
			(xy 342.195472 -256.919937) (xy 342.151398 -256.894491) (xy 342.111976 -256.862304) (xy 342.078228 -256.82421)
			(xy 342.051027 -256.781196) (xy 342.031079 -256.734376) (xy 342.0189 -256.684962) (xy 342.014805 -256.634234)
			(xy 341.708994 -256.634234) (xy 341.708504 -256.659223) (xy 341.700685 -256.708586) (xy 341.685241 -256.756118)
			(xy 341.662551 -256.80065) (xy 341.633175 -256.841083) (xy 341.597835 -256.876423) (xy 341.557402 -256.905799)
			(xy 341.51287 -256.928489) (xy 341.465338 -256.943933) (xy 341.415975 -256.951752) (xy 341.365997 -256.951752)
			(xy 341.316634 -256.943933) (xy 341.269102 -256.928489) (xy 341.22457 -256.905799) (xy 341.184137 -256.876423)
			(xy 341.148797 -256.841083) (xy 341.119421 -256.80065) (xy 341.096731 -256.756118) (xy 341.081287 -256.708586)
			(xy 341.073468 -256.659223) (xy 340.768704 -256.659223) (xy 340.760885 -256.708586) (xy 340.745441 -256.756118)
			(xy 340.722751 -256.80065) (xy 340.693375 -256.841083) (xy 340.658035 -256.876423) (xy 340.617602 -256.905799)
			(xy 340.57307 -256.928489) (xy 340.525538 -256.943933) (xy 340.476175 -256.951752) (xy 340.426197 -256.951752)
			(xy 340.376834 -256.943933) (xy 340.329302 -256.928489) (xy 340.28477 -256.905799) (xy 340.244337 -256.876423)
			(xy 340.208997 -256.841083) (xy 340.179621 -256.80065) (xy 340.156931 -256.756118) (xy 340.141487 -256.708586)
			(xy 340.133668 -256.659223) (xy 339.82865 -256.659223) (xy 339.820831 -256.708586) (xy 339.805387 -256.756118)
			(xy 339.782697 -256.80065) (xy 339.753321 -256.841083) (xy 339.717981 -256.876423) (xy 339.677548 -256.905799)
			(xy 339.633016 -256.928489) (xy 339.585484 -256.943933) (xy 339.536121 -256.951752) (xy 339.486143 -256.951752)
			(xy 339.43678 -256.943933) (xy 339.389248 -256.928489) (xy 339.344716 -256.905799) (xy 339.304283 -256.876423)
			(xy 339.268943 -256.841083) (xy 339.239567 -256.80065) (xy 339.216877 -256.756118) (xy 339.201433 -256.708586)
			(xy 339.193614 -256.659223) (xy 338.886297 -256.659223) (xy 338.886288 -256.65968) (xy 338.878124 -256.709914)
			(xy 338.862008 -256.758188) (xy 338.838357 -256.803251) (xy 338.807784 -256.843937) (xy 338.77108 -256.879192)
			(xy 338.729196 -256.908102) (xy 338.683217 -256.929919) (xy 338.634333 -256.944079) (xy 338.583812 -256.950213)
			(xy 338.53296 -256.948164) (xy 338.483096 -256.937984) (xy 338.43551 -256.919937) (xy 338.391436 -256.894491)
			(xy 338.352014 -256.862304) (xy 338.318266 -256.82421) (xy 338.291065 -256.781196) (xy 338.271117 -256.734376)
			(xy 338.258938 -256.684962) (xy 338.254843 -256.634234) (xy 338.012532 -256.634234) (xy 338.012532 -258.183888)
			(xy 346.529152 -258.183888) (xy 346.529152 -257.676396) (xy 346.529684 -257.666394) (xy 346.537336 -257.647911)
			(xy 346.551474 -257.63376) (xy 346.56995 -257.626092) (xy 346.579952 -257.625596) (xy 346.794328 -257.625596)
			(xy 346.794328 -257.616452) (xy 346.79475 -257.606438) (xy 346.80243 -257.58794) (xy 346.816604 -257.573787)
			(xy 346.835113 -257.566135) (xy 346.845128 -257.565652) (xy 347.04909 -257.565652) (xy 347.069146 -257.566096)
			(xy 347.108553 -257.573585) (xy 347.145869 -257.588302) (xy 347.179779 -257.609728) (xy 347.209091 -257.637111)
			(xy 347.221302 -257.653028) (xy 347.228922 -257.66141) (xy 347.249507 -257.679944) (xy 347.285152 -257.722341)
			(xy 347.313807 -257.769744) (xy 347.334781 -257.82101) (xy 347.34757 -257.874904) (xy 347.351864 -257.930128)
			(xy 347.347561 -257.985351) (xy 347.334764 -258.039243) (xy 347.313782 -258.090505) (xy 347.28512 -258.137904)
			(xy 347.249468 -258.180296) (xy 347.228922 -258.198874) (xy 347.221302 -258.207256) (xy 347.209105 -258.223183)
			(xy 347.179785 -258.250558) (xy 347.145871 -258.271978) (xy 347.108554 -258.28669) (xy 347.069146 -258.294176)
			(xy 347.04909 -258.294632) (xy 346.794328 -258.294632) (xy 346.794328 -258.285488) (xy 346.793822 -258.275483)
			(xy 346.786164 -258.256996) (xy 346.772017 -258.242845) (xy 346.753533 -258.235181) (xy 346.743528 -258.234688)
			(xy 346.579952 -258.234688) (xy 346.56994 -258.234251) (xy 346.551445 -258.226573) (xy 346.537293 -258.212405)
			(xy 346.529637 -258.193901) (xy 346.529152 -258.183888) (xy 338.012532 -258.183888) (xy 338.012532 -259.084064)
			(xy 346.529152 -259.084064) (xy 346.529152 -258.576064) (xy 346.529657 -258.56606) (xy 346.53732 -258.547577)
			(xy 346.551466 -258.533427) (xy 346.569948 -258.52576) (xy 346.579952 -258.525264) (xy 346.794328 -258.525264)
			(xy 346.794328 -258.51612) (xy 346.794737 -258.506097) (xy 346.802405 -258.487575) (xy 346.816582 -258.473401)
			(xy 346.835105 -258.465735) (xy 346.845128 -258.46532) (xy 347.04909 -258.46532) (xy 347.069159 -258.465808)
			(xy 347.108589 -258.473317) (xy 347.145917 -258.488073) (xy 347.179824 -258.509554) (xy 347.209112 -258.537)
			(xy 347.221302 -258.55295) (xy 347.228922 -258.561332) (xy 347.249429 -258.579948) (xy 347.285074 -258.622334)
			(xy 347.313731 -258.669724) (xy 347.334709 -258.720979) (xy 347.347504 -258.774862) (xy 347.351805 -258.830076)
			(xy 347.347511 -258.885291) (xy 347.334724 -258.939176) (xy 347.313753 -258.990433) (xy 347.285102 -259.037828)
			(xy 347.249462 -259.080218) (xy 347.228922 -259.098796) (xy 347.221302 -259.107178) (xy 347.209127 -259.123136)
			(xy 347.179814 -259.150553) (xy 347.145901 -259.17202) (xy 347.108579 -259.186783) (xy 347.069157 -259.194325)
			(xy 347.04909 -259.194808) (xy 346.794328 -259.194808) (xy 346.794328 -259.185664) (xy 346.793842 -259.175657)
			(xy 346.786176 -259.15717) (xy 346.772023 -259.14302) (xy 346.753535 -259.135356) (xy 346.743528 -259.134864)
			(xy 346.579952 -259.134864) (xy 346.569937 -259.13445) (xy 346.551437 -259.126768) (xy 346.537285 -259.112592)
			(xy 346.529633 -259.09408) (xy 346.529152 -259.084064) (xy 338.012532 -259.084064) (xy 338.012532 -259.983732)
			(xy 346.529152 -259.983732) (xy 346.529152 -259.47624) (xy 346.52972 -259.466241) (xy 346.537357 -259.447759)
			(xy 346.551485 -259.433607) (xy 346.569954 -259.425937) (xy 346.579952 -259.42544) (xy 346.794328 -259.42544)
			(xy 346.794328 -259.416296) (xy 346.794717 -259.406271) (xy 346.802393 -259.387749) (xy 346.816575 -259.373575)
			(xy 346.835103 -259.365911) (xy 346.845128 -259.365496) (xy 347.04909 -259.365496) (xy 347.069147 -259.365923)
			(xy 347.108556 -259.373414) (xy 347.145872 -259.388134) (xy 347.179783 -259.409565) (xy 347.209093 -259.436952)
			(xy 347.221302 -259.452872) (xy 347.228922 -259.461254) (xy 347.249451 -259.479847) (xy 347.285096 -259.522236)
			(xy 347.313753 -259.56963) (xy 347.33473 -259.620888) (xy 347.347522 -259.674774) (xy 347.351822 -259.729991)
			(xy 347.347525 -259.785208) (xy 347.334735 -259.839095) (xy 347.313761 -259.890354) (xy 347.285107 -259.937749)
			(xy 347.249464 -259.98014) (xy 347.228922 -259.998718) (xy 347.221302 -260.0071) (xy 347.209116 -260.023036)
			(xy 347.179793 -260.050408) (xy 347.145875 -260.071825) (xy 347.108556 -260.086535) (xy 347.069147 -260.09402)
			(xy 347.04909 -260.094476) (xy 346.794328 -260.094476) (xy 346.794328 -260.085332) (xy 346.793855 -260.075316)
			(xy 346.786201 -260.056805) (xy 346.772045 -260.042633) (xy 346.753543 -260.034957) (xy 346.743528 -260.034532)
			(xy 346.579952 -260.034532) (xy 346.569945 -260.034052) (xy 346.551459 -260.026383) (xy 346.537308 -260.012228)
			(xy 346.529645 -259.993739) (xy 346.529152 -259.983732) (xy 338.012532 -259.983732) (xy 338.012532 -260.782562)
			(xy 338.012935 -260.791726) (xy 338.019488 -260.808842) (xy 338.031738 -260.822474) (xy 338.03971 -260.827012)
			(xy 338.045044 -260.829044) (xy 338.068712 -260.838678) (xy 338.112871 -260.864387) (xy 338.152353 -260.896825)
			(xy 338.186142 -260.935157) (xy 338.213368 -260.978397) (xy 338.233332 -261.025433) (xy 338.24552 -261.075056)
			(xy 338.24962 -261.125989) (xy 338.247612 -261.150959) (xy 338.553534 -261.150959) (xy 338.553534 -261.100981)
			(xy 338.561353 -261.051618) (xy 338.576797 -261.004086) (xy 338.599487 -260.959554) (xy 338.628863 -260.919121)
			(xy 338.664203 -260.883781) (xy 338.704636 -260.854405) (xy 338.749168 -260.831715) (xy 338.7967 -260.816271)
			(xy 338.846063 -260.808452) (xy 338.896041 -260.808452) (xy 338.945404 -260.816271) (xy 338.992936 -260.831715)
			(xy 339.037468 -260.854405) (xy 339.077901 -260.883781) (xy 339.113241 -260.919121) (xy 339.142617 -260.959554)
			(xy 339.165307 -261.004086) (xy 339.180751 -261.051618) (xy 339.18857 -261.100981) (xy 339.18906 -261.12597)
			(xy 339.18857 -261.150959) (xy 339.493588 -261.150959) (xy 339.493588 -261.100981) (xy 339.501407 -261.051618)
			(xy 339.516851 -261.004086) (xy 339.539541 -260.959554) (xy 339.568917 -260.919121) (xy 339.604257 -260.883781)
			(xy 339.64469 -260.854405) (xy 339.689222 -260.831715) (xy 339.736754 -260.816271) (xy 339.786117 -260.808452)
			(xy 339.836095 -260.808452) (xy 339.885458 -260.816271) (xy 339.93299 -260.831715) (xy 339.977522 -260.854405)
			(xy 340.017955 -260.883781) (xy 340.053295 -260.919121) (xy 340.082671 -260.959554) (xy 340.105361 -261.004086)
			(xy 340.120805 -261.051618) (xy 340.128624 -261.100981) (xy 340.129114 -261.12597) (xy 340.128624 -261.150959)
			(xy 340.433642 -261.150959) (xy 340.433642 -261.100981) (xy 340.441461 -261.051618) (xy 340.456905 -261.004086)
			(xy 340.479595 -260.959554) (xy 340.508971 -260.919121) (xy 340.544311 -260.883781) (xy 340.584744 -260.854405)
			(xy 340.629276 -260.831715) (xy 340.676808 -260.816271) (xy 340.726171 -260.808452) (xy 340.776149 -260.808452)
			(xy 340.825512 -260.816271) (xy 340.873044 -260.831715) (xy 340.917576 -260.854405) (xy 340.958009 -260.883781)
			(xy 340.993349 -260.919121) (xy 341.022725 -260.959554) (xy 341.045415 -261.004086) (xy 341.060859 -261.051618)
			(xy 341.068678 -261.100981) (xy 341.069168 -261.12597) (xy 341.068678 -261.150959) (xy 342.313496 -261.150959)
			(xy 342.313496 -261.100981) (xy 342.321315 -261.051618) (xy 342.336759 -261.004086) (xy 342.359449 -260.959554)
			(xy 342.388825 -260.919121) (xy 342.424165 -260.883781) (xy 342.464598 -260.854405) (xy 342.50913 -260.831715)
			(xy 342.556662 -260.816271) (xy 342.606025 -260.808452) (xy 342.656003 -260.808452) (xy 342.705366 -260.816271)
			(xy 342.752898 -260.831715) (xy 342.79743 -260.854405) (xy 342.837863 -260.883781) (xy 342.873203 -260.919121)
			(xy 342.902579 -260.959554) (xy 342.925269 -261.004086) (xy 342.940713 -261.051618) (xy 342.948532 -261.100981)
			(xy 342.949022 -261.12597) (xy 342.948532 -261.150959) (xy 343.25355 -261.150959) (xy 343.25355 -261.100981)
			(xy 343.261369 -261.051618) (xy 343.276813 -261.004086) (xy 343.299503 -260.959554) (xy 343.328879 -260.919121)
			(xy 343.364219 -260.883781) (xy 343.404652 -260.854405) (xy 343.449184 -260.831715) (xy 343.496716 -260.816271)
			(xy 343.546079 -260.808452) (xy 343.596057 -260.808452) (xy 343.64542 -260.816271) (xy 343.692952 -260.831715)
			(xy 343.737484 -260.854405) (xy 343.777917 -260.883781) (xy 343.813257 -260.919121) (xy 343.842633 -260.959554)
			(xy 343.865323 -261.004086) (xy 343.880767 -261.051618) (xy 343.888586 -261.100981) (xy 343.889076 -261.12597)
			(xy 343.888586 -261.150959) (xy 344.193604 -261.150959) (xy 344.193604 -261.100981) (xy 344.201423 -261.051618)
			(xy 344.216867 -261.004086) (xy 344.239557 -260.959554) (xy 344.268933 -260.919121) (xy 344.304273 -260.883781)
			(xy 344.344706 -260.854405) (xy 344.389238 -260.831715) (xy 344.43677 -260.816271) (xy 344.486133 -260.808452)
			(xy 344.536111 -260.808452) (xy 344.585474 -260.816271) (xy 344.633006 -260.831715) (xy 344.677538 -260.854405)
			(xy 344.717971 -260.883781) (xy 344.753311 -260.919121) (xy 344.782687 -260.959554) (xy 344.805377 -261.004086)
			(xy 344.820821 -261.051618) (xy 344.82864 -261.100981) (xy 344.82913 -261.12597) (xy 344.82864 -261.150959)
			(xy 346.073712 -261.150959) (xy 346.073712 -261.100981) (xy 346.081531 -261.051618) (xy 346.096975 -261.004086)
			(xy 346.119665 -260.959554) (xy 346.149041 -260.919121) (xy 346.184381 -260.883781) (xy 346.224814 -260.854405)
			(xy 346.269346 -260.831715) (xy 346.316878 -260.816271) (xy 346.366241 -260.808452) (xy 346.416219 -260.808452)
			(xy 346.465582 -260.816271) (xy 346.513114 -260.831715) (xy 346.557646 -260.854405) (xy 346.598079 -260.883781)
			(xy 346.633419 -260.919121) (xy 346.662795 -260.959554) (xy 346.685485 -261.004086) (xy 346.700929 -261.051618)
			(xy 346.708748 -261.100981) (xy 346.709238 -261.12597) (xy 346.708748 -261.150959) (xy 346.700929 -261.200322)
			(xy 346.685485 -261.247854) (xy 346.662795 -261.292386) (xy 346.633419 -261.332819) (xy 346.598079 -261.368159)
			(xy 346.557646 -261.397535) (xy 346.513114 -261.420225) (xy 346.465582 -261.435669) (xy 346.416219 -261.443488)
			(xy 346.366241 -261.443488) (xy 346.316878 -261.435669) (xy 346.269346 -261.420225) (xy 346.224814 -261.397535)
			(xy 346.184381 -261.368159) (xy 346.149041 -261.332819) (xy 346.119665 -261.292386) (xy 346.096975 -261.247854)
			(xy 346.081531 -261.200322) (xy 346.073712 -261.150959) (xy 344.82864 -261.150959) (xy 344.820821 -261.200322)
			(xy 344.805377 -261.247854) (xy 344.782687 -261.292386) (xy 344.753311 -261.332819) (xy 344.717971 -261.368159)
			(xy 344.677538 -261.397535) (xy 344.633006 -261.420225) (xy 344.585474 -261.435669) (xy 344.536111 -261.443488)
			(xy 344.486133 -261.443488) (xy 344.43677 -261.435669) (xy 344.389238 -261.420225) (xy 344.344706 -261.397535)
			(xy 344.304273 -261.368159) (xy 344.268933 -261.332819) (xy 344.239557 -261.292386) (xy 344.216867 -261.247854)
			(xy 344.201423 -261.200322) (xy 344.193604 -261.150959) (xy 343.888586 -261.150959) (xy 343.880767 -261.200322)
			(xy 343.865323 -261.247854) (xy 343.842633 -261.292386) (xy 343.813257 -261.332819) (xy 343.777917 -261.368159)
			(xy 343.737484 -261.397535) (xy 343.692952 -261.420225) (xy 343.64542 -261.435669) (xy 343.596057 -261.443488)
			(xy 343.546079 -261.443488) (xy 343.496716 -261.435669) (xy 343.449184 -261.420225) (xy 343.404652 -261.397535)
			(xy 343.364219 -261.368159) (xy 343.328879 -261.332819) (xy 343.299503 -261.292386) (xy 343.276813 -261.247854)
			(xy 343.261369 -261.200322) (xy 343.25355 -261.150959) (xy 342.948532 -261.150959) (xy 342.940713 -261.200322)
			(xy 342.925269 -261.247854) (xy 342.902579 -261.292386) (xy 342.873203 -261.332819) (xy 342.837863 -261.368159)
			(xy 342.79743 -261.397535) (xy 342.752898 -261.420225) (xy 342.705366 -261.435669) (xy 342.656003 -261.443488)
			(xy 342.606025 -261.443488) (xy 342.556662 -261.435669) (xy 342.50913 -261.420225) (xy 342.464598 -261.397535)
			(xy 342.424165 -261.368159) (xy 342.388825 -261.332819) (xy 342.359449 -261.292386) (xy 342.336759 -261.247854)
			(xy 342.321315 -261.200322) (xy 342.313496 -261.150959) (xy 341.068678 -261.150959) (xy 341.060859 -261.200322)
			(xy 341.045415 -261.247854) (xy 341.022725 -261.292386) (xy 340.993349 -261.332819) (xy 340.958009 -261.368159)
			(xy 340.917576 -261.397535) (xy 340.873044 -261.420225) (xy 340.825512 -261.435669) (xy 340.776149 -261.443488)
			(xy 340.726171 -261.443488) (xy 340.676808 -261.435669) (xy 340.629276 -261.420225) (xy 340.584744 -261.397535)
			(xy 340.544311 -261.368159) (xy 340.508971 -261.332819) (xy 340.479595 -261.292386) (xy 340.456905 -261.247854)
			(xy 340.441461 -261.200322) (xy 340.433642 -261.150959) (xy 340.128624 -261.150959) (xy 340.120805 -261.200322)
			(xy 340.105361 -261.247854) (xy 340.082671 -261.292386) (xy 340.053295 -261.332819) (xy 340.017955 -261.368159)
			(xy 339.977522 -261.397535) (xy 339.93299 -261.420225) (xy 339.885458 -261.435669) (xy 339.836095 -261.443488)
			(xy 339.786117 -261.443488) (xy 339.736754 -261.435669) (xy 339.689222 -261.420225) (xy 339.64469 -261.397535)
			(xy 339.604257 -261.368159) (xy 339.568917 -261.332819) (xy 339.539541 -261.292386) (xy 339.516851 -261.247854)
			(xy 339.501407 -261.200322) (xy 339.493588 -261.150959) (xy 339.18857 -261.150959) (xy 339.180751 -261.200322)
			(xy 339.165307 -261.247854) (xy 339.142617 -261.292386) (xy 339.113241 -261.332819) (xy 339.077901 -261.368159)
			(xy 339.037468 -261.397535) (xy 338.992936 -261.420225) (xy 338.945404 -261.435669) (xy 338.896041 -261.443488)
			(xy 338.846063 -261.443488) (xy 338.7967 -261.435669) (xy 338.749168 -261.420225) (xy 338.704636 -261.397535)
			(xy 338.664203 -261.368159) (xy 338.628863 -261.332819) (xy 338.599487 -261.292386) (xy 338.576797 -261.247854)
			(xy 338.561353 -261.200322) (xy 338.553534 -261.150959) (xy 338.247612 -261.150959) (xy 338.245524 -261.176923)
			(xy 338.233339 -261.226546) (xy 338.213378 -261.273584) (xy 338.186154 -261.316826) (xy 338.152369 -261.35516)
			(xy 338.112889 -261.3876) (xy 338.068732 -261.413312) (xy 338.045044 -261.422896) (xy 338.03971 -261.424928)
			(xy 338.031755 -261.429482) (xy 338.019535 -261.443123) (xy 338.012972 -261.460222) (xy 338.012532 -261.469378)
			(xy 338.012532 -261.633716) (xy 338.012957 -261.643264) (xy 338.02006 -261.660991) (xy 338.033242 -261.674809)
			(xy 338.041742 -261.679182) (xy 338.057998 -261.68604) (xy 338.058506 -261.68604) (xy 338.12734 -261.715504)
			(xy 338.134245 -261.718198) (xy 338.148963 -261.719881) (xy 338.156296 -261.718806) (xy 338.1629 -261.71779)
			(xy 338.176362 -261.710678) (xy 338.18195 -261.705598) (xy 338.199792 -261.689244) (xy 338.239501 -261.661579)
			(xy 338.282944 -261.640248) (xy 338.329117 -261.625746) (xy 338.376954 -261.618406) (xy 338.401152 -261.617968)
			(xy 338.426148 -261.618429) (xy 338.475524 -261.626243) (xy 338.52307 -261.641685) (xy 338.567615 -261.664376)
			(xy 338.608061 -261.693756) (xy 338.643413 -261.729102) (xy 338.672799 -261.769544) (xy 338.695497 -261.814085)
			(xy 338.710946 -261.861629) (xy 338.718767 -261.911005) (xy 338.718767 -261.960965) (xy 339.023688 -261.960965)
			(xy 339.023688 -261.910987) (xy 339.031507 -261.861624) (xy 339.046951 -261.814092) (xy 339.069641 -261.76956)
			(xy 339.099017 -261.729127) (xy 339.134357 -261.693787) (xy 339.17479 -261.664411) (xy 339.219322 -261.641721)
			(xy 339.266854 -261.626277) (xy 339.316217 -261.618458) (xy 339.366195 -261.618458) (xy 339.415558 -261.626277)
			(xy 339.46309 -261.641721) (xy 339.507622 -261.664411) (xy 339.548055 -261.693787) (xy 339.583395 -261.729127)
			(xy 339.612771 -261.76956) (xy 339.635461 -261.814092) (xy 339.650905 -261.861624) (xy 339.658724 -261.910987)
			(xy 339.659214 -261.935976) (xy 339.964771 -261.935976) (xy 339.968866 -261.885248) (xy 339.981045 -261.835834)
			(xy 340.000993 -261.789014) (xy 340.028194 -261.746) (xy 340.061942 -261.707906) (xy 340.101364 -261.675719)
			(xy 340.145438 -261.650273) (xy 340.193024 -261.632226) (xy 340.242888 -261.622046) (xy 340.29374 -261.619997)
			(xy 340.344261 -261.626131) (xy 340.393145 -261.640291) (xy 340.439124 -261.662108) (xy 340.481008 -261.691018)
			(xy 340.517712 -261.726273) (xy 340.548285 -261.766959) (xy 340.571936 -261.812022) (xy 340.588052 -261.860296)
			(xy 340.596216 -261.91053) (xy 340.596728 -261.935976) (xy 340.596225 -261.960965) (xy 340.903542 -261.960965)
			(xy 340.903542 -261.910987) (xy 340.911361 -261.861624) (xy 340.926805 -261.814092) (xy 340.949495 -261.76956)
			(xy 340.978871 -261.729127) (xy 341.014211 -261.693787) (xy 341.054644 -261.664411) (xy 341.099176 -261.641721)
			(xy 341.146708 -261.626277) (xy 341.196071 -261.618458) (xy 341.246049 -261.618458) (xy 341.295412 -261.626277)
			(xy 341.342944 -261.641721) (xy 341.387476 -261.664411) (xy 341.427909 -261.693787) (xy 341.463249 -261.729127)
			(xy 341.492625 -261.76956) (xy 341.515315 -261.814092) (xy 341.530759 -261.861624) (xy 341.538578 -261.910987)
			(xy 341.539068 -261.935976) (xy 341.538578 -261.960965) (xy 341.843596 -261.960965) (xy 341.843596 -261.910987)
			(xy 341.851415 -261.861624) (xy 341.866859 -261.814092) (xy 341.889549 -261.76956) (xy 341.918925 -261.729127)
			(xy 341.954265 -261.693787) (xy 341.994698 -261.664411) (xy 342.03923 -261.641721) (xy 342.086762 -261.626277)
			(xy 342.136125 -261.618458) (xy 342.186103 -261.618458) (xy 342.235466 -261.626277) (xy 342.282998 -261.641721)
			(xy 342.32753 -261.664411) (xy 342.367963 -261.693787) (xy 342.403303 -261.729127) (xy 342.432679 -261.76956)
			(xy 342.455369 -261.814092) (xy 342.470813 -261.861624) (xy 342.478632 -261.910987) (xy 342.479122 -261.935976)
			(xy 342.478632 -261.960965) (xy 342.78365 -261.960965) (xy 342.78365 -261.910987) (xy 342.791469 -261.861624)
			(xy 342.806913 -261.814092) (xy 342.829603 -261.76956) (xy 342.858979 -261.729127) (xy 342.894319 -261.693787)
			(xy 342.934752 -261.664411) (xy 342.979284 -261.641721) (xy 343.026816 -261.626277) (xy 343.076179 -261.618458)
			(xy 343.126157 -261.618458) (xy 343.17552 -261.626277) (xy 343.223052 -261.641721) (xy 343.267584 -261.664411)
			(xy 343.308017 -261.693787) (xy 343.343357 -261.729127) (xy 343.372733 -261.76956) (xy 343.395423 -261.814092)
			(xy 343.410867 -261.861624) (xy 343.418686 -261.910987) (xy 343.419176 -261.935976) (xy 343.724987 -261.935976)
			(xy 343.729082 -261.885248) (xy 343.741261 -261.835834) (xy 343.761209 -261.789014) (xy 343.78841 -261.746)
			(xy 343.822158 -261.707906) (xy 343.86158 -261.675719) (xy 343.905654 -261.650273) (xy 343.95324 -261.632226)
			(xy 344.003104 -261.622046) (xy 344.053956 -261.619997) (xy 344.104477 -261.626131) (xy 344.153361 -261.640291)
			(xy 344.19934 -261.662108) (xy 344.241224 -261.691018) (xy 344.277928 -261.726273) (xy 344.308501 -261.766959)
			(xy 344.332152 -261.812022) (xy 344.348268 -261.860296) (xy 344.356432 -261.91053) (xy 344.356944 -261.935976)
			(xy 345.603068 -261.935976) (xy 345.603831 -261.905008) (xy 345.615854 -261.84425) (xy 345.626944 -261.815326)
			(xy 345.6305 -261.806182) (xy 345.6305 -261.720838) (xy 345.630877 -261.699791) (xy 345.638878 -261.658469)
			(xy 345.654813 -261.619513) (xy 345.678067 -261.584431) (xy 345.70774 -261.55458) (xy 345.742682 -261.531116)
			(xy 345.781542 -261.514947) (xy 345.822815 -261.5067) (xy 345.84386 -261.506208) (xy 346.098876 -261.506208)
			(xy 346.098876 -261.515352) (xy 346.099358 -261.525367) (xy 346.107008 -261.543879) (xy 346.121161 -261.558052)
			(xy 346.139661 -261.565728) (xy 346.149676 -261.566152) (xy 346.312744 -261.566152) (xy 346.322749 -261.566651)
			(xy 346.341232 -261.574316) (xy 346.355382 -261.588465) (xy 346.363048 -261.606948) (xy 346.363544 -261.616952)
			(xy 346.363544 -262.124952) (xy 346.363042 -262.134965) (xy 346.355396 -262.153472) (xy 346.34125 -262.167645)
			(xy 346.322756 -262.175324) (xy 346.312744 -262.175752) (xy 346.148406 -262.175752) (xy 346.139973 -262.176053)
			(xy 346.124009 -262.181487) (xy 346.117164 -262.18642) (xy 346.098876 -262.199628) (xy 346.098876 -262.205978)
			(xy 346.069158 -262.235696) (xy 346.02801 -262.235696) (xy 346.02039 -262.237982) (xy 345.996243 -262.245446)
			(xy 345.946346 -262.253481) (xy 345.921076 -262.253984) (xy 345.8923 -262.253364) (xy 345.835688 -262.243012)
			(xy 345.808554 -262.23341) (xy 345.800934 -262.231124) (xy 345.779028 -262.226081) (xy 345.737875 -262.208013)
			(xy 345.701404 -262.181747) (xy 345.671223 -262.148442) (xy 345.648665 -262.109568) (xy 345.641168 -262.088376)
			(xy 345.63812 -262.08101) (xy 345.627087 -262.058443) (xy 345.611491 -262.010694) (xy 345.603566 -261.961091)
			(xy 345.603068 -261.935976) (xy 344.356944 -261.935976) (xy 344.356432 -261.961422) (xy 344.348268 -262.011656)
			(xy 344.332152 -262.05993) (xy 344.308501 -262.104993) (xy 344.277928 -262.145679) (xy 344.241224 -262.180934)
			(xy 344.19934 -262.209844) (xy 344.153361 -262.231661) (xy 344.104477 -262.245821) (xy 344.053956 -262.251955)
			(xy 344.003104 -262.249906) (xy 343.95324 -262.239726) (xy 343.905654 -262.221679) (xy 343.86158 -262.196233)
			(xy 343.822158 -262.164046) (xy 343.78841 -262.125952) (xy 343.761209 -262.082938) (xy 343.741261 -262.036118)
			(xy 343.729082 -261.986704) (xy 343.724987 -261.935976) (xy 343.419176 -261.935976) (xy 343.418686 -261.960965)
			(xy 343.410867 -262.010328) (xy 343.395423 -262.05786) (xy 343.372733 -262.102392) (xy 343.343357 -262.142825)
			(xy 343.308017 -262.178165) (xy 343.267584 -262.207541) (xy 343.223052 -262.230231) (xy 343.17552 -262.245675)
			(xy 343.126157 -262.253494) (xy 343.076179 -262.253494) (xy 343.026816 -262.245675) (xy 342.979284 -262.230231)
			(xy 342.934752 -262.207541) (xy 342.894319 -262.178165) (xy 342.858979 -262.142825) (xy 342.829603 -262.102392)
			(xy 342.806913 -262.05786) (xy 342.791469 -262.010328) (xy 342.78365 -261.960965) (xy 342.478632 -261.960965)
			(xy 342.470813 -262.010328) (xy 342.455369 -262.05786) (xy 342.432679 -262.102392) (xy 342.403303 -262.142825)
			(xy 342.367963 -262.178165) (xy 342.32753 -262.207541) (xy 342.282998 -262.230231) (xy 342.235466 -262.245675)
			(xy 342.186103 -262.253494) (xy 342.136125 -262.253494) (xy 342.086762 -262.245675) (xy 342.03923 -262.230231)
			(xy 341.994698 -262.207541) (xy 341.954265 -262.178165) (xy 341.918925 -262.142825) (xy 341.889549 -262.102392)
			(xy 341.866859 -262.05786) (xy 341.851415 -262.010328) (xy 341.843596 -261.960965) (xy 341.538578 -261.960965)
			(xy 341.530759 -262.010328) (xy 341.515315 -262.05786) (xy 341.492625 -262.102392) (xy 341.463249 -262.142825)
			(xy 341.427909 -262.178165) (xy 341.387476 -262.207541) (xy 341.342944 -262.230231) (xy 341.295412 -262.245675)
			(xy 341.246049 -262.253494) (xy 341.196071 -262.253494) (xy 341.146708 -262.245675) (xy 341.099176 -262.230231)
			(xy 341.054644 -262.207541) (xy 341.014211 -262.178165) (xy 340.978871 -262.142825) (xy 340.949495 -262.102392)
			(xy 340.926805 -262.05786) (xy 340.911361 -262.010328) (xy 340.903542 -261.960965) (xy 340.596225 -261.960965)
			(xy 340.596216 -261.961422) (xy 340.588052 -262.011656) (xy 340.571936 -262.05993) (xy 340.548285 -262.104993)
			(xy 340.517712 -262.145679) (xy 340.481008 -262.180934) (xy 340.439124 -262.209844) (xy 340.393145 -262.231661)
			(xy 340.344261 -262.245821) (xy 340.29374 -262.251955) (xy 340.242888 -262.249906) (xy 340.193024 -262.239726)
			(xy 340.145438 -262.221679) (xy 340.101364 -262.196233) (xy 340.061942 -262.164046) (xy 340.028194 -262.125952)
			(xy 340.000993 -262.082938) (xy 339.981045 -262.036118) (xy 339.968866 -261.986704) (xy 339.964771 -261.935976)
			(xy 339.659214 -261.935976) (xy 339.658724 -261.960965) (xy 339.650905 -262.010328) (xy 339.635461 -262.05786)
			(xy 339.612771 -262.102392) (xy 339.583395 -262.142825) (xy 339.548055 -262.178165) (xy 339.507622 -262.207541)
			(xy 339.46309 -262.230231) (xy 339.415558 -262.245675) (xy 339.366195 -262.253494) (xy 339.316217 -262.253494)
			(xy 339.266854 -262.245675) (xy 339.219322 -262.230231) (xy 339.17479 -262.207541) (xy 339.134357 -262.178165)
			(xy 339.099017 -262.142825) (xy 339.069641 -262.102392) (xy 339.046951 -262.05786) (xy 339.031507 -262.010328)
			(xy 339.023688 -261.960965) (xy 338.718767 -261.960965) (xy 338.718767 -261.960996) (xy 338.710946 -262.010371)
			(xy 338.695497 -262.057915) (xy 338.672799 -262.102456) (xy 338.643413 -262.142898) (xy 338.608061 -262.178244)
			(xy 338.567615 -262.207624) (xy 338.52307 -262.230315) (xy 338.475524 -262.245757) (xy 338.426148 -262.253571)
			(xy 338.401152 -262.253984) (xy 338.376952 -262.253535) (xy 338.329111 -262.246209) (xy 338.282933 -262.231717)
			(xy 338.239484 -262.210394) (xy 338.199769 -262.182733) (xy 338.18195 -262.166354) (xy 338.176362 -262.161274)
			(xy 338.1629 -262.154162) (xy 338.156296 -262.153146) (xy 338.148962 -262.152103) (xy 338.134251 -262.153782)
			(xy 338.12734 -262.156448) (xy 338.058506 -262.185912) (xy 338.057998 -262.185912) (xy 338.041742 -262.19277)
			(xy 338.033234 -262.197129) (xy 338.020058 -262.210957) (xy 338.012951 -262.228686) (xy 338.012532 -262.238236)
			(xy 338.012532 -262.402574) (xy 338.012937 -262.411737) (xy 338.019492 -262.428849) (xy 338.031743 -262.442478)
			(xy 338.03971 -262.447024) (xy 338.045044 -262.449056) (xy 338.068711 -262.45869) (xy 338.112869 -262.484399)
			(xy 338.152348 -262.516836) (xy 338.186135 -262.555167) (xy 338.21336 -262.598406) (xy 338.233323 -262.645441)
			(xy 338.24551 -262.695062) (xy 338.249607 -262.745982) (xy 338.554817 -262.745982) (xy 338.558912 -262.695254)
			(xy 338.571091 -262.64584) (xy 338.591039 -262.59902) (xy 338.61824 -262.556006) (xy 338.651988 -262.517912)
			(xy 338.69141 -262.485725) (xy 338.735484 -262.460279) (xy 338.78307 -262.442232) (xy 338.832934 -262.432052)
			(xy 338.883786 -262.430003) (xy 338.934307 -262.436137) (xy 338.983191 -262.450297) (xy 339.02917 -262.472114)
			(xy 339.071054 -262.501024) (xy 339.107758 -262.536279) (xy 339.138331 -262.576965) (xy 339.161982 -262.622028)
			(xy 339.178098 -262.670302) (xy 339.186262 -262.720536) (xy 339.186774 -262.745982) (xy 339.186271 -262.770971)
			(xy 339.493588 -262.770971) (xy 339.493588 -262.720993) (xy 339.501407 -262.67163) (xy 339.516851 -262.624098)
			(xy 339.539541 -262.579566) (xy 339.568917 -262.539133) (xy 339.604257 -262.503793) (xy 339.64469 -262.474417)
			(xy 339.689222 -262.451727) (xy 339.736754 -262.436283) (xy 339.786117 -262.428464) (xy 339.836095 -262.428464)
			(xy 339.885458 -262.436283) (xy 339.93299 -262.451727) (xy 339.977522 -262.474417) (xy 340.017955 -262.503793)
			(xy 340.053295 -262.539133) (xy 340.082671 -262.579566) (xy 340.105361 -262.624098) (xy 340.120805 -262.67163)
			(xy 340.128624 -262.720993) (xy 340.129114 -262.745982) (xy 340.434925 -262.745982) (xy 340.43902 -262.695254)
			(xy 340.451199 -262.64584) (xy 340.471147 -262.59902) (xy 340.498348 -262.556006) (xy 340.532096 -262.517912)
			(xy 340.571518 -262.485725) (xy 340.615592 -262.460279) (xy 340.663178 -262.442232) (xy 340.713042 -262.432052)
			(xy 340.763894 -262.430003) (xy 340.814415 -262.436137) (xy 340.863299 -262.450297) (xy 340.909278 -262.472114)
			(xy 340.951162 -262.501024) (xy 340.987866 -262.536279) (xy 341.018439 -262.576965) (xy 341.04209 -262.622028)
			(xy 341.058206 -262.670302) (xy 341.06637 -262.720536) (xy 341.066882 -262.745982) (xy 341.066379 -262.770971)
			(xy 341.373696 -262.770971) (xy 341.373696 -262.720993) (xy 341.381515 -262.67163) (xy 341.396959 -262.624098)
			(xy 341.419649 -262.579566) (xy 341.449025 -262.539133) (xy 341.484365 -262.503793) (xy 341.524798 -262.474417)
			(xy 341.56933 -262.451727) (xy 341.616862 -262.436283) (xy 341.666225 -262.428464) (xy 341.716203 -262.428464)
			(xy 341.765566 -262.436283) (xy 341.813098 -262.451727) (xy 341.85763 -262.474417) (xy 341.898063 -262.503793)
			(xy 341.933403 -262.539133) (xy 341.962779 -262.579566) (xy 341.985469 -262.624098) (xy 342.000913 -262.67163)
			(xy 342.008732 -262.720993) (xy 342.009222 -262.745982) (xy 342.314779 -262.745982) (xy 342.318874 -262.695254)
			(xy 342.331053 -262.64584) (xy 342.351001 -262.59902) (xy 342.378202 -262.556006) (xy 342.41195 -262.517912)
			(xy 342.451372 -262.485725) (xy 342.495446 -262.460279) (xy 342.543032 -262.442232) (xy 342.592896 -262.432052)
			(xy 342.643748 -262.430003) (xy 342.694269 -262.436137) (xy 342.743153 -262.450297) (xy 342.789132 -262.472114)
			(xy 342.831016 -262.501024) (xy 342.86772 -262.536279) (xy 342.898293 -262.576965) (xy 342.921944 -262.622028)
			(xy 342.93806 -262.670302) (xy 342.946224 -262.720536) (xy 342.946736 -262.745982) (xy 343.254833 -262.745982)
			(xy 343.258928 -262.695254) (xy 343.271107 -262.64584) (xy 343.291055 -262.59902) (xy 343.318256 -262.556006)
			(xy 343.352004 -262.517912) (xy 343.391426 -262.485725) (xy 343.4355 -262.460279) (xy 343.483086 -262.442232)
			(xy 343.53295 -262.432052) (xy 343.583802 -262.430003) (xy 343.634323 -262.436137) (xy 343.683207 -262.450297)
			(xy 343.729186 -262.472114) (xy 343.77107 -262.501024) (xy 343.807774 -262.536279) (xy 343.838347 -262.576965)
			(xy 343.861998 -262.622028) (xy 343.878114 -262.670302) (xy 343.886278 -262.720536) (xy 343.88679 -262.745982)
			(xy 343.886287 -262.770971) (xy 344.193604 -262.770971) (xy 344.193604 -262.720993) (xy 344.201423 -262.67163)
			(xy 344.216867 -262.624098) (xy 344.239557 -262.579566) (xy 344.268933 -262.539133) (xy 344.304273 -262.503793)
			(xy 344.344706 -262.474417) (xy 344.389238 -262.451727) (xy 344.43677 -262.436283) (xy 344.486133 -262.428464)
			(xy 344.536111 -262.428464) (xy 344.585474 -262.436283) (xy 344.633006 -262.451727) (xy 344.677538 -262.474417)
			(xy 344.717971 -262.503793) (xy 344.753311 -262.539133) (xy 344.782687 -262.579566) (xy 344.805377 -262.624098)
			(xy 344.820821 -262.67163) (xy 344.82864 -262.720993) (xy 344.82913 -262.745982) (xy 344.82864 -262.770971)
			(xy 346.073712 -262.770971) (xy 346.073712 -262.720993) (xy 346.081531 -262.67163) (xy 346.096975 -262.624098)
			(xy 346.119665 -262.579566) (xy 346.149041 -262.539133) (xy 346.184381 -262.503793) (xy 346.224814 -262.474417)
			(xy 346.269346 -262.451727) (xy 346.316878 -262.436283) (xy 346.366241 -262.428464) (xy 346.416219 -262.428464)
			(xy 346.465582 -262.436283) (xy 346.513114 -262.451727) (xy 346.557646 -262.474417) (xy 346.598079 -262.503793)
			(xy 346.633419 -262.539133) (xy 346.662795 -262.579566) (xy 346.685485 -262.624098) (xy 346.700929 -262.67163)
			(xy 346.708748 -262.720993) (xy 346.709238 -262.745982) (xy 346.708748 -262.770971) (xy 346.700929 -262.820334)
			(xy 346.685485 -262.867866) (xy 346.662795 -262.912398) (xy 346.633419 -262.952831) (xy 346.598079 -262.988171)
			(xy 346.557646 -263.017547) (xy 346.513114 -263.040237) (xy 346.465582 -263.055681) (xy 346.416219 -263.0635)
			(xy 346.366241 -263.0635) (xy 346.316878 -263.055681) (xy 346.269346 -263.040237) (xy 346.224814 -263.017547)
			(xy 346.184381 -262.988171) (xy 346.149041 -262.952831) (xy 346.119665 -262.912398) (xy 346.096975 -262.867866)
			(xy 346.081531 -262.820334) (xy 346.073712 -262.770971) (xy 344.82864 -262.770971) (xy 344.820821 -262.820334)
			(xy 344.805377 -262.867866) (xy 344.782687 -262.912398) (xy 344.753311 -262.952831) (xy 344.717971 -262.988171)
			(xy 344.677538 -263.017547) (xy 344.633006 -263.040237) (xy 344.585474 -263.055681) (xy 344.536111 -263.0635)
			(xy 344.486133 -263.0635) (xy 344.43677 -263.055681) (xy 344.389238 -263.040237) (xy 344.344706 -263.017547)
			(xy 344.304273 -262.988171) (xy 344.268933 -262.952831) (xy 344.239557 -262.912398) (xy 344.216867 -262.867866)
			(xy 344.201423 -262.820334) (xy 344.193604 -262.770971) (xy 343.886287 -262.770971) (xy 343.886278 -262.771428)
			(xy 343.878114 -262.821662) (xy 343.861998 -262.869936) (xy 343.838347 -262.914999) (xy 343.807774 -262.955685)
			(xy 343.77107 -262.99094) (xy 343.729186 -263.01985) (xy 343.683207 -263.041667) (xy 343.634323 -263.055827)
			(xy 343.583802 -263.061961) (xy 343.53295 -263.059912) (xy 343.483086 -263.049732) (xy 343.4355 -263.031685)
			(xy 343.391426 -263.006239) (xy 343.352004 -262.974052) (xy 343.318256 -262.935958) (xy 343.291055 -262.892944)
			(xy 343.271107 -262.846124) (xy 343.258928 -262.79671) (xy 343.254833 -262.745982) (xy 342.946736 -262.745982)
			(xy 342.946224 -262.771428) (xy 342.93806 -262.821662) (xy 342.921944 -262.869936) (xy 342.898293 -262.914999)
			(xy 342.86772 -262.955685) (xy 342.831016 -262.99094) (xy 342.789132 -263.01985) (xy 342.743153 -263.041667)
			(xy 342.694269 -263.055827) (xy 342.643748 -263.061961) (xy 342.592896 -263.059912) (xy 342.543032 -263.049732)
			(xy 342.495446 -263.031685) (xy 342.451372 -263.006239) (xy 342.41195 -262.974052) (xy 342.378202 -262.935958)
			(xy 342.351001 -262.892944) (xy 342.331053 -262.846124) (xy 342.318874 -262.79671) (xy 342.314779 -262.745982)
			(xy 342.009222 -262.745982) (xy 342.008732 -262.770971) (xy 342.000913 -262.820334) (xy 341.985469 -262.867866)
			(xy 341.962779 -262.912398) (xy 341.933403 -262.952831) (xy 341.898063 -262.988171) (xy 341.85763 -263.017547)
			(xy 341.813098 -263.040237) (xy 341.765566 -263.055681) (xy 341.716203 -263.0635) (xy 341.666225 -263.0635)
			(xy 341.616862 -263.055681) (xy 341.56933 -263.040237) (xy 341.524798 -263.017547) (xy 341.484365 -262.988171)
			(xy 341.449025 -262.952831) (xy 341.419649 -262.912398) (xy 341.396959 -262.867866) (xy 341.381515 -262.820334)
			(xy 341.373696 -262.770971) (xy 341.066379 -262.770971) (xy 341.06637 -262.771428) (xy 341.058206 -262.821662)
			(xy 341.04209 -262.869936) (xy 341.018439 -262.914999) (xy 340.987866 -262.955685) (xy 340.951162 -262.99094)
			(xy 340.909278 -263.01985) (xy 340.863299 -263.041667) (xy 340.814415 -263.055827) (xy 340.763894 -263.061961)
			(xy 340.713042 -263.059912) (xy 340.663178 -263.049732) (xy 340.615592 -263.031685) (xy 340.571518 -263.006239)
			(xy 340.532096 -262.974052) (xy 340.498348 -262.935958) (xy 340.471147 -262.892944) (xy 340.451199 -262.846124)
			(xy 340.43902 -262.79671) (xy 340.434925 -262.745982) (xy 340.129114 -262.745982) (xy 340.128624 -262.770971)
			(xy 340.120805 -262.820334) (xy 340.105361 -262.867866) (xy 340.082671 -262.912398) (xy 340.053295 -262.952831)
			(xy 340.017955 -262.988171) (xy 339.977522 -263.017547) (xy 339.93299 -263.040237) (xy 339.885458 -263.055681)
			(xy 339.836095 -263.0635) (xy 339.786117 -263.0635) (xy 339.736754 -263.055681) (xy 339.689222 -263.040237)
			(xy 339.64469 -263.017547) (xy 339.604257 -262.988171) (xy 339.568917 -262.952831) (xy 339.539541 -262.912398)
			(xy 339.516851 -262.867866) (xy 339.501407 -262.820334) (xy 339.493588 -262.770971) (xy 339.186271 -262.770971)
			(xy 339.186262 -262.771428) (xy 339.178098 -262.821662) (xy 339.161982 -262.869936) (xy 339.138331 -262.914999)
			(xy 339.107758 -262.955685) (xy 339.071054 -262.99094) (xy 339.02917 -263.01985) (xy 338.983191 -263.041667)
			(xy 338.934307 -263.055827) (xy 338.883786 -263.061961) (xy 338.832934 -263.059912) (xy 338.78307 -263.049732)
			(xy 338.735484 -263.031685) (xy 338.69141 -263.006239) (xy 338.651988 -262.974052) (xy 338.61824 -262.935958)
			(xy 338.591039 -262.892944) (xy 338.571091 -262.846124) (xy 338.558912 -262.79671) (xy 338.554817 -262.745982)
			(xy 338.249607 -262.745982) (xy 338.249608 -262.745994) (xy 338.245512 -262.796925) (xy 338.233327 -262.846547)
			(xy 338.213366 -262.893583) (xy 338.186143 -262.936823) (xy 338.152358 -262.975155) (xy 338.112879 -263.007594)
			(xy 338.068723 -263.033304) (xy 338.045044 -263.042908) (xy 338.03971 -263.04494) (xy 338.031757 -263.049495)
			(xy 338.019539 -263.063136) (xy 338.01298 -263.080235) (xy 338.012532 -263.08939) (xy 338.012532 -263.253728)
			(xy 338.012942 -263.263286) (xy 338.020026 -263.281038) (xy 338.033205 -263.294882) (xy 338.041742 -263.299194)
			(xy 338.057998 -263.306052) (xy 338.058506 -263.306052) (xy 338.12734 -263.335516) (xy 338.134245 -263.33821)
			(xy 338.148963 -263.339892) (xy 338.156296 -263.338818) (xy 338.1629 -263.337802) (xy 338.176362 -263.33069)
			(xy 338.18195 -263.32561) (xy 338.199791 -263.309256) (xy 338.239501 -263.281589) (xy 338.282943 -263.260258)
			(xy 338.329116 -263.245755) (xy 338.376954 -263.238415) (xy 338.401152 -263.23798) (xy 338.426147 -263.238441)
			(xy 338.475521 -263.246254) (xy 338.523066 -263.261696) (xy 338.567609 -263.284386) (xy 338.608053 -263.313765)
			(xy 338.643404 -263.34911) (xy 338.672789 -263.38955) (xy 338.695486 -263.43409) (xy 338.710935 -263.481632)
			(xy 338.718755 -263.531005) (xy 338.718755 -263.555988) (xy 339.024971 -263.555988) (xy 339.029066 -263.50526)
			(xy 339.041245 -263.455846) (xy 339.061193 -263.409026) (xy 339.088394 -263.366012) (xy 339.122142 -263.327918)
			(xy 339.161564 -263.295731) (xy 339.205638 -263.270285) (xy 339.253224 -263.252238) (xy 339.303088 -263.242058)
			(xy 339.35394 -263.240009) (xy 339.404461 -263.246143) (xy 339.453345 -263.260303) (xy 339.499324 -263.28212)
			(xy 339.541208 -263.31103) (xy 339.577912 -263.346285) (xy 339.608485 -263.386971) (xy 339.632136 -263.432034)
			(xy 339.648252 -263.480308) (xy 339.656416 -263.530542) (xy 339.656928 -263.555988) (xy 339.964771 -263.555988)
			(xy 339.968866 -263.50526) (xy 339.981045 -263.455846) (xy 340.000993 -263.409026) (xy 340.028194 -263.366012)
			(xy 340.061942 -263.327918) (xy 340.101364 -263.295731) (xy 340.145438 -263.270285) (xy 340.193024 -263.252238)
			(xy 340.242888 -263.242058) (xy 340.29374 -263.240009) (xy 340.344261 -263.246143) (xy 340.393145 -263.260303)
			(xy 340.439124 -263.28212) (xy 340.481008 -263.31103) (xy 340.517712 -263.346285) (xy 340.548285 -263.386971)
			(xy 340.571936 -263.432034) (xy 340.588052 -263.480308) (xy 340.596216 -263.530542) (xy 340.596728 -263.555988)
			(xy 341.844879 -263.555988) (xy 341.848974 -263.50526) (xy 341.861153 -263.455846) (xy 341.881101 -263.409026)
			(xy 341.908302 -263.366012) (xy 341.94205 -263.327918) (xy 341.981472 -263.295731) (xy 342.025546 -263.270285)
			(xy 342.073132 -263.252238) (xy 342.122996 -263.242058) (xy 342.173848 -263.240009) (xy 342.224369 -263.246143)
			(xy 342.273253 -263.260303) (xy 342.319232 -263.28212) (xy 342.361116 -263.31103) (xy 342.39782 -263.346285)
			(xy 342.428393 -263.386971) (xy 342.452044 -263.432034) (xy 342.46816 -263.480308) (xy 342.476324 -263.530542)
			(xy 342.476836 -263.555988) (xy 342.476333 -263.580977) (xy 342.78365 -263.580977) (xy 342.78365 -263.530999)
			(xy 342.791469 -263.481636) (xy 342.806913 -263.434104) (xy 342.829603 -263.389572) (xy 342.858979 -263.349139)
			(xy 342.894319 -263.313799) (xy 342.934752 -263.284423) (xy 342.979284 -263.261733) (xy 343.026816 -263.246289)
			(xy 343.076179 -263.23847) (xy 343.126157 -263.23847) (xy 343.17552 -263.246289) (xy 343.223052 -263.261733)
			(xy 343.267584 -263.284423) (xy 343.308017 -263.313799) (xy 343.343357 -263.349139) (xy 343.372733 -263.389572)
			(xy 343.395423 -263.434104) (xy 343.410867 -263.481636) (xy 343.418686 -263.530999) (xy 343.419176 -263.555988)
			(xy 343.724987 -263.555988) (xy 343.729082 -263.50526) (xy 343.741261 -263.455846) (xy 343.761209 -263.409026)
			(xy 343.78841 -263.366012) (xy 343.822158 -263.327918) (xy 343.86158 -263.295731) (xy 343.905654 -263.270285)
			(xy 343.95324 -263.252238) (xy 344.003104 -263.242058) (xy 344.053956 -263.240009) (xy 344.104477 -263.246143)
			(xy 344.153361 -263.260303) (xy 344.19934 -263.28212) (xy 344.241224 -263.31103) (xy 344.277928 -263.346285)
			(xy 344.308501 -263.386971) (xy 344.332152 -263.432034) (xy 344.348268 -263.480308) (xy 344.356432 -263.530542)
			(xy 344.356944 -263.555988) (xy 345.603068 -263.555988) (xy 345.603835 -263.52502) (xy 345.615855 -263.464262)
			(xy 345.626944 -263.435338) (xy 345.6305 -263.426194) (xy 345.6305 -263.371838) (xy 345.630877 -263.350791)
			(xy 345.638878 -263.309469) (xy 345.654813 -263.270513) (xy 345.678067 -263.235431) (xy 345.70774 -263.20558)
			(xy 345.742682 -263.182116) (xy 345.781542 -263.165947) (xy 345.822815 -263.1577) (xy 345.84386 -263.157208)
			(xy 346.098876 -263.157208) (xy 346.098876 -263.166352) (xy 346.099358 -263.176367) (xy 346.107008 -263.194879)
			(xy 346.121161 -263.209052) (xy 346.139661 -263.216728) (xy 346.149676 -263.217152) (xy 346.312744 -263.217152)
			(xy 346.322749 -263.217651) (xy 346.341232 -263.225316) (xy 346.355382 -263.239465) (xy 346.363048 -263.257948)
			(xy 346.363544 -263.267952) (xy 346.363544 -263.672066) (xy 347.4085 -263.672066) (xy 347.4085 -263.671558)
			(xy 347.4085 -263.371838) (xy 347.408877 -263.350791) (xy 347.416878 -263.309469) (xy 347.432813 -263.270513)
			(xy 347.456067 -263.235431) (xy 347.48574 -263.20558) (xy 347.520682 -263.182116) (xy 347.559542 -263.165947)
			(xy 347.600815 -263.1577) (xy 347.62186 -263.157208) (xy 347.876876 -263.157208) (xy 347.876876 -263.166352)
			(xy 347.877358 -263.176367) (xy 347.885008 -263.194879) (xy 347.899161 -263.209052) (xy 347.917661 -263.216728)
			(xy 347.927676 -263.217152) (xy 348.090744 -263.217152) (xy 348.100749 -263.217651) (xy 348.119232 -263.225316)
			(xy 348.133382 -263.239465) (xy 348.141048 -263.257948) (xy 348.141544 -263.267952) (xy 348.141544 -263.775952)
			(xy 348.141042 -263.785965) (xy 348.133396 -263.804472) (xy 348.11925 -263.818645) (xy 348.100756 -263.826324)
			(xy 348.090744 -263.826752) (xy 347.981778 -263.826752) (xy 347.975419 -263.826919) (xy 347.963082 -263.830001)
			(xy 347.957394 -263.832848) (xy 347.956886 -263.833356) (xy 347.945598 -263.839519) (xy 347.9222 -263.850197)
			(xy 347.91015 -263.854692) (xy 347.89491 -263.86028) (xy 347.876876 -263.886188) (xy 347.876876 -263.886696)
			(xy 347.62186 -263.886696) (xy 347.600814 -263.886213) (xy 347.559539 -263.877964) (xy 347.520678 -263.861795)
			(xy 347.485734 -263.83833) (xy 347.45606 -263.808479) (xy 347.432804 -263.773395) (xy 347.416867 -263.734438)
			(xy 347.408865 -263.693114) (xy 347.4085 -263.672066) (xy 346.363544 -263.672066) (xy 346.363544 -263.775952)
			(xy 346.363042 -263.785965) (xy 346.355396 -263.804472) (xy 346.34125 -263.818645) (xy 346.322756 -263.826324)
			(xy 346.312744 -263.826752) (xy 346.098876 -263.826752) (xy 346.098876 -263.835896) (xy 346.098477 -263.84592)
			(xy 346.090804 -263.864441) (xy 346.076625 -263.878615) (xy 346.0581 -263.886281) (xy 346.048076 -263.886696)
			(xy 345.84386 -263.886696) (xy 345.82419 -263.886228) (xy 345.785516 -263.879014) (xy 345.748819 -263.864837)
			(xy 345.71534 -263.844178) (xy 345.686212 -263.817734) (xy 345.662421 -263.786403) (xy 345.644772 -263.751243)
			(xy 345.633863 -263.713445) (xy 345.631516 -263.69391) (xy 345.631112 -263.690126) (xy 345.629323 -263.682731)
			(xy 345.62796 -263.679178) (xy 345.620078 -263.659608) (xy 345.608993 -263.618901) (xy 345.603408 -263.577083)
			(xy 345.603068 -263.555988) (xy 344.356944 -263.555988) (xy 344.356432 -263.581434) (xy 344.348268 -263.631668)
			(xy 344.332152 -263.679942) (xy 344.308501 -263.725005) (xy 344.277928 -263.765691) (xy 344.241224 -263.800946)
			(xy 344.19934 -263.829856) (xy 344.153361 -263.851673) (xy 344.104477 -263.865833) (xy 344.053956 -263.871967)
			(xy 344.003104 -263.869918) (xy 343.95324 -263.859738) (xy 343.905654 -263.841691) (xy 343.86158 -263.816245)
			(xy 343.822158 -263.784058) (xy 343.78841 -263.745964) (xy 343.761209 -263.70295) (xy 343.741261 -263.65613)
			(xy 343.729082 -263.606716) (xy 343.724987 -263.555988) (xy 343.419176 -263.555988) (xy 343.418686 -263.580977)
			(xy 343.410867 -263.63034) (xy 343.395423 -263.677872) (xy 343.372733 -263.722404) (xy 343.343357 -263.762837)
			(xy 343.308017 -263.798177) (xy 343.267584 -263.827553) (xy 343.223052 -263.850243) (xy 343.17552 -263.865687)
			(xy 343.126157 -263.873506) (xy 343.076179 -263.873506) (xy 343.026816 -263.865687) (xy 342.979284 -263.850243)
			(xy 342.934752 -263.827553) (xy 342.894319 -263.798177) (xy 342.858979 -263.762837) (xy 342.829603 -263.722404)
			(xy 342.806913 -263.677872) (xy 342.791469 -263.63034) (xy 342.78365 -263.580977) (xy 342.476333 -263.580977)
			(xy 342.476324 -263.581434) (xy 342.46816 -263.631668) (xy 342.452044 -263.679942) (xy 342.428393 -263.725005)
			(xy 342.39782 -263.765691) (xy 342.361116 -263.800946) (xy 342.319232 -263.829856) (xy 342.273253 -263.851673)
			(xy 342.224369 -263.865833) (xy 342.173848 -263.871967) (xy 342.122996 -263.869918) (xy 342.073132 -263.859738)
			(xy 342.025546 -263.841691) (xy 341.981472 -263.816245) (xy 341.94205 -263.784058) (xy 341.908302 -263.745964)
			(xy 341.881101 -263.70295) (xy 341.861153 -263.65613) (xy 341.848974 -263.606716) (xy 341.844879 -263.555988)
			(xy 340.596728 -263.555988) (xy 340.596216 -263.581434) (xy 340.588052 -263.631668) (xy 340.571936 -263.679942)
			(xy 340.548285 -263.725005) (xy 340.517712 -263.765691) (xy 340.481008 -263.800946) (xy 340.439124 -263.829856)
			(xy 340.393145 -263.851673) (xy 340.344261 -263.865833) (xy 340.29374 -263.871967) (xy 340.242888 -263.869918)
			(xy 340.193024 -263.859738) (xy 340.145438 -263.841691) (xy 340.101364 -263.816245) (xy 340.061942 -263.784058)
			(xy 340.028194 -263.745964) (xy 340.000993 -263.70295) (xy 339.981045 -263.65613) (xy 339.968866 -263.606716)
			(xy 339.964771 -263.555988) (xy 339.656928 -263.555988) (xy 339.656416 -263.581434) (xy 339.648252 -263.631668)
			(xy 339.632136 -263.679942) (xy 339.608485 -263.725005) (xy 339.577912 -263.765691) (xy 339.541208 -263.800946)
			(xy 339.499324 -263.829856) (xy 339.453345 -263.851673) (xy 339.404461 -263.865833) (xy 339.35394 -263.871967)
			(xy 339.303088 -263.869918) (xy 339.253224 -263.859738) (xy 339.205638 -263.841691) (xy 339.161564 -263.816245)
			(xy 339.122142 -263.784058) (xy 339.088394 -263.745964) (xy 339.061193 -263.70295) (xy 339.041245 -263.65613)
			(xy 339.029066 -263.606716) (xy 339.024971 -263.555988) (xy 338.718755 -263.555988) (xy 338.718755 -263.580995)
			(xy 338.710935 -263.630368) (xy 338.695486 -263.67791) (xy 338.672789 -263.72245) (xy 338.643404 -263.76289)
			(xy 338.608053 -263.798235) (xy 338.567609 -263.827614) (xy 338.523066 -263.850304) (xy 338.475521 -263.865746)
			(xy 338.426147 -263.873559) (xy 338.401152 -263.873996) (xy 338.376953 -263.873547) (xy 338.329114 -263.866219)
			(xy 338.282938 -263.851724) (xy 338.239492 -263.830397) (xy 338.199782 -263.802731) (xy 338.18195 -263.786366)
			(xy 338.176362 -263.781286) (xy 338.1629 -263.774174) (xy 338.156296 -263.773158) (xy 338.148962 -263.772115)
			(xy 338.134251 -263.773794) (xy 338.12734 -263.77646) (xy 338.058506 -263.805924) (xy 338.057998 -263.805924)
			(xy 338.041742 -263.812782) (xy 338.033235 -263.817141) (xy 338.020063 -263.83097) (xy 338.01296 -263.848699)
			(xy 338.012532 -263.858248) (xy 338.012532 -264.022586) (xy 338.012939 -264.031748) (xy 338.019497 -264.048857)
			(xy 338.031749 -264.062482) (xy 338.03971 -264.067036) (xy 338.045044 -264.069068) (xy 338.06871 -264.078702)
			(xy 338.112866 -264.104411) (xy 338.152344 -264.136847) (xy 338.186129 -264.175177) (xy 338.213352 -264.218415)
			(xy 338.233314 -264.265448) (xy 338.2455 -264.315068) (xy 338.249597 -264.365994) (xy 338.554817 -264.365994)
			(xy 338.558912 -264.315266) (xy 338.571091 -264.265852) (xy 338.591039 -264.219032) (xy 338.61824 -264.176018)
			(xy 338.651988 -264.137924) (xy 338.69141 -264.105737) (xy 338.735484 -264.080291) (xy 338.78307 -264.062244)
			(xy 338.832934 -264.052064) (xy 338.883786 -264.050015) (xy 338.934307 -264.056149) (xy 338.983191 -264.070309)
			(xy 339.02917 -264.092126) (xy 339.071054 -264.121036) (xy 339.107758 -264.156291) (xy 339.138331 -264.196977)
			(xy 339.161982 -264.24204) (xy 339.178098 -264.290314) (xy 339.186262 -264.340548) (xy 339.186774 -264.365994)
			(xy 339.186271 -264.390983) (xy 339.493588 -264.390983) (xy 339.493588 -264.341005) (xy 339.501407 -264.291642)
			(xy 339.516851 -264.24411) (xy 339.539541 -264.199578) (xy 339.568917 -264.159145) (xy 339.604257 -264.123805)
			(xy 339.64469 -264.094429) (xy 339.689222 -264.071739) (xy 339.736754 -264.056295) (xy 339.786117 -264.048476)
			(xy 339.836095 -264.048476) (xy 339.885458 -264.056295) (xy 339.93299 -264.071739) (xy 339.977522 -264.094429)
			(xy 340.017955 -264.123805) (xy 340.053295 -264.159145) (xy 340.082671 -264.199578) (xy 340.105361 -264.24411)
			(xy 340.120805 -264.291642) (xy 340.128624 -264.341005) (xy 340.129114 -264.365994) (xy 340.434925 -264.365994)
			(xy 340.43902 -264.315266) (xy 340.451199 -264.265852) (xy 340.471147 -264.219032) (xy 340.498348 -264.176018)
			(xy 340.532096 -264.137924) (xy 340.571518 -264.105737) (xy 340.615592 -264.080291) (xy 340.663178 -264.062244)
			(xy 340.713042 -264.052064) (xy 340.763894 -264.050015) (xy 340.814415 -264.056149) (xy 340.863299 -264.070309)
			(xy 340.909278 -264.092126) (xy 340.951162 -264.121036) (xy 340.987866 -264.156291) (xy 341.018439 -264.196977)
			(xy 341.04209 -264.24204) (xy 341.058206 -264.290314) (xy 341.06637 -264.340548) (xy 341.066882 -264.365994)
			(xy 341.066379 -264.390983) (xy 341.373696 -264.390983) (xy 341.373696 -264.341005) (xy 341.381515 -264.291642)
			(xy 341.396959 -264.24411) (xy 341.419649 -264.199578) (xy 341.449025 -264.159145) (xy 341.484365 -264.123805)
			(xy 341.524798 -264.094429) (xy 341.56933 -264.071739) (xy 341.616862 -264.056295) (xy 341.666225 -264.048476)
			(xy 341.716203 -264.048476) (xy 341.765566 -264.056295) (xy 341.813098 -264.071739) (xy 341.85763 -264.094429)
			(xy 341.898063 -264.123805) (xy 341.933403 -264.159145) (xy 341.962779 -264.199578) (xy 341.985469 -264.24411)
			(xy 342.000913 -264.291642) (xy 342.008732 -264.341005) (xy 342.009222 -264.365994) (xy 342.314779 -264.365994)
			(xy 342.318874 -264.315266) (xy 342.331053 -264.265852) (xy 342.351001 -264.219032) (xy 342.378202 -264.176018)
			(xy 342.41195 -264.137924) (xy 342.451372 -264.105737) (xy 342.495446 -264.080291) (xy 342.543032 -264.062244)
			(xy 342.592896 -264.052064) (xy 342.643748 -264.050015) (xy 342.694269 -264.056149) (xy 342.743153 -264.070309)
			(xy 342.789132 -264.092126) (xy 342.831016 -264.121036) (xy 342.86772 -264.156291) (xy 342.898293 -264.196977)
			(xy 342.921944 -264.24204) (xy 342.93806 -264.290314) (xy 342.946224 -264.340548) (xy 342.946736 -264.365994)
			(xy 343.254833 -264.365994) (xy 343.258928 -264.315266) (xy 343.271107 -264.265852) (xy 343.291055 -264.219032)
			(xy 343.318256 -264.176018) (xy 343.352004 -264.137924) (xy 343.391426 -264.105737) (xy 343.4355 -264.080291)
			(xy 343.483086 -264.062244) (xy 343.53295 -264.052064) (xy 343.583802 -264.050015) (xy 343.634323 -264.056149)
			(xy 343.683207 -264.070309) (xy 343.729186 -264.092126) (xy 343.77107 -264.121036) (xy 343.807774 -264.156291)
			(xy 343.838347 -264.196977) (xy 343.861998 -264.24204) (xy 343.878114 -264.290314) (xy 343.886278 -264.340548)
			(xy 343.88679 -264.365994) (xy 343.886287 -264.390983) (xy 344.193604 -264.390983) (xy 344.193604 -264.341005)
			(xy 344.201423 -264.291642) (xy 344.216867 -264.24411) (xy 344.239557 -264.199578) (xy 344.268933 -264.159145)
			(xy 344.304273 -264.123805) (xy 344.344706 -264.094429) (xy 344.389238 -264.071739) (xy 344.43677 -264.056295)
			(xy 344.486133 -264.048476) (xy 344.536111 -264.048476) (xy 344.585474 -264.056295) (xy 344.633006 -264.071739)
			(xy 344.677538 -264.094429) (xy 344.717971 -264.123805) (xy 344.753311 -264.159145) (xy 344.782687 -264.199578)
			(xy 344.805377 -264.24411) (xy 344.820821 -264.291642) (xy 344.82864 -264.341005) (xy 344.82913 -264.365994)
			(xy 344.82864 -264.390983) (xy 344.820821 -264.440346) (xy 344.805377 -264.487878) (xy 344.782687 -264.53241)
			(xy 344.753311 -264.572843) (xy 344.717971 -264.608183) (xy 344.677538 -264.637559) (xy 344.633006 -264.660249)
			(xy 344.585474 -264.675693) (xy 344.536111 -264.683512) (xy 344.486133 -264.683512) (xy 344.43677 -264.675693)
			(xy 344.389238 -264.660249) (xy 344.344706 -264.637559) (xy 344.304273 -264.608183) (xy 344.268933 -264.572843)
			(xy 344.239557 -264.53241) (xy 344.216867 -264.487878) (xy 344.201423 -264.440346) (xy 344.193604 -264.390983)
			(xy 343.886287 -264.390983) (xy 343.886278 -264.39144) (xy 343.878114 -264.441674) (xy 343.861998 -264.489948)
			(xy 343.838347 -264.535011) (xy 343.807774 -264.575697) (xy 343.77107 -264.610952) (xy 343.729186 -264.639862)
			(xy 343.683207 -264.661679) (xy 343.634323 -264.675839) (xy 343.583802 -264.681973) (xy 343.53295 -264.679924)
			(xy 343.483086 -264.669744) (xy 343.4355 -264.651697) (xy 343.391426 -264.626251) (xy 343.352004 -264.594064)
			(xy 343.318256 -264.55597) (xy 343.291055 -264.512956) (xy 343.271107 -264.466136) (xy 343.258928 -264.416722)
			(xy 343.254833 -264.365994) (xy 342.946736 -264.365994) (xy 342.946224 -264.39144) (xy 342.93806 -264.441674)
			(xy 342.921944 -264.489948) (xy 342.898293 -264.535011) (xy 342.86772 -264.575697) (xy 342.831016 -264.610952)
			(xy 342.789132 -264.639862) (xy 342.743153 -264.661679) (xy 342.694269 -264.675839) (xy 342.643748 -264.681973)
			(xy 342.592896 -264.679924) (xy 342.543032 -264.669744) (xy 342.495446 -264.651697) (xy 342.451372 -264.626251)
			(xy 342.41195 -264.594064) (xy 342.378202 -264.55597) (xy 342.351001 -264.512956) (xy 342.331053 -264.466136)
			(xy 342.318874 -264.416722) (xy 342.314779 -264.365994) (xy 342.009222 -264.365994) (xy 342.008732 -264.390983)
			(xy 342.000913 -264.440346) (xy 341.985469 -264.487878) (xy 341.962779 -264.53241) (xy 341.933403 -264.572843)
			(xy 341.898063 -264.608183) (xy 341.85763 -264.637559) (xy 341.813098 -264.660249) (xy 341.765566 -264.675693)
			(xy 341.716203 -264.683512) (xy 341.666225 -264.683512) (xy 341.616862 -264.675693) (xy 341.56933 -264.660249)
			(xy 341.524798 -264.637559) (xy 341.484365 -264.608183) (xy 341.449025 -264.572843) (xy 341.419649 -264.53241)
			(xy 341.396959 -264.487878) (xy 341.381515 -264.440346) (xy 341.373696 -264.390983) (xy 341.066379 -264.390983)
			(xy 341.06637 -264.39144) (xy 341.058206 -264.441674) (xy 341.04209 -264.489948) (xy 341.018439 -264.535011)
			(xy 340.987866 -264.575697) (xy 340.951162 -264.610952) (xy 340.909278 -264.639862) (xy 340.863299 -264.661679)
			(xy 340.814415 -264.675839) (xy 340.763894 -264.681973) (xy 340.713042 -264.679924) (xy 340.663178 -264.669744)
			(xy 340.615592 -264.651697) (xy 340.571518 -264.626251) (xy 340.532096 -264.594064) (xy 340.498348 -264.55597)
			(xy 340.471147 -264.512956) (xy 340.451199 -264.466136) (xy 340.43902 -264.416722) (xy 340.434925 -264.365994)
			(xy 340.129114 -264.365994) (xy 340.128624 -264.390983) (xy 340.120805 -264.440346) (xy 340.105361 -264.487878)
			(xy 340.082671 -264.53241) (xy 340.053295 -264.572843) (xy 340.017955 -264.608183) (xy 339.977522 -264.637559)
			(xy 339.93299 -264.660249) (xy 339.885458 -264.675693) (xy 339.836095 -264.683512) (xy 339.786117 -264.683512)
			(xy 339.736754 -264.675693) (xy 339.689222 -264.660249) (xy 339.64469 -264.637559) (xy 339.604257 -264.608183)
			(xy 339.568917 -264.572843) (xy 339.539541 -264.53241) (xy 339.516851 -264.487878) (xy 339.501407 -264.440346)
			(xy 339.493588 -264.390983) (xy 339.186271 -264.390983) (xy 339.186262 -264.39144) (xy 339.178098 -264.441674)
			(xy 339.161982 -264.489948) (xy 339.138331 -264.535011) (xy 339.107758 -264.575697) (xy 339.071054 -264.610952)
			(xy 339.02917 -264.639862) (xy 338.983191 -264.661679) (xy 338.934307 -264.675839) (xy 338.883786 -264.681973)
			(xy 338.832934 -264.679924) (xy 338.78307 -264.669744) (xy 338.735484 -264.651697) (xy 338.69141 -264.626251)
			(xy 338.651988 -264.594064) (xy 338.61824 -264.55597) (xy 338.591039 -264.512956) (xy 338.571091 -264.466136)
			(xy 338.558912 -264.416722) (xy 338.554817 -264.365994) (xy 338.249597 -264.365994) (xy 338.249597 -264.365998)
			(xy 338.2455 -264.416928) (xy 338.233315 -264.466548) (xy 338.213354 -264.513581) (xy 338.186131 -264.55682)
			(xy 338.152347 -264.59515) (xy 338.112869 -264.627587) (xy 338.068714 -264.653296) (xy 338.045044 -264.66292)
			(xy 338.03971 -264.664952) (xy 338.031758 -264.669508) (xy 338.019544 -264.68315) (xy 338.012989 -264.700247)
			(xy 338.012532 -264.709402) (xy 338.012532 -264.87374) (xy 338.012944 -264.883296) (xy 338.020031 -264.901045)
			(xy 338.03321 -264.914886) (xy 338.041742 -264.919206) (xy 338.057998 -264.926064) (xy 338.058506 -264.926064)
			(xy 338.12734 -264.955528) (xy 338.134245 -264.958221) (xy 338.148963 -264.959903) (xy 338.156296 -264.95883)
			(xy 338.1629 -264.957814) (xy 338.176362 -264.950702) (xy 338.18195 -264.945622) (xy 338.199791 -264.929267)
			(xy 338.2395 -264.9016) (xy 338.282943 -264.880268) (xy 338.329116 -264.865764) (xy 338.376953 -264.858424)
			(xy 338.401152 -264.857992) (xy 338.426146 -264.858453) (xy 338.475519 -264.866266) (xy 338.523061 -264.881707)
			(xy 338.567602 -264.904396) (xy 338.608046 -264.933774) (xy 338.643395 -264.969118) (xy 338.672779 -265.009557)
			(xy 338.695475 -265.054094) (xy 338.710923 -265.101635) (xy 338.718743 -265.151006) (xy 338.718743 -265.176)
			(xy 339.024971 -265.176) (xy 339.029066 -265.125272) (xy 339.041245 -265.075858) (xy 339.061193 -265.029038)
			(xy 339.088394 -264.986024) (xy 339.122142 -264.94793) (xy 339.161564 -264.915743) (xy 339.205638 -264.890297)
			(xy 339.253224 -264.87225) (xy 339.303088 -264.86207) (xy 339.35394 -264.860021) (xy 339.404461 -264.866155)
			(xy 339.453345 -264.880315) (xy 339.499324 -264.902132) (xy 339.541208 -264.931042) (xy 339.577912 -264.966297)
			(xy 339.608485 -265.006983) (xy 339.632136 -265.052046) (xy 339.648252 -265.10032) (xy 339.656416 -265.150554)
			(xy 339.656928 -265.176) (xy 339.656425 -265.200989) (xy 339.963488 -265.200989) (xy 339.963488 -265.151011)
			(xy 339.971307 -265.101648) (xy 339.986751 -265.054116) (xy 340.009441 -265.009584) (xy 340.038817 -264.969151)
			(xy 340.074157 -264.933811) (xy 340.11459 -264.904435) (xy 340.159122 -264.881745) (xy 340.206654 -264.866301)
			(xy 340.256017 -264.858482) (xy 340.305995 -264.858482) (xy 340.355358 -264.866301) (xy 340.40289 -264.881745)
			(xy 340.447422 -264.904435) (xy 340.487855 -264.933811) (xy 340.523195 -264.969151) (xy 340.552571 -265.009584)
			(xy 340.575261 -265.054116) (xy 340.590705 -265.101648) (xy 340.598524 -265.151011) (xy 340.599014 -265.176)
			(xy 340.598524 -265.200989) (xy 340.903542 -265.200989) (xy 340.903542 -265.151011) (xy 340.911361 -265.101648)
			(xy 340.926805 -265.054116) (xy 340.949495 -265.009584) (xy 340.978871 -264.969151) (xy 341.014211 -264.933811)
			(xy 341.054644 -264.904435) (xy 341.099176 -264.881745) (xy 341.146708 -264.866301) (xy 341.196071 -264.858482)
			(xy 341.246049 -264.858482) (xy 341.295412 -264.866301) (xy 341.342944 -264.881745) (xy 341.387476 -264.904435)
			(xy 341.427909 -264.933811) (xy 341.463249 -264.969151) (xy 341.492625 -265.009584) (xy 341.515315 -265.054116)
			(xy 341.530759 -265.101648) (xy 341.538578 -265.151011) (xy 341.539068 -265.176) (xy 341.844879 -265.176)
			(xy 341.848974 -265.125272) (xy 341.861153 -265.075858) (xy 341.881101 -265.029038) (xy 341.908302 -264.986024)
			(xy 341.94205 -264.94793) (xy 341.981472 -264.915743) (xy 342.025546 -264.890297) (xy 342.073132 -264.87225)
			(xy 342.122996 -264.86207) (xy 342.173848 -264.860021) (xy 342.224369 -264.866155) (xy 342.273253 -264.880315)
			(xy 342.319232 -264.902132) (xy 342.361116 -264.931042) (xy 342.39782 -264.966297) (xy 342.428393 -265.006983)
			(xy 342.452044 -265.052046) (xy 342.46816 -265.10032) (xy 342.476324 -265.150554) (xy 342.476836 -265.176)
			(xy 342.476333 -265.200989) (xy 342.78365 -265.200989) (xy 342.78365 -265.151011) (xy 342.791469 -265.101648)
			(xy 342.806913 -265.054116) (xy 342.829603 -265.009584) (xy 342.858979 -264.969151) (xy 342.894319 -264.933811)
			(xy 342.934752 -264.904435) (xy 342.979284 -264.881745) (xy 343.026816 -264.866301) (xy 343.076179 -264.858482)
			(xy 343.126157 -264.858482) (xy 343.17552 -264.866301) (xy 343.223052 -264.881745) (xy 343.267584 -264.904435)
			(xy 343.308017 -264.933811) (xy 343.343357 -264.969151) (xy 343.372733 -265.009584) (xy 343.395423 -265.054116)
			(xy 343.410867 -265.101648) (xy 343.418686 -265.151011) (xy 343.419176 -265.176) (xy 343.418686 -265.200989)
			(xy 343.723704 -265.200989) (xy 343.723704 -265.151011) (xy 343.731523 -265.101648) (xy 343.746967 -265.054116)
			(xy 343.769657 -265.009584) (xy 343.799033 -264.969151) (xy 343.834373 -264.933811) (xy 343.874806 -264.904435)
			(xy 343.919338 -264.881745) (xy 343.96687 -264.866301) (xy 344.016233 -264.858482) (xy 344.066211 -264.858482)
			(xy 344.115574 -264.866301) (xy 344.163106 -264.881745) (xy 344.207638 -264.904435) (xy 344.248071 -264.933811)
			(xy 344.283411 -264.969151) (xy 344.312787 -265.009584) (xy 344.335477 -265.054116) (xy 344.350921 -265.101648)
			(xy 344.35874 -265.151011) (xy 344.35923 -265.176) (xy 345.603068 -265.176) (xy 345.603838 -265.145033)
			(xy 345.615856 -265.084274) (xy 345.626944 -265.05535) (xy 345.6305 -265.046206) (xy 345.6305 -264.895838)
			(xy 345.630877 -264.874791) (xy 345.638878 -264.833469) (xy 345.654813 -264.794513) (xy 345.678067 -264.759431)
			(xy 345.70774 -264.72958) (xy 345.742682 -264.706116) (xy 345.781542 -264.689947) (xy 345.822815 -264.6817)
			(xy 345.84386 -264.681208) (xy 346.030296 -264.681208) (xy 346.039254 -264.68088) (xy 346.056083 -264.674737)
			(xy 346.069761 -264.663168) (xy 346.074492 -264.655554) (xy 346.124784 -264.567162) (xy 346.12453 -264.539984)
			(xy 346.117672 -264.528046) (xy 346.103728 -264.503338) (xy 346.083903 -264.450187) (xy 346.073839 -264.394358)
			(xy 346.073222 -264.365994) (xy 346.073712 -264.341005) (xy 346.081531 -264.291642) (xy 346.096975 -264.24411)
			(xy 346.119665 -264.199578) (xy 346.149041 -264.159145) (xy 346.184381 -264.123805) (xy 346.224814 -264.094429)
			(xy 346.269346 -264.071739) (xy 346.316878 -264.056295) (xy 346.366241 -264.048476) (xy 346.416219 -264.048476)
			(xy 346.465582 -264.056295) (xy 346.513114 -264.071739) (xy 346.557646 -264.094429) (xy 346.598079 -264.123805)
			(xy 346.633419 -264.159145) (xy 346.662795 -264.199578) (xy 346.685485 -264.24411) (xy 346.700929 -264.291642)
			(xy 346.708748 -264.341005) (xy 346.709238 -264.365994) (xy 346.708767 -264.391663) (xy 346.700527 -264.442336)
			(xy 346.684261 -264.491029) (xy 346.66039 -264.53648) (xy 346.629533 -264.57751) (xy 346.59249 -264.613055)
			(xy 346.550222 -264.642193) (xy 346.503825 -264.664169) (xy 346.454502 -264.678413) (xy 346.429076 -264.68197)
			(xy 346.420324 -264.683396) (xy 346.404474 -264.691314) (xy 346.398088 -264.697464) (xy 346.377514 -264.719308)
			(xy 346.371154 -264.726643) (xy 346.363972 -264.744662) (xy 346.363544 -264.75436) (xy 346.363544 -265.196066)
			(xy 347.4085 -265.196066) (xy 347.4085 -265.195558) (xy 347.4085 -264.895838) (xy 347.408877 -264.874791)
			(xy 347.416878 -264.833469) (xy 347.432813 -264.794513) (xy 347.456067 -264.759431) (xy 347.48574 -264.72958)
			(xy 347.520682 -264.706116) (xy 347.559542 -264.689947) (xy 347.600815 -264.6817) (xy 347.62186 -264.681208)
			(xy 347.876876 -264.681208) (xy 347.876876 -264.690352) (xy 347.877358 -264.700367) (xy 347.885008 -264.718879)
			(xy 347.899161 -264.733052) (xy 347.917661 -264.740728) (xy 347.927676 -264.741152) (xy 347.953076 -264.741152)
			(xy 347.962768 -264.740744) (xy 347.980793 -264.733632) (xy 347.994865 -264.720311) (xy 347.999304 -264.711688)
			(xy 348.044008 -264.614406) (xy 348.03969 -264.584688) (xy 348.030038 -264.573512) (xy 348.012067 -264.551672)
			(xy 347.983344 -264.502957) (xy 347.963678 -264.449934) (xy 347.953689 -264.39427) (xy 347.953076 -264.365994)
			(xy 347.953563 -264.341003) (xy 347.961383 -264.291637) (xy 347.976829 -264.244102) (xy 347.999521 -264.199568)
			(xy 348.028901 -264.159132) (xy 348.064244 -264.123791) (xy 348.104681 -264.094413) (xy 348.149216 -264.071723)
			(xy 348.196752 -264.056279) (xy 348.246118 -264.048462) (xy 348.2961 -264.048463) (xy 348.345466 -264.056284)
			(xy 348.393002 -264.07173) (xy 348.437535 -264.094423) (xy 348.47797 -264.123803) (xy 348.513311 -264.159147)
			(xy 348.542689 -264.199584) (xy 348.565378 -264.244119) (xy 348.580822 -264.291655) (xy 348.588639 -264.341022)
			(xy 348.588637 -264.391004) (xy 348.580816 -264.44037) (xy 348.565368 -264.487905) (xy 348.542675 -264.532438)
			(xy 348.513295 -264.572873) (xy 348.477951 -264.608214) (xy 348.437513 -264.63759) (xy 348.392978 -264.660279)
			(xy 348.345442 -264.675722) (xy 348.296075 -264.683539) (xy 348.271084 -264.684002) (xy 348.250002 -264.68324)
			(xy 348.239334 -264.682478) (xy 348.219522 -264.68959) (xy 348.157546 -264.747756) (xy 348.150301 -264.755268)
			(xy 348.142046 -264.774415) (xy 348.141544 -264.78484) (xy 348.141544 -265.321034) (xy 348.111826 -265.350752)
			(xy 348.09303 -265.350752) (xy 348.081381 -265.351392) (xy 348.060482 -265.3617) (xy 348.052898 -265.370564)
			(xy 348.037687 -265.389396) (xy 348.002601 -265.422743) (xy 347.962872 -265.450395) (xy 347.919415 -265.471715)
			(xy 347.873232 -265.486211) (xy 347.825386 -265.49355) (xy 347.801184 -265.494008) (xy 347.778323 -265.493576)
			(xy 347.733074 -265.487019) (xy 347.689233 -265.474043) (xy 347.647704 -265.454915) (xy 347.609347 -265.430032)
			(xy 347.591888 -265.415268) (xy 347.587182 -265.411452) (xy 347.576399 -265.405933) (xy 347.570552 -265.404346)
			(xy 347.550933 -265.398984) (xy 347.514042 -265.381874) (xy 347.481049 -265.358099) (xy 347.453144 -265.328517)
			(xy 347.431334 -265.294194) (xy 347.416404 -265.256368) (xy 347.408892 -265.216401) (xy 347.4085 -265.196066)
			(xy 346.363544 -265.196066) (xy 346.363544 -265.299952) (xy 346.363042 -265.309965) (xy 346.355396 -265.328472)
			(xy 346.34125 -265.342645) (xy 346.322756 -265.350324) (xy 346.312744 -265.350752) (xy 346.212922 -265.350752)
			(xy 346.201273 -265.351388) (xy 346.180373 -265.361699) (xy 346.17279 -265.370564) (xy 346.157584 -265.3894)
			(xy 346.122497 -265.422746) (xy 346.082767 -265.450398) (xy 346.039309 -265.471717) (xy 345.993125 -265.486213)
			(xy 345.945279 -265.493551) (xy 345.921076 -265.494008) (xy 345.896086 -265.49354) (xy 345.846722 -265.485718)
			(xy 345.79919 -265.47027) (xy 345.754659 -265.447578) (xy 345.714225 -265.418199) (xy 345.678886 -265.382856)
			(xy 345.64951 -265.342421) (xy 345.62682 -265.297888) (xy 345.611376 -265.250354) (xy 345.603558 -265.20099)
			(xy 345.603068 -265.176) (xy 344.35923 -265.176) (xy 344.35874 -265.200989) (xy 344.350921 -265.250352)
			(xy 344.335477 -265.297884) (xy 344.312787 -265.342416) (xy 344.283411 -265.382849) (xy 344.248071 -265.418189)
			(xy 344.207638 -265.447565) (xy 344.163106 -265.470255) (xy 344.115574 -265.485699) (xy 344.066211 -265.493518)
			(xy 344.016233 -265.493518) (xy 343.96687 -265.485699) (xy 343.919338 -265.470255) (xy 343.874806 -265.447565)
			(xy 343.834373 -265.418189) (xy 343.799033 -265.382849) (xy 343.769657 -265.342416) (xy 343.746967 -265.297884)
			(xy 343.731523 -265.250352) (xy 343.723704 -265.200989) (xy 343.418686 -265.200989) (xy 343.410867 -265.250352)
			(xy 343.395423 -265.297884) (xy 343.372733 -265.342416) (xy 343.343357 -265.382849) (xy 343.308017 -265.418189)
			(xy 343.267584 -265.447565) (xy 343.223052 -265.470255) (xy 343.17552 -265.485699) (xy 343.126157 -265.493518)
			(xy 343.076179 -265.493518) (xy 343.026816 -265.485699) (xy 342.979284 -265.470255) (xy 342.934752 -265.447565)
			(xy 342.894319 -265.418189) (xy 342.858979 -265.382849) (xy 342.829603 -265.342416) (xy 342.806913 -265.297884)
			(xy 342.791469 -265.250352) (xy 342.78365 -265.200989) (xy 342.476333 -265.200989) (xy 342.476324 -265.201446)
			(xy 342.46816 -265.25168) (xy 342.452044 -265.299954) (xy 342.428393 -265.345017) (xy 342.39782 -265.385703)
			(xy 342.361116 -265.420958) (xy 342.319232 -265.449868) (xy 342.273253 -265.471685) (xy 342.224369 -265.485845)
			(xy 342.173848 -265.491979) (xy 342.122996 -265.48993) (xy 342.073132 -265.47975) (xy 342.025546 -265.461703)
			(xy 341.981472 -265.436257) (xy 341.94205 -265.40407) (xy 341.908302 -265.365976) (xy 341.881101 -265.322962)
			(xy 341.861153 -265.276142) (xy 341.848974 -265.226728) (xy 341.844879 -265.176) (xy 341.539068 -265.176)
			(xy 341.538578 -265.200989) (xy 341.530759 -265.250352) (xy 341.515315 -265.297884) (xy 341.492625 -265.342416)
			(xy 341.463249 -265.382849) (xy 341.427909 -265.418189) (xy 341.387476 -265.447565) (xy 341.342944 -265.470255)
			(xy 341.295412 -265.485699) (xy 341.246049 -265.493518) (xy 341.196071 -265.493518) (xy 341.146708 -265.485699)
			(xy 341.099176 -265.470255) (xy 341.054644 -265.447565) (xy 341.014211 -265.418189) (xy 340.978871 -265.382849)
			(xy 340.949495 -265.342416) (xy 340.926805 -265.297884) (xy 340.911361 -265.250352) (xy 340.903542 -265.200989)
			(xy 340.598524 -265.200989) (xy 340.590705 -265.250352) (xy 340.575261 -265.297884) (xy 340.552571 -265.342416)
			(xy 340.523195 -265.382849) (xy 340.487855 -265.418189) (xy 340.447422 -265.447565) (xy 340.40289 -265.470255)
			(xy 340.355358 -265.485699) (xy 340.305995 -265.493518) (xy 340.256017 -265.493518) (xy 340.206654 -265.485699)
			(xy 340.159122 -265.470255) (xy 340.11459 -265.447565) (xy 340.074157 -265.418189) (xy 340.038817 -265.382849)
			(xy 340.009441 -265.342416) (xy 339.986751 -265.297884) (xy 339.971307 -265.250352) (xy 339.963488 -265.200989)
			(xy 339.656425 -265.200989) (xy 339.656416 -265.201446) (xy 339.648252 -265.25168) (xy 339.632136 -265.299954)
			(xy 339.608485 -265.345017) (xy 339.577912 -265.385703) (xy 339.541208 -265.420958) (xy 339.499324 -265.449868)
			(xy 339.453345 -265.471685) (xy 339.404461 -265.485845) (xy 339.35394 -265.491979) (xy 339.303088 -265.48993)
			(xy 339.253224 -265.47975) (xy 339.205638 -265.461703) (xy 339.161564 -265.436257) (xy 339.122142 -265.40407)
			(xy 339.088394 -265.365976) (xy 339.061193 -265.322962) (xy 339.041245 -265.276142) (xy 339.029066 -265.226728)
			(xy 339.024971 -265.176) (xy 338.718743 -265.176) (xy 338.718743 -265.200994) (xy 338.710923 -265.250365)
			(xy 338.695475 -265.297906) (xy 338.672779 -265.342443) (xy 338.643395 -265.382882) (xy 338.608046 -265.418226)
			(xy 338.567602 -265.447604) (xy 338.523061 -265.470293) (xy 338.475519 -265.485734) (xy 338.426146 -265.493547)
			(xy 338.401152 -265.494008) (xy 338.376953 -265.493559) (xy 338.329113 -265.486231) (xy 338.282937 -265.471736)
			(xy 338.239491 -265.45041) (xy 338.19978 -265.422745) (xy 338.18195 -265.406378) (xy 338.176362 -265.401298)
			(xy 338.1629 -265.394186) (xy 338.156296 -265.39317) (xy 338.148962 -265.392127) (xy 338.134251 -265.393806)
			(xy 338.12734 -265.396472) (xy 338.058506 -265.425936) (xy 338.057998 -265.425936) (xy 338.041742 -265.432794)
			(xy 338.033237 -265.437154) (xy 338.020068 -265.450984) (xy 338.012969 -265.468712) (xy 338.012532 -265.47826)
			(xy 338.012532 -265.642598) (xy 338.012924 -265.651768) (xy 338.019463 -265.668902) (xy 338.03171 -265.682553)
			(xy 338.03971 -265.687048) (xy 338.045044 -265.68908) (xy 338.068709 -265.698714) (xy 338.112863 -265.724422)
			(xy 338.152339 -265.756858) (xy 338.186122 -265.795187) (xy 338.213344 -265.838424) (xy 338.233304 -265.885456)
			(xy 338.245489 -265.935074) (xy 338.249586 -265.986002) (xy 338.247575 -266.010995) (xy 338.553534 -266.010995)
			(xy 338.553534 -265.961017) (xy 338.561353 -265.911654) (xy 338.576797 -265.864122) (xy 338.599487 -265.81959)
			(xy 338.628863 -265.779157) (xy 338.664203 -265.743817) (xy 338.704636 -265.714441) (xy 338.749168 -265.691751)
			(xy 338.7967 -265.676307) (xy 338.846063 -265.668488) (xy 338.896041 -265.668488) (xy 338.945404 -265.676307)
			(xy 338.992936 -265.691751) (xy 339.037468 -265.714441) (xy 339.077901 -265.743817) (xy 339.113241 -265.779157)
			(xy 339.142617 -265.81959) (xy 339.165307 -265.864122) (xy 339.180751 -265.911654) (xy 339.18857 -265.961017)
			(xy 339.18906 -265.986006) (xy 339.18857 -266.010995) (xy 339.493588 -266.010995) (xy 339.493588 -265.961017)
			(xy 339.501407 -265.911654) (xy 339.516851 -265.864122) (xy 339.539541 -265.81959) (xy 339.568917 -265.779157)
			(xy 339.604257 -265.743817) (xy 339.64469 -265.714441) (xy 339.689222 -265.691751) (xy 339.736754 -265.676307)
			(xy 339.786117 -265.668488) (xy 339.836095 -265.668488) (xy 339.885458 -265.676307) (xy 339.93299 -265.691751)
			(xy 339.977522 -265.714441) (xy 340.017955 -265.743817) (xy 340.053295 -265.779157) (xy 340.082671 -265.81959)
			(xy 340.105361 -265.864122) (xy 340.120805 -265.911654) (xy 340.128624 -265.961017) (xy 340.129114 -265.986006)
			(xy 340.434925 -265.986006) (xy 340.43902 -265.935278) (xy 340.451199 -265.885864) (xy 340.471147 -265.839044)
			(xy 340.498348 -265.79603) (xy 340.532096 -265.757936) (xy 340.571518 -265.725749) (xy 340.615592 -265.700303)
			(xy 340.663178 -265.682256) (xy 340.713042 -265.672076) (xy 340.763894 -265.670027) (xy 340.814415 -265.676161)
			(xy 340.863299 -265.690321) (xy 340.909278 -265.712138) (xy 340.951162 -265.741048) (xy 340.987866 -265.776303)
			(xy 341.018439 -265.816989) (xy 341.04209 -265.862052) (xy 341.058206 -265.910326) (xy 341.06637 -265.96056)
			(xy 341.066882 -265.986006) (xy 341.066379 -266.010995) (xy 342.313496 -266.010995) (xy 342.313496 -265.961017)
			(xy 342.321315 -265.911654) (xy 342.336759 -265.864122) (xy 342.359449 -265.81959) (xy 342.388825 -265.779157)
			(xy 342.424165 -265.743817) (xy 342.464598 -265.714441) (xy 342.50913 -265.691751) (xy 342.556662 -265.676307)
			(xy 342.606025 -265.668488) (xy 342.656003 -265.668488) (xy 342.705366 -265.676307) (xy 342.752898 -265.691751)
			(xy 342.79743 -265.714441) (xy 342.837863 -265.743817) (xy 342.873203 -265.779157) (xy 342.902579 -265.81959)
			(xy 342.925269 -265.864122) (xy 342.940713 -265.911654) (xy 342.948532 -265.961017) (xy 342.949022 -265.986006)
			(xy 343.254833 -265.986006) (xy 343.258928 -265.935278) (xy 343.271107 -265.885864) (xy 343.291055 -265.839044)
			(xy 343.318256 -265.79603) (xy 343.352004 -265.757936) (xy 343.391426 -265.725749) (xy 343.4355 -265.700303)
			(xy 343.483086 -265.682256) (xy 343.53295 -265.672076) (xy 343.583802 -265.670027) (xy 343.634323 -265.676161)
			(xy 343.683207 -265.690321) (xy 343.729186 -265.712138) (xy 343.77107 -265.741048) (xy 343.807774 -265.776303)
			(xy 343.838347 -265.816989) (xy 343.861998 -265.862052) (xy 343.878114 -265.910326) (xy 343.886278 -265.96056)
			(xy 343.88679 -265.986006) (xy 343.886287 -266.010995) (xy 344.193604 -266.010995) (xy 344.193604 -265.961017)
			(xy 344.201423 -265.911654) (xy 344.216867 -265.864122) (xy 344.239557 -265.81959) (xy 344.268933 -265.779157)
			(xy 344.304273 -265.743817) (xy 344.344706 -265.714441) (xy 344.389238 -265.691751) (xy 344.43677 -265.676307)
			(xy 344.486133 -265.668488) (xy 344.536111 -265.668488) (xy 344.585474 -265.676307) (xy 344.633006 -265.691751)
			(xy 344.677538 -265.714441) (xy 344.717971 -265.743817) (xy 344.753311 -265.779157) (xy 344.782687 -265.81959)
			(xy 344.805377 -265.864122) (xy 344.820821 -265.911654) (xy 344.82864 -265.961017) (xy 344.82913 -265.986006)
			(xy 344.82864 -266.010995) (xy 344.820821 -266.060358) (xy 344.805377 -266.10789) (xy 344.782687 -266.152422)
			(xy 344.753311 -266.192855) (xy 344.717971 -266.228195) (xy 344.677538 -266.257571) (xy 344.633006 -266.280261)
			(xy 344.585474 -266.295705) (xy 344.536111 -266.303524) (xy 344.486133 -266.303524) (xy 344.43677 -266.295705)
			(xy 344.389238 -266.280261) (xy 344.344706 -266.257571) (xy 344.304273 -266.228195) (xy 344.268933 -266.192855)
			(xy 344.239557 -266.152422) (xy 344.216867 -266.10789) (xy 344.201423 -266.060358) (xy 344.193604 -266.010995)
			(xy 343.886287 -266.010995) (xy 343.886278 -266.011452) (xy 343.878114 -266.061686) (xy 343.861998 -266.10996)
			(xy 343.838347 -266.155023) (xy 343.807774 -266.195709) (xy 343.77107 -266.230964) (xy 343.729186 -266.259874)
			(xy 343.683207 -266.281691) (xy 343.634323 -266.295851) (xy 343.583802 -266.301985) (xy 343.53295 -266.299936)
			(xy 343.483086 -266.289756) (xy 343.4355 -266.271709) (xy 343.391426 -266.246263) (xy 343.352004 -266.214076)
			(xy 343.318256 -266.175982) (xy 343.291055 -266.132968) (xy 343.271107 -266.086148) (xy 343.258928 -266.036734)
			(xy 343.254833 -265.986006) (xy 342.949022 -265.986006) (xy 342.948532 -266.010995) (xy 342.940713 -266.060358)
			(xy 342.925269 -266.10789) (xy 342.902579 -266.152422) (xy 342.873203 -266.192855) (xy 342.837863 -266.228195)
			(xy 342.79743 -266.257571) (xy 342.752898 -266.280261) (xy 342.705366 -266.295705) (xy 342.656003 -266.303524)
			(xy 342.606025 -266.303524) (xy 342.556662 -266.295705) (xy 342.50913 -266.280261) (xy 342.464598 -266.257571)
			(xy 342.424165 -266.228195) (xy 342.388825 -266.192855) (xy 342.359449 -266.152422) (xy 342.336759 -266.10789)
			(xy 342.321315 -266.060358) (xy 342.313496 -266.010995) (xy 341.066379 -266.010995) (xy 341.06637 -266.011452)
			(xy 341.058206 -266.061686) (xy 341.04209 -266.10996) (xy 341.018439 -266.155023) (xy 340.987866 -266.195709)
			(xy 340.951162 -266.230964) (xy 340.909278 -266.259874) (xy 340.863299 -266.281691) (xy 340.814415 -266.295851)
			(xy 340.763894 -266.301985) (xy 340.713042 -266.299936) (xy 340.663178 -266.289756) (xy 340.615592 -266.271709)
			(xy 340.571518 -266.246263) (xy 340.532096 -266.214076) (xy 340.498348 -266.175982) (xy 340.471147 -266.132968)
			(xy 340.451199 -266.086148) (xy 340.43902 -266.036734) (xy 340.434925 -265.986006) (xy 340.129114 -265.986006)
			(xy 340.128624 -266.010995) (xy 340.120805 -266.060358) (xy 340.105361 -266.10789) (xy 340.082671 -266.152422)
			(xy 340.053295 -266.192855) (xy 340.017955 -266.228195) (xy 339.977522 -266.257571) (xy 339.93299 -266.280261)
			(xy 339.885458 -266.295705) (xy 339.836095 -266.303524) (xy 339.786117 -266.303524) (xy 339.736754 -266.295705)
			(xy 339.689222 -266.280261) (xy 339.64469 -266.257571) (xy 339.604257 -266.228195) (xy 339.568917 -266.192855)
			(xy 339.539541 -266.152422) (xy 339.516851 -266.10789) (xy 339.501407 -266.060358) (xy 339.493588 -266.010995)
			(xy 339.18857 -266.010995) (xy 339.180751 -266.060358) (xy 339.165307 -266.10789) (xy 339.142617 -266.152422)
			(xy 339.113241 -266.192855) (xy 339.077901 -266.228195) (xy 339.037468 -266.257571) (xy 338.992936 -266.280261)
			(xy 338.945404 -266.295705) (xy 338.896041 -266.303524) (xy 338.846063 -266.303524) (xy 338.7967 -266.295705)
			(xy 338.749168 -266.280261) (xy 338.704636 -266.257571) (xy 338.664203 -266.228195) (xy 338.628863 -266.192855)
			(xy 338.599487 -266.152422) (xy 338.576797 -266.10789) (xy 338.561353 -266.060358) (xy 338.553534 -266.010995)
			(xy 338.247575 -266.010995) (xy 338.245489 -266.03693) (xy 338.233303 -266.086548) (xy 338.213342 -266.13358)
			(xy 338.18612 -266.176816) (xy 338.152336 -266.215145) (xy 338.112859 -266.24758) (xy 338.068705 -266.273288)
			(xy 338.045044 -266.282932) (xy 338.03971 -266.284964) (xy 338.031748 -266.289515) (xy 338.01951 -266.303153)
			(xy 338.012926 -266.320253) (xy 338.012532 -266.329414) (xy 338.012532 -266.493752) (xy 338.012946 -266.503307)
			(xy 338.020035 -266.521053) (xy 338.033215 -266.53489) (xy 338.041742 -266.539218) (xy 338.057998 -266.546076)
			(xy 338.058506 -266.546076) (xy 338.12734 -266.57554) (xy 338.134244 -266.578237) (xy 338.148963 -266.579921)
			(xy 338.156296 -266.578842) (xy 338.1629 -266.577826) (xy 338.176362 -266.570714) (xy 338.18195 -266.565634)
			(xy 338.199793 -266.549283) (xy 338.239504 -266.521623) (xy 338.282947 -266.500297) (xy 338.329119 -266.485798)
			(xy 338.376955 -266.47846) (xy 338.401152 -266.478004) (xy 338.426145 -266.478465) (xy 338.475516 -266.486278)
			(xy 338.523057 -266.501718) (xy 338.567596 -266.524406) (xy 338.608038 -266.553783) (xy 338.643386 -266.589126)
			(xy 338.672769 -266.629563) (xy 338.695464 -266.674099) (xy 338.710911 -266.721637) (xy 338.718731 -266.771007)
			(xy 338.718731 -266.796012) (xy 339.024971 -266.796012) (xy 339.029066 -266.745284) (xy 339.041245 -266.69587)
			(xy 339.061193 -266.64905) (xy 339.088394 -266.606036) (xy 339.122142 -266.567942) (xy 339.161564 -266.535755)
			(xy 339.205638 -266.510309) (xy 339.253224 -266.492262) (xy 339.303088 -266.482082) (xy 339.35394 -266.480033)
			(xy 339.404461 -266.486167) (xy 339.453345 -266.500327) (xy 339.499324 -266.522144) (xy 339.541208 -266.551054)
			(xy 339.577912 -266.586309) (xy 339.608485 -266.626995) (xy 339.632136 -266.672058) (xy 339.648252 -266.720332)
			(xy 339.656416 -266.770566) (xy 339.656928 -266.796012) (xy 339.964771 -266.796012) (xy 339.968866 -266.745284)
			(xy 339.981045 -266.69587) (xy 340.000993 -266.64905) (xy 340.028194 -266.606036) (xy 340.061942 -266.567942)
			(xy 340.101364 -266.535755) (xy 340.145438 -266.510309) (xy 340.193024 -266.492262) (xy 340.242888 -266.482082)
			(xy 340.29374 -266.480033) (xy 340.344261 -266.486167) (xy 340.393145 -266.500327) (xy 340.439124 -266.522144)
			(xy 340.481008 -266.551054) (xy 340.517712 -266.586309) (xy 340.548285 -266.626995) (xy 340.571936 -266.672058)
			(xy 340.588052 -266.720332) (xy 340.596216 -266.770566) (xy 340.596728 -266.796012) (xy 340.596225 -266.821001)
			(xy 340.903542 -266.821001) (xy 340.903542 -266.771023) (xy 340.911361 -266.72166) (xy 340.926805 -266.674128)
			(xy 340.949495 -266.629596) (xy 340.978871 -266.589163) (xy 341.014211 -266.553823) (xy 341.054644 -266.524447)
			(xy 341.099176 -266.501757) (xy 341.146708 -266.486313) (xy 341.196071 -266.478494) (xy 341.246049 -266.478494)
			(xy 341.295412 -266.486313) (xy 341.342944 -266.501757) (xy 341.387476 -266.524447) (xy 341.427909 -266.553823)
			(xy 341.463249 -266.589163) (xy 341.492625 -266.629596) (xy 341.515315 -266.674128) (xy 341.530759 -266.72166)
			(xy 341.538578 -266.771023) (xy 341.539068 -266.796012) (xy 341.844879 -266.796012) (xy 341.848974 -266.745284)
			(xy 341.861153 -266.69587) (xy 341.881101 -266.64905) (xy 341.908302 -266.606036) (xy 341.94205 -266.567942)
			(xy 341.981472 -266.535755) (xy 342.025546 -266.510309) (xy 342.073132 -266.492262) (xy 342.122996 -266.482082)
			(xy 342.173848 -266.480033) (xy 342.224369 -266.486167) (xy 342.273253 -266.500327) (xy 342.319232 -266.522144)
			(xy 342.361116 -266.551054) (xy 342.39782 -266.586309) (xy 342.428393 -266.626995) (xy 342.452044 -266.672058)
			(xy 342.46816 -266.720332) (xy 342.476324 -266.770566) (xy 342.476836 -266.796012) (xy 342.476333 -266.821001)
			(xy 342.78365 -266.821001) (xy 342.78365 -266.771023) (xy 342.791469 -266.72166) (xy 342.806913 -266.674128)
			(xy 342.829603 -266.629596) (xy 342.858979 -266.589163) (xy 342.894319 -266.553823) (xy 342.934752 -266.524447)
			(xy 342.979284 -266.501757) (xy 343.026816 -266.486313) (xy 343.076179 -266.478494) (xy 343.126157 -266.478494)
			(xy 343.17552 -266.486313) (xy 343.223052 -266.501757) (xy 343.267584 -266.524447) (xy 343.308017 -266.553823)
			(xy 343.343357 -266.589163) (xy 343.372733 -266.629596) (xy 343.395423 -266.674128) (xy 343.410867 -266.72166)
			(xy 343.418686 -266.771023) (xy 343.419176 -266.796012) (xy 343.724987 -266.796012) (xy 343.729082 -266.745284)
			(xy 343.741261 -266.69587) (xy 343.761209 -266.64905) (xy 343.78841 -266.606036) (xy 343.822158 -266.567942)
			(xy 343.86158 -266.535755) (xy 343.905654 -266.510309) (xy 343.95324 -266.492262) (xy 344.003104 -266.482082)
			(xy 344.053956 -266.480033) (xy 344.104477 -266.486167) (xy 344.153361 -266.500327) (xy 344.19934 -266.522144)
			(xy 344.241224 -266.551054) (xy 344.277928 -266.586309) (xy 344.308501 -266.626995) (xy 344.332152 -266.672058)
			(xy 344.348268 -266.720332) (xy 344.356432 -266.770566) (xy 344.356944 -266.796012) (xy 344.356432 -266.821458)
			(xy 344.348268 -266.871692) (xy 344.332152 -266.919966) (xy 344.308501 -266.965029) (xy 344.277928 -267.005715)
			(xy 344.241224 -267.04097) (xy 344.19934 -267.06988) (xy 344.153361 -267.091697) (xy 344.104477 -267.105857)
			(xy 344.053956 -267.111991) (xy 344.003104 -267.109942) (xy 343.95324 -267.099762) (xy 343.905654 -267.081715)
			(xy 343.86158 -267.056269) (xy 343.822158 -267.024082) (xy 343.78841 -266.985988) (xy 343.761209 -266.942974)
			(xy 343.741261 -266.896154) (xy 343.729082 -266.84674) (xy 343.724987 -266.796012) (xy 343.419176 -266.796012)
			(xy 343.418686 -266.821001) (xy 343.410867 -266.870364) (xy 343.395423 -266.917896) (xy 343.372733 -266.962428)
			(xy 343.343357 -267.002861) (xy 343.308017 -267.038201) (xy 343.267584 -267.067577) (xy 343.223052 -267.090267)
			(xy 343.17552 -267.105711) (xy 343.126157 -267.11353) (xy 343.076179 -267.11353) (xy 343.026816 -267.105711)
			(xy 342.979284 -267.090267) (xy 342.934752 -267.067577) (xy 342.894319 -267.038201) (xy 342.858979 -267.002861)
			(xy 342.829603 -266.962428) (xy 342.806913 -266.917896) (xy 342.791469 -266.870364) (xy 342.78365 -266.821001)
			(xy 342.476333 -266.821001) (xy 342.476324 -266.821458) (xy 342.46816 -266.871692) (xy 342.452044 -266.919966)
			(xy 342.428393 -266.965029) (xy 342.39782 -267.005715) (xy 342.361116 -267.04097) (xy 342.319232 -267.06988)
			(xy 342.273253 -267.091697) (xy 342.224369 -267.105857) (xy 342.173848 -267.111991) (xy 342.122996 -267.109942)
			(xy 342.073132 -267.099762) (xy 342.025546 -267.081715) (xy 341.981472 -267.056269) (xy 341.94205 -267.024082)
			(xy 341.908302 -266.985988) (xy 341.881101 -266.942974) (xy 341.861153 -266.896154) (xy 341.848974 -266.84674)
			(xy 341.844879 -266.796012) (xy 341.539068 -266.796012) (xy 341.538578 -266.821001) (xy 341.530759 -266.870364)
			(xy 341.515315 -266.917896) (xy 341.492625 -266.962428) (xy 341.463249 -267.002861) (xy 341.427909 -267.038201)
			(xy 341.387476 -267.067577) (xy 341.342944 -267.090267) (xy 341.295412 -267.105711) (xy 341.246049 -267.11353)
			(xy 341.196071 -267.11353) (xy 341.146708 -267.105711) (xy 341.099176 -267.090267) (xy 341.054644 -267.067577)
			(xy 341.014211 -267.038201) (xy 340.978871 -267.002861) (xy 340.949495 -266.962428) (xy 340.926805 -266.917896)
			(xy 340.911361 -266.870364) (xy 340.903542 -266.821001) (xy 340.596225 -266.821001) (xy 340.596216 -266.821458)
			(xy 340.588052 -266.871692) (xy 340.571936 -266.919966) (xy 340.548285 -266.965029) (xy 340.517712 -267.005715)
			(xy 340.481008 -267.04097) (xy 340.439124 -267.06988) (xy 340.393145 -267.091697) (xy 340.344261 -267.105857)
			(xy 340.29374 -267.111991) (xy 340.242888 -267.109942) (xy 340.193024 -267.099762) (xy 340.145438 -267.081715)
			(xy 340.101364 -267.056269) (xy 340.061942 -267.024082) (xy 340.028194 -266.985988) (xy 340.000993 -266.942974)
			(xy 339.981045 -266.896154) (xy 339.968866 -266.84674) (xy 339.964771 -266.796012) (xy 339.656928 -266.796012)
			(xy 339.656416 -266.821458) (xy 339.648252 -266.871692) (xy 339.632136 -266.919966) (xy 339.608485 -266.965029)
			(xy 339.577912 -267.005715) (xy 339.541208 -267.04097) (xy 339.499324 -267.06988) (xy 339.453345 -267.091697)
			(xy 339.404461 -267.105857) (xy 339.35394 -267.111991) (xy 339.303088 -267.109942) (xy 339.253224 -267.099762)
			(xy 339.205638 -267.081715) (xy 339.161564 -267.056269) (xy 339.122142 -267.024082) (xy 339.088394 -266.985988)
			(xy 339.061193 -266.942974) (xy 339.041245 -266.896154) (xy 339.029066 -266.84674) (xy 339.024971 -266.796012)
			(xy 338.718731 -266.796012) (xy 338.718731 -266.820993) (xy 338.710911 -266.870363) (xy 338.695464 -266.917901)
			(xy 338.672769 -266.962437) (xy 338.643386 -267.002874) (xy 338.608038 -267.038217) (xy 338.567596 -267.067594)
			(xy 338.523057 -267.090282) (xy 338.475516 -267.105722) (xy 338.426145 -267.113535) (xy 338.401152 -267.11402)
			(xy 338.376953 -267.113571) (xy 338.329113 -267.106243) (xy 338.282936 -267.091749) (xy 338.23949 -267.070423)
			(xy 338.199778 -267.042759) (xy 338.18195 -267.02639) (xy 338.176362 -267.02131) (xy 338.1629 -267.014198)
			(xy 338.156296 -267.013182) (xy 338.148962 -267.012139) (xy 338.134252 -267.013819) (xy 338.12734 -267.016484)
			(xy 338.058506 -267.045948) (xy 338.057998 -267.045948) (xy 338.041742 -267.052806) (xy 338.033238 -267.057167)
			(xy 338.020072 -267.070997) (xy 338.012978 -267.088725) (xy 338.012532 -267.098272) (xy 338.012532 -267.26261)
			(xy 338.012926 -267.271779) (xy 338.019468 -267.288909) (xy 338.031715 -267.302557) (xy 338.03971 -267.30706)
			(xy 338.045044 -267.309092) (xy 338.068708 -267.318726) (xy 338.11286 -267.344434) (xy 338.152334 -267.376869)
			(xy 338.186116 -267.415197) (xy 338.213336 -267.458433) (xy 338.233295 -267.505464) (xy 338.245479 -267.55508)
			(xy 338.249575 -267.606006) (xy 338.249574 -267.606018) (xy 338.554817 -267.606018) (xy 338.558912 -267.55529)
			(xy 338.571091 -267.505876) (xy 338.591039 -267.459056) (xy 338.61824 -267.416042) (xy 338.651988 -267.377948)
			(xy 338.69141 -267.345761) (xy 338.735484 -267.320315) (xy 338.78307 -267.302268) (xy 338.832934 -267.292088)
			(xy 338.883786 -267.290039) (xy 338.934307 -267.296173) (xy 338.983191 -267.310333) (xy 339.02917 -267.33215)
			(xy 339.071054 -267.36106) (xy 339.107758 -267.396315) (xy 339.138331 -267.437001) (xy 339.161982 -267.482064)
			(xy 339.178098 -267.530338) (xy 339.186262 -267.580572) (xy 339.186774 -267.606018) (xy 339.186271 -267.631007)
			(xy 339.493588 -267.631007) (xy 339.493588 -267.581029) (xy 339.501407 -267.531666) (xy 339.516851 -267.484134)
			(xy 339.539541 -267.439602) (xy 339.568917 -267.399169) (xy 339.604257 -267.363829) (xy 339.64469 -267.334453)
			(xy 339.689222 -267.311763) (xy 339.736754 -267.296319) (xy 339.786117 -267.2885) (xy 339.836095 -267.2885)
			(xy 339.885458 -267.296319) (xy 339.93299 -267.311763) (xy 339.977522 -267.334453) (xy 340.017955 -267.363829)
			(xy 340.053295 -267.399169) (xy 340.082671 -267.439602) (xy 340.105361 -267.484134) (xy 340.120805 -267.531666)
			(xy 340.128624 -267.581029) (xy 340.129114 -267.606018) (xy 340.128624 -267.631007) (xy 340.433642 -267.631007)
			(xy 340.433642 -267.581029) (xy 340.441461 -267.531666) (xy 340.456905 -267.484134) (xy 340.479595 -267.439602)
			(xy 340.508971 -267.399169) (xy 340.544311 -267.363829) (xy 340.584744 -267.334453) (xy 340.629276 -267.311763)
			(xy 340.676808 -267.296319) (xy 340.726171 -267.2885) (xy 340.776149 -267.2885) (xy 340.825512 -267.296319)
			(xy 340.873044 -267.311763) (xy 340.917576 -267.334453) (xy 340.958009 -267.363829) (xy 340.993349 -267.399169)
			(xy 341.022725 -267.439602) (xy 341.045415 -267.484134) (xy 341.060859 -267.531666) (xy 341.068678 -267.581029)
			(xy 341.069168 -267.606018) (xy 341.068678 -267.631007) (xy 341.373696 -267.631007) (xy 341.373696 -267.581029)
			(xy 341.381515 -267.531666) (xy 341.396959 -267.484134) (xy 341.419649 -267.439602) (xy 341.449025 -267.399169)
			(xy 341.484365 -267.363829) (xy 341.524798 -267.334453) (xy 341.56933 -267.311763) (xy 341.616862 -267.296319)
			(xy 341.666225 -267.2885) (xy 341.716203 -267.2885) (xy 341.765566 -267.296319) (xy 341.813098 -267.311763)
			(xy 341.85763 -267.334453) (xy 341.898063 -267.363829) (xy 341.933403 -267.399169) (xy 341.962779 -267.439602)
			(xy 341.985469 -267.484134) (xy 342.000913 -267.531666) (xy 342.008732 -267.581029) (xy 342.009222 -267.606018)
			(xy 342.314779 -267.606018) (xy 342.318874 -267.55529) (xy 342.331053 -267.505876) (xy 342.351001 -267.459056)
			(xy 342.378202 -267.416042) (xy 342.41195 -267.377948) (xy 342.451372 -267.345761) (xy 342.495446 -267.320315)
			(xy 342.543032 -267.302268) (xy 342.592896 -267.292088) (xy 342.643748 -267.290039) (xy 342.694269 -267.296173)
			(xy 342.743153 -267.310333) (xy 342.789132 -267.33215) (xy 342.831016 -267.36106) (xy 342.86772 -267.396315)
			(xy 342.898293 -267.437001) (xy 342.921944 -267.482064) (xy 342.93806 -267.530338) (xy 342.946224 -267.580572)
			(xy 342.946736 -267.606018) (xy 342.946233 -267.631007) (xy 343.25355 -267.631007) (xy 343.25355 -267.581029)
			(xy 343.261369 -267.531666) (xy 343.276813 -267.484134) (xy 343.299503 -267.439602) (xy 343.328879 -267.399169)
			(xy 343.364219 -267.363829) (xy 343.404652 -267.334453) (xy 343.449184 -267.311763) (xy 343.496716 -267.296319)
			(xy 343.546079 -267.2885) (xy 343.596057 -267.2885) (xy 343.64542 -267.296319) (xy 343.692952 -267.311763)
			(xy 343.737484 -267.334453) (xy 343.777917 -267.363829) (xy 343.813257 -267.399169) (xy 343.842633 -267.439602)
			(xy 343.865323 -267.484134) (xy 343.880767 -267.531666) (xy 343.888586 -267.581029) (xy 343.889076 -267.606018)
			(xy 343.888586 -267.631007) (xy 343.880767 -267.68037) (xy 343.865323 -267.727902) (xy 343.842633 -267.772434)
			(xy 343.813257 -267.812867) (xy 343.777917 -267.848207) (xy 343.737484 -267.877583) (xy 343.692952 -267.900273)
			(xy 343.64542 -267.915717) (xy 343.596057 -267.923536) (xy 343.546079 -267.923536) (xy 343.496716 -267.915717)
			(xy 343.449184 -267.900273) (xy 343.404652 -267.877583) (xy 343.364219 -267.848207) (xy 343.328879 -267.812867)
			(xy 343.299503 -267.772434) (xy 343.276813 -267.727902) (xy 343.261369 -267.68037) (xy 343.25355 -267.631007)
			(xy 342.946233 -267.631007) (xy 342.946224 -267.631464) (xy 342.93806 -267.681698) (xy 342.921944 -267.729972)
			(xy 342.898293 -267.775035) (xy 342.86772 -267.815721) (xy 342.831016 -267.850976) (xy 342.789132 -267.879886)
			(xy 342.743153 -267.901703) (xy 342.694269 -267.915863) (xy 342.643748 -267.921997) (xy 342.592896 -267.919948)
			(xy 342.543032 -267.909768) (xy 342.495446 -267.891721) (xy 342.451372 -267.866275) (xy 342.41195 -267.834088)
			(xy 342.378202 -267.795994) (xy 342.351001 -267.75298) (xy 342.331053 -267.70616) (xy 342.318874 -267.656746)
			(xy 342.314779 -267.606018) (xy 342.009222 -267.606018) (xy 342.008732 -267.631007) (xy 342.000913 -267.68037)
			(xy 341.985469 -267.727902) (xy 341.962779 -267.772434) (xy 341.933403 -267.812867) (xy 341.898063 -267.848207)
			(xy 341.85763 -267.877583) (xy 341.813098 -267.900273) (xy 341.765566 -267.915717) (xy 341.716203 -267.923536)
			(xy 341.666225 -267.923536) (xy 341.616862 -267.915717) (xy 341.56933 -267.900273) (xy 341.524798 -267.877583)
			(xy 341.484365 -267.848207) (xy 341.449025 -267.812867) (xy 341.419649 -267.772434) (xy 341.396959 -267.727902)
			(xy 341.381515 -267.68037) (xy 341.373696 -267.631007) (xy 341.068678 -267.631007) (xy 341.060859 -267.68037)
			(xy 341.045415 -267.727902) (xy 341.022725 -267.772434) (xy 340.993349 -267.812867) (xy 340.958009 -267.848207)
			(xy 340.917576 -267.877583) (xy 340.873044 -267.900273) (xy 340.825512 -267.915717) (xy 340.776149 -267.923536)
			(xy 340.726171 -267.923536) (xy 340.676808 -267.915717) (xy 340.629276 -267.900273) (xy 340.584744 -267.877583)
			(xy 340.544311 -267.848207) (xy 340.508971 -267.812867) (xy 340.479595 -267.772434) (xy 340.456905 -267.727902)
			(xy 340.441461 -267.68037) (xy 340.433642 -267.631007) (xy 340.128624 -267.631007) (xy 340.120805 -267.68037)
			(xy 340.105361 -267.727902) (xy 340.082671 -267.772434) (xy 340.053295 -267.812867) (xy 340.017955 -267.848207)
			(xy 339.977522 -267.877583) (xy 339.93299 -267.900273) (xy 339.885458 -267.915717) (xy 339.836095 -267.923536)
			(xy 339.786117 -267.923536) (xy 339.736754 -267.915717) (xy 339.689222 -267.900273) (xy 339.64469 -267.877583)
			(xy 339.604257 -267.848207) (xy 339.568917 -267.812867) (xy 339.539541 -267.772434) (xy 339.516851 -267.727902)
			(xy 339.501407 -267.68037) (xy 339.493588 -267.631007) (xy 339.186271 -267.631007) (xy 339.186262 -267.631464)
			(xy 339.178098 -267.681698) (xy 339.161982 -267.729972) (xy 339.138331 -267.775035) (xy 339.107758 -267.815721)
			(xy 339.071054 -267.850976) (xy 339.02917 -267.879886) (xy 338.983191 -267.901703) (xy 338.934307 -267.915863)
			(xy 338.883786 -267.921997) (xy 338.832934 -267.919948) (xy 338.78307 -267.909768) (xy 338.735484 -267.891721)
			(xy 338.69141 -267.866275) (xy 338.651988 -267.834088) (xy 338.61824 -267.795994) (xy 338.591039 -267.75298)
			(xy 338.571091 -267.70616) (xy 338.558912 -267.656746) (xy 338.554817 -267.606018) (xy 338.249574 -267.606018)
			(xy 338.245477 -267.656933) (xy 338.233291 -267.706549) (xy 338.21333 -267.753579) (xy 338.186108 -267.796813)
			(xy 338.152325 -267.83514) (xy 338.112849 -267.867573) (xy 338.068697 -267.893279) (xy 338.045044 -267.902944)
			(xy 338.03971 -267.904976) (xy 338.03175 -267.909528) (xy 338.019515 -267.923166) (xy 338.012935 -267.940266)
			(xy 338.012532 -267.949426) (xy 338.012532 -268.113764) (xy 338.012948 -268.123318) (xy 338.02004 -268.14106)
			(xy 338.03322 -268.154893) (xy 338.041742 -268.15923) (xy 338.057998 -268.166088) (xy 338.058506 -268.166088)
			(xy 338.12734 -268.195552) (xy 338.134244 -268.198248) (xy 338.148963 -268.199932) (xy 338.156296 -268.198854)
			(xy 338.1629 -268.197838) (xy 338.176362 -268.190726) (xy 338.18195 -268.185646) (xy 338.199793 -268.169295)
			(xy 338.239504 -268.141633) (xy 338.282947 -268.120307) (xy 338.329119 -268.105807) (xy 338.376954 -268.098469)
			(xy 338.401152 -268.098016) (xy 338.426144 -268.098477) (xy 338.475513 -268.10629) (xy 338.523052 -268.12173)
			(xy 338.56759 -268.144417) (xy 338.60803 -268.173793) (xy 338.643376 -268.209134) (xy 338.672758 -268.249569)
			(xy 338.695452 -268.294104) (xy 338.710899 -268.34164) (xy 338.718719 -268.391008) (xy 338.718719 -268.440992)
			(xy 338.718716 -268.441013) (xy 339.023688 -268.441013) (xy 339.023688 -268.391035) (xy 339.031507 -268.341672)
			(xy 339.046951 -268.29414) (xy 339.069641 -268.249608) (xy 339.099017 -268.209175) (xy 339.134357 -268.173835)
			(xy 339.17479 -268.144459) (xy 339.219322 -268.121769) (xy 339.266854 -268.106325) (xy 339.316217 -268.098506)
			(xy 339.366195 -268.098506) (xy 339.415558 -268.106325) (xy 339.46309 -268.121769) (xy 339.507622 -268.144459)
			(xy 339.548055 -268.173835) (xy 339.583395 -268.209175) (xy 339.612771 -268.249608) (xy 339.635461 -268.29414)
			(xy 339.650905 -268.341672) (xy 339.658724 -268.391035) (xy 339.659214 -268.416024) (xy 339.658724 -268.441013)
			(xy 339.963488 -268.441013) (xy 339.963488 -268.391035) (xy 339.971307 -268.341672) (xy 339.986751 -268.29414)
			(xy 340.009441 -268.249608) (xy 340.038817 -268.209175) (xy 340.074157 -268.173835) (xy 340.11459 -268.144459)
			(xy 340.159122 -268.121769) (xy 340.206654 -268.106325) (xy 340.256017 -268.098506) (xy 340.305995 -268.098506)
			(xy 340.355358 -268.106325) (xy 340.40289 -268.121769) (xy 340.447422 -268.144459) (xy 340.487855 -268.173835)
			(xy 340.523195 -268.209175) (xy 340.552571 -268.249608) (xy 340.575261 -268.29414) (xy 340.590705 -268.341672)
			(xy 340.598524 -268.391035) (xy 340.599014 -268.416024) (xy 340.598524 -268.441013) (xy 341.843596 -268.441013)
			(xy 341.843596 -268.391035) (xy 341.851415 -268.341672) (xy 341.866859 -268.29414) (xy 341.889549 -268.249608)
			(xy 341.918925 -268.209175) (xy 341.954265 -268.173835) (xy 341.994698 -268.144459) (xy 342.03923 -268.121769)
			(xy 342.086762 -268.106325) (xy 342.136125 -268.098506) (xy 342.186103 -268.098506) (xy 342.235466 -268.106325)
			(xy 342.282998 -268.121769) (xy 342.32753 -268.144459) (xy 342.367963 -268.173835) (xy 342.403303 -268.209175)
			(xy 342.432679 -268.249608) (xy 342.455369 -268.29414) (xy 342.470813 -268.341672) (xy 342.478632 -268.391035)
			(xy 342.479122 -268.416024) (xy 342.478632 -268.441013) (xy 342.78365 -268.441013) (xy 342.78365 -268.391035)
			(xy 342.791469 -268.341672) (xy 342.806913 -268.29414) (xy 342.829603 -268.249608) (xy 342.858979 -268.209175)
			(xy 342.894319 -268.173835) (xy 342.934752 -268.144459) (xy 342.979284 -268.121769) (xy 343.026816 -268.106325)
			(xy 343.076179 -268.098506) (xy 343.126157 -268.098506) (xy 343.17552 -268.106325) (xy 343.223052 -268.121769)
			(xy 343.267584 -268.144459) (xy 343.308017 -268.173835) (xy 343.343357 -268.209175) (xy 343.372733 -268.249608)
			(xy 343.395423 -268.29414) (xy 343.410867 -268.341672) (xy 343.418686 -268.391035) (xy 343.419176 -268.416024)
			(xy 343.418686 -268.441013) (xy 343.723704 -268.441013) (xy 343.723704 -268.391035) (xy 343.731523 -268.341672)
			(xy 343.746967 -268.29414) (xy 343.769657 -268.249608) (xy 343.799033 -268.209175) (xy 343.834373 -268.173835)
			(xy 343.874806 -268.144459) (xy 343.919338 -268.121769) (xy 343.96687 -268.106325) (xy 344.016233 -268.098506)
			(xy 344.066211 -268.098506) (xy 344.115574 -268.106325) (xy 344.163106 -268.121769) (xy 344.207638 -268.144459)
			(xy 344.248071 -268.173835) (xy 344.283411 -268.209175) (xy 344.312787 -268.249608) (xy 344.335477 -268.29414)
			(xy 344.350921 -268.341672) (xy 344.35874 -268.391035) (xy 344.35923 -268.416024) (xy 344.35874 -268.441013)
			(xy 344.350921 -268.490376) (xy 344.335477 -268.537908) (xy 344.312787 -268.58244) (xy 344.283411 -268.622873)
			(xy 344.248071 -268.658213) (xy 344.207638 -268.687589) (xy 344.163106 -268.710279) (xy 344.115574 -268.725723)
			(xy 344.066211 -268.733542) (xy 344.016233 -268.733542) (xy 343.96687 -268.725723) (xy 343.919338 -268.710279)
			(xy 343.874806 -268.687589) (xy 343.834373 -268.658213) (xy 343.799033 -268.622873) (xy 343.769657 -268.58244)
			(xy 343.746967 -268.537908) (xy 343.731523 -268.490376) (xy 343.723704 -268.441013) (xy 343.418686 -268.441013)
			(xy 343.410867 -268.490376) (xy 343.395423 -268.537908) (xy 343.372733 -268.58244) (xy 343.343357 -268.622873)
			(xy 343.308017 -268.658213) (xy 343.267584 -268.687589) (xy 343.223052 -268.710279) (xy 343.17552 -268.725723)
			(xy 343.126157 -268.733542) (xy 343.076179 -268.733542) (xy 343.026816 -268.725723) (xy 342.979284 -268.710279)
			(xy 342.934752 -268.687589) (xy 342.894319 -268.658213) (xy 342.858979 -268.622873) (xy 342.829603 -268.58244)
			(xy 342.806913 -268.537908) (xy 342.791469 -268.490376) (xy 342.78365 -268.441013) (xy 342.478632 -268.441013)
			(xy 342.470813 -268.490376) (xy 342.455369 -268.537908) (xy 342.432679 -268.58244) (xy 342.403303 -268.622873)
			(xy 342.367963 -268.658213) (xy 342.32753 -268.687589) (xy 342.282998 -268.710279) (xy 342.235466 -268.725723)
			(xy 342.186103 -268.733542) (xy 342.136125 -268.733542) (xy 342.086762 -268.725723) (xy 342.03923 -268.710279)
			(xy 341.994698 -268.687589) (xy 341.954265 -268.658213) (xy 341.918925 -268.622873) (xy 341.889549 -268.58244)
			(xy 341.866859 -268.537908) (xy 341.851415 -268.490376) (xy 341.843596 -268.441013) (xy 340.598524 -268.441013)
			(xy 340.590705 -268.490376) (xy 340.575261 -268.537908) (xy 340.552571 -268.58244) (xy 340.523195 -268.622873)
			(xy 340.487855 -268.658213) (xy 340.447422 -268.687589) (xy 340.40289 -268.710279) (xy 340.355358 -268.725723)
			(xy 340.305995 -268.733542) (xy 340.256017 -268.733542) (xy 340.206654 -268.725723) (xy 340.159122 -268.710279)
			(xy 340.11459 -268.687589) (xy 340.074157 -268.658213) (xy 340.038817 -268.622873) (xy 340.009441 -268.58244)
			(xy 339.986751 -268.537908) (xy 339.971307 -268.490376) (xy 339.963488 -268.441013) (xy 339.658724 -268.441013)
			(xy 339.650905 -268.490376) (xy 339.635461 -268.537908) (xy 339.612771 -268.58244) (xy 339.583395 -268.622873)
			(xy 339.548055 -268.658213) (xy 339.507622 -268.687589) (xy 339.46309 -268.710279) (xy 339.415558 -268.725723)
			(xy 339.366195 -268.733542) (xy 339.316217 -268.733542) (xy 339.266854 -268.725723) (xy 339.219322 -268.710279)
			(xy 339.17479 -268.687589) (xy 339.134357 -268.658213) (xy 339.099017 -268.622873) (xy 339.069641 -268.58244)
			(xy 339.046951 -268.537908) (xy 339.031507 -268.490376) (xy 339.023688 -268.441013) (xy 338.718716 -268.441013)
			(xy 338.710899 -268.49036) (xy 338.695452 -268.537896) (xy 338.672758 -268.582431) (xy 338.643376 -268.622866)
			(xy 338.60803 -268.658207) (xy 338.56759 -268.687583) (xy 338.523052 -268.71027) (xy 338.475513 -268.72571)
			(xy 338.426144 -268.733523) (xy 338.401152 -268.734032) (xy 338.376953 -268.733583) (xy 338.329113 -268.726255)
			(xy 338.282936 -268.711762) (xy 338.239489 -268.690436) (xy 338.199776 -268.662773) (xy 338.18195 -268.646402)
			(xy 338.176362 -268.641322) (xy 338.1629 -268.63421) (xy 338.156296 -268.633194) (xy 338.148963 -268.632151)
			(xy 338.134252 -268.633831) (xy 338.12734 -268.636496) (xy 338.058506 -268.66596) (xy 338.057998 -268.66596)
			(xy 338.041742 -268.672818) (xy 338.033228 -268.677174) (xy 338.020038 -268.691) (xy 338.012914 -268.708731)
			(xy 338.012532 -268.718284) (xy 338.012532 -268.882622) (xy 338.012928 -268.89179) (xy 338.019473 -268.908917)
			(xy 338.031721 -268.922561) (xy 338.03971 -268.927072) (xy 338.045044 -268.929104) (xy 338.068707 -268.938738)
			(xy 338.112857 -268.964446) (xy 338.15233 -268.99688) (xy 338.18611 -269.035207) (xy 338.213328 -269.078442)
			(xy 338.233286 -269.125471) (xy 338.245469 -269.175086) (xy 338.249564 -269.226011) (xy 338.249562 -269.22603)
			(xy 338.554817 -269.22603) (xy 338.558912 -269.175302) (xy 338.571091 -269.125888) (xy 338.591039 -269.079068)
			(xy 338.61824 -269.036054) (xy 338.651988 -268.99796) (xy 338.69141 -268.965773) (xy 338.735484 -268.940327)
			(xy 338.78307 -268.92228) (xy 338.832934 -268.9121) (xy 338.883786 -268.910051) (xy 338.934307 -268.916185)
			(xy 338.983191 -268.930345) (xy 339.02917 -268.952162) (xy 339.071054 -268.981072) (xy 339.107758 -269.016327)
			(xy 339.138331 -269.057013) (xy 339.161982 -269.102076) (xy 339.178098 -269.15035) (xy 339.186262 -269.200584)
			(xy 339.186774 -269.22603) (xy 339.186271 -269.251019) (xy 339.493588 -269.251019) (xy 339.493588 -269.201041)
			(xy 339.501407 -269.151678) (xy 339.516851 -269.104146) (xy 339.539541 -269.059614) (xy 339.568917 -269.019181)
			(xy 339.604257 -268.983841) (xy 339.64469 -268.954465) (xy 339.689222 -268.931775) (xy 339.736754 -268.916331)
			(xy 339.786117 -268.908512) (xy 339.836095 -268.908512) (xy 339.885458 -268.916331) (xy 339.93299 -268.931775)
			(xy 339.977522 -268.954465) (xy 340.017955 -268.983841) (xy 340.053295 -269.019181) (xy 340.082671 -269.059614)
			(xy 340.105361 -269.104146) (xy 340.120805 -269.151678) (xy 340.128624 -269.201041) (xy 340.129114 -269.22603)
			(xy 340.128624 -269.251019) (xy 340.433642 -269.251019) (xy 340.433642 -269.201041) (xy 340.441461 -269.151678)
			(xy 340.456905 -269.104146) (xy 340.479595 -269.059614) (xy 340.508971 -269.019181) (xy 340.544311 -268.983841)
			(xy 340.584744 -268.954465) (xy 340.629276 -268.931775) (xy 340.676808 -268.916331) (xy 340.726171 -268.908512)
			(xy 340.776149 -268.908512) (xy 340.825512 -268.916331) (xy 340.873044 -268.931775) (xy 340.917576 -268.954465)
			(xy 340.958009 -268.983841) (xy 340.993349 -269.019181) (xy 341.022725 -269.059614) (xy 341.045415 -269.104146)
			(xy 341.060859 -269.151678) (xy 341.068678 -269.201041) (xy 341.069168 -269.22603) (xy 341.068678 -269.251019)
			(xy 341.373696 -269.251019) (xy 341.373696 -269.201041) (xy 341.381515 -269.151678) (xy 341.396959 -269.104146)
			(xy 341.419649 -269.059614) (xy 341.449025 -269.019181) (xy 341.484365 -268.983841) (xy 341.524798 -268.954465)
			(xy 341.56933 -268.931775) (xy 341.616862 -268.916331) (xy 341.666225 -268.908512) (xy 341.716203 -268.908512)
			(xy 341.765566 -268.916331) (xy 341.813098 -268.931775) (xy 341.85763 -268.954465) (xy 341.898063 -268.983841)
			(xy 341.933403 -269.019181) (xy 341.962779 -269.059614) (xy 341.985469 -269.104146) (xy 342.000913 -269.151678)
			(xy 342.008732 -269.201041) (xy 342.009222 -269.22603) (xy 342.314779 -269.22603) (xy 342.318874 -269.175302)
			(xy 342.331053 -269.125888) (xy 342.351001 -269.079068) (xy 342.378202 -269.036054) (xy 342.41195 -268.99796)
			(xy 342.451372 -268.965773) (xy 342.495446 -268.940327) (xy 342.543032 -268.92228) (xy 342.592896 -268.9121)
			(xy 342.643748 -268.910051) (xy 342.694269 -268.916185) (xy 342.743153 -268.930345) (xy 342.789132 -268.952162)
			(xy 342.831016 -268.981072) (xy 342.86772 -269.016327) (xy 342.898293 -269.057013) (xy 342.921944 -269.102076)
			(xy 342.93806 -269.15035) (xy 342.946224 -269.200584) (xy 342.946736 -269.22603) (xy 342.946233 -269.251019)
			(xy 343.25355 -269.251019) (xy 343.25355 -269.201041) (xy 343.261369 -269.151678) (xy 343.276813 -269.104146)
			(xy 343.299503 -269.059614) (xy 343.328879 -269.019181) (xy 343.364219 -268.983841) (xy 343.404652 -268.954465)
			(xy 343.449184 -268.931775) (xy 343.496716 -268.916331) (xy 343.546079 -268.908512) (xy 343.596057 -268.908512)
			(xy 343.64542 -268.916331) (xy 343.692952 -268.931775) (xy 343.737484 -268.954465) (xy 343.777917 -268.983841)
			(xy 343.813257 -269.019181) (xy 343.842633 -269.059614) (xy 343.865323 -269.104146) (xy 343.880767 -269.151678)
			(xy 343.888586 -269.201041) (xy 343.889076 -269.22603) (xy 343.888586 -269.251019) (xy 343.880767 -269.300382)
			(xy 343.865323 -269.347914) (xy 343.842633 -269.392446) (xy 343.813257 -269.432879) (xy 343.777917 -269.468219)
			(xy 343.737484 -269.497595) (xy 343.692952 -269.520285) (xy 343.64542 -269.535729) (xy 343.596057 -269.543548)
			(xy 343.546079 -269.543548) (xy 343.496716 -269.535729) (xy 343.449184 -269.520285) (xy 343.404652 -269.497595)
			(xy 343.364219 -269.468219) (xy 343.328879 -269.432879) (xy 343.299503 -269.392446) (xy 343.276813 -269.347914)
			(xy 343.261369 -269.300382) (xy 343.25355 -269.251019) (xy 342.946233 -269.251019) (xy 342.946224 -269.251476)
			(xy 342.93806 -269.30171) (xy 342.921944 -269.349984) (xy 342.898293 -269.395047) (xy 342.86772 -269.435733)
			(xy 342.831016 -269.470988) (xy 342.789132 -269.499898) (xy 342.743153 -269.521715) (xy 342.694269 -269.535875)
			(xy 342.643748 -269.542009) (xy 342.592896 -269.53996) (xy 342.543032 -269.52978) (xy 342.495446 -269.511733)
			(xy 342.451372 -269.486287) (xy 342.41195 -269.4541) (xy 342.378202 -269.416006) (xy 342.351001 -269.372992)
			(xy 342.331053 -269.326172) (xy 342.318874 -269.276758) (xy 342.314779 -269.22603) (xy 342.009222 -269.22603)
			(xy 342.008732 -269.251019) (xy 342.000913 -269.300382) (xy 341.985469 -269.347914) (xy 341.962779 -269.392446)
			(xy 341.933403 -269.432879) (xy 341.898063 -269.468219) (xy 341.85763 -269.497595) (xy 341.813098 -269.520285)
			(xy 341.765566 -269.535729) (xy 341.716203 -269.543548) (xy 341.666225 -269.543548) (xy 341.616862 -269.535729)
			(xy 341.56933 -269.520285) (xy 341.524798 -269.497595) (xy 341.484365 -269.468219) (xy 341.449025 -269.432879)
			(xy 341.419649 -269.392446) (xy 341.396959 -269.347914) (xy 341.381515 -269.300382) (xy 341.373696 -269.251019)
			(xy 341.068678 -269.251019) (xy 341.060859 -269.300382) (xy 341.045415 -269.347914) (xy 341.022725 -269.392446)
			(xy 340.993349 -269.432879) (xy 340.958009 -269.468219) (xy 340.917576 -269.497595) (xy 340.873044 -269.520285)
			(xy 340.825512 -269.535729) (xy 340.776149 -269.543548) (xy 340.726171 -269.543548) (xy 340.676808 -269.535729)
			(xy 340.629276 -269.520285) (xy 340.584744 -269.497595) (xy 340.544311 -269.468219) (xy 340.508971 -269.432879)
			(xy 340.479595 -269.392446) (xy 340.456905 -269.347914) (xy 340.441461 -269.300382) (xy 340.433642 -269.251019)
			(xy 340.128624 -269.251019) (xy 340.120805 -269.300382) (xy 340.105361 -269.347914) (xy 340.082671 -269.392446)
			(xy 340.053295 -269.432879) (xy 340.017955 -269.468219) (xy 339.977522 -269.497595) (xy 339.93299 -269.520285)
			(xy 339.885458 -269.535729) (xy 339.836095 -269.543548) (xy 339.786117 -269.543548) (xy 339.736754 -269.535729)
			(xy 339.689222 -269.520285) (xy 339.64469 -269.497595) (xy 339.604257 -269.468219) (xy 339.568917 -269.432879)
			(xy 339.539541 -269.392446) (xy 339.516851 -269.347914) (xy 339.501407 -269.300382) (xy 339.493588 -269.251019)
			(xy 339.186271 -269.251019) (xy 339.186262 -269.251476) (xy 339.178098 -269.30171) (xy 339.161982 -269.349984)
			(xy 339.138331 -269.395047) (xy 339.107758 -269.435733) (xy 339.071054 -269.470988) (xy 339.02917 -269.499898)
			(xy 338.983191 -269.521715) (xy 338.934307 -269.535875) (xy 338.883786 -269.542009) (xy 338.832934 -269.53996)
			(xy 338.78307 -269.52978) (xy 338.735484 -269.511733) (xy 338.69141 -269.486287) (xy 338.651988 -269.4541)
			(xy 338.61824 -269.416006) (xy 338.591039 -269.372992) (xy 338.571091 -269.326172) (xy 338.558912 -269.276758)
			(xy 338.554817 -269.22603) (xy 338.249562 -269.22603) (xy 338.245465 -269.276935) (xy 338.233279 -269.326549)
			(xy 338.213318 -269.373577) (xy 338.186097 -269.41681) (xy 338.152314 -269.455135) (xy 338.112839 -269.487567)
			(xy 338.068688 -269.513271) (xy 338.045044 -269.522956) (xy 338.03971 -269.524988) (xy 338.031751 -269.529541)
			(xy 338.01952 -269.54318) (xy 338.012944 -269.560279) (xy 338.012532 -269.569438) (xy 338.012532 -269.733776)
			(xy 338.01295 -269.743329) (xy 338.020045 -269.761067) (xy 338.033225 -269.774897) (xy 338.041742 -269.779242)
			(xy 338.057998 -269.7861) (xy 338.058506 -269.7861) (xy 338.12734 -269.815564) (xy 338.134244 -269.81826)
			(xy 338.148963 -269.819943) (xy 338.156296 -269.818866) (xy 338.1629 -269.81785) (xy 338.176362 -269.810738)
			(xy 338.18195 -269.805658) (xy 338.199793 -269.789306) (xy 338.239503 -269.761644) (xy 338.282946 -269.740316)
			(xy 338.329118 -269.725816) (xy 338.376954 -269.718477) (xy 338.401152 -269.718028) (xy 338.426143 -269.718489)
			(xy 338.47551 -269.726301) (xy 338.523047 -269.741741) (xy 338.567583 -269.764427) (xy 338.608022 -269.793802)
			(xy 338.643367 -269.829141) (xy 338.672748 -269.869576) (xy 338.695441 -269.914108) (xy 338.710887 -269.961643)
			(xy 338.718707 -270.011009) (xy 338.718707 -270.036036) (xy 339.024971 -270.036036) (xy 339.029066 -269.985308)
			(xy 339.041245 -269.935894) (xy 339.061193 -269.889074) (xy 339.088394 -269.84606) (xy 339.122142 -269.807966)
			(xy 339.161564 -269.775779) (xy 339.205638 -269.750333) (xy 339.253224 -269.732286) (xy 339.303088 -269.722106)
			(xy 339.35394 -269.720057) (xy 339.404461 -269.726191) (xy 339.453345 -269.740351) (xy 339.499324 -269.762168)
			(xy 339.541208 -269.791078) (xy 339.577912 -269.826333) (xy 339.608485 -269.867019) (xy 339.632136 -269.912082)
			(xy 339.648252 -269.960356) (xy 339.656416 -270.01059) (xy 339.656928 -270.036036) (xy 339.964771 -270.036036)
			(xy 339.968866 -269.985308) (xy 339.981045 -269.935894) (xy 340.000993 -269.889074) (xy 340.028194 -269.84606)
			(xy 340.061942 -269.807966) (xy 340.101364 -269.775779) (xy 340.145438 -269.750333) (xy 340.193024 -269.732286)
			(xy 340.242888 -269.722106) (xy 340.29374 -269.720057) (xy 340.344261 -269.726191) (xy 340.393145 -269.740351)
			(xy 340.439124 -269.762168) (xy 340.481008 -269.791078) (xy 340.517712 -269.826333) (xy 340.548285 -269.867019)
			(xy 340.571936 -269.912082) (xy 340.588052 -269.960356) (xy 340.596216 -270.01059) (xy 340.596728 -270.036036)
			(xy 340.596225 -270.061025) (xy 340.903542 -270.061025) (xy 340.903542 -270.011047) (xy 340.911361 -269.961684)
			(xy 340.926805 -269.914152) (xy 340.949495 -269.86962) (xy 340.978871 -269.829187) (xy 341.014211 -269.793847)
			(xy 341.054644 -269.764471) (xy 341.099176 -269.741781) (xy 341.146708 -269.726337) (xy 341.196071 -269.718518)
			(xy 341.246049 -269.718518) (xy 341.295412 -269.726337) (xy 341.342944 -269.741781) (xy 341.387476 -269.764471)
			(xy 341.427909 -269.793847) (xy 341.463249 -269.829187) (xy 341.492625 -269.86962) (xy 341.515315 -269.914152)
			(xy 341.530759 -269.961684) (xy 341.538578 -270.011047) (xy 341.539068 -270.036036) (xy 341.844879 -270.036036)
			(xy 341.848974 -269.985308) (xy 341.861153 -269.935894) (xy 341.881101 -269.889074) (xy 341.908302 -269.84606)
			(xy 341.94205 -269.807966) (xy 341.981472 -269.775779) (xy 342.025546 -269.750333) (xy 342.073132 -269.732286)
			(xy 342.122996 -269.722106) (xy 342.173848 -269.720057) (xy 342.224369 -269.726191) (xy 342.273253 -269.740351)
			(xy 342.319232 -269.762168) (xy 342.361116 -269.791078) (xy 342.39782 -269.826333) (xy 342.428393 -269.867019)
			(xy 342.452044 -269.912082) (xy 342.46816 -269.960356) (xy 342.476324 -270.01059) (xy 342.476836 -270.036036)
			(xy 342.476333 -270.061025) (xy 342.78365 -270.061025) (xy 342.78365 -270.011047) (xy 342.791469 -269.961684)
			(xy 342.806913 -269.914152) (xy 342.829603 -269.86962) (xy 342.858979 -269.829187) (xy 342.894319 -269.793847)
			(xy 342.934752 -269.764471) (xy 342.979284 -269.741781) (xy 343.026816 -269.726337) (xy 343.076179 -269.718518)
			(xy 343.126157 -269.718518) (xy 343.17552 -269.726337) (xy 343.223052 -269.741781) (xy 343.267584 -269.764471)
			(xy 343.308017 -269.793847) (xy 343.343357 -269.829187) (xy 343.372733 -269.86962) (xy 343.395423 -269.914152)
			(xy 343.410867 -269.961684) (xy 343.418686 -270.011047) (xy 343.419176 -270.036036) (xy 343.724987 -270.036036)
			(xy 343.729082 -269.985308) (xy 343.741261 -269.935894) (xy 343.761209 -269.889074) (xy 343.78841 -269.84606)
			(xy 343.822158 -269.807966) (xy 343.86158 -269.775779) (xy 343.905654 -269.750333) (xy 343.95324 -269.732286)
			(xy 344.003104 -269.722106) (xy 344.053956 -269.720057) (xy 344.104477 -269.726191) (xy 344.153361 -269.740351)
			(xy 344.19934 -269.762168) (xy 344.241224 -269.791078) (xy 344.277928 -269.826333) (xy 344.308501 -269.867019)
			(xy 344.332152 -269.912082) (xy 344.348268 -269.960356) (xy 344.356432 -270.01059) (xy 344.356944 -270.036036)
			(xy 344.356432 -270.061482) (xy 344.348268 -270.111716) (xy 344.332152 -270.15999) (xy 344.308501 -270.205053)
			(xy 344.277928 -270.245739) (xy 344.241224 -270.280994) (xy 344.19934 -270.309904) (xy 344.153361 -270.331721)
			(xy 344.104477 -270.345881) (xy 344.053956 -270.352015) (xy 344.003104 -270.349966) (xy 343.95324 -270.339786)
			(xy 343.905654 -270.321739) (xy 343.86158 -270.296293) (xy 343.822158 -270.264106) (xy 343.78841 -270.226012)
			(xy 343.761209 -270.182998) (xy 343.741261 -270.136178) (xy 343.729082 -270.086764) (xy 343.724987 -270.036036)
			(xy 343.419176 -270.036036) (xy 343.418686 -270.061025) (xy 343.410867 -270.110388) (xy 343.395423 -270.15792)
			(xy 343.372733 -270.202452) (xy 343.343357 -270.242885) (xy 343.308017 -270.278225) (xy 343.267584 -270.307601)
			(xy 343.223052 -270.330291) (xy 343.17552 -270.345735) (xy 343.126157 -270.353554) (xy 343.076179 -270.353554)
			(xy 343.026816 -270.345735) (xy 342.979284 -270.330291) (xy 342.934752 -270.307601) (xy 342.894319 -270.278225)
			(xy 342.858979 -270.242885) (xy 342.829603 -270.202452) (xy 342.806913 -270.15792) (xy 342.791469 -270.110388)
			(xy 342.78365 -270.061025) (xy 342.476333 -270.061025) (xy 342.476324 -270.061482) (xy 342.46816 -270.111716)
			(xy 342.452044 -270.15999) (xy 342.428393 -270.205053) (xy 342.39782 -270.245739) (xy 342.361116 -270.280994)
			(xy 342.319232 -270.309904) (xy 342.273253 -270.331721) (xy 342.224369 -270.345881) (xy 342.173848 -270.352015)
			(xy 342.122996 -270.349966) (xy 342.073132 -270.339786) (xy 342.025546 -270.321739) (xy 341.981472 -270.296293)
			(xy 341.94205 -270.264106) (xy 341.908302 -270.226012) (xy 341.881101 -270.182998) (xy 341.861153 -270.136178)
			(xy 341.848974 -270.086764) (xy 341.844879 -270.036036) (xy 341.539068 -270.036036) (xy 341.538578 -270.061025)
			(xy 341.530759 -270.110388) (xy 341.515315 -270.15792) (xy 341.492625 -270.202452) (xy 341.463249 -270.242885)
			(xy 341.427909 -270.278225) (xy 341.387476 -270.307601) (xy 341.342944 -270.330291) (xy 341.295412 -270.345735)
			(xy 341.246049 -270.353554) (xy 341.196071 -270.353554) (xy 341.146708 -270.345735) (xy 341.099176 -270.330291)
			(xy 341.054644 -270.307601) (xy 341.014211 -270.278225) (xy 340.978871 -270.242885) (xy 340.949495 -270.202452)
			(xy 340.926805 -270.15792) (xy 340.911361 -270.110388) (xy 340.903542 -270.061025) (xy 340.596225 -270.061025)
			(xy 340.596216 -270.061482) (xy 340.588052 -270.111716) (xy 340.571936 -270.15999) (xy 340.548285 -270.205053)
			(xy 340.517712 -270.245739) (xy 340.481008 -270.280994) (xy 340.439124 -270.309904) (xy 340.393145 -270.331721)
			(xy 340.344261 -270.345881) (xy 340.29374 -270.352015) (xy 340.242888 -270.349966) (xy 340.193024 -270.339786)
			(xy 340.145438 -270.321739) (xy 340.101364 -270.296293) (xy 340.061942 -270.264106) (xy 340.028194 -270.226012)
			(xy 340.000993 -270.182998) (xy 339.981045 -270.136178) (xy 339.968866 -270.086764) (xy 339.964771 -270.036036)
			(xy 339.656928 -270.036036) (xy 339.656416 -270.061482) (xy 339.648252 -270.111716) (xy 339.632136 -270.15999)
			(xy 339.608485 -270.205053) (xy 339.577912 -270.245739) (xy 339.541208 -270.280994) (xy 339.499324 -270.309904)
			(xy 339.453345 -270.331721) (xy 339.404461 -270.345881) (xy 339.35394 -270.352015) (xy 339.303088 -270.349966)
			(xy 339.253224 -270.339786) (xy 339.205638 -270.321739) (xy 339.161564 -270.296293) (xy 339.122142 -270.264106)
			(xy 339.088394 -270.226012) (xy 339.061193 -270.182998) (xy 339.041245 -270.136178) (xy 339.029066 -270.086764)
			(xy 339.024971 -270.036036) (xy 338.718707 -270.036036) (xy 338.718707 -270.060991) (xy 338.710887 -270.110357)
			(xy 338.695441 -270.157892) (xy 338.672748 -270.202424) (xy 338.643367 -270.242859) (xy 338.608022 -270.278198)
			(xy 338.567583 -270.307573) (xy 338.523047 -270.330259) (xy 338.47551 -270.345699) (xy 338.426143 -270.353511)
			(xy 338.401152 -270.354044) (xy 338.376953 -270.353595) (xy 338.329112 -270.346268) (xy 338.282935 -270.331774)
			(xy 338.239488 -270.31045) (xy 338.199775 -270.282787) (xy 338.18195 -270.266414) (xy 338.176362 -270.261334)
			(xy 338.1629 -270.254222) (xy 338.156296 -270.253206) (xy 338.148963 -270.252163) (xy 338.134252 -270.253843)
			(xy 338.12734 -270.256508) (xy 338.058506 -270.285972) (xy 338.057998 -270.285972) (xy 338.041742 -270.29283)
			(xy 338.03323 -270.297187) (xy 338.020043 -270.311013) (xy 338.012922 -270.328743) (xy 338.012532 -270.338296)
			(xy 338.012532 -270.502634) (xy 338.01293 -270.511801) (xy 338.019477 -270.528924) (xy 338.031726 -270.542565)
			(xy 338.03971 -270.547084) (xy 338.045044 -270.549116) (xy 338.068707 -270.55875) (xy 338.112854 -270.584457)
			(xy 338.152325 -270.616891) (xy 338.186103 -270.655218) (xy 338.21332 -270.698451) (xy 338.233277 -270.745479)
			(xy 338.245458 -270.795092) (xy 338.249552 -270.846015) (xy 338.24955 -270.846042) (xy 338.554817 -270.846042)
			(xy 338.558912 -270.795314) (xy 338.571091 -270.7459) (xy 338.591039 -270.69908) (xy 338.61824 -270.656066)
			(xy 338.651988 -270.617972) (xy 338.69141 -270.585785) (xy 338.735484 -270.560339) (xy 338.78307 -270.542292)
			(xy 338.832934 -270.532112) (xy 338.883786 -270.530063) (xy 338.934307 -270.536197) (xy 338.983191 -270.550357)
			(xy 339.02917 -270.572174) (xy 339.071054 -270.601084) (xy 339.107758 -270.636339) (xy 339.138331 -270.677025)
			(xy 339.161982 -270.722088) (xy 339.178098 -270.770362) (xy 339.186262 -270.820596) (xy 339.186774 -270.846042)
			(xy 339.186271 -270.871031) (xy 339.493588 -270.871031) (xy 339.493588 -270.821053) (xy 339.501407 -270.77169)
			(xy 339.516851 -270.724158) (xy 339.539541 -270.679626) (xy 339.568917 -270.639193) (xy 339.604257 -270.603853)
			(xy 339.64469 -270.574477) (xy 339.689222 -270.551787) (xy 339.736754 -270.536343) (xy 339.786117 -270.528524)
			(xy 339.836095 -270.528524) (xy 339.885458 -270.536343) (xy 339.93299 -270.551787) (xy 339.977522 -270.574477)
			(xy 340.017955 -270.603853) (xy 340.053295 -270.639193) (xy 340.082671 -270.679626) (xy 340.105361 -270.724158)
			(xy 340.120805 -270.77169) (xy 340.128624 -270.821053) (xy 340.129114 -270.846042) (xy 340.434925 -270.846042)
			(xy 340.43902 -270.795314) (xy 340.451199 -270.7459) (xy 340.471147 -270.69908) (xy 340.498348 -270.656066)
			(xy 340.532096 -270.617972) (xy 340.571518 -270.585785) (xy 340.615592 -270.560339) (xy 340.663178 -270.542292)
			(xy 340.713042 -270.532112) (xy 340.763894 -270.530063) (xy 340.814415 -270.536197) (xy 340.863299 -270.550357)
			(xy 340.909278 -270.572174) (xy 340.951162 -270.601084) (xy 340.987866 -270.636339) (xy 341.018439 -270.677025)
			(xy 341.04209 -270.722088) (xy 341.058206 -270.770362) (xy 341.06637 -270.820596) (xy 341.066882 -270.846042)
			(xy 342.314779 -270.846042) (xy 342.318874 -270.795314) (xy 342.331053 -270.7459) (xy 342.351001 -270.69908)
			(xy 342.378202 -270.656066) (xy 342.41195 -270.617972) (xy 342.451372 -270.585785) (xy 342.495446 -270.560339)
			(xy 342.543032 -270.542292) (xy 342.592896 -270.532112) (xy 342.643748 -270.530063) (xy 342.694269 -270.536197)
			(xy 342.743153 -270.550357) (xy 342.789132 -270.572174) (xy 342.831016 -270.601084) (xy 342.86772 -270.636339)
			(xy 342.898293 -270.677025) (xy 342.921944 -270.722088) (xy 342.93806 -270.770362) (xy 342.946224 -270.820596)
			(xy 342.946736 -270.846042) (xy 343.254833 -270.846042) (xy 343.258928 -270.795314) (xy 343.271107 -270.7459)
			(xy 343.291055 -270.69908) (xy 343.318256 -270.656066) (xy 343.352004 -270.617972) (xy 343.391426 -270.585785)
			(xy 343.4355 -270.560339) (xy 343.483086 -270.542292) (xy 343.53295 -270.532112) (xy 343.583802 -270.530063)
			(xy 343.634323 -270.536197) (xy 343.683207 -270.550357) (xy 343.729186 -270.572174) (xy 343.77107 -270.601084)
			(xy 343.807774 -270.636339) (xy 343.838347 -270.677025) (xy 343.861998 -270.722088) (xy 343.878114 -270.770362)
			(xy 343.886278 -270.820596) (xy 343.88679 -270.846042) (xy 343.886278 -270.871488) (xy 343.878114 -270.921722)
			(xy 343.861998 -270.969996) (xy 343.838347 -271.015059) (xy 343.807774 -271.055745) (xy 343.77107 -271.091)
			(xy 343.729186 -271.11991) (xy 343.683207 -271.141727) (xy 343.634323 -271.155887) (xy 343.583802 -271.162021)
			(xy 343.53295 -271.159972) (xy 343.483086 -271.149792) (xy 343.4355 -271.131745) (xy 343.391426 -271.106299)
			(xy 343.352004 -271.074112) (xy 343.318256 -271.036018) (xy 343.291055 -270.993004) (xy 343.271107 -270.946184)
			(xy 343.258928 -270.89677) (xy 343.254833 -270.846042) (xy 342.946736 -270.846042) (xy 342.946224 -270.871488)
			(xy 342.93806 -270.921722) (xy 342.921944 -270.969996) (xy 342.898293 -271.015059) (xy 342.86772 -271.055745)
			(xy 342.831016 -271.091) (xy 342.789132 -271.11991) (xy 342.743153 -271.141727) (xy 342.694269 -271.155887)
			(xy 342.643748 -271.162021) (xy 342.592896 -271.159972) (xy 342.543032 -271.149792) (xy 342.495446 -271.131745)
			(xy 342.451372 -271.106299) (xy 342.41195 -271.074112) (xy 342.378202 -271.036018) (xy 342.351001 -270.993004)
			(xy 342.331053 -270.946184) (xy 342.318874 -270.89677) (xy 342.314779 -270.846042) (xy 341.066882 -270.846042)
			(xy 341.06637 -270.871488) (xy 341.058206 -270.921722) (xy 341.04209 -270.969996) (xy 341.018439 -271.015059)
			(xy 340.987866 -271.055745) (xy 340.951162 -271.091) (xy 340.909278 -271.11991) (xy 340.863299 -271.141727)
			(xy 340.814415 -271.155887) (xy 340.763894 -271.162021) (xy 340.713042 -271.159972) (xy 340.663178 -271.149792)
			(xy 340.615592 -271.131745) (xy 340.571518 -271.106299) (xy 340.532096 -271.074112) (xy 340.498348 -271.036018)
			(xy 340.471147 -270.993004) (xy 340.451199 -270.946184) (xy 340.43902 -270.89677) (xy 340.434925 -270.846042)
			(xy 340.129114 -270.846042) (xy 340.128624 -270.871031) (xy 340.120805 -270.920394) (xy 340.105361 -270.967926)
			(xy 340.082671 -271.012458) (xy 340.053295 -271.052891) (xy 340.017955 -271.088231) (xy 339.977522 -271.117607)
			(xy 339.93299 -271.140297) (xy 339.885458 -271.155741) (xy 339.836095 -271.16356) (xy 339.786117 -271.16356)
			(xy 339.736754 -271.155741) (xy 339.689222 -271.140297) (xy 339.64469 -271.117607) (xy 339.604257 -271.088231)
			(xy 339.568917 -271.052891) (xy 339.539541 -271.012458) (xy 339.516851 -270.967926) (xy 339.501407 -270.920394)
			(xy 339.493588 -270.871031) (xy 339.186271 -270.871031) (xy 339.186262 -270.871488) (xy 339.178098 -270.921722)
			(xy 339.161982 -270.969996) (xy 339.138331 -271.015059) (xy 339.107758 -271.055745) (xy 339.071054 -271.091)
			(xy 339.02917 -271.11991) (xy 338.983191 -271.141727) (xy 338.934307 -271.155887) (xy 338.883786 -271.162021)
			(xy 338.832934 -271.159972) (xy 338.78307 -271.149792) (xy 338.735484 -271.131745) (xy 338.69141 -271.106299)
			(xy 338.651988 -271.074112) (xy 338.61824 -271.036018) (xy 338.591039 -270.993004) (xy 338.571091 -270.946184)
			(xy 338.558912 -270.89677) (xy 338.554817 -270.846042) (xy 338.24955 -270.846042) (xy 338.245453 -270.896937)
			(xy 338.233267 -270.94655) (xy 338.213306 -270.993576) (xy 338.186085 -271.036807) (xy 338.152303 -271.07513)
			(xy 338.11283 -271.10756) (xy 338.068679 -271.133263) (xy 338.045044 -271.142968) (xy 338.03971 -271.145)
			(xy 338.031752 -271.149553) (xy 338.019524 -271.163193) (xy 338.012952 -271.180292) (xy 338.012532 -271.18945)
			(xy 338.012532 -271.353788) (xy 338.012952 -271.363339) (xy 338.020049 -271.381074) (xy 338.03323 -271.3949)
			(xy 338.041742 -271.399254) (xy 338.057998 -271.406112) (xy 338.058506 -271.406112) (xy 338.12734 -271.435576)
			(xy 338.134244 -271.438271) (xy 338.148963 -271.439954) (xy 338.156296 -271.438878) (xy 338.1629 -271.437862)
			(xy 338.176362 -271.43075) (xy 338.18195 -271.42567) (xy 338.199792 -271.409318) (xy 338.239503 -271.381654)
			(xy 338.282945 -271.360326) (xy 338.329118 -271.345825) (xy 338.376954 -271.338486) (xy 338.401152 -271.33804)
			(xy 338.426142 -271.338501) (xy 338.475507 -271.346313) (xy 338.523043 -271.361752) (xy 338.567577 -271.384437)
			(xy 338.608014 -271.413811) (xy 338.643358 -271.449149) (xy 338.672737 -271.489582) (xy 338.69543 -271.534113)
			(xy 338.710876 -271.581646) (xy 338.718695 -271.63101) (xy 338.718695 -271.656048) (xy 339.024971 -271.656048)
			(xy 339.029066 -271.60532) (xy 339.041245 -271.555906) (xy 339.061193 -271.509086) (xy 339.088394 -271.466072)
			(xy 339.122142 -271.427978) (xy 339.161564 -271.395791) (xy 339.205638 -271.370345) (xy 339.253224 -271.352298)
			(xy 339.303088 -271.342118) (xy 339.35394 -271.340069) (xy 339.404461 -271.346203) (xy 339.453345 -271.360363)
			(xy 339.499324 -271.38218) (xy 339.541208 -271.41109) (xy 339.577912 -271.446345) (xy 339.608485 -271.487031)
			(xy 339.632136 -271.532094) (xy 339.648252 -271.580368) (xy 339.656416 -271.630602) (xy 339.656928 -271.656048)
			(xy 339.964771 -271.656048) (xy 339.968866 -271.60532) (xy 339.981045 -271.555906) (xy 340.000993 -271.509086)
			(xy 340.028194 -271.466072) (xy 340.061942 -271.427978) (xy 340.101364 -271.395791) (xy 340.145438 -271.370345)
			(xy 340.193024 -271.352298) (xy 340.242888 -271.342118) (xy 340.29374 -271.340069) (xy 340.344261 -271.346203)
			(xy 340.393145 -271.360363) (xy 340.439124 -271.38218) (xy 340.481008 -271.41109) (xy 340.517712 -271.446345)
			(xy 340.548285 -271.487031) (xy 340.571936 -271.532094) (xy 340.588052 -271.580368) (xy 340.596216 -271.630602)
			(xy 340.596728 -271.656048) (xy 340.596225 -271.681037) (xy 340.903542 -271.681037) (xy 340.903542 -271.631059)
			(xy 340.911361 -271.581696) (xy 340.926805 -271.534164) (xy 340.949495 -271.489632) (xy 340.978871 -271.449199)
			(xy 341.014211 -271.413859) (xy 341.054644 -271.384483) (xy 341.099176 -271.361793) (xy 341.146708 -271.346349)
			(xy 341.196071 -271.33853) (xy 341.246049 -271.33853) (xy 341.295412 -271.346349) (xy 341.342944 -271.361793)
			(xy 341.387476 -271.384483) (xy 341.427909 -271.413859) (xy 341.463249 -271.449199) (xy 341.492625 -271.489632)
			(xy 341.515315 -271.534164) (xy 341.530759 -271.581696) (xy 341.538578 -271.631059) (xy 341.539068 -271.656048)
			(xy 341.844879 -271.656048) (xy 341.848974 -271.60532) (xy 341.861153 -271.555906) (xy 341.881101 -271.509086)
			(xy 341.908302 -271.466072) (xy 341.94205 -271.427978) (xy 341.981472 -271.395791) (xy 342.025546 -271.370345)
			(xy 342.073132 -271.352298) (xy 342.122996 -271.342118) (xy 342.173848 -271.340069) (xy 342.224369 -271.346203)
			(xy 342.273253 -271.360363) (xy 342.319232 -271.38218) (xy 342.361116 -271.41109) (xy 342.39782 -271.446345)
			(xy 342.428393 -271.487031) (xy 342.452044 -271.532094) (xy 342.46816 -271.580368) (xy 342.476324 -271.630602)
			(xy 342.476836 -271.656048) (xy 342.476333 -271.681037) (xy 342.78365 -271.681037) (xy 342.78365 -271.631059)
			(xy 342.791469 -271.581696) (xy 342.806913 -271.534164) (xy 342.829603 -271.489632) (xy 342.858979 -271.449199)
			(xy 342.894319 -271.413859) (xy 342.934752 -271.384483) (xy 342.979284 -271.361793) (xy 343.026816 -271.346349)
			(xy 343.076179 -271.33853) (xy 343.126157 -271.33853) (xy 343.17552 -271.346349) (xy 343.223052 -271.361793)
			(xy 343.267584 -271.384483) (xy 343.308017 -271.413859) (xy 343.343357 -271.449199) (xy 343.372733 -271.489632)
			(xy 343.395423 -271.534164) (xy 343.410867 -271.581696) (xy 343.418686 -271.631059) (xy 343.419176 -271.656048)
			(xy 343.724987 -271.656048) (xy 343.729082 -271.60532) (xy 343.741261 -271.555906) (xy 343.761209 -271.509086)
			(xy 343.78841 -271.466072) (xy 343.822158 -271.427978) (xy 343.86158 -271.395791) (xy 343.905654 -271.370345)
			(xy 343.95324 -271.352298) (xy 344.003104 -271.342118) (xy 344.053956 -271.340069) (xy 344.104477 -271.346203)
			(xy 344.153361 -271.360363) (xy 344.19934 -271.38218) (xy 344.241224 -271.41109) (xy 344.277928 -271.446345)
			(xy 344.308501 -271.487031) (xy 344.332152 -271.532094) (xy 344.348268 -271.580368) (xy 344.356432 -271.630602)
			(xy 344.356944 -271.656048) (xy 344.356432 -271.681494) (xy 344.348268 -271.731728) (xy 344.332152 -271.780002)
			(xy 344.308501 -271.825065) (xy 344.277928 -271.865751) (xy 344.241224 -271.901006) (xy 344.19934 -271.929916)
			(xy 344.153361 -271.951733) (xy 344.104477 -271.965893) (xy 344.053956 -271.972027) (xy 344.003104 -271.969978)
			(xy 343.95324 -271.959798) (xy 343.905654 -271.941751) (xy 343.86158 -271.916305) (xy 343.822158 -271.884118)
			(xy 343.78841 -271.846024) (xy 343.761209 -271.80301) (xy 343.741261 -271.75619) (xy 343.729082 -271.706776)
			(xy 343.724987 -271.656048) (xy 343.419176 -271.656048) (xy 343.418686 -271.681037) (xy 343.410867 -271.7304)
			(xy 343.395423 -271.777932) (xy 343.372733 -271.822464) (xy 343.343357 -271.862897) (xy 343.308017 -271.898237)
			(xy 343.267584 -271.927613) (xy 343.223052 -271.950303) (xy 343.17552 -271.965747) (xy 343.126157 -271.973566)
			(xy 343.076179 -271.973566) (xy 343.026816 -271.965747) (xy 342.979284 -271.950303) (xy 342.934752 -271.927613)
			(xy 342.894319 -271.898237) (xy 342.858979 -271.862897) (xy 342.829603 -271.822464) (xy 342.806913 -271.777932)
			(xy 342.791469 -271.7304) (xy 342.78365 -271.681037) (xy 342.476333 -271.681037) (xy 342.476324 -271.681494)
			(xy 342.46816 -271.731728) (xy 342.452044 -271.780002) (xy 342.428393 -271.825065) (xy 342.39782 -271.865751)
			(xy 342.361116 -271.901006) (xy 342.319232 -271.929916) (xy 342.273253 -271.951733) (xy 342.224369 -271.965893)
			(xy 342.173848 -271.972027) (xy 342.122996 -271.969978) (xy 342.073132 -271.959798) (xy 342.025546 -271.941751)
			(xy 341.981472 -271.916305) (xy 341.94205 -271.884118) (xy 341.908302 -271.846024) (xy 341.881101 -271.80301)
			(xy 341.861153 -271.75619) (xy 341.848974 -271.706776) (xy 341.844879 -271.656048) (xy 341.539068 -271.656048)
			(xy 341.538578 -271.681037) (xy 341.530759 -271.7304) (xy 341.515315 -271.777932) (xy 341.492625 -271.822464)
			(xy 341.463249 -271.862897) (xy 341.427909 -271.898237) (xy 341.387476 -271.927613) (xy 341.342944 -271.950303)
			(xy 341.295412 -271.965747) (xy 341.246049 -271.973566) (xy 341.196071 -271.973566) (xy 341.146708 -271.965747)
			(xy 341.099176 -271.950303) (xy 341.054644 -271.927613) (xy 341.014211 -271.898237) (xy 340.978871 -271.862897)
			(xy 340.949495 -271.822464) (xy 340.926805 -271.777932) (xy 340.911361 -271.7304) (xy 340.903542 -271.681037)
			(xy 340.596225 -271.681037) (xy 340.596216 -271.681494) (xy 340.588052 -271.731728) (xy 340.571936 -271.780002)
			(xy 340.548285 -271.825065) (xy 340.517712 -271.865751) (xy 340.481008 -271.901006) (xy 340.439124 -271.929916)
			(xy 340.393145 -271.951733) (xy 340.344261 -271.965893) (xy 340.29374 -271.972027) (xy 340.242888 -271.969978)
			(xy 340.193024 -271.959798) (xy 340.145438 -271.941751) (xy 340.101364 -271.916305) (xy 340.061942 -271.884118)
			(xy 340.028194 -271.846024) (xy 340.000993 -271.80301) (xy 339.981045 -271.75619) (xy 339.968866 -271.706776)
			(xy 339.964771 -271.656048) (xy 339.656928 -271.656048) (xy 339.656416 -271.681494) (xy 339.648252 -271.731728)
			(xy 339.632136 -271.780002) (xy 339.608485 -271.825065) (xy 339.577912 -271.865751) (xy 339.541208 -271.901006)
			(xy 339.499324 -271.929916) (xy 339.453345 -271.951733) (xy 339.404461 -271.965893) (xy 339.35394 -271.972027)
			(xy 339.303088 -271.969978) (xy 339.253224 -271.959798) (xy 339.205638 -271.941751) (xy 339.161564 -271.916305)
			(xy 339.122142 -271.884118) (xy 339.088394 -271.846024) (xy 339.061193 -271.80301) (xy 339.041245 -271.75619)
			(xy 339.029066 -271.706776) (xy 339.024971 -271.656048) (xy 338.718695 -271.656048) (xy 338.718695 -271.68099)
			(xy 338.710876 -271.730354) (xy 338.69543 -271.777887) (xy 338.672737 -271.822418) (xy 338.643358 -271.862851)
			(xy 338.608014 -271.898189) (xy 338.567577 -271.927563) (xy 338.523043 -271.950248) (xy 338.475507 -271.965687)
			(xy 338.426142 -271.973499) (xy 338.401152 -271.974056) (xy 338.376953 -271.973607) (xy 338.329112 -271.96628)
			(xy 338.282935 -271.951787) (xy 338.239487 -271.930463) (xy 338.199773 -271.902801) (xy 338.18195 -271.886426)
			(xy 338.176362 -271.881346) (xy 338.1629 -271.874234) (xy 338.156296 -271.873218) (xy 338.148963 -271.872174)
			(xy 338.134252 -271.873856) (xy 338.12734 -271.87652) (xy 338.058506 -271.905984) (xy 338.057998 -271.905984)
			(xy 338.041742 -271.912842) (xy 338.033231 -271.917199) (xy 338.020047 -271.931026) (xy 338.012931 -271.948756)
			(xy 338.012532 -271.958308) (xy 338.012532 -272.122646) (xy 338.012932 -272.131812) (xy 338.019482 -272.148932)
			(xy 338.031731 -272.162569) (xy 338.03971 -272.167096) (xy 338.045044 -272.169128) (xy 338.068714 -272.178762)
			(xy 338.112875 -272.204472) (xy 338.152359 -272.23691) (xy 338.18615 -272.275243) (xy 338.213379 -272.318485)
			(xy 338.233344 -272.365523) (xy 338.245534 -272.415148) (xy 338.249632 -272.466054) (xy 338.554817 -272.466054)
			(xy 338.558912 -272.415326) (xy 338.571091 -272.365912) (xy 338.591039 -272.319092) (xy 338.61824 -272.276078)
			(xy 338.651988 -272.237984) (xy 338.69141 -272.205797) (xy 338.735484 -272.180351) (xy 338.78307 -272.162304)
			(xy 338.832934 -272.152124) (xy 338.883786 -272.150075) (xy 338.934307 -272.156209) (xy 338.983191 -272.170369)
			(xy 339.02917 -272.192186) (xy 339.071054 -272.221096) (xy 339.107758 -272.256351) (xy 339.138331 -272.297037)
			(xy 339.161982 -272.3421) (xy 339.178098 -272.390374) (xy 339.186262 -272.440608) (xy 339.186774 -272.466054)
			(xy 339.186271 -272.491043) (xy 339.493588 -272.491043) (xy 339.493588 -272.441065) (xy 339.501407 -272.391702)
			(xy 339.516851 -272.34417) (xy 339.539541 -272.299638) (xy 339.568917 -272.259205) (xy 339.604257 -272.223865)
			(xy 339.64469 -272.194489) (xy 339.689222 -272.171799) (xy 339.736754 -272.156355) (xy 339.786117 -272.148536)
			(xy 339.836095 -272.148536) (xy 339.885458 -272.156355) (xy 339.93299 -272.171799) (xy 339.977522 -272.194489)
			(xy 340.017955 -272.223865) (xy 340.053295 -272.259205) (xy 340.082671 -272.299638) (xy 340.105361 -272.34417)
			(xy 340.120805 -272.391702) (xy 340.128624 -272.441065) (xy 340.129114 -272.466054) (xy 340.434925 -272.466054)
			(xy 340.43902 -272.415326) (xy 340.451199 -272.365912) (xy 340.471147 -272.319092) (xy 340.498348 -272.276078)
			(xy 340.532096 -272.237984) (xy 340.571518 -272.205797) (xy 340.615592 -272.180351) (xy 340.663178 -272.162304)
			(xy 340.713042 -272.152124) (xy 340.763894 -272.150075) (xy 340.814415 -272.156209) (xy 340.863299 -272.170369)
			(xy 340.909278 -272.192186) (xy 340.951162 -272.221096) (xy 340.987866 -272.256351) (xy 341.018439 -272.297037)
			(xy 341.04209 -272.3421) (xy 341.058206 -272.390374) (xy 341.06637 -272.440608) (xy 341.066882 -272.466054)
			(xy 341.066379 -272.491043) (xy 341.373696 -272.491043) (xy 341.373696 -272.441065) (xy 341.381515 -272.391702)
			(xy 341.396959 -272.34417) (xy 341.419649 -272.299638) (xy 341.449025 -272.259205) (xy 341.484365 -272.223865)
			(xy 341.524798 -272.194489) (xy 341.56933 -272.171799) (xy 341.616862 -272.156355) (xy 341.666225 -272.148536)
			(xy 341.716203 -272.148536) (xy 341.765566 -272.156355) (xy 341.813098 -272.171799) (xy 341.85763 -272.194489)
			(xy 341.898063 -272.223865) (xy 341.933403 -272.259205) (xy 341.962779 -272.299638) (xy 341.985469 -272.34417)
			(xy 342.000913 -272.391702) (xy 342.008732 -272.441065) (xy 342.009222 -272.466054) (xy 342.314779 -272.466054)
			(xy 342.318874 -272.415326) (xy 342.331053 -272.365912) (xy 342.351001 -272.319092) (xy 342.378202 -272.276078)
			(xy 342.41195 -272.237984) (xy 342.451372 -272.205797) (xy 342.495446 -272.180351) (xy 342.543032 -272.162304)
			(xy 342.592896 -272.152124) (xy 342.643748 -272.150075) (xy 342.694269 -272.156209) (xy 342.743153 -272.170369)
			(xy 342.789132 -272.192186) (xy 342.831016 -272.221096) (xy 342.86772 -272.256351) (xy 342.898293 -272.297037)
			(xy 342.921944 -272.3421) (xy 342.93806 -272.390374) (xy 342.946224 -272.440608) (xy 342.946736 -272.466054)
			(xy 343.254833 -272.466054) (xy 343.258928 -272.415326) (xy 343.271107 -272.365912) (xy 343.291055 -272.319092)
			(xy 343.318256 -272.276078) (xy 343.352004 -272.237984) (xy 343.391426 -272.205797) (xy 343.4355 -272.180351)
			(xy 343.483086 -272.162304) (xy 343.53295 -272.152124) (xy 343.583802 -272.150075) (xy 343.634323 -272.156209)
			(xy 343.683207 -272.170369) (xy 343.729186 -272.192186) (xy 343.77107 -272.221096) (xy 343.807774 -272.256351)
			(xy 343.838347 -272.297037) (xy 343.861998 -272.3421) (xy 343.878114 -272.390374) (xy 343.886278 -272.440608)
			(xy 343.88679 -272.466054) (xy 343.886278 -272.4915) (xy 343.878114 -272.541734) (xy 343.861998 -272.590008)
			(xy 343.838347 -272.635071) (xy 343.807774 -272.675757) (xy 343.77107 -272.711012) (xy 343.729186 -272.739922)
			(xy 343.683207 -272.761739) (xy 343.634323 -272.775899) (xy 343.583802 -272.782033) (xy 343.53295 -272.779984)
			(xy 343.483086 -272.769804) (xy 343.4355 -272.751757) (xy 343.391426 -272.726311) (xy 343.352004 -272.694124)
			(xy 343.318256 -272.65603) (xy 343.291055 -272.613016) (xy 343.271107 -272.566196) (xy 343.258928 -272.516782)
			(xy 343.254833 -272.466054) (xy 342.946736 -272.466054) (xy 342.946224 -272.4915) (xy 342.93806 -272.541734)
			(xy 342.921944 -272.590008) (xy 342.898293 -272.635071) (xy 342.86772 -272.675757) (xy 342.831016 -272.711012)
			(xy 342.789132 -272.739922) (xy 342.743153 -272.761739) (xy 342.694269 -272.775899) (xy 342.643748 -272.782033)
			(xy 342.592896 -272.779984) (xy 342.543032 -272.769804) (xy 342.495446 -272.751757) (xy 342.451372 -272.726311)
			(xy 342.41195 -272.694124) (xy 342.378202 -272.65603) (xy 342.351001 -272.613016) (xy 342.331053 -272.566196)
			(xy 342.318874 -272.516782) (xy 342.314779 -272.466054) (xy 342.009222 -272.466054) (xy 342.008732 -272.491043)
			(xy 342.000913 -272.540406) (xy 341.985469 -272.587938) (xy 341.962779 -272.63247) (xy 341.933403 -272.672903)
			(xy 341.898063 -272.708243) (xy 341.85763 -272.737619) (xy 341.813098 -272.760309) (xy 341.765566 -272.775753)
			(xy 341.716203 -272.783572) (xy 341.666225 -272.783572) (xy 341.616862 -272.775753) (xy 341.56933 -272.760309)
			(xy 341.524798 -272.737619) (xy 341.484365 -272.708243) (xy 341.449025 -272.672903) (xy 341.419649 -272.63247)
			(xy 341.396959 -272.587938) (xy 341.381515 -272.540406) (xy 341.373696 -272.491043) (xy 341.066379 -272.491043)
			(xy 341.06637 -272.4915) (xy 341.058206 -272.541734) (xy 341.04209 -272.590008) (xy 341.018439 -272.635071)
			(xy 340.987866 -272.675757) (xy 340.951162 -272.711012) (xy 340.909278 -272.739922) (xy 340.863299 -272.761739)
			(xy 340.814415 -272.775899) (xy 340.763894 -272.782033) (xy 340.713042 -272.779984) (xy 340.663178 -272.769804)
			(xy 340.615592 -272.751757) (xy 340.571518 -272.726311) (xy 340.532096 -272.694124) (xy 340.498348 -272.65603)
			(xy 340.471147 -272.613016) (xy 340.451199 -272.566196) (xy 340.43902 -272.516782) (xy 340.434925 -272.466054)
			(xy 340.129114 -272.466054) (xy 340.128624 -272.491043) (xy 340.120805 -272.540406) (xy 340.105361 -272.587938)
			(xy 340.082671 -272.63247) (xy 340.053295 -272.672903) (xy 340.017955 -272.708243) (xy 339.977522 -272.737619)
			(xy 339.93299 -272.760309) (xy 339.885458 -272.775753) (xy 339.836095 -272.783572) (xy 339.786117 -272.783572)
			(xy 339.736754 -272.775753) (xy 339.689222 -272.760309) (xy 339.64469 -272.737619) (xy 339.604257 -272.708243)
			(xy 339.568917 -272.672903) (xy 339.539541 -272.63247) (xy 339.516851 -272.587938) (xy 339.501407 -272.540406)
			(xy 339.493588 -272.491043) (xy 339.186271 -272.491043) (xy 339.186262 -272.4915) (xy 339.178098 -272.541734)
			(xy 339.161982 -272.590008) (xy 339.138331 -272.635071) (xy 339.107758 -272.675757) (xy 339.071054 -272.711012)
			(xy 339.02917 -272.739922) (xy 338.983191 -272.761739) (xy 338.934307 -272.775899) (xy 338.883786 -272.782033)
			(xy 338.832934 -272.779984) (xy 338.78307 -272.769804) (xy 338.735484 -272.751757) (xy 338.69141 -272.726311)
			(xy 338.651988 -272.694124) (xy 338.61824 -272.65603) (xy 338.591039 -272.613016) (xy 338.571091 -272.566196)
			(xy 338.558912 -272.516782) (xy 338.554817 -272.466054) (xy 338.249632 -272.466054) (xy 338.249634 -272.466083)
			(xy 338.24554 -272.517019) (xy 338.233355 -272.566646) (xy 338.213394 -272.613686) (xy 338.18617 -272.65693)
			(xy 338.152383 -272.695267) (xy 338.112902 -272.727709) (xy 338.068743 -272.753423) (xy 338.045044 -272.76298)
			(xy 338.03971 -272.765012) (xy 338.031754 -272.769566) (xy 338.019529 -272.783206) (xy 338.012961 -272.800305)
			(xy 338.012532 -272.809462) (xy 338.012532 -272.9738) (xy 338.012954 -272.98335) (xy 338.020054 -273.001082)
			(xy 338.033235 -273.014904) (xy 338.041742 -273.019266) (xy 338.057998 -273.026124) (xy 338.058506 -273.026124)
			(xy 338.12734 -273.055588) (xy 338.134245 -273.058283) (xy 338.148963 -273.059965) (xy 338.156296 -273.05889)
			(xy 338.1629 -273.057874) (xy 338.176362 -273.050762) (xy 338.18195 -273.045682) (xy 338.199792 -273.029329)
			(xy 338.239502 -273.001665) (xy 338.282945 -272.980336) (xy 338.329117 -272.965834) (xy 338.376954 -272.958495)
			(xy 338.401152 -272.958052) (xy 338.426149 -272.958513) (xy 338.475528 -272.966327) (xy 338.523076 -272.98177)
			(xy 338.567623 -273.004462) (xy 338.608072 -273.033844) (xy 338.643425 -273.069192) (xy 338.672813 -273.109636)
			(xy 338.695512 -273.154179) (xy 338.710962 -273.201725) (xy 338.718783 -273.251103) (xy 338.718783 -273.27606)
			(xy 339.024971 -273.27606) (xy 339.029066 -273.225332) (xy 339.041245 -273.175918) (xy 339.061193 -273.129098)
			(xy 339.088394 -273.086084) (xy 339.122142 -273.04799) (xy 339.161564 -273.015803) (xy 339.205638 -272.990357)
			(xy 339.253224 -272.97231) (xy 339.303088 -272.96213) (xy 339.35394 -272.960081) (xy 339.404461 -272.966215)
			(xy 339.453345 -272.980375) (xy 339.499324 -273.002192) (xy 339.541208 -273.031102) (xy 339.577912 -273.066357)
			(xy 339.608485 -273.107043) (xy 339.632136 -273.152106) (xy 339.648252 -273.20038) (xy 339.656416 -273.250614)
			(xy 339.656928 -273.27606) (xy 339.964771 -273.27606) (xy 339.968866 -273.225332) (xy 339.981045 -273.175918)
			(xy 340.000993 -273.129098) (xy 340.028194 -273.086084) (xy 340.061942 -273.04799) (xy 340.101364 -273.015803)
			(xy 340.145438 -272.990357) (xy 340.193024 -272.97231) (xy 340.242888 -272.96213) (xy 340.29374 -272.960081)
			(xy 340.344261 -272.966215) (xy 340.393145 -272.980375) (xy 340.439124 -273.002192) (xy 340.481008 -273.031102)
			(xy 340.517712 -273.066357) (xy 340.548285 -273.107043) (xy 340.571936 -273.152106) (xy 340.588052 -273.20038)
			(xy 340.596216 -273.250614) (xy 340.596728 -273.27606) (xy 341.844879 -273.27606) (xy 341.848974 -273.225332)
			(xy 341.861153 -273.175918) (xy 341.881101 -273.129098) (xy 341.908302 -273.086084) (xy 341.94205 -273.04799)
			(xy 341.981472 -273.015803) (xy 342.025546 -272.990357) (xy 342.073132 -272.97231) (xy 342.122996 -272.96213)
			(xy 342.173848 -272.960081) (xy 342.224369 -272.966215) (xy 342.273253 -272.980375) (xy 342.319232 -273.002192)
			(xy 342.361116 -273.031102) (xy 342.39782 -273.066357) (xy 342.428393 -273.107043) (xy 342.452044 -273.152106)
			(xy 342.46816 -273.20038) (xy 342.476324 -273.250614) (xy 342.476836 -273.27606) (xy 342.476333 -273.301049)
			(xy 342.78365 -273.301049) (xy 342.78365 -273.251071) (xy 342.791469 -273.201708) (xy 342.806913 -273.154176)
			(xy 342.829603 -273.109644) (xy 342.858979 -273.069211) (xy 342.894319 -273.033871) (xy 342.934752 -273.004495)
			(xy 342.979284 -272.981805) (xy 343.026816 -272.966361) (xy 343.076179 -272.958542) (xy 343.126157 -272.958542)
			(xy 343.17552 -272.966361) (xy 343.223052 -272.981805) (xy 343.267584 -273.004495) (xy 343.308017 -273.033871)
			(xy 343.343357 -273.069211) (xy 343.372733 -273.109644) (xy 343.395423 -273.154176) (xy 343.410867 -273.201708)
			(xy 343.418686 -273.251071) (xy 343.419176 -273.27606) (xy 343.724987 -273.27606) (xy 343.729082 -273.225332)
			(xy 343.741261 -273.175918) (xy 343.761209 -273.129098) (xy 343.78841 -273.086084) (xy 343.822158 -273.04799)
			(xy 343.86158 -273.015803) (xy 343.905654 -272.990357) (xy 343.95324 -272.97231) (xy 344.003104 -272.96213)
			(xy 344.053956 -272.960081) (xy 344.104477 -272.966215) (xy 344.153361 -272.980375) (xy 344.19934 -273.002192)
			(xy 344.241224 -273.031102) (xy 344.277928 -273.066357) (xy 344.308501 -273.107043) (xy 344.332152 -273.152106)
			(xy 344.348268 -273.20038) (xy 344.356432 -273.250614) (xy 344.356944 -273.27606) (xy 344.356432 -273.301506)
			(xy 344.348268 -273.35174) (xy 344.332152 -273.400014) (xy 344.308501 -273.445077) (xy 344.277928 -273.485763)
			(xy 344.241224 -273.521018) (xy 344.19934 -273.549928) (xy 344.153361 -273.571745) (xy 344.104477 -273.585905)
			(xy 344.053956 -273.592039) (xy 344.003104 -273.58999) (xy 343.95324 -273.57981) (xy 343.905654 -273.561763)
			(xy 343.86158 -273.536317) (xy 343.822158 -273.50413) (xy 343.78841 -273.466036) (xy 343.761209 -273.423022)
			(xy 343.741261 -273.376202) (xy 343.729082 -273.326788) (xy 343.724987 -273.27606) (xy 343.419176 -273.27606)
			(xy 343.418686 -273.301049) (xy 343.410867 -273.350412) (xy 343.395423 -273.397944) (xy 343.372733 -273.442476)
			(xy 343.343357 -273.482909) (xy 343.308017 -273.518249) (xy 343.267584 -273.547625) (xy 343.223052 -273.570315)
			(xy 343.17552 -273.585759) (xy 343.126157 -273.593578) (xy 343.076179 -273.593578) (xy 343.026816 -273.585759)
			(xy 342.979284 -273.570315) (xy 342.934752 -273.547625) (xy 342.894319 -273.518249) (xy 342.858979 -273.482909)
			(xy 342.829603 -273.442476) (xy 342.806913 -273.397944) (xy 342.791469 -273.350412) (xy 342.78365 -273.301049)
			(xy 342.476333 -273.301049) (xy 342.476324 -273.301506) (xy 342.46816 -273.35174) (xy 342.452044 -273.400014)
			(xy 342.428393 -273.445077) (xy 342.39782 -273.485763) (xy 342.361116 -273.521018) (xy 342.319232 -273.549928)
			(xy 342.273253 -273.571745) (xy 342.224369 -273.585905) (xy 342.173848 -273.592039) (xy 342.122996 -273.58999)
			(xy 342.073132 -273.57981) (xy 342.025546 -273.561763) (xy 341.981472 -273.536317) (xy 341.94205 -273.50413)
			(xy 341.908302 -273.466036) (xy 341.881101 -273.423022) (xy 341.861153 -273.376202) (xy 341.848974 -273.326788)
			(xy 341.844879 -273.27606) (xy 340.596728 -273.27606) (xy 340.596216 -273.301506) (xy 340.588052 -273.35174)
			(xy 340.571936 -273.400014) (xy 340.548285 -273.445077) (xy 340.517712 -273.485763) (xy 340.481008 -273.521018)
			(xy 340.439124 -273.549928) (xy 340.393145 -273.571745) (xy 340.344261 -273.585905) (xy 340.29374 -273.592039)
			(xy 340.242888 -273.58999) (xy 340.193024 -273.57981) (xy 340.145438 -273.561763) (xy 340.101364 -273.536317)
			(xy 340.061942 -273.50413) (xy 340.028194 -273.466036) (xy 340.000993 -273.423022) (xy 339.981045 -273.376202)
			(xy 339.968866 -273.326788) (xy 339.964771 -273.27606) (xy 339.656928 -273.27606) (xy 339.656416 -273.301506)
			(xy 339.648252 -273.35174) (xy 339.632136 -273.400014) (xy 339.608485 -273.445077) (xy 339.577912 -273.485763)
			(xy 339.541208 -273.521018) (xy 339.499324 -273.549928) (xy 339.453345 -273.571745) (xy 339.404461 -273.585905)
			(xy 339.35394 -273.592039) (xy 339.303088 -273.58999) (xy 339.253224 -273.57981) (xy 339.205638 -273.561763)
			(xy 339.161564 -273.536317) (xy 339.122142 -273.50413) (xy 339.088394 -273.466036) (xy 339.061193 -273.423022)
			(xy 339.041245 -273.376202) (xy 339.029066 -273.326788) (xy 339.024971 -273.27606) (xy 338.718783 -273.27606)
			(xy 338.718783 -273.301097) (xy 338.710962 -273.350475) (xy 338.695512 -273.398021) (xy 338.672813 -273.442564)
			(xy 338.643425 -273.483008) (xy 338.608072 -273.518356) (xy 338.567623 -273.547738) (xy 338.523076 -273.57043)
			(xy 338.475528 -273.585873) (xy 338.426149 -273.593687) (xy 338.401152 -273.594068) (xy 338.376953 -273.593619)
			(xy 338.329112 -273.586292) (xy 338.282934 -273.5718) (xy 338.239486 -273.550476) (xy 338.199771 -273.522815)
			(xy 338.18195 -273.506438) (xy 338.176362 -273.501358) (xy 338.1629 -273.494246) (xy 338.156296 -273.49323)
			(xy 338.148963 -273.492186) (xy 338.134252 -273.493868) (xy 338.12734 -273.496532) (xy 338.058506 -273.525996)
			(xy 338.057998 -273.525996) (xy 338.041742 -273.532854) (xy 338.033233 -273.537212) (xy 338.020052 -273.55104)
			(xy 338.01294 -273.568769) (xy 338.012532 -273.57832) (xy 338.012532 -273.75231) (xy 338.017866 -273.757898)
			(xy 338.017866 -273.75993) (xy 338.024724 -273.770344) (xy 338.049881 -273.778363) (xy 338.097445 -273.801283)
			(xy 338.140744 -273.831495) (xy 338.17867 -273.868228) (xy 338.21025 -273.910539) (xy 338.234678 -273.957347)
			(xy 338.251326 -274.007451) (xy 338.259768 -274.05957) (xy 338.259779 -274.086066) (xy 338.554817 -274.086066)
			(xy 338.558912 -274.035338) (xy 338.571091 -273.985924) (xy 338.591039 -273.939104) (xy 338.61824 -273.89609)
			(xy 338.651988 -273.857996) (xy 338.69141 -273.825809) (xy 338.735484 -273.800363) (xy 338.78307 -273.782316)
			(xy 338.832934 -273.772136) (xy 338.883786 -273.770087) (xy 338.934307 -273.776221) (xy 338.983191 -273.790381)
			(xy 339.02917 -273.812198) (xy 339.071054 -273.841108) (xy 339.107758 -273.876363) (xy 339.138331 -273.917049)
			(xy 339.161982 -273.962112) (xy 339.178098 -274.010386) (xy 339.186262 -274.06062) (xy 339.186774 -274.086066)
			(xy 339.186271 -274.111055) (xy 339.493588 -274.111055) (xy 339.493588 -274.061077) (xy 339.501407 -274.011714)
			(xy 339.516851 -273.964182) (xy 339.539541 -273.91965) (xy 339.568917 -273.879217) (xy 339.604257 -273.843877)
			(xy 339.64469 -273.814501) (xy 339.689222 -273.791811) (xy 339.736754 -273.776367) (xy 339.786117 -273.768548)
			(xy 339.836095 -273.768548) (xy 339.885458 -273.776367) (xy 339.93299 -273.791811) (xy 339.977522 -273.814501)
			(xy 340.017955 -273.843877) (xy 340.053295 -273.879217) (xy 340.082671 -273.91965) (xy 340.105361 -273.964182)
			(xy 340.120805 -274.011714) (xy 340.128624 -274.061077) (xy 340.129114 -274.086066) (xy 340.434925 -274.086066)
			(xy 340.43902 -274.035338) (xy 340.451199 -273.985924) (xy 340.471147 -273.939104) (xy 340.498348 -273.89609)
			(xy 340.532096 -273.857996) (xy 340.571518 -273.825809) (xy 340.615592 -273.800363) (xy 340.663178 -273.782316)
			(xy 340.713042 -273.772136) (xy 340.763894 -273.770087) (xy 340.814415 -273.776221) (xy 340.863299 -273.790381)
			(xy 340.909278 -273.812198) (xy 340.951162 -273.841108) (xy 340.987866 -273.876363) (xy 341.018439 -273.917049)
			(xy 341.04209 -273.962112) (xy 341.058206 -274.010386) (xy 341.06637 -274.06062) (xy 341.066882 -274.086066)
			(xy 341.066379 -274.111055) (xy 341.373696 -274.111055) (xy 341.373696 -274.061077) (xy 341.381515 -274.011714)
			(xy 341.396959 -273.964182) (xy 341.419649 -273.91965) (xy 341.449025 -273.879217) (xy 341.484365 -273.843877)
			(xy 341.524798 -273.814501) (xy 341.56933 -273.791811) (xy 341.616862 -273.776367) (xy 341.666225 -273.768548)
			(xy 341.716203 -273.768548) (xy 341.765566 -273.776367) (xy 341.813098 -273.791811) (xy 341.85763 -273.814501)
			(xy 341.898063 -273.843877) (xy 341.933403 -273.879217) (xy 341.962779 -273.91965) (xy 341.985469 -273.964182)
			(xy 342.000913 -274.011714) (xy 342.008732 -274.061077) (xy 342.009222 -274.086066) (xy 342.314779 -274.086066)
			(xy 342.318874 -274.035338) (xy 342.331053 -273.985924) (xy 342.351001 -273.939104) (xy 342.378202 -273.89609)
			(xy 342.41195 -273.857996) (xy 342.451372 -273.825809) (xy 342.495446 -273.800363) (xy 342.543032 -273.782316)
			(xy 342.592896 -273.772136) (xy 342.643748 -273.770087) (xy 342.694269 -273.776221) (xy 342.743153 -273.790381)
			(xy 342.789132 -273.812198) (xy 342.831016 -273.841108) (xy 342.86772 -273.876363) (xy 342.898293 -273.917049)
			(xy 342.921944 -273.962112) (xy 342.93806 -274.010386) (xy 342.946224 -274.06062) (xy 342.946736 -274.086066)
			(xy 343.254833 -274.086066) (xy 343.258928 -274.035338) (xy 343.271107 -273.985924) (xy 343.291055 -273.939104)
			(xy 343.318256 -273.89609) (xy 343.352004 -273.857996) (xy 343.391426 -273.825809) (xy 343.4355 -273.800363)
			(xy 343.483086 -273.782316) (xy 343.53295 -273.772136) (xy 343.583802 -273.770087) (xy 343.634323 -273.776221)
			(xy 343.683207 -273.790381) (xy 343.729186 -273.812198) (xy 343.77107 -273.841108) (xy 343.807774 -273.876363)
			(xy 343.838347 -273.917049) (xy 343.861998 -273.962112) (xy 343.878114 -274.010386) (xy 343.886278 -274.06062)
			(xy 343.88679 -274.086066) (xy 343.886278 -274.111512) (xy 343.878114 -274.161746) (xy 343.861998 -274.21002)
			(xy 343.838347 -274.255083) (xy 343.807774 -274.295769) (xy 343.77107 -274.331024) (xy 343.729186 -274.359934)
			(xy 343.683207 -274.381751) (xy 343.634323 -274.395911) (xy 343.583802 -274.402045) (xy 343.53295 -274.399996)
			(xy 343.483086 -274.389816) (xy 343.4355 -274.371769) (xy 343.391426 -274.346323) (xy 343.352004 -274.314136)
			(xy 343.318256 -274.276042) (xy 343.291055 -274.233028) (xy 343.271107 -274.186208) (xy 343.258928 -274.136794)
			(xy 343.254833 -274.086066) (xy 342.946736 -274.086066) (xy 342.946224 -274.111512) (xy 342.93806 -274.161746)
			(xy 342.921944 -274.21002) (xy 342.898293 -274.255083) (xy 342.86772 -274.295769) (xy 342.831016 -274.331024)
			(xy 342.789132 -274.359934) (xy 342.743153 -274.381751) (xy 342.694269 -274.395911) (xy 342.643748 -274.402045)
			(xy 342.592896 -274.399996) (xy 342.543032 -274.389816) (xy 342.495446 -274.371769) (xy 342.451372 -274.346323)
			(xy 342.41195 -274.314136) (xy 342.378202 -274.276042) (xy 342.351001 -274.233028) (xy 342.331053 -274.186208)
			(xy 342.318874 -274.136794) (xy 342.314779 -274.086066) (xy 342.009222 -274.086066) (xy 342.008732 -274.111055)
			(xy 342.000913 -274.160418) (xy 341.985469 -274.20795) (xy 341.962779 -274.252482) (xy 341.933403 -274.292915)
			(xy 341.898063 -274.328255) (xy 341.85763 -274.357631) (xy 341.813098 -274.380321) (xy 341.765566 -274.395765)
			(xy 341.716203 -274.403584) (xy 341.666225 -274.403584) (xy 341.616862 -274.395765) (xy 341.56933 -274.380321)
			(xy 341.524798 -274.357631) (xy 341.484365 -274.328255) (xy 341.449025 -274.292915) (xy 341.419649 -274.252482)
			(xy 341.396959 -274.20795) (xy 341.381515 -274.160418) (xy 341.373696 -274.111055) (xy 341.066379 -274.111055)
			(xy 341.06637 -274.111512) (xy 341.058206 -274.161746) (xy 341.04209 -274.21002) (xy 341.018439 -274.255083)
			(xy 340.987866 -274.295769) (xy 340.951162 -274.331024) (xy 340.909278 -274.359934) (xy 340.863299 -274.381751)
			(xy 340.814415 -274.395911) (xy 340.763894 -274.402045) (xy 340.713042 -274.399996) (xy 340.663178 -274.389816)
			(xy 340.615592 -274.371769) (xy 340.571518 -274.346323) (xy 340.532096 -274.314136) (xy 340.498348 -274.276042)
			(xy 340.471147 -274.233028) (xy 340.451199 -274.186208) (xy 340.43902 -274.136794) (xy 340.434925 -274.086066)
			(xy 340.129114 -274.086066) (xy 340.128624 -274.111055) (xy 340.120805 -274.160418) (xy 340.105361 -274.20795)
			(xy 340.082671 -274.252482) (xy 340.053295 -274.292915) (xy 340.017955 -274.328255) (xy 339.977522 -274.357631)
			(xy 339.93299 -274.380321) (xy 339.885458 -274.395765) (xy 339.836095 -274.403584) (xy 339.786117 -274.403584)
			(xy 339.736754 -274.395765) (xy 339.689222 -274.380321) (xy 339.64469 -274.357631) (xy 339.604257 -274.328255)
			(xy 339.568917 -274.292915) (xy 339.539541 -274.252482) (xy 339.516851 -274.20795) (xy 339.501407 -274.160418)
			(xy 339.493588 -274.111055) (xy 339.186271 -274.111055) (xy 339.186262 -274.111512) (xy 339.178098 -274.161746)
			(xy 339.161982 -274.21002) (xy 339.138331 -274.255083) (xy 339.107758 -274.295769) (xy 339.071054 -274.331024)
			(xy 339.02917 -274.359934) (xy 338.983191 -274.381751) (xy 338.934307 -274.395911) (xy 338.883786 -274.402045)
			(xy 338.832934 -274.399996) (xy 338.78307 -274.389816) (xy 338.735484 -274.371769) (xy 338.69141 -274.346323)
			(xy 338.651988 -274.314136) (xy 338.61824 -274.276042) (xy 338.591039 -274.233028) (xy 338.571091 -274.186208)
			(xy 338.558912 -274.136794) (xy 338.554817 -274.086066) (xy 338.259779 -274.086066) (xy 338.259789 -274.112368)
			(xy 338.251388 -274.164493) (xy 338.23478 -274.214611) (xy 338.21039 -274.261438) (xy 338.178843 -274.303775)
			(xy 338.140947 -274.340537) (xy 338.097672 -274.370784) (xy 338.050126 -274.393741) (xy 338.024978 -274.401788)
			(xy 338.021709 -274.407693) (xy 338.018107 -274.420696) (xy 338.017866 -274.427442) (xy 338.017866 -274.588732)
			(xy 338.018311 -274.598109) (xy 338.025244 -274.61554) (xy 338.038037 -274.629259) (xy 338.046314 -274.63369)
			(xy 338.084414 -274.650454) (xy 338.134198 -274.672552) (xy 338.138372 -274.673982) (xy 338.147059 -274.675517)
			(xy 338.15147 -274.6756) (xy 338.174584 -274.66671) (xy 338.184998 -274.662646) (xy 338.188046 -274.660106)
			(xy 338.205657 -274.644738) (xy 338.244544 -274.618807) (xy 338.286811 -274.598854) (xy 338.331546 -274.58531)
			(xy 338.377782 -274.578468) (xy 338.401152 -274.578064) (xy 338.426148 -274.578525) (xy 338.475525 -274.586339)
			(xy 338.523072 -274.601781) (xy 338.567617 -274.624472) (xy 338.608064 -274.653853) (xy 338.643416 -274.6892)
			(xy 338.672803 -274.729642) (xy 338.6955 -274.774184) (xy 338.71095 -274.821728) (xy 338.718771 -274.871104)
			(xy 338.718771 -274.896072) (xy 339.024971 -274.896072) (xy 339.029066 -274.845344) (xy 339.041245 -274.79593)
			(xy 339.061193 -274.74911) (xy 339.088394 -274.706096) (xy 339.122142 -274.668002) (xy 339.161564 -274.635815)
			(xy 339.205638 -274.610369) (xy 339.253224 -274.592322) (xy 339.303088 -274.582142) (xy 339.35394 -274.580093)
			(xy 339.404461 -274.586227) (xy 339.453345 -274.600387) (xy 339.499324 -274.622204) (xy 339.541208 -274.651114)
			(xy 339.577912 -274.686369) (xy 339.608485 -274.727055) (xy 339.632136 -274.772118) (xy 339.648252 -274.820392)
			(xy 339.656416 -274.870626) (xy 339.656928 -274.896072) (xy 339.964771 -274.896072) (xy 339.968866 -274.845344)
			(xy 339.981045 -274.79593) (xy 340.000993 -274.74911) (xy 340.028194 -274.706096) (xy 340.061942 -274.668002)
			(xy 340.101364 -274.635815) (xy 340.145438 -274.610369) (xy 340.193024 -274.592322) (xy 340.242888 -274.582142)
			(xy 340.29374 -274.580093) (xy 340.344261 -274.586227) (xy 340.393145 -274.600387) (xy 340.439124 -274.622204)
			(xy 340.481008 -274.651114) (xy 340.517712 -274.686369) (xy 340.548285 -274.727055) (xy 340.571936 -274.772118)
			(xy 340.588052 -274.820392) (xy 340.596216 -274.870626) (xy 340.596728 -274.896072) (xy 340.596225 -274.921061)
			(xy 340.903542 -274.921061) (xy 340.903542 -274.871083) (xy 340.911361 -274.82172) (xy 340.926805 -274.774188)
			(xy 340.949495 -274.729656) (xy 340.978871 -274.689223) (xy 341.014211 -274.653883) (xy 341.054644 -274.624507)
			(xy 341.099176 -274.601817) (xy 341.146708 -274.586373) (xy 341.196071 -274.578554) (xy 341.246049 -274.578554)
			(xy 341.295412 -274.586373) (xy 341.342944 -274.601817) (xy 341.387476 -274.624507) (xy 341.427909 -274.653883)
			(xy 341.463249 -274.689223) (xy 341.492625 -274.729656) (xy 341.515315 -274.774188) (xy 341.530759 -274.82172)
			(xy 341.538578 -274.871083) (xy 341.539068 -274.896072) (xy 341.844879 -274.896072) (xy 341.848974 -274.845344)
			(xy 341.861153 -274.79593) (xy 341.881101 -274.74911) (xy 341.908302 -274.706096) (xy 341.94205 -274.668002)
			(xy 341.981472 -274.635815) (xy 342.025546 -274.610369) (xy 342.073132 -274.592322) (xy 342.122996 -274.582142)
			(xy 342.173848 -274.580093) (xy 342.224369 -274.586227) (xy 342.273253 -274.600387) (xy 342.319232 -274.622204)
			(xy 342.361116 -274.651114) (xy 342.39782 -274.686369) (xy 342.428393 -274.727055) (xy 342.452044 -274.772118)
			(xy 342.46816 -274.820392) (xy 342.476324 -274.870626) (xy 342.476836 -274.896072) (xy 342.476333 -274.921061)
			(xy 342.78365 -274.921061) (xy 342.78365 -274.871083) (xy 342.791469 -274.82172) (xy 342.806913 -274.774188)
			(xy 342.829603 -274.729656) (xy 342.858979 -274.689223) (xy 342.894319 -274.653883) (xy 342.934752 -274.624507)
			(xy 342.979284 -274.601817) (xy 343.026816 -274.586373) (xy 343.076179 -274.578554) (xy 343.126157 -274.578554)
			(xy 343.17552 -274.586373) (xy 343.223052 -274.601817) (xy 343.267584 -274.624507) (xy 343.308017 -274.653883)
			(xy 343.343357 -274.689223) (xy 343.372733 -274.729656) (xy 343.395423 -274.774188) (xy 343.410867 -274.82172)
			(xy 343.418686 -274.871083) (xy 343.419176 -274.896072) (xy 343.724987 -274.896072) (xy 343.729082 -274.845344)
			(xy 343.741261 -274.79593) (xy 343.761209 -274.74911) (xy 343.78841 -274.706096) (xy 343.822158 -274.668002)
			(xy 343.86158 -274.635815) (xy 343.905654 -274.610369) (xy 343.95324 -274.592322) (xy 344.003104 -274.582142)
			(xy 344.053956 -274.580093) (xy 344.104477 -274.586227) (xy 344.153361 -274.600387) (xy 344.19934 -274.622204)
			(xy 344.241224 -274.651114) (xy 344.277928 -274.686369) (xy 344.308501 -274.727055) (xy 344.332152 -274.772118)
			(xy 344.348268 -274.820392) (xy 344.356432 -274.870626) (xy 344.356944 -274.896072) (xy 344.356432 -274.921518)
			(xy 344.348268 -274.971752) (xy 344.332152 -275.020026) (xy 344.308501 -275.065089) (xy 344.277928 -275.105775)
			(xy 344.241224 -275.14103) (xy 344.19934 -275.16994) (xy 344.153361 -275.191757) (xy 344.104477 -275.205917)
			(xy 344.053956 -275.212051) (xy 344.003104 -275.210002) (xy 343.95324 -275.199822) (xy 343.905654 -275.181775)
			(xy 343.86158 -275.156329) (xy 343.822158 -275.124142) (xy 343.78841 -275.086048) (xy 343.761209 -275.043034)
			(xy 343.741261 -274.996214) (xy 343.729082 -274.9468) (xy 343.724987 -274.896072) (xy 343.419176 -274.896072)
			(xy 343.418686 -274.921061) (xy 343.410867 -274.970424) (xy 343.395423 -275.017956) (xy 343.372733 -275.062488)
			(xy 343.343357 -275.102921) (xy 343.308017 -275.138261) (xy 343.267584 -275.167637) (xy 343.223052 -275.190327)
			(xy 343.17552 -275.205771) (xy 343.126157 -275.21359) (xy 343.076179 -275.21359) (xy 343.026816 -275.205771)
			(xy 342.979284 -275.190327) (xy 342.934752 -275.167637) (xy 342.894319 -275.138261) (xy 342.858979 -275.102921)
			(xy 342.829603 -275.062488) (xy 342.806913 -275.017956) (xy 342.791469 -274.970424) (xy 342.78365 -274.921061)
			(xy 342.476333 -274.921061) (xy 342.476324 -274.921518) (xy 342.46816 -274.971752) (xy 342.452044 -275.020026)
			(xy 342.428393 -275.065089) (xy 342.39782 -275.105775) (xy 342.361116 -275.14103) (xy 342.319232 -275.16994)
			(xy 342.273253 -275.191757) (xy 342.224369 -275.205917) (xy 342.173848 -275.212051) (xy 342.122996 -275.210002)
			(xy 342.073132 -275.199822) (xy 342.025546 -275.181775) (xy 341.981472 -275.156329) (xy 341.94205 -275.124142)
			(xy 341.908302 -275.086048) (xy 341.881101 -275.043034) (xy 341.861153 -274.996214) (xy 341.848974 -274.9468)
			(xy 341.844879 -274.896072) (xy 341.539068 -274.896072) (xy 341.538578 -274.921061) (xy 341.530759 -274.970424)
			(xy 341.515315 -275.017956) (xy 341.492625 -275.062488) (xy 341.463249 -275.102921) (xy 341.427909 -275.138261)
			(xy 341.387476 -275.167637) (xy 341.342944 -275.190327) (xy 341.295412 -275.205771) (xy 341.246049 -275.21359)
			(xy 341.196071 -275.21359) (xy 341.146708 -275.205771) (xy 341.099176 -275.190327) (xy 341.054644 -275.167637)
			(xy 341.014211 -275.138261) (xy 340.978871 -275.102921) (xy 340.949495 -275.062488) (xy 340.926805 -275.017956)
			(xy 340.911361 -274.970424) (xy 340.903542 -274.921061) (xy 340.596225 -274.921061) (xy 340.596216 -274.921518)
			(xy 340.588052 -274.971752) (xy 340.571936 -275.020026) (xy 340.548285 -275.065089) (xy 340.517712 -275.105775)
			(xy 340.481008 -275.14103) (xy 340.439124 -275.16994) (xy 340.393145 -275.191757) (xy 340.344261 -275.205917)
			(xy 340.29374 -275.212051) (xy 340.242888 -275.210002) (xy 340.193024 -275.199822) (xy 340.145438 -275.181775)
			(xy 340.101364 -275.156329) (xy 340.061942 -275.124142) (xy 340.028194 -275.086048) (xy 340.000993 -275.043034)
			(xy 339.981045 -274.996214) (xy 339.968866 -274.9468) (xy 339.964771 -274.896072) (xy 339.656928 -274.896072)
			(xy 339.656416 -274.921518) (xy 339.648252 -274.971752) (xy 339.632136 -275.020026) (xy 339.608485 -275.065089)
			(xy 339.577912 -275.105775) (xy 339.541208 -275.14103) (xy 339.499324 -275.16994) (xy 339.453345 -275.191757)
			(xy 339.404461 -275.205917) (xy 339.35394 -275.212051) (xy 339.303088 -275.210002) (xy 339.253224 -275.199822)
			(xy 339.205638 -275.181775) (xy 339.161564 -275.156329) (xy 339.122142 -275.124142) (xy 339.088394 -275.086048)
			(xy 339.061193 -275.043034) (xy 339.041245 -274.996214) (xy 339.029066 -274.9468) (xy 339.024971 -274.896072)
			(xy 338.718771 -274.896072) (xy 338.718771 -274.921096) (xy 338.71095 -274.970472) (xy 338.6955 -275.018016)
			(xy 338.672803 -275.062558) (xy 338.643416 -275.103) (xy 338.608064 -275.138347) (xy 338.567617 -275.167728)
			(xy 338.523072 -275.190419) (xy 338.475525 -275.205861) (xy 338.426148 -275.213675) (xy 338.401152 -275.21408)
			(xy 338.377784 -275.213663) (xy 338.331554 -275.206811) (xy 338.286825 -275.193261) (xy 338.244564 -275.173306)
			(xy 338.205681 -275.147377) (xy 338.188046 -275.132038) (xy 338.184998 -275.129498) (xy 338.174584 -275.125434)
			(xy 338.15147 -275.116544) (xy 338.14706 -275.116642) (xy 338.138376 -275.118177) (xy 338.134198 -275.119592)
			(xy 338.084414 -275.14169) (xy 338.046314 -275.158454) (xy 338.038012 -275.162849) (xy 338.025202 -275.17657)
			(xy 338.018301 -275.194027) (xy 338.017866 -275.203412) (xy 338.017866 -275.364702) (xy 338.018325 -275.373883)
			(xy 338.024977 -275.391005) (xy 338.037295 -275.40463) (xy 338.045298 -275.409152) (xy 338.049616 -275.41093)
			(xy 338.072857 -275.420767) (xy 338.116146 -275.446706) (xy 338.154795 -275.479157) (xy 338.187834 -275.517304)
			(xy 338.214433 -275.560191) (xy 338.233924 -275.606741) (xy 338.245818 -275.655785) (xy 338.249817 -275.706078)
			(xy 338.554817 -275.706078) (xy 338.558912 -275.65535) (xy 338.571091 -275.605936) (xy 338.591039 -275.559116)
			(xy 338.61824 -275.516102) (xy 338.651988 -275.478008) (xy 338.69141 -275.445821) (xy 338.735484 -275.420375)
			(xy 338.78307 -275.402328) (xy 338.832934 -275.392148) (xy 338.883786 -275.390099) (xy 338.934307 -275.396233)
			(xy 338.983191 -275.410393) (xy 339.02917 -275.43221) (xy 339.071054 -275.46112) (xy 339.107758 -275.496375)
			(xy 339.138331 -275.537061) (xy 339.161982 -275.582124) (xy 339.178098 -275.630398) (xy 339.186262 -275.680632)
			(xy 339.186774 -275.706078) (xy 339.186271 -275.731067) (xy 339.493588 -275.731067) (xy 339.493588 -275.681089)
			(xy 339.501407 -275.631726) (xy 339.516851 -275.584194) (xy 339.539541 -275.539662) (xy 339.568917 -275.499229)
			(xy 339.604257 -275.463889) (xy 339.64469 -275.434513) (xy 339.689222 -275.411823) (xy 339.736754 -275.396379)
			(xy 339.786117 -275.38856) (xy 339.836095 -275.38856) (xy 339.885458 -275.396379) (xy 339.93299 -275.411823)
			(xy 339.977522 -275.434513) (xy 340.017955 -275.463889) (xy 340.053295 -275.499229) (xy 340.082671 -275.539662)
			(xy 340.105361 -275.584194) (xy 340.120805 -275.631726) (xy 340.128624 -275.681089) (xy 340.129114 -275.706078)
			(xy 340.434925 -275.706078) (xy 340.43902 -275.65535) (xy 340.451199 -275.605936) (xy 340.471147 -275.559116)
			(xy 340.498348 -275.516102) (xy 340.532096 -275.478008) (xy 340.571518 -275.445821) (xy 340.615592 -275.420375)
			(xy 340.663178 -275.402328) (xy 340.713042 -275.392148) (xy 340.763894 -275.390099) (xy 340.814415 -275.396233)
			(xy 340.863299 -275.410393) (xy 340.909278 -275.43221) (xy 340.951162 -275.46112) (xy 340.987866 -275.496375)
			(xy 341.018439 -275.537061) (xy 341.04209 -275.582124) (xy 341.058206 -275.630398) (xy 341.06637 -275.680632)
			(xy 341.066882 -275.706078) (xy 342.314779 -275.706078) (xy 342.318874 -275.65535) (xy 342.331053 -275.605936)
			(xy 342.351001 -275.559116) (xy 342.378202 -275.516102) (xy 342.41195 -275.478008) (xy 342.451372 -275.445821)
			(xy 342.495446 -275.420375) (xy 342.543032 -275.402328) (xy 342.592896 -275.392148) (xy 342.643748 -275.390099)
			(xy 342.694269 -275.396233) (xy 342.743153 -275.410393) (xy 342.789132 -275.43221) (xy 342.831016 -275.46112)
			(xy 342.86772 -275.496375) (xy 342.898293 -275.537061) (xy 342.921944 -275.582124) (xy 342.93806 -275.630398)
			(xy 342.946224 -275.680632) (xy 342.946736 -275.706078) (xy 343.254833 -275.706078) (xy 343.258928 -275.65535)
			(xy 343.271107 -275.605936) (xy 343.291055 -275.559116) (xy 343.318256 -275.516102) (xy 343.352004 -275.478008)
			(xy 343.391426 -275.445821) (xy 343.4355 -275.420375) (xy 343.483086 -275.402328) (xy 343.53295 -275.392148)
			(xy 343.583802 -275.390099) (xy 343.634323 -275.396233) (xy 343.683207 -275.410393) (xy 343.729186 -275.43221)
			(xy 343.77107 -275.46112) (xy 343.807774 -275.496375) (xy 343.838347 -275.537061) (xy 343.861998 -275.582124)
			(xy 343.878114 -275.630398) (xy 343.886278 -275.680632) (xy 343.88679 -275.706078) (xy 343.886278 -275.731524)
			(xy 343.878114 -275.781758) (xy 343.861998 -275.830032) (xy 343.838347 -275.875095) (xy 343.807774 -275.915781)
			(xy 343.77107 -275.951036) (xy 343.729186 -275.979946) (xy 343.683207 -276.001763) (xy 343.634323 -276.015923)
			(xy 343.583802 -276.022057) (xy 343.53295 -276.020008) (xy 343.483086 -276.009828) (xy 343.4355 -275.991781)
			(xy 343.391426 -275.966335) (xy 343.352004 -275.934148) (xy 343.318256 -275.896054) (xy 343.291055 -275.85304)
			(xy 343.271107 -275.80622) (xy 343.258928 -275.756806) (xy 343.254833 -275.706078) (xy 342.946736 -275.706078)
			(xy 342.946224 -275.731524) (xy 342.93806 -275.781758) (xy 342.921944 -275.830032) (xy 342.898293 -275.875095)
			(xy 342.86772 -275.915781) (xy 342.831016 -275.951036) (xy 342.789132 -275.979946) (xy 342.743153 -276.001763)
			(xy 342.694269 -276.015923) (xy 342.643748 -276.022057) (xy 342.592896 -276.020008) (xy 342.543032 -276.009828)
			(xy 342.495446 -275.991781) (xy 342.451372 -275.966335) (xy 342.41195 -275.934148) (xy 342.378202 -275.896054)
			(xy 342.351001 -275.85304) (xy 342.331053 -275.80622) (xy 342.318874 -275.756806) (xy 342.314779 -275.706078)
			(xy 341.066882 -275.706078) (xy 341.06637 -275.731524) (xy 341.058206 -275.781758) (xy 341.04209 -275.830032)
			(xy 341.018439 -275.875095) (xy 340.987866 -275.915781) (xy 340.951162 -275.951036) (xy 340.909278 -275.979946)
			(xy 340.863299 -276.001763) (xy 340.814415 -276.015923) (xy 340.763894 -276.022057) (xy 340.713042 -276.020008)
			(xy 340.663178 -276.009828) (xy 340.615592 -275.991781) (xy 340.571518 -275.966335) (xy 340.532096 -275.934148)
			(xy 340.498348 -275.896054) (xy 340.471147 -275.85304) (xy 340.451199 -275.80622) (xy 340.43902 -275.756806)
			(xy 340.434925 -275.706078) (xy 340.129114 -275.706078) (xy 340.128624 -275.731067) (xy 340.120805 -275.78043)
			(xy 340.105361 -275.827962) (xy 340.082671 -275.872494) (xy 340.053295 -275.912927) (xy 340.017955 -275.948267)
			(xy 339.977522 -275.977643) (xy 339.93299 -276.000333) (xy 339.885458 -276.015777) (xy 339.836095 -276.023596)
			(xy 339.786117 -276.023596) (xy 339.736754 -276.015777) (xy 339.689222 -276.000333) (xy 339.64469 -275.977643)
			(xy 339.604257 -275.948267) (xy 339.568917 -275.912927) (xy 339.539541 -275.872494) (xy 339.516851 -275.827962)
			(xy 339.501407 -275.78043) (xy 339.493588 -275.731067) (xy 339.186271 -275.731067) (xy 339.186262 -275.731524)
			(xy 339.178098 -275.781758) (xy 339.161982 -275.830032) (xy 339.138331 -275.875095) (xy 339.107758 -275.915781)
			(xy 339.071054 -275.951036) (xy 339.02917 -275.979946) (xy 338.983191 -276.001763) (xy 338.934307 -276.015923)
			(xy 338.883786 -276.022057) (xy 338.832934 -276.020008) (xy 338.78307 -276.009828) (xy 338.735484 -275.991781)
			(xy 338.69141 -275.966335) (xy 338.651988 -275.934148) (xy 338.61824 -275.896054) (xy 338.591039 -275.85304)
			(xy 338.571091 -275.80622) (xy 338.558912 -275.756806) (xy 338.554817 -275.706078) (xy 338.249817 -275.706078)
			(xy 338.249818 -275.706092) (xy 338.245821 -275.756399) (xy 338.233929 -275.805443) (xy 338.21444 -275.851994)
			(xy 338.187844 -275.894882) (xy 338.154807 -275.933032) (xy 338.11616 -275.965484) (xy 338.072872 -275.991426)
			(xy 338.049616 -276.001226) (xy 338.045298 -276.003004) (xy 338.037279 -276.007512) (xy 338.024931 -276.021127)
			(xy 338.018288 -276.038265) (xy 338.017866 -276.047454) (xy 338.017866 -276.208744) (xy 338.018313 -276.21812)
			(xy 338.025248 -276.235547) (xy 338.038042 -276.249263) (xy 338.046314 -276.253702) (xy 338.084414 -276.270466)
			(xy 338.134198 -276.292564) (xy 338.138371 -276.293996) (xy 338.147059 -276.295534) (xy 338.15147 -276.295612)
			(xy 338.174584 -276.286722) (xy 338.184998 -276.282658) (xy 338.188046 -276.280118) (xy 338.205659 -276.264754)
			(xy 338.244548 -276.238829) (xy 338.286815 -276.218882) (xy 338.331549 -276.205342) (xy 338.377783 -276.198503)
			(xy 338.401152 -276.198076) (xy 338.426147 -276.198537) (xy 338.475522 -276.20635) (xy 338.523067 -276.221792)
			(xy 338.567611 -276.244482) (xy 338.608056 -276.273862) (xy 338.643407 -276.309207) (xy 338.672792 -276.349648)
			(xy 338.695489 -276.394188) (xy 338.710938 -276.441731) (xy 338.718759 -276.491105) (xy 338.718759 -276.516084)
			(xy 339.024971 -276.516084) (xy 339.029066 -276.465356) (xy 339.041245 -276.415942) (xy 339.061193 -276.369122)
			(xy 339.088394 -276.326108) (xy 339.122142 -276.288014) (xy 339.161564 -276.255827) (xy 339.205638 -276.230381)
			(xy 339.253224 -276.212334) (xy 339.303088 -276.202154) (xy 339.35394 -276.200105) (xy 339.404461 -276.206239)
			(xy 339.453345 -276.220399) (xy 339.499324 -276.242216) (xy 339.541208 -276.271126) (xy 339.577912 -276.306381)
			(xy 339.608485 -276.347067) (xy 339.632136 -276.39213) (xy 339.648252 -276.440404) (xy 339.656416 -276.490638)
			(xy 339.656928 -276.516084) (xy 339.964771 -276.516084) (xy 339.968866 -276.465356) (xy 339.981045 -276.415942)
			(xy 340.000993 -276.369122) (xy 340.028194 -276.326108) (xy 340.061942 -276.288014) (xy 340.101364 -276.255827)
			(xy 340.145438 -276.230381) (xy 340.193024 -276.212334) (xy 340.242888 -276.202154) (xy 340.29374 -276.200105)
			(xy 340.344261 -276.206239) (xy 340.393145 -276.220399) (xy 340.439124 -276.242216) (xy 340.481008 -276.271126)
			(xy 340.517712 -276.306381) (xy 340.548285 -276.347067) (xy 340.571936 -276.39213) (xy 340.588052 -276.440404)
			(xy 340.596216 -276.490638) (xy 340.596728 -276.516084) (xy 340.596225 -276.541073) (xy 340.903542 -276.541073)
			(xy 340.903542 -276.491095) (xy 340.911361 -276.441732) (xy 340.926805 -276.3942) (xy 340.949495 -276.349668)
			(xy 340.978871 -276.309235) (xy 341.014211 -276.273895) (xy 341.054644 -276.244519) (xy 341.099176 -276.221829)
			(xy 341.146708 -276.206385) (xy 341.196071 -276.198566) (xy 341.246049 -276.198566) (xy 341.295412 -276.206385)
			(xy 341.342944 -276.221829) (xy 341.387476 -276.244519) (xy 341.427909 -276.273895) (xy 341.463249 -276.309235)
			(xy 341.492625 -276.349668) (xy 341.515315 -276.3942) (xy 341.530759 -276.441732) (xy 341.538578 -276.491095)
			(xy 341.539068 -276.516084) (xy 341.844879 -276.516084) (xy 341.848974 -276.465356) (xy 341.861153 -276.415942)
			(xy 341.881101 -276.369122) (xy 341.908302 -276.326108) (xy 341.94205 -276.288014) (xy 341.981472 -276.255827)
			(xy 342.025546 -276.230381) (xy 342.073132 -276.212334) (xy 342.122996 -276.202154) (xy 342.173848 -276.200105)
			(xy 342.224369 -276.206239) (xy 342.273253 -276.220399) (xy 342.319232 -276.242216) (xy 342.361116 -276.271126)
			(xy 342.39782 -276.306381) (xy 342.428393 -276.347067) (xy 342.452044 -276.39213) (xy 342.46816 -276.440404)
			(xy 342.476324 -276.490638) (xy 342.476836 -276.516084) (xy 342.476333 -276.541073) (xy 342.78365 -276.541073)
			(xy 342.78365 -276.491095) (xy 342.791469 -276.441732) (xy 342.806913 -276.3942) (xy 342.829603 -276.349668)
			(xy 342.858979 -276.309235) (xy 342.894319 -276.273895) (xy 342.934752 -276.244519) (xy 342.979284 -276.221829)
			(xy 343.026816 -276.206385) (xy 343.076179 -276.198566) (xy 343.126157 -276.198566) (xy 343.17552 -276.206385)
			(xy 343.223052 -276.221829) (xy 343.267584 -276.244519) (xy 343.308017 -276.273895) (xy 343.343357 -276.309235)
			(xy 343.372733 -276.349668) (xy 343.395423 -276.3942) (xy 343.410867 -276.441732) (xy 343.418686 -276.491095)
			(xy 343.419176 -276.516084) (xy 343.724987 -276.516084) (xy 343.729082 -276.465356) (xy 343.741261 -276.415942)
			(xy 343.761209 -276.369122) (xy 343.78841 -276.326108) (xy 343.822158 -276.288014) (xy 343.86158 -276.255827)
			(xy 343.905654 -276.230381) (xy 343.95324 -276.212334) (xy 344.003104 -276.202154) (xy 344.053956 -276.200105)
			(xy 344.104477 -276.206239) (xy 344.153361 -276.220399) (xy 344.19934 -276.242216) (xy 344.241224 -276.271126)
			(xy 344.277928 -276.306381) (xy 344.308501 -276.347067) (xy 344.332152 -276.39213) (xy 344.348268 -276.440404)
			(xy 344.356432 -276.490638) (xy 344.356944 -276.516084) (xy 344.356432 -276.54153) (xy 344.348268 -276.591764)
			(xy 344.332152 -276.640038) (xy 344.308501 -276.685101) (xy 344.277928 -276.725787) (xy 344.241224 -276.761042)
			(xy 344.19934 -276.789952) (xy 344.153361 -276.811769) (xy 344.104477 -276.825929) (xy 344.053956 -276.832063)
			(xy 344.003104 -276.830014) (xy 343.95324 -276.819834) (xy 343.905654 -276.801787) (xy 343.86158 -276.776341)
			(xy 343.822158 -276.744154) (xy 343.78841 -276.70606) (xy 343.761209 -276.663046) (xy 343.741261 -276.616226)
			(xy 343.729082 -276.566812) (xy 343.724987 -276.516084) (xy 343.419176 -276.516084) (xy 343.418686 -276.541073)
			(xy 343.410867 -276.590436) (xy 343.395423 -276.637968) (xy 343.372733 -276.6825) (xy 343.343357 -276.722933)
			(xy 343.308017 -276.758273) (xy 343.267584 -276.787649) (xy 343.223052 -276.810339) (xy 343.17552 -276.825783)
			(xy 343.126157 -276.833602) (xy 343.076179 -276.833602) (xy 343.026816 -276.825783) (xy 342.979284 -276.810339)
			(xy 342.934752 -276.787649) (xy 342.894319 -276.758273) (xy 342.858979 -276.722933) (xy 342.829603 -276.6825)
			(xy 342.806913 -276.637968) (xy 342.791469 -276.590436) (xy 342.78365 -276.541073) (xy 342.476333 -276.541073)
			(xy 342.476324 -276.54153) (xy 342.46816 -276.591764) (xy 342.452044 -276.640038) (xy 342.428393 -276.685101)
			(xy 342.39782 -276.725787) (xy 342.361116 -276.761042) (xy 342.319232 -276.789952) (xy 342.273253 -276.811769)
			(xy 342.224369 -276.825929) (xy 342.173848 -276.832063) (xy 342.122996 -276.830014) (xy 342.073132 -276.819834)
			(xy 342.025546 -276.801787) (xy 341.981472 -276.776341) (xy 341.94205 -276.744154) (xy 341.908302 -276.70606)
			(xy 341.881101 -276.663046) (xy 341.861153 -276.616226) (xy 341.848974 -276.566812) (xy 341.844879 -276.516084)
			(xy 341.539068 -276.516084) (xy 341.538578 -276.541073) (xy 341.530759 -276.590436) (xy 341.515315 -276.637968)
			(xy 341.492625 -276.6825) (xy 341.463249 -276.722933) (xy 341.427909 -276.758273) (xy 341.387476 -276.787649)
			(xy 341.342944 -276.810339) (xy 341.295412 -276.825783) (xy 341.246049 -276.833602) (xy 341.196071 -276.833602)
			(xy 341.146708 -276.825783) (xy 341.099176 -276.810339) (xy 341.054644 -276.787649) (xy 341.014211 -276.758273)
			(xy 340.978871 -276.722933) (xy 340.949495 -276.6825) (xy 340.926805 -276.637968) (xy 340.911361 -276.590436)
			(xy 340.903542 -276.541073) (xy 340.596225 -276.541073) (xy 340.596216 -276.54153) (xy 340.588052 -276.591764)
			(xy 340.571936 -276.640038) (xy 340.548285 -276.685101) (xy 340.517712 -276.725787) (xy 340.481008 -276.761042)
			(xy 340.439124 -276.789952) (xy 340.393145 -276.811769) (xy 340.344261 -276.825929) (xy 340.29374 -276.832063)
			(xy 340.242888 -276.830014) (xy 340.193024 -276.819834) (xy 340.145438 -276.801787) (xy 340.101364 -276.776341)
			(xy 340.061942 -276.744154) (xy 340.028194 -276.70606) (xy 340.000993 -276.663046) (xy 339.981045 -276.616226)
			(xy 339.968866 -276.566812) (xy 339.964771 -276.516084) (xy 339.656928 -276.516084) (xy 339.656416 -276.54153)
			(xy 339.648252 -276.591764) (xy 339.632136 -276.640038) (xy 339.608485 -276.685101) (xy 339.577912 -276.725787)
			(xy 339.541208 -276.761042) (xy 339.499324 -276.789952) (xy 339.453345 -276.811769) (xy 339.404461 -276.825929)
			(xy 339.35394 -276.832063) (xy 339.303088 -276.830014) (xy 339.253224 -276.819834) (xy 339.205638 -276.801787)
			(xy 339.161564 -276.776341) (xy 339.122142 -276.744154) (xy 339.088394 -276.70606) (xy 339.061193 -276.663046)
			(xy 339.041245 -276.616226) (xy 339.029066 -276.566812) (xy 339.024971 -276.516084) (xy 338.718759 -276.516084)
			(xy 338.718759 -276.541095) (xy 338.710938 -276.590469) (xy 338.695489 -276.638012) (xy 338.672792 -276.682552)
			(xy 338.643407 -276.722993) (xy 338.608056 -276.758338) (xy 338.567611 -276.787718) (xy 338.523067 -276.810408)
			(xy 338.475522 -276.82585) (xy 338.426147 -276.833663) (xy 338.401152 -276.834092) (xy 338.377784 -276.833675)
			(xy 338.331553 -276.826823) (xy 338.286825 -276.813274) (xy 338.244563 -276.79332) (xy 338.205679 -276.767391)
			(xy 338.188046 -276.75205) (xy 338.184998 -276.74951) (xy 338.174584 -276.745446) (xy 338.15147 -276.736556)
			(xy 338.14706 -276.736654) (xy 338.138375 -276.738186) (xy 338.134198 -276.739604) (xy 338.084414 -276.761702)
			(xy 338.046314 -276.778466) (xy 338.038013 -276.782862) (xy 338.025206 -276.796583) (xy 338.01831 -276.81404)
			(xy 338.017866 -276.823424) (xy 338.017866 -276.984714) (xy 338.018327 -276.993894) (xy 338.024981 -277.011012)
			(xy 338.0373 -277.024634) (xy 338.045298 -277.029164) (xy 338.049616 -277.030942) (xy 338.072856 -277.040779)
			(xy 338.116143 -277.066718) (xy 338.15479 -277.099168) (xy 338.187827 -277.137315) (xy 338.214424 -277.180201)
			(xy 338.233914 -277.226749) (xy 338.245808 -277.275791) (xy 338.249806 -277.32609) (xy 338.554817 -277.32609)
			(xy 338.558912 -277.275362) (xy 338.571091 -277.225948) (xy 338.591039 -277.179128) (xy 338.61824 -277.136114)
			(xy 338.651988 -277.09802) (xy 338.69141 -277.065833) (xy 338.735484 -277.040387) (xy 338.78307 -277.02234)
			(xy 338.832934 -277.01216) (xy 338.883786 -277.010111) (xy 338.934307 -277.016245) (xy 338.983191 -277.030405)
			(xy 339.02917 -277.052222) (xy 339.071054 -277.081132) (xy 339.107758 -277.116387) (xy 339.138331 -277.157073)
			(xy 339.161982 -277.202136) (xy 339.178098 -277.25041) (xy 339.186262 -277.300644) (xy 339.186774 -277.32609)
			(xy 339.186271 -277.351079) (xy 339.493588 -277.351079) (xy 339.493588 -277.301101) (xy 339.501407 -277.251738)
			(xy 339.516851 -277.204206) (xy 339.539541 -277.159674) (xy 339.568917 -277.119241) (xy 339.604257 -277.083901)
			(xy 339.64469 -277.054525) (xy 339.689222 -277.031835) (xy 339.736754 -277.016391) (xy 339.786117 -277.008572)
			(xy 339.836095 -277.008572) (xy 339.885458 -277.016391) (xy 339.93299 -277.031835) (xy 339.977522 -277.054525)
			(xy 340.017955 -277.083901) (xy 340.053295 -277.119241) (xy 340.082671 -277.159674) (xy 340.105361 -277.204206)
			(xy 340.120805 -277.251738) (xy 340.128624 -277.301101) (xy 340.129114 -277.32609) (xy 340.434925 -277.32609)
			(xy 340.43902 -277.275362) (xy 340.451199 -277.225948) (xy 340.471147 -277.179128) (xy 340.498348 -277.136114)
			(xy 340.532096 -277.09802) (xy 340.571518 -277.065833) (xy 340.615592 -277.040387) (xy 340.663178 -277.02234)
			(xy 340.713042 -277.01216) (xy 340.763894 -277.010111) (xy 340.814415 -277.016245) (xy 340.863299 -277.030405)
			(xy 340.909278 -277.052222) (xy 340.951162 -277.081132) (xy 340.987866 -277.116387) (xy 341.018439 -277.157073)
			(xy 341.04209 -277.202136) (xy 341.058206 -277.25041) (xy 341.06637 -277.300644) (xy 341.066882 -277.32609)
			(xy 341.066379 -277.351079) (xy 341.373696 -277.351079) (xy 341.373696 -277.301101) (xy 341.381515 -277.251738)
			(xy 341.396959 -277.204206) (xy 341.419649 -277.159674) (xy 341.449025 -277.119241) (xy 341.484365 -277.083901)
			(xy 341.524798 -277.054525) (xy 341.56933 -277.031835) (xy 341.616862 -277.016391) (xy 341.666225 -277.008572)
			(xy 341.716203 -277.008572) (xy 341.765566 -277.016391) (xy 341.813098 -277.031835) (xy 341.85763 -277.054525)
			(xy 341.898063 -277.083901) (xy 341.933403 -277.119241) (xy 341.962779 -277.159674) (xy 341.985469 -277.204206)
			(xy 342.000913 -277.251738) (xy 342.008732 -277.301101) (xy 342.009222 -277.32609) (xy 342.314779 -277.32609)
			(xy 342.318874 -277.275362) (xy 342.331053 -277.225948) (xy 342.351001 -277.179128) (xy 342.378202 -277.136114)
			(xy 342.41195 -277.09802) (xy 342.451372 -277.065833) (xy 342.495446 -277.040387) (xy 342.543032 -277.02234)
			(xy 342.592896 -277.01216) (xy 342.643748 -277.010111) (xy 342.694269 -277.016245) (xy 342.743153 -277.030405)
			(xy 342.789132 -277.052222) (xy 342.831016 -277.081132) (xy 342.86772 -277.116387) (xy 342.898293 -277.157073)
			(xy 342.921944 -277.202136) (xy 342.93806 -277.25041) (xy 342.946224 -277.300644) (xy 342.946736 -277.32609)
			(xy 343.254833 -277.32609) (xy 343.258928 -277.275362) (xy 343.271107 -277.225948) (xy 343.291055 -277.179128)
			(xy 343.318256 -277.136114) (xy 343.352004 -277.09802) (xy 343.391426 -277.065833) (xy 343.4355 -277.040387)
			(xy 343.483086 -277.02234) (xy 343.53295 -277.01216) (xy 343.583802 -277.010111) (xy 343.634323 -277.016245)
			(xy 343.683207 -277.030405) (xy 343.729186 -277.052222) (xy 343.77107 -277.081132) (xy 343.807774 -277.116387)
			(xy 343.838347 -277.157073) (xy 343.861998 -277.202136) (xy 343.878114 -277.25041) (xy 343.886278 -277.300644)
			(xy 343.88679 -277.32609) (xy 343.886278 -277.351536) (xy 343.878114 -277.40177) (xy 343.861998 -277.450044)
			(xy 343.838347 -277.495107) (xy 343.807774 -277.535793) (xy 343.77107 -277.571048) (xy 343.729186 -277.599958)
			(xy 343.683207 -277.621775) (xy 343.634323 -277.635935) (xy 343.583802 -277.642069) (xy 343.53295 -277.64002)
			(xy 343.483086 -277.62984) (xy 343.4355 -277.611793) (xy 343.391426 -277.586347) (xy 343.352004 -277.55416)
			(xy 343.318256 -277.516066) (xy 343.291055 -277.473052) (xy 343.271107 -277.426232) (xy 343.258928 -277.376818)
			(xy 343.254833 -277.32609) (xy 342.946736 -277.32609) (xy 342.946224 -277.351536) (xy 342.93806 -277.40177)
			(xy 342.921944 -277.450044) (xy 342.898293 -277.495107) (xy 342.86772 -277.535793) (xy 342.831016 -277.571048)
			(xy 342.789132 -277.599958) (xy 342.743153 -277.621775) (xy 342.694269 -277.635935) (xy 342.643748 -277.642069)
			(xy 342.592896 -277.64002) (xy 342.543032 -277.62984) (xy 342.495446 -277.611793) (xy 342.451372 -277.586347)
			(xy 342.41195 -277.55416) (xy 342.378202 -277.516066) (xy 342.351001 -277.473052) (xy 342.331053 -277.426232)
			(xy 342.318874 -277.376818) (xy 342.314779 -277.32609) (xy 342.009222 -277.32609) (xy 342.008732 -277.351079)
			(xy 342.000913 -277.400442) (xy 341.985469 -277.447974) (xy 341.962779 -277.492506) (xy 341.933403 -277.532939)
			(xy 341.898063 -277.568279) (xy 341.85763 -277.597655) (xy 341.813098 -277.620345) (xy 341.765566 -277.635789)
			(xy 341.716203 -277.643608) (xy 341.666225 -277.643608) (xy 341.616862 -277.635789) (xy 341.56933 -277.620345)
			(xy 341.524798 -277.597655) (xy 341.484365 -277.568279) (xy 341.449025 -277.532939) (xy 341.419649 -277.492506)
			(xy 341.396959 -277.447974) (xy 341.381515 -277.400442) (xy 341.373696 -277.351079) (xy 341.066379 -277.351079)
			(xy 341.06637 -277.351536) (xy 341.058206 -277.40177) (xy 341.04209 -277.450044) (xy 341.018439 -277.495107)
			(xy 340.987866 -277.535793) (xy 340.951162 -277.571048) (xy 340.909278 -277.599958) (xy 340.863299 -277.621775)
			(xy 340.814415 -277.635935) (xy 340.763894 -277.642069) (xy 340.713042 -277.64002) (xy 340.663178 -277.62984)
			(xy 340.615592 -277.611793) (xy 340.571518 -277.586347) (xy 340.532096 -277.55416) (xy 340.498348 -277.516066)
			(xy 340.471147 -277.473052) (xy 340.451199 -277.426232) (xy 340.43902 -277.376818) (xy 340.434925 -277.32609)
			(xy 340.129114 -277.32609) (xy 340.128624 -277.351079) (xy 340.120805 -277.400442) (xy 340.105361 -277.447974)
			(xy 340.082671 -277.492506) (xy 340.053295 -277.532939) (xy 340.017955 -277.568279) (xy 339.977522 -277.597655)
			(xy 339.93299 -277.620345) (xy 339.885458 -277.635789) (xy 339.836095 -277.643608) (xy 339.786117 -277.643608)
			(xy 339.736754 -277.635789) (xy 339.689222 -277.620345) (xy 339.64469 -277.597655) (xy 339.604257 -277.568279)
			(xy 339.568917 -277.532939) (xy 339.539541 -277.492506) (xy 339.516851 -277.447974) (xy 339.501407 -277.400442)
			(xy 339.493588 -277.351079) (xy 339.186271 -277.351079) (xy 339.186262 -277.351536) (xy 339.178098 -277.40177)
			(xy 339.161982 -277.450044) (xy 339.138331 -277.495107) (xy 339.107758 -277.535793) (xy 339.071054 -277.571048)
			(xy 339.02917 -277.599958) (xy 338.983191 -277.621775) (xy 338.934307 -277.635935) (xy 338.883786 -277.642069)
			(xy 338.832934 -277.64002) (xy 338.78307 -277.62984) (xy 338.735484 -277.611793) (xy 338.69141 -277.586347)
			(xy 338.651988 -277.55416) (xy 338.61824 -277.516066) (xy 338.591039 -277.473052) (xy 338.571091 -277.426232)
			(xy 338.558912 -277.376818) (xy 338.554817 -277.32609) (xy 338.249806 -277.32609) (xy 338.249806 -277.326096)
			(xy 338.245809 -277.376402) (xy 338.233917 -277.425444) (xy 338.214428 -277.471993) (xy 338.187832 -277.514879)
			(xy 338.154796 -277.553027) (xy 338.116149 -277.585477) (xy 338.072863 -277.611417) (xy 338.049616 -277.621238)
			(xy 338.045298 -277.623016) (xy 338.03728 -277.627525) (xy 338.024936 -277.64114) (xy 338.018297 -277.658278)
			(xy 338.017866 -277.667466) (xy 338.017866 -277.828756) (xy 338.018315 -277.83813) (xy 338.025253 -277.855554)
			(xy 338.038047 -277.869267) (xy 338.046314 -277.873714) (xy 338.084414 -277.890478) (xy 338.134198 -277.912576)
			(xy 338.138371 -277.914008) (xy 338.147059 -277.915545) (xy 338.15147 -277.915624) (xy 338.174584 -277.906734)
			(xy 338.184998 -277.90267) (xy 338.188046 -277.90013) (xy 338.205659 -277.884765) (xy 338.244547 -277.85884)
			(xy 338.286814 -277.838892) (xy 338.331548 -277.825352) (xy 338.377783 -277.818512) (xy 338.401152 -277.818088)
			(xy 338.426146 -277.818549) (xy 338.475519 -277.826362) (xy 338.523063 -277.841803) (xy 338.567605 -277.864493)
			(xy 338.608048 -277.893871) (xy 338.643398 -277.929215) (xy 338.672782 -277.969654) (xy 338.695478 -278.014193)
			(xy 338.710927 -278.061734) (xy 338.718747 -278.111106) (xy 338.718747 -278.136096) (xy 339.024971 -278.136096)
			(xy 339.029066 -278.085368) (xy 339.041245 -278.035954) (xy 339.061193 -277.989134) (xy 339.088394 -277.94612)
			(xy 339.122142 -277.908026) (xy 339.161564 -277.875839) (xy 339.205638 -277.850393) (xy 339.253224 -277.832346)
			(xy 339.303088 -277.822166) (xy 339.35394 -277.820117) (xy 339.404461 -277.826251) (xy 339.453345 -277.840411)
			(xy 339.499324 -277.862228) (xy 339.541208 -277.891138) (xy 339.577912 -277.926393) (xy 339.608485 -277.967079)
			(xy 339.632136 -278.012142) (xy 339.648252 -278.060416) (xy 339.656416 -278.11065) (xy 339.656928 -278.136096)
			(xy 339.964771 -278.136096) (xy 339.968866 -278.085368) (xy 339.981045 -278.035954) (xy 340.000993 -277.989134)
			(xy 340.028194 -277.94612) (xy 340.061942 -277.908026) (xy 340.101364 -277.875839) (xy 340.145438 -277.850393)
			(xy 340.193024 -277.832346) (xy 340.242888 -277.822166) (xy 340.29374 -277.820117) (xy 340.344261 -277.826251)
			(xy 340.393145 -277.840411) (xy 340.439124 -277.862228) (xy 340.481008 -277.891138) (xy 340.517712 -277.926393)
			(xy 340.548285 -277.967079) (xy 340.571936 -278.012142) (xy 340.588052 -278.060416) (xy 340.596216 -278.11065)
			(xy 340.596728 -278.136096) (xy 341.844879 -278.136096) (xy 341.848974 -278.085368) (xy 341.861153 -278.035954)
			(xy 341.881101 -277.989134) (xy 341.908302 -277.94612) (xy 341.94205 -277.908026) (xy 341.981472 -277.875839)
			(xy 342.025546 -277.850393) (xy 342.073132 -277.832346) (xy 342.122996 -277.822166) (xy 342.173848 -277.820117)
			(xy 342.224369 -277.826251) (xy 342.273253 -277.840411) (xy 342.319232 -277.862228) (xy 342.361116 -277.891138)
			(xy 342.39782 -277.926393) (xy 342.428393 -277.967079) (xy 342.452044 -278.012142) (xy 342.46816 -278.060416)
			(xy 342.476324 -278.11065) (xy 342.476836 -278.136096) (xy 342.476333 -278.161085) (xy 342.78365 -278.161085)
			(xy 342.78365 -278.111107) (xy 342.791469 -278.061744) (xy 342.806913 -278.014212) (xy 342.829603 -277.96968)
			(xy 342.858979 -277.929247) (xy 342.894319 -277.893907) (xy 342.934752 -277.864531) (xy 342.979284 -277.841841)
			(xy 343.026816 -277.826397) (xy 343.076179 -277.818578) (xy 343.126157 -277.818578) (xy 343.17552 -277.826397)
			(xy 343.223052 -277.841841) (xy 343.267584 -277.864531) (xy 343.308017 -277.893907) (xy 343.343357 -277.929247)
			(xy 343.372733 -277.96968) (xy 343.395423 -278.014212) (xy 343.410867 -278.061744) (xy 343.418686 -278.111107)
			(xy 343.419176 -278.136096) (xy 343.724987 -278.136096) (xy 343.729082 -278.085368) (xy 343.741261 -278.035954)
			(xy 343.761209 -277.989134) (xy 343.78841 -277.94612) (xy 343.822158 -277.908026) (xy 343.86158 -277.875839)
			(xy 343.905654 -277.850393) (xy 343.95324 -277.832346) (xy 344.003104 -277.822166) (xy 344.053956 -277.820117)
			(xy 344.104477 -277.826251) (xy 344.153361 -277.840411) (xy 344.19934 -277.862228) (xy 344.241224 -277.891138)
			(xy 344.277928 -277.926393) (xy 344.308501 -277.967079) (xy 344.332152 -278.012142) (xy 344.348268 -278.060416)
			(xy 344.356432 -278.11065) (xy 344.356944 -278.136096) (xy 344.356432 -278.161542) (xy 344.348268 -278.211776)
			(xy 344.332152 -278.26005) (xy 344.308501 -278.305113) (xy 344.277928 -278.345799) (xy 344.241224 -278.381054)
			(xy 344.19934 -278.409964) (xy 344.153361 -278.431781) (xy 344.104477 -278.445941) (xy 344.053956 -278.452075)
			(xy 344.003104 -278.450026) (xy 343.95324 -278.439846) (xy 343.905654 -278.421799) (xy 343.86158 -278.396353)
			(xy 343.822158 -278.364166) (xy 343.78841 -278.326072) (xy 343.761209 -278.283058) (xy 343.741261 -278.236238)
			(xy 343.729082 -278.186824) (xy 343.724987 -278.136096) (xy 343.419176 -278.136096) (xy 343.418686 -278.161085)
			(xy 343.410867 -278.210448) (xy 343.395423 -278.25798) (xy 343.372733 -278.302512) (xy 343.343357 -278.342945)
			(xy 343.308017 -278.378285) (xy 343.267584 -278.407661) (xy 343.223052 -278.430351) (xy 343.17552 -278.445795)
			(xy 343.126157 -278.453614) (xy 343.076179 -278.453614) (xy 343.026816 -278.445795) (xy 342.979284 -278.430351)
			(xy 342.934752 -278.407661) (xy 342.894319 -278.378285) (xy 342.858979 -278.342945) (xy 342.829603 -278.302512)
			(xy 342.806913 -278.25798) (xy 342.791469 -278.210448) (xy 342.78365 -278.161085) (xy 342.476333 -278.161085)
			(xy 342.476324 -278.161542) (xy 342.46816 -278.211776) (xy 342.452044 -278.26005) (xy 342.428393 -278.305113)
			(xy 342.39782 -278.345799) (xy 342.361116 -278.381054) (xy 342.319232 -278.409964) (xy 342.273253 -278.431781)
			(xy 342.224369 -278.445941) (xy 342.173848 -278.452075) (xy 342.122996 -278.450026) (xy 342.073132 -278.439846)
			(xy 342.025546 -278.421799) (xy 341.981472 -278.396353) (xy 341.94205 -278.364166) (xy 341.908302 -278.326072)
			(xy 341.881101 -278.283058) (xy 341.861153 -278.236238) (xy 341.848974 -278.186824) (xy 341.844879 -278.136096)
			(xy 340.596728 -278.136096) (xy 340.596216 -278.161542) (xy 340.588052 -278.211776) (xy 340.571936 -278.26005)
			(xy 340.548285 -278.305113) (xy 340.517712 -278.345799) (xy 340.481008 -278.381054) (xy 340.439124 -278.409964)
			(xy 340.393145 -278.431781) (xy 340.344261 -278.445941) (xy 340.29374 -278.452075) (xy 340.242888 -278.450026)
			(xy 340.193024 -278.439846) (xy 340.145438 -278.421799) (xy 340.101364 -278.396353) (xy 340.061942 -278.364166)
			(xy 340.028194 -278.326072) (xy 340.000993 -278.283058) (xy 339.981045 -278.236238) (xy 339.968866 -278.186824)
			(xy 339.964771 -278.136096) (xy 339.656928 -278.136096) (xy 339.656416 -278.161542) (xy 339.648252 -278.211776)
			(xy 339.632136 -278.26005) (xy 339.608485 -278.305113) (xy 339.577912 -278.345799) (xy 339.541208 -278.381054)
			(xy 339.499324 -278.409964) (xy 339.453345 -278.431781) (xy 339.404461 -278.445941) (xy 339.35394 -278.452075)
			(xy 339.303088 -278.450026) (xy 339.253224 -278.439846) (xy 339.205638 -278.421799) (xy 339.161564 -278.396353)
			(xy 339.122142 -278.364166) (xy 339.088394 -278.326072) (xy 339.061193 -278.283058) (xy 339.041245 -278.236238)
			(xy 339.029066 -278.186824) (xy 339.024971 -278.136096) (xy 338.718747 -278.136096) (xy 338.718747 -278.161094)
			(xy 338.710927 -278.210466) (xy 338.695478 -278.258007) (xy 338.672782 -278.302546) (xy 338.643398 -278.342985)
			(xy 338.608048 -278.378329) (xy 338.567605 -278.407707) (xy 338.523063 -278.430397) (xy 338.475519 -278.445838)
			(xy 338.426146 -278.453651) (xy 338.401152 -278.454104) (xy 338.377784 -278.453687) (xy 338.331553 -278.446835)
			(xy 338.286824 -278.433286) (xy 338.244562 -278.413333) (xy 338.205677 -278.387405) (xy 338.188046 -278.372062)
			(xy 338.184998 -278.369522) (xy 338.174584 -278.365458) (xy 338.15147 -278.356568) (xy 338.14706 -278.356666)
			(xy 338.138375 -278.358199) (xy 338.134198 -278.359616) (xy 338.084414 -278.381714) (xy 338.046314 -278.398478)
			(xy 338.038015 -278.402874) (xy 338.025211 -278.416597) (xy 338.018319 -278.434053) (xy 338.017866 -278.443436)
			(xy 338.017866 -278.604726) (xy 338.018329 -278.613905) (xy 338.024986 -278.63102) (xy 338.037305 -278.644638)
			(xy 338.045298 -278.649176) (xy 338.049616 -278.650954) (xy 338.072855 -278.660791) (xy 338.116141 -278.68673)
			(xy 338.154786 -278.719179) (xy 338.187821 -278.757325) (xy 338.214416 -278.80021) (xy 338.233905 -278.846757)
			(xy 338.245797 -278.895797) (xy 338.249795 -278.946101) (xy 338.249795 -278.946102) (xy 338.554817 -278.946102)
			(xy 338.558912 -278.895374) (xy 338.571091 -278.84596) (xy 338.591039 -278.79914) (xy 338.61824 -278.756126)
			(xy 338.651988 -278.718032) (xy 338.69141 -278.685845) (xy 338.735484 -278.660399) (xy 338.78307 -278.642352)
			(xy 338.832934 -278.632172) (xy 338.883786 -278.630123) (xy 338.934307 -278.636257) (xy 338.983191 -278.650417)
			(xy 339.02917 -278.672234) (xy 339.071054 -278.701144) (xy 339.107758 -278.736399) (xy 339.138331 -278.777085)
			(xy 339.161982 -278.822148) (xy 339.178098 -278.870422) (xy 339.186262 -278.920656) (xy 339.186774 -278.946102)
			(xy 339.186271 -278.971091) (xy 339.493588 -278.971091) (xy 339.493588 -278.921113) (xy 339.501407 -278.87175)
			(xy 339.516851 -278.824218) (xy 339.539541 -278.779686) (xy 339.568917 -278.739253) (xy 339.604257 -278.703913)
			(xy 339.64469 -278.674537) (xy 339.689222 -278.651847) (xy 339.736754 -278.636403) (xy 339.786117 -278.628584)
			(xy 339.836095 -278.628584) (xy 339.885458 -278.636403) (xy 339.93299 -278.651847) (xy 339.977522 -278.674537)
			(xy 340.017955 -278.703913) (xy 340.053295 -278.739253) (xy 340.082671 -278.779686) (xy 340.105361 -278.824218)
			(xy 340.120805 -278.87175) (xy 340.128624 -278.921113) (xy 340.129114 -278.946102) (xy 340.434925 -278.946102)
			(xy 340.43902 -278.895374) (xy 340.451199 -278.84596) (xy 340.471147 -278.79914) (xy 340.498348 -278.756126)
			(xy 340.532096 -278.718032) (xy 340.571518 -278.685845) (xy 340.615592 -278.660399) (xy 340.663178 -278.642352)
			(xy 340.713042 -278.632172) (xy 340.763894 -278.630123) (xy 340.814415 -278.636257) (xy 340.863299 -278.650417)
			(xy 340.909278 -278.672234) (xy 340.951162 -278.701144) (xy 340.987866 -278.736399) (xy 341.018439 -278.777085)
			(xy 341.04209 -278.822148) (xy 341.058206 -278.870422) (xy 341.06637 -278.920656) (xy 341.066882 -278.946102)
			(xy 341.066379 -278.971091) (xy 341.373696 -278.971091) (xy 341.373696 -278.921113) (xy 341.381515 -278.87175)
			(xy 341.396959 -278.824218) (xy 341.419649 -278.779686) (xy 341.449025 -278.739253) (xy 341.484365 -278.703913)
			(xy 341.524798 -278.674537) (xy 341.56933 -278.651847) (xy 341.616862 -278.636403) (xy 341.666225 -278.628584)
			(xy 341.716203 -278.628584) (xy 341.765566 -278.636403) (xy 341.813098 -278.651847) (xy 341.85763 -278.674537)
			(xy 341.898063 -278.703913) (xy 341.933403 -278.739253) (xy 341.962779 -278.779686) (xy 341.985469 -278.824218)
			(xy 342.000913 -278.87175) (xy 342.008732 -278.921113) (xy 342.009222 -278.946102) (xy 342.314779 -278.946102)
			(xy 342.318874 -278.895374) (xy 342.331053 -278.84596) (xy 342.351001 -278.79914) (xy 342.378202 -278.756126)
			(xy 342.41195 -278.718032) (xy 342.451372 -278.685845) (xy 342.495446 -278.660399) (xy 342.543032 -278.642352)
			(xy 342.592896 -278.632172) (xy 342.643748 -278.630123) (xy 342.694269 -278.636257) (xy 342.743153 -278.650417)
			(xy 342.789132 -278.672234) (xy 342.831016 -278.701144) (xy 342.86772 -278.736399) (xy 342.898293 -278.777085)
			(xy 342.921944 -278.822148) (xy 342.93806 -278.870422) (xy 342.946224 -278.920656) (xy 342.946736 -278.946102)
			(xy 343.254833 -278.946102) (xy 343.258928 -278.895374) (xy 343.271107 -278.84596) (xy 343.291055 -278.79914)
			(xy 343.318256 -278.756126) (xy 343.352004 -278.718032) (xy 343.391426 -278.685845) (xy 343.4355 -278.660399)
			(xy 343.483086 -278.642352) (xy 343.53295 -278.632172) (xy 343.583802 -278.630123) (xy 343.634323 -278.636257)
			(xy 343.683207 -278.650417) (xy 343.729186 -278.672234) (xy 343.77107 -278.701144) (xy 343.807774 -278.736399)
			(xy 343.838347 -278.777085) (xy 343.861998 -278.822148) (xy 343.878114 -278.870422) (xy 343.886278 -278.920656)
			(xy 343.88679 -278.946102) (xy 343.886278 -278.971548) (xy 343.878114 -279.021782) (xy 343.861998 -279.070056)
			(xy 343.838347 -279.115119) (xy 343.807774 -279.155805) (xy 343.77107 -279.19106) (xy 343.729186 -279.21997)
			(xy 343.683207 -279.241787) (xy 343.634323 -279.255947) (xy 343.583802 -279.262081) (xy 343.53295 -279.260032)
			(xy 343.483086 -279.249852) (xy 343.4355 -279.231805) (xy 343.391426 -279.206359) (xy 343.352004 -279.174172)
			(xy 343.318256 -279.136078) (xy 343.291055 -279.093064) (xy 343.271107 -279.046244) (xy 343.258928 -278.99683)
			(xy 343.254833 -278.946102) (xy 342.946736 -278.946102) (xy 342.946224 -278.971548) (xy 342.93806 -279.021782)
			(xy 342.921944 -279.070056) (xy 342.898293 -279.115119) (xy 342.86772 -279.155805) (xy 342.831016 -279.19106)
			(xy 342.789132 -279.21997) (xy 342.743153 -279.241787) (xy 342.694269 -279.255947) (xy 342.643748 -279.262081)
			(xy 342.592896 -279.260032) (xy 342.543032 -279.249852) (xy 342.495446 -279.231805) (xy 342.451372 -279.206359)
			(xy 342.41195 -279.174172) (xy 342.378202 -279.136078) (xy 342.351001 -279.093064) (xy 342.331053 -279.046244)
			(xy 342.318874 -278.99683) (xy 342.314779 -278.946102) (xy 342.009222 -278.946102) (xy 342.008732 -278.971091)
			(xy 342.000913 -279.020454) (xy 341.985469 -279.067986) (xy 341.962779 -279.112518) (xy 341.933403 -279.152951)
			(xy 341.898063 -279.188291) (xy 341.85763 -279.217667) (xy 341.813098 -279.240357) (xy 341.765566 -279.255801)
			(xy 341.716203 -279.26362) (xy 341.666225 -279.26362) (xy 341.616862 -279.255801) (xy 341.56933 -279.240357)
			(xy 341.524798 -279.217667) (xy 341.484365 -279.188291) (xy 341.449025 -279.152951) (xy 341.419649 -279.112518)
			(xy 341.396959 -279.067986) (xy 341.381515 -279.020454) (xy 341.373696 -278.971091) (xy 341.066379 -278.971091)
			(xy 341.06637 -278.971548) (xy 341.058206 -279.021782) (xy 341.04209 -279.070056) (xy 341.018439 -279.115119)
			(xy 340.987866 -279.155805) (xy 340.951162 -279.19106) (xy 340.909278 -279.21997) (xy 340.863299 -279.241787)
			(xy 340.814415 -279.255947) (xy 340.763894 -279.262081) (xy 340.713042 -279.260032) (xy 340.663178 -279.249852)
			(xy 340.615592 -279.231805) (xy 340.571518 -279.206359) (xy 340.532096 -279.174172) (xy 340.498348 -279.136078)
			(xy 340.471147 -279.093064) (xy 340.451199 -279.046244) (xy 340.43902 -278.99683) (xy 340.434925 -278.946102)
			(xy 340.129114 -278.946102) (xy 340.128624 -278.971091) (xy 340.120805 -279.020454) (xy 340.105361 -279.067986)
			(xy 340.082671 -279.112518) (xy 340.053295 -279.152951) (xy 340.017955 -279.188291) (xy 339.977522 -279.217667)
			(xy 339.93299 -279.240357) (xy 339.885458 -279.255801) (xy 339.836095 -279.26362) (xy 339.786117 -279.26362)
			(xy 339.736754 -279.255801) (xy 339.689222 -279.240357) (xy 339.64469 -279.217667) (xy 339.604257 -279.188291)
			(xy 339.568917 -279.152951) (xy 339.539541 -279.112518) (xy 339.516851 -279.067986) (xy 339.501407 -279.020454)
			(xy 339.493588 -278.971091) (xy 339.186271 -278.971091) (xy 339.186262 -278.971548) (xy 339.178098 -279.021782)
			(xy 339.161982 -279.070056) (xy 339.138331 -279.115119) (xy 339.107758 -279.155805) (xy 339.071054 -279.19106)
			(xy 339.02917 -279.21997) (xy 338.983191 -279.241787) (xy 338.934307 -279.255947) (xy 338.883786 -279.262081)
			(xy 338.832934 -279.260032) (xy 338.78307 -279.249852) (xy 338.735484 -279.231805) (xy 338.69141 -279.206359)
			(xy 338.651988 -279.174172) (xy 338.61824 -279.136078) (xy 338.591039 -279.093064) (xy 338.571091 -279.046244)
			(xy 338.558912 -278.99683) (xy 338.554817 -278.946102) (xy 338.249795 -278.946102) (xy 338.245797 -278.996404)
			(xy 338.233905 -279.045445) (xy 338.214416 -279.091992) (xy 338.18782 -279.134876) (xy 338.154785 -279.173022)
			(xy 338.116139 -279.205471) (xy 338.072854 -279.231409) (xy 338.049616 -279.24125) (xy 338.045298 -279.243028)
			(xy 338.037282 -279.247537) (xy 338.02494 -279.261153) (xy 338.018305 -279.278291) (xy 338.017866 -279.287478)
			(xy 338.017866 -279.448768) (xy 338.0183 -279.458151) (xy 338.025219 -279.4756) (xy 338.03801 -279.489339)
			(xy 338.046314 -279.493726) (xy 338.084414 -279.51049) (xy 338.134198 -279.532588) (xy 338.138372 -279.534019)
			(xy 338.147059 -279.535556) (xy 338.15147 -279.535636) (xy 338.174584 -279.526746) (xy 338.184998 -279.522682)
			(xy 338.188046 -279.520142) (xy 338.205659 -279.504777) (xy 338.244547 -279.47885) (xy 338.286814 -279.458902)
			(xy 338.331548 -279.445361) (xy 338.377783 -279.438521) (xy 338.401152 -279.4381) (xy 338.426145 -279.438561)
			(xy 338.475517 -279.446374) (xy 338.523058 -279.461814) (xy 338.567598 -279.484503) (xy 338.60804 -279.51388)
			(xy 338.643389 -279.549223) (xy 338.672772 -279.589661) (xy 338.695467 -279.634198) (xy 338.710915 -279.681737)
			(xy 338.718735 -279.731107) (xy 338.718735 -279.756108) (xy 339.024971 -279.756108) (xy 339.029066 -279.70538)
			(xy 339.041245 -279.655966) (xy 339.061193 -279.609146) (xy 339.088394 -279.566132) (xy 339.122142 -279.528038)
			(xy 339.161564 -279.495851) (xy 339.205638 -279.470405) (xy 339.253224 -279.452358) (xy 339.303088 -279.442178)
			(xy 339.35394 -279.440129) (xy 339.404461 -279.446263) (xy 339.453345 -279.460423) (xy 339.499324 -279.48224)
			(xy 339.541208 -279.51115) (xy 339.577912 -279.546405) (xy 339.608485 -279.587091) (xy 339.632136 -279.632154)
			(xy 339.648252 -279.680428) (xy 339.656416 -279.730662) (xy 339.656928 -279.756108) (xy 339.964771 -279.756108)
			(xy 339.968866 -279.70538) (xy 339.981045 -279.655966) (xy 340.000993 -279.609146) (xy 340.028194 -279.566132)
			(xy 340.061942 -279.528038) (xy 340.101364 -279.495851) (xy 340.145438 -279.470405) (xy 340.193024 -279.452358)
			(xy 340.242888 -279.442178) (xy 340.29374 -279.440129) (xy 340.344261 -279.446263) (xy 340.393145 -279.460423)
			(xy 340.439124 -279.48224) (xy 340.481008 -279.51115) (xy 340.517712 -279.546405) (xy 340.548285 -279.587091)
			(xy 340.571936 -279.632154) (xy 340.588052 -279.680428) (xy 340.596216 -279.730662) (xy 340.596728 -279.756108)
			(xy 340.596225 -279.781097) (xy 340.903542 -279.781097) (xy 340.903542 -279.731119) (xy 340.911361 -279.681756)
			(xy 340.926805 -279.634224) (xy 340.949495 -279.589692) (xy 340.978871 -279.549259) (xy 341.014211 -279.513919)
			(xy 341.054644 -279.484543) (xy 341.099176 -279.461853) (xy 341.146708 -279.446409) (xy 341.196071 -279.43859)
			(xy 341.246049 -279.43859) (xy 341.295412 -279.446409) (xy 341.342944 -279.461853) (xy 341.387476 -279.484543)
			(xy 341.427909 -279.513919) (xy 341.463249 -279.549259) (xy 341.492625 -279.589692) (xy 341.515315 -279.634224)
			(xy 341.530759 -279.681756) (xy 341.538578 -279.731119) (xy 341.539068 -279.756108) (xy 341.844879 -279.756108)
			(xy 341.848974 -279.70538) (xy 341.861153 -279.655966) (xy 341.881101 -279.609146) (xy 341.908302 -279.566132)
			(xy 341.94205 -279.528038) (xy 341.981472 -279.495851) (xy 342.025546 -279.470405) (xy 342.073132 -279.452358)
			(xy 342.122996 -279.442178) (xy 342.173848 -279.440129) (xy 342.224369 -279.446263) (xy 342.273253 -279.460423)
			(xy 342.319232 -279.48224) (xy 342.361116 -279.51115) (xy 342.39782 -279.546405) (xy 342.428393 -279.587091)
			(xy 342.452044 -279.632154) (xy 342.46816 -279.680428) (xy 342.476324 -279.730662) (xy 342.476836 -279.756108)
			(xy 342.476333 -279.781097) (xy 342.78365 -279.781097) (xy 342.78365 -279.731119) (xy 342.791469 -279.681756)
			(xy 342.806913 -279.634224) (xy 342.829603 -279.589692) (xy 342.858979 -279.549259) (xy 342.894319 -279.513919)
			(xy 342.934752 -279.484543) (xy 342.979284 -279.461853) (xy 343.026816 -279.446409) (xy 343.076179 -279.43859)
			(xy 343.126157 -279.43859) (xy 343.17552 -279.446409) (xy 343.223052 -279.461853) (xy 343.267584 -279.484543)
			(xy 343.308017 -279.513919) (xy 343.343357 -279.549259) (xy 343.372733 -279.589692) (xy 343.395423 -279.634224)
			(xy 343.410867 -279.681756) (xy 343.418686 -279.731119) (xy 343.419176 -279.756108) (xy 343.724987 -279.756108)
			(xy 343.729082 -279.70538) (xy 343.741261 -279.655966) (xy 343.761209 -279.609146) (xy 343.78841 -279.566132)
			(xy 343.822158 -279.528038) (xy 343.86158 -279.495851) (xy 343.905654 -279.470405) (xy 343.95324 -279.452358)
			(xy 344.003104 -279.442178) (xy 344.053956 -279.440129) (xy 344.104477 -279.446263) (xy 344.153361 -279.460423)
			(xy 344.19934 -279.48224) (xy 344.241224 -279.51115) (xy 344.277928 -279.546405) (xy 344.308501 -279.587091)
			(xy 344.332152 -279.632154) (xy 344.348268 -279.680428) (xy 344.356432 -279.730662) (xy 344.356944 -279.756108)
			(xy 344.356432 -279.781554) (xy 344.348268 -279.831788) (xy 344.332152 -279.880062) (xy 344.308501 -279.925125)
			(xy 344.277928 -279.965811) (xy 344.241224 -280.001066) (xy 344.19934 -280.029976) (xy 344.153361 -280.051793)
			(xy 344.104477 -280.065953) (xy 344.053956 -280.072087) (xy 344.003104 -280.070038) (xy 343.95324 -280.059858)
			(xy 343.905654 -280.041811) (xy 343.86158 -280.016365) (xy 343.822158 -279.984178) (xy 343.78841 -279.946084)
			(xy 343.761209 -279.90307) (xy 343.741261 -279.85625) (xy 343.729082 -279.806836) (xy 343.724987 -279.756108)
			(xy 343.419176 -279.756108) (xy 343.418686 -279.781097) (xy 343.410867 -279.83046) (xy 343.395423 -279.877992)
			(xy 343.372733 -279.922524) (xy 343.343357 -279.962957) (xy 343.308017 -279.998297) (xy 343.267584 -280.027673)
			(xy 343.223052 -280.050363) (xy 343.17552 -280.065807) (xy 343.126157 -280.073626) (xy 343.076179 -280.073626)
			(xy 343.026816 -280.065807) (xy 342.979284 -280.050363) (xy 342.934752 -280.027673) (xy 342.894319 -279.998297)
			(xy 342.858979 -279.962957) (xy 342.829603 -279.922524) (xy 342.806913 -279.877992) (xy 342.791469 -279.83046)
			(xy 342.78365 -279.781097) (xy 342.476333 -279.781097) (xy 342.476324 -279.781554) (xy 342.46816 -279.831788)
			(xy 342.452044 -279.880062) (xy 342.428393 -279.925125) (xy 342.39782 -279.965811) (xy 342.361116 -280.001066)
			(xy 342.319232 -280.029976) (xy 342.273253 -280.051793) (xy 342.224369 -280.065953) (xy 342.173848 -280.072087)
			(xy 342.122996 -280.070038) (xy 342.073132 -280.059858) (xy 342.025546 -280.041811) (xy 341.981472 -280.016365)
			(xy 341.94205 -279.984178) (xy 341.908302 -279.946084) (xy 341.881101 -279.90307) (xy 341.861153 -279.85625)
			(xy 341.848974 -279.806836) (xy 341.844879 -279.756108) (xy 341.539068 -279.756108) (xy 341.538578 -279.781097)
			(xy 341.530759 -279.83046) (xy 341.515315 -279.877992) (xy 341.492625 -279.922524) (xy 341.463249 -279.962957)
			(xy 341.427909 -279.998297) (xy 341.387476 -280.027673) (xy 341.342944 -280.050363) (xy 341.295412 -280.065807)
			(xy 341.246049 -280.073626) (xy 341.196071 -280.073626) (xy 341.146708 -280.065807) (xy 341.099176 -280.050363)
			(xy 341.054644 -280.027673) (xy 341.014211 -279.998297) (xy 340.978871 -279.962957) (xy 340.949495 -279.922524)
			(xy 340.926805 -279.877992) (xy 340.911361 -279.83046) (xy 340.903542 -279.781097) (xy 340.596225 -279.781097)
			(xy 340.596216 -279.781554) (xy 340.588052 -279.831788) (xy 340.571936 -279.880062) (xy 340.548285 -279.925125)
			(xy 340.517712 -279.965811) (xy 340.481008 -280.001066) (xy 340.439124 -280.029976) (xy 340.393145 -280.051793)
			(xy 340.344261 -280.065953) (xy 340.29374 -280.072087) (xy 340.242888 -280.070038) (xy 340.193024 -280.059858)
			(xy 340.145438 -280.041811) (xy 340.101364 -280.016365) (xy 340.061942 -279.984178) (xy 340.028194 -279.946084)
			(xy 340.000993 -279.90307) (xy 339.981045 -279.85625) (xy 339.968866 -279.806836) (xy 339.964771 -279.756108)
			(xy 339.656928 -279.756108) (xy 339.656416 -279.781554) (xy 339.648252 -279.831788) (xy 339.632136 -279.880062)
			(xy 339.608485 -279.925125) (xy 339.577912 -279.965811) (xy 339.541208 -280.001066) (xy 339.499324 -280.029976)
			(xy 339.453345 -280.051793) (xy 339.404461 -280.065953) (xy 339.35394 -280.072087) (xy 339.303088 -280.070038)
			(xy 339.253224 -280.059858) (xy 339.205638 -280.041811) (xy 339.161564 -280.016365) (xy 339.122142 -279.984178)
			(xy 339.088394 -279.946084) (xy 339.061193 -279.90307) (xy 339.041245 -279.85625) (xy 339.029066 -279.806836)
			(xy 339.024971 -279.756108) (xy 338.718735 -279.756108) (xy 338.718735 -279.781093) (xy 338.710915 -279.830463)
			(xy 338.695467 -279.878002) (xy 338.672772 -279.922539) (xy 338.643389 -279.962977) (xy 338.60804 -279.99832)
			(xy 338.567598 -280.027697) (xy 338.523058 -280.050386) (xy 338.475517 -280.065826) (xy 338.426145 -280.073639)
			(xy 338.401152 -280.074116) (xy 338.377784 -280.073699) (xy 338.331553 -280.066847) (xy 338.286823 -280.053299)
			(xy 338.244561 -280.033346) (xy 338.205676 -280.007419) (xy 338.188046 -279.992074) (xy 338.184998 -279.989534)
			(xy 338.174584 -279.98547) (xy 338.15147 -279.97658) (xy 338.14706 -279.976678) (xy 338.138375 -279.978211)
			(xy 338.134198 -279.979628) (xy 338.084414 -280.001726) (xy 338.046314 -280.01849) (xy 338.038016 -280.022887)
			(xy 338.025216 -280.03661) (xy 338.018328 -280.054066) (xy 338.017866 -280.063448) (xy 338.017866 -280.224738)
			(xy 338.018331 -280.233916) (xy 338.02499 -280.251027) (xy 338.03731 -280.264642) (xy 338.045298 -280.269188)
			(xy 338.049616 -280.270966) (xy 338.072854 -280.280803) (xy 338.116138 -280.306742) (xy 338.154781 -280.33919)
			(xy 338.187814 -280.377335) (xy 338.214409 -280.420219) (xy 338.233896 -280.466764) (xy 338.245787 -280.515803)
			(xy 338.249784 -280.566105) (xy 338.249783 -280.566114) (xy 338.554817 -280.566114) (xy 338.558912 -280.515386)
			(xy 338.571091 -280.465972) (xy 338.591039 -280.419152) (xy 338.61824 -280.376138) (xy 338.651988 -280.338044)
			(xy 338.69141 -280.305857) (xy 338.735484 -280.280411) (xy 338.78307 -280.262364) (xy 338.832934 -280.252184)
			(xy 338.883786 -280.250135) (xy 338.934307 -280.256269) (xy 338.983191 -280.270429) (xy 339.02917 -280.292246)
			(xy 339.071054 -280.321156) (xy 339.107758 -280.356411) (xy 339.138331 -280.397097) (xy 339.161982 -280.44216)
			(xy 339.178098 -280.490434) (xy 339.186262 -280.540668) (xy 339.186774 -280.566114) (xy 339.186271 -280.591103)
			(xy 339.493588 -280.591103) (xy 339.493588 -280.541125) (xy 339.501407 -280.491762) (xy 339.516851 -280.44423)
			(xy 339.539541 -280.399698) (xy 339.568917 -280.359265) (xy 339.604257 -280.323925) (xy 339.64469 -280.294549)
			(xy 339.689222 -280.271859) (xy 339.736754 -280.256415) (xy 339.786117 -280.248596) (xy 339.836095 -280.248596)
			(xy 339.885458 -280.256415) (xy 339.93299 -280.271859) (xy 339.977522 -280.294549) (xy 340.017955 -280.323925)
			(xy 340.053295 -280.359265) (xy 340.082671 -280.399698) (xy 340.105361 -280.44423) (xy 340.120805 -280.491762)
			(xy 340.128624 -280.541125) (xy 340.129114 -280.566114) (xy 340.434925 -280.566114) (xy 340.43902 -280.515386)
			(xy 340.451199 -280.465972) (xy 340.471147 -280.419152) (xy 340.498348 -280.376138) (xy 340.532096 -280.338044)
			(xy 340.571518 -280.305857) (xy 340.615592 -280.280411) (xy 340.663178 -280.262364) (xy 340.713042 -280.252184)
			(xy 340.763894 -280.250135) (xy 340.814415 -280.256269) (xy 340.863299 -280.270429) (xy 340.909278 -280.292246)
			(xy 340.951162 -280.321156) (xy 340.987866 -280.356411) (xy 341.018439 -280.397097) (xy 341.04209 -280.44216)
			(xy 341.058206 -280.490434) (xy 341.06637 -280.540668) (xy 341.066882 -280.566114) (xy 342.314779 -280.566114)
			(xy 342.318874 -280.515386) (xy 342.331053 -280.465972) (xy 342.351001 -280.419152) (xy 342.378202 -280.376138)
			(xy 342.41195 -280.338044) (xy 342.451372 -280.305857) (xy 342.495446 -280.280411) (xy 342.543032 -280.262364)
			(xy 342.592896 -280.252184) (xy 342.643748 -280.250135) (xy 342.694269 -280.256269) (xy 342.743153 -280.270429)
			(xy 342.789132 -280.292246) (xy 342.831016 -280.321156) (xy 342.86772 -280.356411) (xy 342.898293 -280.397097)
			(xy 342.921944 -280.44216) (xy 342.93806 -280.490434) (xy 342.946224 -280.540668) (xy 342.946736 -280.566114)
			(xy 343.254833 -280.566114) (xy 343.258928 -280.515386) (xy 343.271107 -280.465972) (xy 343.291055 -280.419152)
			(xy 343.318256 -280.376138) (xy 343.352004 -280.338044) (xy 343.391426 -280.305857) (xy 343.4355 -280.280411)
			(xy 343.483086 -280.262364) (xy 343.53295 -280.252184) (xy 343.583802 -280.250135) (xy 343.634323 -280.256269)
			(xy 343.683207 -280.270429) (xy 343.729186 -280.292246) (xy 343.77107 -280.321156) (xy 343.807774 -280.356411)
			(xy 343.838347 -280.397097) (xy 343.861998 -280.44216) (xy 343.878114 -280.490434) (xy 343.886278 -280.540668)
			(xy 343.88679 -280.566114) (xy 343.886278 -280.59156) (xy 343.878114 -280.641794) (xy 343.861998 -280.690068)
			(xy 343.838347 -280.735131) (xy 343.807774 -280.775817) (xy 343.77107 -280.811072) (xy 343.729186 -280.839982)
			(xy 343.683207 -280.861799) (xy 343.634323 -280.875959) (xy 343.583802 -280.882093) (xy 343.53295 -280.880044)
			(xy 343.483086 -280.869864) (xy 343.4355 -280.851817) (xy 343.391426 -280.826371) (xy 343.352004 -280.794184)
			(xy 343.318256 -280.75609) (xy 343.291055 -280.713076) (xy 343.271107 -280.666256) (xy 343.258928 -280.616842)
			(xy 343.254833 -280.566114) (xy 342.946736 -280.566114) (xy 342.946224 -280.59156) (xy 342.93806 -280.641794)
			(xy 342.921944 -280.690068) (xy 342.898293 -280.735131) (xy 342.86772 -280.775817) (xy 342.831016 -280.811072)
			(xy 342.789132 -280.839982) (xy 342.743153 -280.861799) (xy 342.694269 -280.875959) (xy 342.643748 -280.882093)
			(xy 342.592896 -280.880044) (xy 342.543032 -280.869864) (xy 342.495446 -280.851817) (xy 342.451372 -280.826371)
			(xy 342.41195 -280.794184) (xy 342.378202 -280.75609) (xy 342.351001 -280.713076) (xy 342.331053 -280.666256)
			(xy 342.318874 -280.616842) (xy 342.314779 -280.566114) (xy 341.066882 -280.566114) (xy 341.06637 -280.59156)
			(xy 341.058206 -280.641794) (xy 341.04209 -280.690068) (xy 341.018439 -280.735131) (xy 340.987866 -280.775817)
			(xy 340.951162 -280.811072) (xy 340.909278 -280.839982) (xy 340.863299 -280.861799) (xy 340.814415 -280.875959)
			(xy 340.763894 -280.882093) (xy 340.713042 -280.880044) (xy 340.663178 -280.869864) (xy 340.615592 -280.851817)
			(xy 340.571518 -280.826371) (xy 340.532096 -280.794184) (xy 340.498348 -280.75609) (xy 340.471147 -280.713076)
			(xy 340.451199 -280.666256) (xy 340.43902 -280.616842) (xy 340.434925 -280.566114) (xy 340.129114 -280.566114)
			(xy 340.128624 -280.591103) (xy 340.120805 -280.640466) (xy 340.105361 -280.687998) (xy 340.082671 -280.73253)
			(xy 340.053295 -280.772963) (xy 340.017955 -280.808303) (xy 339.977522 -280.837679) (xy 339.93299 -280.860369)
			(xy 339.885458 -280.875813) (xy 339.836095 -280.883632) (xy 339.786117 -280.883632) (xy 339.736754 -280.875813)
			(xy 339.689222 -280.860369) (xy 339.64469 -280.837679) (xy 339.604257 -280.808303) (xy 339.568917 -280.772963)
			(xy 339.539541 -280.73253) (xy 339.516851 -280.687998) (xy 339.501407 -280.640466) (xy 339.493588 -280.591103)
			(xy 339.186271 -280.591103) (xy 339.186262 -280.59156) (xy 339.178098 -280.641794) (xy 339.161982 -280.690068)
			(xy 339.138331 -280.735131) (xy 339.107758 -280.775817) (xy 339.071054 -280.811072) (xy 339.02917 -280.839982)
			(xy 338.983191 -280.861799) (xy 338.934307 -280.875959) (xy 338.883786 -280.882093) (xy 338.832934 -280.880044)
			(xy 338.78307 -280.869864) (xy 338.735484 -280.851817) (xy 338.69141 -280.826371) (xy 338.651988 -280.794184)
			(xy 338.61824 -280.75609) (xy 338.591039 -280.713076) (xy 338.571091 -280.666256) (xy 338.558912 -280.616842)
			(xy 338.554817 -280.566114) (xy 338.249783 -280.566114) (xy 338.245785 -280.616407) (xy 338.233893 -280.665446)
			(xy 338.214404 -280.711991) (xy 338.187808 -280.754873) (xy 338.154774 -280.793017) (xy 338.116129 -280.825465)
			(xy 338.072845 -280.851401) (xy 338.049616 -280.861262) (xy 338.045298 -280.86304) (xy 338.037283 -280.86755)
			(xy 338.024945 -280.881167) (xy 338.018314 -280.898303) (xy 338.017866 -280.90749) (xy 338.017866 -281.06878)
			(xy 338.018302 -281.078162) (xy 338.025224 -281.095608) (xy 338.038015 -281.109342) (xy 338.046314 -281.113738)
			(xy 338.084414 -281.130502) (xy 338.134198 -281.1526) (xy 338.138372 -281.154031) (xy 338.147059 -281.155568)
			(xy 338.15147 -281.155648) (xy 338.174584 -281.146758) (xy 338.184998 -281.142694) (xy 338.188046 -281.140154)
			(xy 338.205658 -281.124788) (xy 338.244546 -281.098861) (xy 338.286813 -281.078911) (xy 338.331547 -281.06537)
			(xy 338.377783 -281.058529) (xy 338.401152 -281.058112) (xy 338.426144 -281.058573) (xy 338.475514 -281.066386)
			(xy 338.523053 -281.081826) (xy 338.567592 -281.104514) (xy 338.608032 -281.13389) (xy 338.643379 -281.169231)
			(xy 338.672761 -281.209667) (xy 338.695456 -281.254202) (xy 338.710903 -281.301739) (xy 338.718723 -281.351108)
			(xy 338.718723 -281.37612) (xy 339.024971 -281.37612) (xy 339.029066 -281.325392) (xy 339.041245 -281.275978)
			(xy 339.061193 -281.229158) (xy 339.088394 -281.186144) (xy 339.122142 -281.14805) (xy 339.161564 -281.115863)
			(xy 339.205638 -281.090417) (xy 339.253224 -281.07237) (xy 339.303088 -281.06219) (xy 339.35394 -281.060141)
			(xy 339.404461 -281.066275) (xy 339.453345 -281.080435) (xy 339.499324 -281.102252) (xy 339.541208 -281.131162)
			(xy 339.577912 -281.166417) (xy 339.608485 -281.207103) (xy 339.632136 -281.252166) (xy 339.648252 -281.30044)
			(xy 339.656416 -281.350674) (xy 339.656928 -281.37612) (xy 339.964771 -281.37612) (xy 339.968866 -281.325392)
			(xy 339.981045 -281.275978) (xy 340.000993 -281.229158) (xy 340.028194 -281.186144) (xy 340.061942 -281.14805)
			(xy 340.101364 -281.115863) (xy 340.145438 -281.090417) (xy 340.193024 -281.07237) (xy 340.242888 -281.06219)
			(xy 340.29374 -281.060141) (xy 340.344261 -281.066275) (xy 340.393145 -281.080435) (xy 340.439124 -281.102252)
			(xy 340.481008 -281.131162) (xy 340.517712 -281.166417) (xy 340.548285 -281.207103) (xy 340.571936 -281.252166)
			(xy 340.588052 -281.30044) (xy 340.596216 -281.350674) (xy 340.596728 -281.37612) (xy 340.596225 -281.401109)
			(xy 340.903542 -281.401109) (xy 340.903542 -281.351131) (xy 340.911361 -281.301768) (xy 340.926805 -281.254236)
			(xy 340.949495 -281.209704) (xy 340.978871 -281.169271) (xy 341.014211 -281.133931) (xy 341.054644 -281.104555)
			(xy 341.099176 -281.081865) (xy 341.146708 -281.066421) (xy 341.196071 -281.058602) (xy 341.246049 -281.058602)
			(xy 341.295412 -281.066421) (xy 341.342944 -281.081865) (xy 341.387476 -281.104555) (xy 341.427909 -281.133931)
			(xy 341.463249 -281.169271) (xy 341.492625 -281.209704) (xy 341.515315 -281.254236) (xy 341.530759 -281.301768)
			(xy 341.538578 -281.351131) (xy 341.539068 -281.37612) (xy 341.844879 -281.37612) (xy 341.848974 -281.325392)
			(xy 341.861153 -281.275978) (xy 341.881101 -281.229158) (xy 341.908302 -281.186144) (xy 341.94205 -281.14805)
			(xy 341.981472 -281.115863) (xy 342.025546 -281.090417) (xy 342.073132 -281.07237) (xy 342.122996 -281.06219)
			(xy 342.173848 -281.060141) (xy 342.224369 -281.066275) (xy 342.273253 -281.080435) (xy 342.319232 -281.102252)
			(xy 342.361116 -281.131162) (xy 342.39782 -281.166417) (xy 342.428393 -281.207103) (xy 342.452044 -281.252166)
			(xy 342.46816 -281.30044) (xy 342.476324 -281.350674) (xy 342.476836 -281.37612) (xy 342.476333 -281.401109)
			(xy 342.78365 -281.401109) (xy 342.78365 -281.351131) (xy 342.791469 -281.301768) (xy 342.806913 -281.254236)
			(xy 342.829603 -281.209704) (xy 342.858979 -281.169271) (xy 342.894319 -281.133931) (xy 342.934752 -281.104555)
			(xy 342.979284 -281.081865) (xy 343.026816 -281.066421) (xy 343.076179 -281.058602) (xy 343.126157 -281.058602)
			(xy 343.17552 -281.066421) (xy 343.223052 -281.081865) (xy 343.267584 -281.104555) (xy 343.308017 -281.133931)
			(xy 343.343357 -281.169271) (xy 343.372733 -281.209704) (xy 343.395423 -281.254236) (xy 343.410867 -281.301768)
			(xy 343.418686 -281.351131) (xy 343.419176 -281.37612) (xy 343.724987 -281.37612) (xy 343.729082 -281.325392)
			(xy 343.741261 -281.275978) (xy 343.761209 -281.229158) (xy 343.78841 -281.186144) (xy 343.822158 -281.14805)
			(xy 343.86158 -281.115863) (xy 343.905654 -281.090417) (xy 343.95324 -281.07237) (xy 344.003104 -281.06219)
			(xy 344.053956 -281.060141) (xy 344.104477 -281.066275) (xy 344.153361 -281.080435) (xy 344.19934 -281.102252)
			(xy 344.241224 -281.131162) (xy 344.277928 -281.166417) (xy 344.308501 -281.207103) (xy 344.332152 -281.252166)
			(xy 344.348268 -281.30044) (xy 344.356432 -281.350674) (xy 344.356944 -281.37612) (xy 344.356432 -281.401566)
			(xy 344.348268 -281.4518) (xy 344.332152 -281.500074) (xy 344.308501 -281.545137) (xy 344.277928 -281.585823)
			(xy 344.241224 -281.621078) (xy 344.19934 -281.649988) (xy 344.153361 -281.671805) (xy 344.104477 -281.685965)
			(xy 344.053956 -281.692099) (xy 344.003104 -281.69005) (xy 343.95324 -281.67987) (xy 343.905654 -281.661823)
			(xy 343.86158 -281.636377) (xy 343.822158 -281.60419) (xy 343.78841 -281.566096) (xy 343.761209 -281.523082)
			(xy 343.741261 -281.476262) (xy 343.729082 -281.426848) (xy 343.724987 -281.37612) (xy 343.419176 -281.37612)
			(xy 343.418686 -281.401109) (xy 343.410867 -281.450472) (xy 343.395423 -281.498004) (xy 343.372733 -281.542536)
			(xy 343.343357 -281.582969) (xy 343.308017 -281.618309) (xy 343.267584 -281.647685) (xy 343.223052 -281.670375)
			(xy 343.17552 -281.685819) (xy 343.126157 -281.693638) (xy 343.076179 -281.693638) (xy 343.026816 -281.685819)
			(xy 342.979284 -281.670375) (xy 342.934752 -281.647685) (xy 342.894319 -281.618309) (xy 342.858979 -281.582969)
			(xy 342.829603 -281.542536) (xy 342.806913 -281.498004) (xy 342.791469 -281.450472) (xy 342.78365 -281.401109)
			(xy 342.476333 -281.401109) (xy 342.476324 -281.401566) (xy 342.46816 -281.4518) (xy 342.452044 -281.500074)
			(xy 342.428393 -281.545137) (xy 342.39782 -281.585823) (xy 342.361116 -281.621078) (xy 342.319232 -281.649988)
			(xy 342.273253 -281.671805) (xy 342.224369 -281.685965) (xy 342.173848 -281.692099) (xy 342.122996 -281.69005)
			(xy 342.073132 -281.67987) (xy 342.025546 -281.661823) (xy 341.981472 -281.636377) (xy 341.94205 -281.60419)
			(xy 341.908302 -281.566096) (xy 341.881101 -281.523082) (xy 341.861153 -281.476262) (xy 341.848974 -281.426848)
			(xy 341.844879 -281.37612) (xy 341.539068 -281.37612) (xy 341.538578 -281.401109) (xy 341.530759 -281.450472)
			(xy 341.515315 -281.498004) (xy 341.492625 -281.542536) (xy 341.463249 -281.582969) (xy 341.427909 -281.618309)
			(xy 341.387476 -281.647685) (xy 341.342944 -281.670375) (xy 341.295412 -281.685819) (xy 341.246049 -281.693638)
			(xy 341.196071 -281.693638) (xy 341.146708 -281.685819) (xy 341.099176 -281.670375) (xy 341.054644 -281.647685)
			(xy 341.014211 -281.618309) (xy 340.978871 -281.582969) (xy 340.949495 -281.542536) (xy 340.926805 -281.498004)
			(xy 340.911361 -281.450472) (xy 340.903542 -281.401109) (xy 340.596225 -281.401109) (xy 340.596216 -281.401566)
			(xy 340.588052 -281.4518) (xy 340.571936 -281.500074) (xy 340.548285 -281.545137) (xy 340.517712 -281.585823)
			(xy 340.481008 -281.621078) (xy 340.439124 -281.649988) (xy 340.393145 -281.671805) (xy 340.344261 -281.685965)
			(xy 340.29374 -281.692099) (xy 340.242888 -281.69005) (xy 340.193024 -281.67987) (xy 340.145438 -281.661823)
			(xy 340.101364 -281.636377) (xy 340.061942 -281.60419) (xy 340.028194 -281.566096) (xy 340.000993 -281.523082)
			(xy 339.981045 -281.476262) (xy 339.968866 -281.426848) (xy 339.964771 -281.37612) (xy 339.656928 -281.37612)
			(xy 339.656416 -281.401566) (xy 339.648252 -281.4518) (xy 339.632136 -281.500074) (xy 339.608485 -281.545137)
			(xy 339.577912 -281.585823) (xy 339.541208 -281.621078) (xy 339.499324 -281.649988) (xy 339.453345 -281.671805)
			(xy 339.404461 -281.685965) (xy 339.35394 -281.692099) (xy 339.303088 -281.69005) (xy 339.253224 -281.67987)
			(xy 339.205638 -281.661823) (xy 339.161564 -281.636377) (xy 339.122142 -281.60419) (xy 339.088394 -281.566096)
			(xy 339.061193 -281.523082) (xy 339.041245 -281.476262) (xy 339.029066 -281.426848) (xy 339.024971 -281.37612)
			(xy 338.718723 -281.37612) (xy 338.718723 -281.401092) (xy 338.710903 -281.450461) (xy 338.695456 -281.497998)
			(xy 338.672761 -281.542533) (xy 338.643379 -281.582969) (xy 338.608032 -281.61831) (xy 338.567592 -281.647686)
			(xy 338.523053 -281.670374) (xy 338.475514 -281.685814) (xy 338.426144 -281.693627) (xy 338.401152 -281.694128)
			(xy 338.377784 -281.693711) (xy 338.331552 -281.68686) (xy 338.286823 -281.673312) (xy 338.24456 -281.653359)
			(xy 338.205674 -281.627433) (xy 338.188046 -281.612086) (xy 338.184998 -281.609546) (xy 338.174584 -281.605482)
			(xy 338.15147 -281.596592) (xy 338.14706 -281.59669) (xy 338.138375 -281.598224) (xy 338.134198 -281.59964)
			(xy 338.084414 -281.621738) (xy 338.046314 -281.638502) (xy 338.038006 -281.642895) (xy 338.025182 -281.656613)
			(xy 338.018264 -281.674071) (xy 338.017866 -281.68346) (xy 338.017866 -281.84475) (xy 338.018333 -281.853927)
			(xy 338.024995 -281.871035) (xy 338.037315 -281.884646) (xy 338.045298 -281.8892) (xy 338.049616 -281.890978)
			(xy 338.072853 -281.900815) (xy 338.116135 -281.926753) (xy 338.154776 -281.959201) (xy 338.187808 -281.997345)
			(xy 338.214401 -282.040228) (xy 338.233887 -282.086772) (xy 338.245777 -282.13581) (xy 338.249772 -282.18611)
			(xy 338.249771 -282.186126) (xy 338.554817 -282.186126) (xy 338.558912 -282.135398) (xy 338.571091 -282.085984)
			(xy 338.591039 -282.039164) (xy 338.61824 -281.99615) (xy 338.651988 -281.958056) (xy 338.69141 -281.925869)
			(xy 338.735484 -281.900423) (xy 338.78307 -281.882376) (xy 338.832934 -281.872196) (xy 338.883786 -281.870147)
			(xy 338.934307 -281.876281) (xy 338.983191 -281.890441) (xy 339.02917 -281.912258) (xy 339.071054 -281.941168)
			(xy 339.107758 -281.976423) (xy 339.138331 -282.017109) (xy 339.161982 -282.062172) (xy 339.178098 -282.110446)
			(xy 339.186262 -282.16068) (xy 339.186774 -282.186126) (xy 339.186271 -282.211115) (xy 339.493588 -282.211115)
			(xy 339.493588 -282.161137) (xy 339.501407 -282.111774) (xy 339.516851 -282.064242) (xy 339.539541 -282.01971)
			(xy 339.568917 -281.979277) (xy 339.604257 -281.943937) (xy 339.64469 -281.914561) (xy 339.689222 -281.891871)
			(xy 339.736754 -281.876427) (xy 339.786117 -281.868608) (xy 339.836095 -281.868608) (xy 339.885458 -281.876427)
			(xy 339.93299 -281.891871) (xy 339.977522 -281.914561) (xy 340.017955 -281.943937) (xy 340.053295 -281.979277)
			(xy 340.082671 -282.01971) (xy 340.105361 -282.064242) (xy 340.120805 -282.111774) (xy 340.128624 -282.161137)
			(xy 340.129114 -282.186126) (xy 340.434925 -282.186126) (xy 340.43902 -282.135398) (xy 340.451199 -282.085984)
			(xy 340.471147 -282.039164) (xy 340.498348 -281.99615) (xy 340.532096 -281.958056) (xy 340.571518 -281.925869)
			(xy 340.615592 -281.900423) (xy 340.663178 -281.882376) (xy 340.713042 -281.872196) (xy 340.763894 -281.870147)
			(xy 340.814415 -281.876281) (xy 340.863299 -281.890441) (xy 340.909278 -281.912258) (xy 340.951162 -281.941168)
			(xy 340.987866 -281.976423) (xy 341.018439 -282.017109) (xy 341.04209 -282.062172) (xy 341.058206 -282.110446)
			(xy 341.06637 -282.16068) (xy 341.066882 -282.186126) (xy 341.066379 -282.211115) (xy 341.373696 -282.211115)
			(xy 341.373696 -282.161137) (xy 341.381515 -282.111774) (xy 341.396959 -282.064242) (xy 341.419649 -282.01971)
			(xy 341.449025 -281.979277) (xy 341.484365 -281.943937) (xy 341.524798 -281.914561) (xy 341.56933 -281.891871)
			(xy 341.616862 -281.876427) (xy 341.666225 -281.868608) (xy 341.716203 -281.868608) (xy 341.765566 -281.876427)
			(xy 341.813098 -281.891871) (xy 341.85763 -281.914561) (xy 341.898063 -281.943937) (xy 341.933403 -281.979277)
			(xy 341.962779 -282.01971) (xy 341.985469 -282.064242) (xy 342.000913 -282.111774) (xy 342.008732 -282.161137)
			(xy 342.009222 -282.186126) (xy 342.314779 -282.186126) (xy 342.318874 -282.135398) (xy 342.331053 -282.085984)
			(xy 342.351001 -282.039164) (xy 342.378202 -281.99615) (xy 342.41195 -281.958056) (xy 342.451372 -281.925869)
			(xy 342.495446 -281.900423) (xy 342.543032 -281.882376) (xy 342.592896 -281.872196) (xy 342.643748 -281.870147)
			(xy 342.694269 -281.876281) (xy 342.743153 -281.890441) (xy 342.789132 -281.912258) (xy 342.831016 -281.941168)
			(xy 342.86772 -281.976423) (xy 342.898293 -282.017109) (xy 342.921944 -282.062172) (xy 342.93806 -282.110446)
			(xy 342.946224 -282.16068) (xy 342.946736 -282.186126) (xy 343.254833 -282.186126) (xy 343.258928 -282.135398)
			(xy 343.271107 -282.085984) (xy 343.291055 -282.039164) (xy 343.318256 -281.99615) (xy 343.352004 -281.958056)
			(xy 343.391426 -281.925869) (xy 343.4355 -281.900423) (xy 343.483086 -281.882376) (xy 343.53295 -281.872196)
			(xy 343.583802 -281.870147) (xy 343.634323 -281.876281) (xy 343.683207 -281.890441) (xy 343.729186 -281.912258)
			(xy 343.77107 -281.941168) (xy 343.807774 -281.976423) (xy 343.838347 -282.017109) (xy 343.861998 -282.062172)
			(xy 343.878114 -282.110446) (xy 343.886278 -282.16068) (xy 343.88679 -282.186126) (xy 343.886278 -282.211572)
			(xy 343.878114 -282.261806) (xy 343.861998 -282.31008) (xy 343.838347 -282.355143) (xy 343.807774 -282.395829)
			(xy 343.77107 -282.431084) (xy 343.729186 -282.459994) (xy 343.683207 -282.481811) (xy 343.634323 -282.495971)
			(xy 343.583802 -282.502105) (xy 343.53295 -282.500056) (xy 343.483086 -282.489876) (xy 343.4355 -282.471829)
			(xy 343.391426 -282.446383) (xy 343.352004 -282.414196) (xy 343.318256 -282.376102) (xy 343.291055 -282.333088)
			(xy 343.271107 -282.286268) (xy 343.258928 -282.236854) (xy 343.254833 -282.186126) (xy 342.946736 -282.186126)
			(xy 342.946224 -282.211572) (xy 342.93806 -282.261806) (xy 342.921944 -282.31008) (xy 342.898293 -282.355143)
			(xy 342.86772 -282.395829) (xy 342.831016 -282.431084) (xy 342.789132 -282.459994) (xy 342.743153 -282.481811)
			(xy 342.694269 -282.495971) (xy 342.643748 -282.502105) (xy 342.592896 -282.500056) (xy 342.543032 -282.489876)
			(xy 342.495446 -282.471829) (xy 342.451372 -282.446383) (xy 342.41195 -282.414196) (xy 342.378202 -282.376102)
			(xy 342.351001 -282.333088) (xy 342.331053 -282.286268) (xy 342.318874 -282.236854) (xy 342.314779 -282.186126)
			(xy 342.009222 -282.186126) (xy 342.008732 -282.211115) (xy 342.000913 -282.260478) (xy 341.985469 -282.30801)
			(xy 341.962779 -282.352542) (xy 341.933403 -282.392975) (xy 341.898063 -282.428315) (xy 341.85763 -282.457691)
			(xy 341.813098 -282.480381) (xy 341.765566 -282.495825) (xy 341.716203 -282.503644) (xy 341.666225 -282.503644)
			(xy 341.616862 -282.495825) (xy 341.56933 -282.480381) (xy 341.524798 -282.457691) (xy 341.484365 -282.428315)
			(xy 341.449025 -282.392975) (xy 341.419649 -282.352542) (xy 341.396959 -282.30801) (xy 341.381515 -282.260478)
			(xy 341.373696 -282.211115) (xy 341.066379 -282.211115) (xy 341.06637 -282.211572) (xy 341.058206 -282.261806)
			(xy 341.04209 -282.31008) (xy 341.018439 -282.355143) (xy 340.987866 -282.395829) (xy 340.951162 -282.431084)
			(xy 340.909278 -282.459994) (xy 340.863299 -282.481811) (xy 340.814415 -282.495971) (xy 340.763894 -282.502105)
			(xy 340.713042 -282.500056) (xy 340.663178 -282.489876) (xy 340.615592 -282.471829) (xy 340.571518 -282.446383)
			(xy 340.532096 -282.414196) (xy 340.498348 -282.376102) (xy 340.471147 -282.333088) (xy 340.451199 -282.286268)
			(xy 340.43902 -282.236854) (xy 340.434925 -282.186126) (xy 340.129114 -282.186126) (xy 340.128624 -282.211115)
			(xy 340.120805 -282.260478) (xy 340.105361 -282.30801) (xy 340.082671 -282.352542) (xy 340.053295 -282.392975)
			(xy 340.017955 -282.428315) (xy 339.977522 -282.457691) (xy 339.93299 -282.480381) (xy 339.885458 -282.495825)
			(xy 339.836095 -282.503644) (xy 339.786117 -282.503644) (xy 339.736754 -282.495825) (xy 339.689222 -282.480381)
			(xy 339.64469 -282.457691) (xy 339.604257 -282.428315) (xy 339.568917 -282.392975) (xy 339.539541 -282.352542)
			(xy 339.516851 -282.30801) (xy 339.501407 -282.260478) (xy 339.493588 -282.211115) (xy 339.186271 -282.211115)
			(xy 339.186262 -282.211572) (xy 339.178098 -282.261806) (xy 339.161982 -282.31008) (xy 339.138331 -282.355143)
			(xy 339.107758 -282.395829) (xy 339.071054 -282.431084) (xy 339.02917 -282.459994) (xy 338.983191 -282.481811)
			(xy 338.934307 -282.495971) (xy 338.883786 -282.502105) (xy 338.832934 -282.500056) (xy 338.78307 -282.489876)
			(xy 338.735484 -282.471829) (xy 338.69141 -282.446383) (xy 338.651988 -282.414196) (xy 338.61824 -282.376102)
			(xy 338.591039 -282.333088) (xy 338.571091 -282.286268) (xy 338.558912 -282.236854) (xy 338.554817 -282.186126)
			(xy 338.249771 -282.186126) (xy 338.245774 -282.236409) (xy 338.233881 -282.285446) (xy 338.214392 -282.331989)
			(xy 338.187797 -282.37487) (xy 338.154763 -282.413012) (xy 338.116119 -282.445458) (xy 338.072836 -282.471393)
			(xy 338.049616 -282.481274) (xy 338.045298 -282.483052) (xy 338.037284 -282.487563) (xy 338.02495 -282.50118)
			(xy 338.018323 -282.518316) (xy 338.017866 -282.527502) (xy 338.017866 -282.688792) (xy 338.018304 -282.698173)
			(xy 338.025228 -282.715615) (xy 338.03802 -282.729346) (xy 338.046314 -282.73375) (xy 338.084414 -282.750514)
			(xy 338.134198 -282.772612) (xy 338.138372 -282.774043) (xy 338.147059 -282.775579) (xy 338.15147 -282.77566)
			(xy 338.174584 -282.76677) (xy 338.184998 -282.762706) (xy 338.188046 -282.760166) (xy 338.205658 -282.7448)
			(xy 338.244546 -282.718872) (xy 338.286813 -282.698921) (xy 338.331547 -282.685379) (xy 338.377782 -282.678538)
			(xy 338.401152 -282.678124) (xy 338.426143 -282.678585) (xy 338.475511 -282.686397) (xy 338.523049 -282.701837)
			(xy 338.567585 -282.724524) (xy 338.608025 -282.753899) (xy 338.64337 -282.789239) (xy 338.672751 -282.829674)
			(xy 338.695445 -282.874207) (xy 338.710891 -282.921742) (xy 338.718711 -282.971109) (xy 338.718711 -282.996132)
			(xy 339.024971 -282.996132) (xy 339.029066 -282.945404) (xy 339.041245 -282.89599) (xy 339.061193 -282.84917)
			(xy 339.088394 -282.806156) (xy 339.122142 -282.768062) (xy 339.161564 -282.735875) (xy 339.205638 -282.710429)
			(xy 339.253224 -282.692382) (xy 339.303088 -282.682202) (xy 339.35394 -282.680153) (xy 339.404461 -282.686287)
			(xy 339.453345 -282.700447) (xy 339.499324 -282.722264) (xy 339.541208 -282.751174) (xy 339.577912 -282.786429)
			(xy 339.608485 -282.827115) (xy 339.632136 -282.872178) (xy 339.648252 -282.920452) (xy 339.656416 -282.970686)
			(xy 339.656928 -282.996132) (xy 339.964771 -282.996132) (xy 339.968866 -282.945404) (xy 339.981045 -282.89599)
			(xy 340.000993 -282.84917) (xy 340.028194 -282.806156) (xy 340.061942 -282.768062) (xy 340.101364 -282.735875)
			(xy 340.145438 -282.710429) (xy 340.193024 -282.692382) (xy 340.242888 -282.682202) (xy 340.29374 -282.680153)
			(xy 340.344261 -282.686287) (xy 340.393145 -282.700447) (xy 340.439124 -282.722264) (xy 340.481008 -282.751174)
			(xy 340.517712 -282.786429) (xy 340.548285 -282.827115) (xy 340.571936 -282.872178) (xy 340.588052 -282.920452)
			(xy 340.596216 -282.970686) (xy 340.596728 -282.996132) (xy 341.844879 -282.996132) (xy 341.848974 -282.945404)
			(xy 341.861153 -282.89599) (xy 341.881101 -282.84917) (xy 341.908302 -282.806156) (xy 341.94205 -282.768062)
			(xy 341.981472 -282.735875) (xy 342.025546 -282.710429) (xy 342.073132 -282.692382) (xy 342.122996 -282.682202)
			(xy 342.173848 -282.680153) (xy 342.224369 -282.686287) (xy 342.273253 -282.700447) (xy 342.319232 -282.722264)
			(xy 342.361116 -282.751174) (xy 342.39782 -282.786429) (xy 342.428393 -282.827115) (xy 342.452044 -282.872178)
			(xy 342.46816 -282.920452) (xy 342.476324 -282.970686) (xy 342.476836 -282.996132) (xy 342.476333 -283.021121)
			(xy 342.78365 -283.021121) (xy 342.78365 -282.971143) (xy 342.791469 -282.92178) (xy 342.806913 -282.874248)
			(xy 342.829603 -282.829716) (xy 342.858979 -282.789283) (xy 342.894319 -282.753943) (xy 342.934752 -282.724567)
			(xy 342.979284 -282.701877) (xy 343.026816 -282.686433) (xy 343.076179 -282.678614) (xy 343.126157 -282.678614)
			(xy 343.17552 -282.686433) (xy 343.223052 -282.701877) (xy 343.267584 -282.724567) (xy 343.308017 -282.753943)
			(xy 343.343357 -282.789283) (xy 343.372733 -282.829716) (xy 343.395423 -282.874248) (xy 343.410867 -282.92178)
			(xy 343.418686 -282.971143) (xy 343.419176 -282.996132) (xy 343.724987 -282.996132) (xy 343.729082 -282.945404)
			(xy 343.741261 -282.89599) (xy 343.761209 -282.84917) (xy 343.78841 -282.806156) (xy 343.822158 -282.768062)
			(xy 343.86158 -282.735875) (xy 343.905654 -282.710429) (xy 343.95324 -282.692382) (xy 344.003104 -282.682202)
			(xy 344.053956 -282.680153) (xy 344.104477 -282.686287) (xy 344.153361 -282.700447) (xy 344.19934 -282.722264)
			(xy 344.241224 -282.751174) (xy 344.277928 -282.786429) (xy 344.308501 -282.827115) (xy 344.332152 -282.872178)
			(xy 344.348268 -282.920452) (xy 344.356432 -282.970686) (xy 344.356944 -282.996132) (xy 344.356432 -283.021578)
			(xy 344.348268 -283.071812) (xy 344.332152 -283.120086) (xy 344.308501 -283.165149) (xy 344.277928 -283.205835)
			(xy 344.241224 -283.24109) (xy 344.19934 -283.27) (xy 344.153361 -283.291817) (xy 344.104477 -283.305977)
			(xy 344.053956 -283.312111) (xy 344.003104 -283.310062) (xy 343.95324 -283.299882) (xy 343.905654 -283.281835)
			(xy 343.86158 -283.256389) (xy 343.822158 -283.224202) (xy 343.78841 -283.186108) (xy 343.761209 -283.143094)
			(xy 343.741261 -283.096274) (xy 343.729082 -283.04686) (xy 343.724987 -282.996132) (xy 343.419176 -282.996132)
			(xy 343.418686 -283.021121) (xy 343.410867 -283.070484) (xy 343.395423 -283.118016) (xy 343.372733 -283.162548)
			(xy 343.343357 -283.202981) (xy 343.308017 -283.238321) (xy 343.267584 -283.267697) (xy 343.223052 -283.290387)
			(xy 343.17552 -283.305831) (xy 343.126157 -283.31365) (xy 343.076179 -283.31365) (xy 343.026816 -283.305831)
			(xy 342.979284 -283.290387) (xy 342.934752 -283.267697) (xy 342.894319 -283.238321) (xy 342.858979 -283.202981)
			(xy 342.829603 -283.162548) (xy 342.806913 -283.118016) (xy 342.791469 -283.070484) (xy 342.78365 -283.021121)
			(xy 342.476333 -283.021121) (xy 342.476324 -283.021578) (xy 342.46816 -283.071812) (xy 342.452044 -283.120086)
			(xy 342.428393 -283.165149) (xy 342.39782 -283.205835) (xy 342.361116 -283.24109) (xy 342.319232 -283.27)
			(xy 342.273253 -283.291817) (xy 342.224369 -283.305977) (xy 342.173848 -283.312111) (xy 342.122996 -283.310062)
			(xy 342.073132 -283.299882) (xy 342.025546 -283.281835) (xy 341.981472 -283.256389) (xy 341.94205 -283.224202)
			(xy 341.908302 -283.186108) (xy 341.881101 -283.143094) (xy 341.861153 -283.096274) (xy 341.848974 -283.04686)
			(xy 341.844879 -282.996132) (xy 340.596728 -282.996132) (xy 340.596216 -283.021578) (xy 340.588052 -283.071812)
			(xy 340.571936 -283.120086) (xy 340.548285 -283.165149) (xy 340.517712 -283.205835) (xy 340.481008 -283.24109)
			(xy 340.439124 -283.27) (xy 340.393145 -283.291817) (xy 340.344261 -283.305977) (xy 340.29374 -283.312111)
			(xy 340.242888 -283.310062) (xy 340.193024 -283.299882) (xy 340.145438 -283.281835) (xy 340.101364 -283.256389)
			(xy 340.061942 -283.224202) (xy 340.028194 -283.186108) (xy 340.000993 -283.143094) (xy 339.981045 -283.096274)
			(xy 339.968866 -283.04686) (xy 339.964771 -282.996132) (xy 339.656928 -282.996132) (xy 339.656416 -283.021578)
			(xy 339.648252 -283.071812) (xy 339.632136 -283.120086) (xy 339.608485 -283.165149) (xy 339.577912 -283.205835)
			(xy 339.541208 -283.24109) (xy 339.499324 -283.27) (xy 339.453345 -283.291817) (xy 339.404461 -283.305977)
			(xy 339.35394 -283.312111) (xy 339.303088 -283.310062) (xy 339.253224 -283.299882) (xy 339.205638 -283.281835)
			(xy 339.161564 -283.256389) (xy 339.122142 -283.224202) (xy 339.088394 -283.186108) (xy 339.061193 -283.143094)
			(xy 339.041245 -283.096274) (xy 339.029066 -283.04686) (xy 339.024971 -282.996132) (xy 338.718711 -282.996132)
			(xy 338.718711 -283.021091) (xy 338.710891 -283.070458) (xy 338.695445 -283.117993) (xy 338.672751 -283.162526)
			(xy 338.64337 -283.202961) (xy 338.608025 -283.238301) (xy 338.567585 -283.267676) (xy 338.523049 -283.290363)
			(xy 338.475511 -283.305803) (xy 338.426143 -283.313615) (xy 338.401152 -283.31414) (xy 338.377784 -283.313723)
			(xy 338.331552 -283.306872) (xy 338.286822 -283.293324) (xy 338.244559 -283.273372) (xy 338.205672 -283.247447)
			(xy 338.188046 -283.232098) (xy 338.184998 -283.229558) (xy 338.174584 -283.225494) (xy 338.15147 -283.216604)
			(xy 338.14706 -283.216702) (xy 338.138375 -283.218236) (xy 338.134198 -283.219652) (xy 338.084414 -283.24175)
			(xy 338.046314 -283.258514) (xy 338.038007 -283.262907) (xy 338.025187 -283.276626) (xy 338.018273 -283.294084)
			(xy 338.017866 -283.303472) (xy 338.017866 -283.464762) (xy 338.018319 -283.473947) (xy 338.024961 -283.49108)
			(xy 338.037277 -283.504717) (xy 338.045298 -283.509212) (xy 338.049616 -283.51099) (xy 338.072852 -283.520827)
			(xy 338.116132 -283.546765) (xy 338.154772 -283.579213) (xy 338.187802 -283.617356) (xy 338.214393 -283.660237)
			(xy 338.233877 -283.70678) (xy 338.245766 -283.755816) (xy 338.249761 -283.806114) (xy 338.249759 -283.806138)
			(xy 338.554817 -283.806138) (xy 338.558912 -283.75541) (xy 338.571091 -283.705996) (xy 338.591039 -283.659176)
			(xy 338.61824 -283.616162) (xy 338.651988 -283.578068) (xy 338.69141 -283.545881) (xy 338.735484 -283.520435)
			(xy 338.78307 -283.502388) (xy 338.832934 -283.492208) (xy 338.883786 -283.490159) (xy 338.934307 -283.496293)
			(xy 338.983191 -283.510453) (xy 339.02917 -283.53227) (xy 339.071054 -283.56118) (xy 339.107758 -283.596435)
			(xy 339.138331 -283.637121) (xy 339.161982 -283.682184) (xy 339.178098 -283.730458) (xy 339.186262 -283.780692)
			(xy 339.186774 -283.806138) (xy 339.186271 -283.831127) (xy 339.493588 -283.831127) (xy 339.493588 -283.781149)
			(xy 339.501407 -283.731786) (xy 339.516851 -283.684254) (xy 339.539541 -283.639722) (xy 339.568917 -283.599289)
			(xy 339.604257 -283.563949) (xy 339.64469 -283.534573) (xy 339.689222 -283.511883) (xy 339.736754 -283.496439)
			(xy 339.786117 -283.48862) (xy 339.836095 -283.48862) (xy 339.885458 -283.496439) (xy 339.93299 -283.511883)
			(xy 339.977522 -283.534573) (xy 340.017955 -283.563949) (xy 340.053295 -283.599289) (xy 340.082671 -283.639722)
			(xy 340.105361 -283.684254) (xy 340.120805 -283.731786) (xy 340.128624 -283.781149) (xy 340.129114 -283.806138)
			(xy 340.434925 -283.806138) (xy 340.43902 -283.75541) (xy 340.451199 -283.705996) (xy 340.471147 -283.659176)
			(xy 340.498348 -283.616162) (xy 340.532096 -283.578068) (xy 340.571518 -283.545881) (xy 340.615592 -283.520435)
			(xy 340.663178 -283.502388) (xy 340.713042 -283.492208) (xy 340.763894 -283.490159) (xy 340.814415 -283.496293)
			(xy 340.863299 -283.510453) (xy 340.909278 -283.53227) (xy 340.951162 -283.56118) (xy 340.987866 -283.596435)
			(xy 341.018439 -283.637121) (xy 341.04209 -283.682184) (xy 341.058206 -283.730458) (xy 341.06637 -283.780692)
			(xy 341.066882 -283.806138) (xy 341.066379 -283.831127) (xy 341.373696 -283.831127) (xy 341.373696 -283.781149)
			(xy 341.381515 -283.731786) (xy 341.396959 -283.684254) (xy 341.419649 -283.639722) (xy 341.449025 -283.599289)
			(xy 341.484365 -283.563949) (xy 341.524798 -283.534573) (xy 341.56933 -283.511883) (xy 341.616862 -283.496439)
			(xy 341.666225 -283.48862) (xy 341.716203 -283.48862) (xy 341.765566 -283.496439) (xy 341.813098 -283.511883)
			(xy 341.85763 -283.534573) (xy 341.898063 -283.563949) (xy 341.933403 -283.599289) (xy 341.962779 -283.639722)
			(xy 341.985469 -283.684254) (xy 342.000913 -283.731786) (xy 342.008732 -283.781149) (xy 342.009222 -283.806138)
			(xy 342.314779 -283.806138) (xy 342.318874 -283.75541) (xy 342.331053 -283.705996) (xy 342.351001 -283.659176)
			(xy 342.378202 -283.616162) (xy 342.41195 -283.578068) (xy 342.451372 -283.545881) (xy 342.495446 -283.520435)
			(xy 342.543032 -283.502388) (xy 342.592896 -283.492208) (xy 342.643748 -283.490159) (xy 342.694269 -283.496293)
			(xy 342.743153 -283.510453) (xy 342.789132 -283.53227) (xy 342.831016 -283.56118) (xy 342.86772 -283.596435)
			(xy 342.898293 -283.637121) (xy 342.921944 -283.682184) (xy 342.93806 -283.730458) (xy 342.946224 -283.780692)
			(xy 342.946736 -283.806138) (xy 343.254833 -283.806138) (xy 343.258928 -283.75541) (xy 343.271107 -283.705996)
			(xy 343.291055 -283.659176) (xy 343.318256 -283.616162) (xy 343.352004 -283.578068) (xy 343.391426 -283.545881)
			(xy 343.4355 -283.520435) (xy 343.483086 -283.502388) (xy 343.53295 -283.492208) (xy 343.583802 -283.490159)
			(xy 343.634323 -283.496293) (xy 343.683207 -283.510453) (xy 343.729186 -283.53227) (xy 343.77107 -283.56118)
			(xy 343.807774 -283.596435) (xy 343.838347 -283.637121) (xy 343.861998 -283.682184) (xy 343.878114 -283.730458)
			(xy 343.886278 -283.780692) (xy 343.88679 -283.806138) (xy 343.886278 -283.831584) (xy 343.878114 -283.881818)
			(xy 343.861998 -283.930092) (xy 343.838347 -283.975155) (xy 343.807774 -284.015841) (xy 343.77107 -284.051096)
			(xy 343.729186 -284.080006) (xy 343.683207 -284.101823) (xy 343.634323 -284.115983) (xy 343.583802 -284.122117)
			(xy 343.53295 -284.120068) (xy 343.483086 -284.109888) (xy 343.4355 -284.091841) (xy 343.391426 -284.066395)
			(xy 343.352004 -284.034208) (xy 343.318256 -283.996114) (xy 343.291055 -283.9531) (xy 343.271107 -283.90628)
			(xy 343.258928 -283.856866) (xy 343.254833 -283.806138) (xy 342.946736 -283.806138) (xy 342.946224 -283.831584)
			(xy 342.93806 -283.881818) (xy 342.921944 -283.930092) (xy 342.898293 -283.975155) (xy 342.86772 -284.015841)
			(xy 342.831016 -284.051096) (xy 342.789132 -284.080006) (xy 342.743153 -284.101823) (xy 342.694269 -284.115983)
			(xy 342.643748 -284.122117) (xy 342.592896 -284.120068) (xy 342.543032 -284.109888) (xy 342.495446 -284.091841)
			(xy 342.451372 -284.066395) (xy 342.41195 -284.034208) (xy 342.378202 -283.996114) (xy 342.351001 -283.9531)
			(xy 342.331053 -283.90628) (xy 342.318874 -283.856866) (xy 342.314779 -283.806138) (xy 342.009222 -283.806138)
			(xy 342.008732 -283.831127) (xy 342.000913 -283.88049) (xy 341.985469 -283.928022) (xy 341.962779 -283.972554)
			(xy 341.933403 -284.012987) (xy 341.898063 -284.048327) (xy 341.85763 -284.077703) (xy 341.813098 -284.100393)
			(xy 341.765566 -284.115837) (xy 341.716203 -284.123656) (xy 341.666225 -284.123656) (xy 341.616862 -284.115837)
			(xy 341.56933 -284.100393) (xy 341.524798 -284.077703) (xy 341.484365 -284.048327) (xy 341.449025 -284.012987)
			(xy 341.419649 -283.972554) (xy 341.396959 -283.928022) (xy 341.381515 -283.88049) (xy 341.373696 -283.831127)
			(xy 341.066379 -283.831127) (xy 341.06637 -283.831584) (xy 341.058206 -283.881818) (xy 341.04209 -283.930092)
			(xy 341.018439 -283.975155) (xy 340.987866 -284.015841) (xy 340.951162 -284.051096) (xy 340.909278 -284.080006)
			(xy 340.863299 -284.101823) (xy 340.814415 -284.115983) (xy 340.763894 -284.122117) (xy 340.713042 -284.120068)
			(xy 340.663178 -284.109888) (xy 340.615592 -284.091841) (xy 340.571518 -284.066395) (xy 340.532096 -284.034208)
			(xy 340.498348 -283.996114) (xy 340.471147 -283.9531) (xy 340.451199 -283.90628) (xy 340.43902 -283.856866)
			(xy 340.434925 -283.806138) (xy 340.129114 -283.806138) (xy 340.128624 -283.831127) (xy 340.120805 -283.88049)
			(xy 340.105361 -283.928022) (xy 340.082671 -283.972554) (xy 340.053295 -284.012987) (xy 340.017955 -284.048327)
			(xy 339.977522 -284.077703) (xy 339.93299 -284.100393) (xy 339.885458 -284.115837) (xy 339.836095 -284.123656)
			(xy 339.786117 -284.123656) (xy 339.736754 -284.115837) (xy 339.689222 -284.100393) (xy 339.64469 -284.077703)
			(xy 339.604257 -284.048327) (xy 339.568917 -284.012987) (xy 339.539541 -283.972554) (xy 339.516851 -283.928022)
			(xy 339.501407 -283.88049) (xy 339.493588 -283.831127) (xy 339.186271 -283.831127) (xy 339.186262 -283.831584)
			(xy 339.178098 -283.881818) (xy 339.161982 -283.930092) (xy 339.138331 -283.975155) (xy 339.107758 -284.015841)
			(xy 339.071054 -284.051096) (xy 339.02917 -284.080006) (xy 338.983191 -284.101823) (xy 338.934307 -284.115983)
			(xy 338.883786 -284.122117) (xy 338.832934 -284.120068) (xy 338.78307 -284.109888) (xy 338.735484 -284.091841)
			(xy 338.69141 -284.066395) (xy 338.651988 -284.034208) (xy 338.61824 -283.996114) (xy 338.591039 -283.9531)
			(xy 338.571091 -283.90628) (xy 338.558912 -283.856866) (xy 338.554817 -283.806138) (xy 338.249759 -283.806138)
			(xy 338.245762 -283.856412) (xy 338.233869 -283.905447) (xy 338.21438 -283.951988) (xy 338.187785 -283.994867)
			(xy 338.154752 -284.033007) (xy 338.116109 -284.065452) (xy 338.072827 -284.091385) (xy 338.049616 -284.101286)
			(xy 338.045298 -284.103064) (xy 338.037286 -284.107575) (xy 338.024954 -284.121193) (xy 338.018331 -284.138329)
			(xy 338.017866 -284.147514) (xy 338.017866 -284.308804) (xy 338.018306 -284.318184) (xy 338.025233 -284.335622)
			(xy 338.038025 -284.34935) (xy 338.046314 -284.353762) (xy 338.084414 -284.370526) (xy 338.134198 -284.392624)
			(xy 338.138372 -284.394054) (xy 338.147059 -284.39559) (xy 338.15147 -284.395672) (xy 338.174584 -284.386782)
			(xy 338.184998 -284.382718) (xy 338.188046 -284.380178) (xy 338.205658 -284.364811) (xy 338.244545 -284.338882)
			(xy 338.286812 -284.318931) (xy 338.331547 -284.305389) (xy 338.377782 -284.298547) (xy 338.401152 -284.298136)
			(xy 338.426142 -284.298597) (xy 338.475508 -284.306409) (xy 338.523044 -284.321848) (xy 338.567579 -284.344534)
			(xy 338.608017 -284.373908) (xy 338.643361 -284.409247) (xy 338.672741 -284.44968) (xy 338.695433 -284.494211)
			(xy 338.71088 -284.541745) (xy 338.718699 -284.59111) (xy 338.718699 -284.616144) (xy 339.024971 -284.616144)
			(xy 339.029066 -284.565416) (xy 339.041245 -284.516002) (xy 339.061193 -284.469182) (xy 339.088394 -284.426168)
			(xy 339.122142 -284.388074) (xy 339.161564 -284.355887) (xy 339.205638 -284.330441) (xy 339.253224 -284.312394)
			(xy 339.303088 -284.302214) (xy 339.35394 -284.300165) (xy 339.404461 -284.306299) (xy 339.453345 -284.320459)
			(xy 339.499324 -284.342276) (xy 339.541208 -284.371186) (xy 339.577912 -284.406441) (xy 339.608485 -284.447127)
			(xy 339.632136 -284.49219) (xy 339.648252 -284.540464) (xy 339.656416 -284.590698) (xy 339.656928 -284.616144)
			(xy 339.964771 -284.616144) (xy 339.968866 -284.565416) (xy 339.981045 -284.516002) (xy 340.000993 -284.469182)
			(xy 340.028194 -284.426168) (xy 340.061942 -284.388074) (xy 340.101364 -284.355887) (xy 340.145438 -284.330441)
			(xy 340.193024 -284.312394) (xy 340.242888 -284.302214) (xy 340.29374 -284.300165) (xy 340.344261 -284.306299)
			(xy 340.393145 -284.320459) (xy 340.439124 -284.342276) (xy 340.481008 -284.371186) (xy 340.517712 -284.406441)
			(xy 340.548285 -284.447127) (xy 340.571936 -284.49219) (xy 340.588052 -284.540464) (xy 340.596216 -284.590698)
			(xy 340.596728 -284.616144) (xy 340.596225 -284.641133) (xy 340.903542 -284.641133) (xy 340.903542 -284.591155)
			(xy 340.911361 -284.541792) (xy 340.926805 -284.49426) (xy 340.949495 -284.449728) (xy 340.978871 -284.409295)
			(xy 341.014211 -284.373955) (xy 341.054644 -284.344579) (xy 341.099176 -284.321889) (xy 341.146708 -284.306445)
			(xy 341.196071 -284.298626) (xy 341.246049 -284.298626) (xy 341.295412 -284.306445) (xy 341.342944 -284.321889)
			(xy 341.387476 -284.344579) (xy 341.427909 -284.373955) (xy 341.463249 -284.409295) (xy 341.492625 -284.449728)
			(xy 341.515315 -284.49426) (xy 341.530759 -284.541792) (xy 341.538578 -284.591155) (xy 341.539068 -284.616144)
			(xy 341.844879 -284.616144) (xy 341.848974 -284.565416) (xy 341.861153 -284.516002) (xy 341.881101 -284.469182)
			(xy 341.908302 -284.426168) (xy 341.94205 -284.388074) (xy 341.981472 -284.355887) (xy 342.025546 -284.330441)
			(xy 342.073132 -284.312394) (xy 342.122996 -284.302214) (xy 342.173848 -284.300165) (xy 342.224369 -284.306299)
			(xy 342.273253 -284.320459) (xy 342.319232 -284.342276) (xy 342.361116 -284.371186) (xy 342.39782 -284.406441)
			(xy 342.428393 -284.447127) (xy 342.452044 -284.49219) (xy 342.46816 -284.540464) (xy 342.476324 -284.590698)
			(xy 342.476836 -284.616144) (xy 342.476333 -284.641133) (xy 342.78365 -284.641133) (xy 342.78365 -284.591155)
			(xy 342.791469 -284.541792) (xy 342.806913 -284.49426) (xy 342.829603 -284.449728) (xy 342.858979 -284.409295)
			(xy 342.894319 -284.373955) (xy 342.934752 -284.344579) (xy 342.979284 -284.321889) (xy 343.026816 -284.306445)
			(xy 343.076179 -284.298626) (xy 343.126157 -284.298626) (xy 343.17552 -284.306445) (xy 343.223052 -284.321889)
			(xy 343.267584 -284.344579) (xy 343.308017 -284.373955) (xy 343.343357 -284.409295) (xy 343.372733 -284.449728)
			(xy 343.395423 -284.49426) (xy 343.410867 -284.541792) (xy 343.418686 -284.591155) (xy 343.419176 -284.616144)
			(xy 343.724987 -284.616144) (xy 343.729082 -284.565416) (xy 343.741261 -284.516002) (xy 343.761209 -284.469182)
			(xy 343.78841 -284.426168) (xy 343.822158 -284.388074) (xy 343.86158 -284.355887) (xy 343.905654 -284.330441)
			(xy 343.95324 -284.312394) (xy 344.003104 -284.302214) (xy 344.053956 -284.300165) (xy 344.104477 -284.306299)
			(xy 344.153361 -284.320459) (xy 344.19934 -284.342276) (xy 344.241224 -284.371186) (xy 344.277928 -284.406441)
			(xy 344.308501 -284.447127) (xy 344.332152 -284.49219) (xy 344.348268 -284.540464) (xy 344.356432 -284.590698)
			(xy 344.356944 -284.616144) (xy 344.356432 -284.64159) (xy 344.348268 -284.691824) (xy 344.332152 -284.740098)
			(xy 344.308501 -284.785161) (xy 344.277928 -284.825847) (xy 344.241224 -284.861102) (xy 344.19934 -284.890012)
			(xy 344.153361 -284.911829) (xy 344.104477 -284.925989) (xy 344.053956 -284.932123) (xy 344.003104 -284.930074)
			(xy 343.95324 -284.919894) (xy 343.905654 -284.901847) (xy 343.86158 -284.876401) (xy 343.822158 -284.844214)
			(xy 343.78841 -284.80612) (xy 343.761209 -284.763106) (xy 343.741261 -284.716286) (xy 343.729082 -284.666872)
			(xy 343.724987 -284.616144) (xy 343.419176 -284.616144) (xy 343.418686 -284.641133) (xy 343.410867 -284.690496)
			(xy 343.395423 -284.738028) (xy 343.372733 -284.78256) (xy 343.343357 -284.822993) (xy 343.308017 -284.858333)
			(xy 343.267584 -284.887709) (xy 343.223052 -284.910399) (xy 343.17552 -284.925843) (xy 343.126157 -284.933662)
			(xy 343.076179 -284.933662) (xy 343.026816 -284.925843) (xy 342.979284 -284.910399) (xy 342.934752 -284.887709)
			(xy 342.894319 -284.858333) (xy 342.858979 -284.822993) (xy 342.829603 -284.78256) (xy 342.806913 -284.738028)
			(xy 342.791469 -284.690496) (xy 342.78365 -284.641133) (xy 342.476333 -284.641133) (xy 342.476324 -284.64159)
			(xy 342.46816 -284.691824) (xy 342.452044 -284.740098) (xy 342.428393 -284.785161) (xy 342.39782 -284.825847)
			(xy 342.361116 -284.861102) (xy 342.319232 -284.890012) (xy 342.273253 -284.911829) (xy 342.224369 -284.925989)
			(xy 342.173848 -284.932123) (xy 342.122996 -284.930074) (xy 342.073132 -284.919894) (xy 342.025546 -284.901847)
			(xy 341.981472 -284.876401) (xy 341.94205 -284.844214) (xy 341.908302 -284.80612) (xy 341.881101 -284.763106)
			(xy 341.861153 -284.716286) (xy 341.848974 -284.666872) (xy 341.844879 -284.616144) (xy 341.539068 -284.616144)
			(xy 341.538578 -284.641133) (xy 341.530759 -284.690496) (xy 341.515315 -284.738028) (xy 341.492625 -284.78256)
			(xy 341.463249 -284.822993) (xy 341.427909 -284.858333) (xy 341.387476 -284.887709) (xy 341.342944 -284.910399)
			(xy 341.295412 -284.925843) (xy 341.246049 -284.933662) (xy 341.196071 -284.933662) (xy 341.146708 -284.925843)
			(xy 341.099176 -284.910399) (xy 341.054644 -284.887709) (xy 341.014211 -284.858333) (xy 340.978871 -284.822993)
			(xy 340.949495 -284.78256) (xy 340.926805 -284.738028) (xy 340.911361 -284.690496) (xy 340.903542 -284.641133)
			(xy 340.596225 -284.641133) (xy 340.596216 -284.64159) (xy 340.588052 -284.691824) (xy 340.571936 -284.740098)
			(xy 340.548285 -284.785161) (xy 340.517712 -284.825847) (xy 340.481008 -284.861102) (xy 340.439124 -284.890012)
			(xy 340.393145 -284.911829) (xy 340.344261 -284.925989) (xy 340.29374 -284.932123) (xy 340.242888 -284.930074)
			(xy 340.193024 -284.919894) (xy 340.145438 -284.901847) (xy 340.101364 -284.876401) (xy 340.061942 -284.844214)
			(xy 340.028194 -284.80612) (xy 340.000993 -284.763106) (xy 339.981045 -284.716286) (xy 339.968866 -284.666872)
			(xy 339.964771 -284.616144) (xy 339.656928 -284.616144) (xy 339.656416 -284.64159) (xy 339.648252 -284.691824)
			(xy 339.632136 -284.740098) (xy 339.608485 -284.785161) (xy 339.577912 -284.825847) (xy 339.541208 -284.861102)
			(xy 339.499324 -284.890012) (xy 339.453345 -284.911829) (xy 339.404461 -284.925989) (xy 339.35394 -284.932123)
			(xy 339.303088 -284.930074) (xy 339.253224 -284.919894) (xy 339.205638 -284.901847) (xy 339.161564 -284.876401)
			(xy 339.122142 -284.844214) (xy 339.088394 -284.80612) (xy 339.061193 -284.763106) (xy 339.041245 -284.716286)
			(xy 339.029066 -284.666872) (xy 339.024971 -284.616144) (xy 338.718699 -284.616144) (xy 338.718699 -284.64109)
			(xy 338.71088 -284.690455) (xy 338.695433 -284.737989) (xy 338.672741 -284.78252) (xy 338.643361 -284.822953)
			(xy 338.608017 -284.858292) (xy 338.567579 -284.887666) (xy 338.523044 -284.910352) (xy 338.475508 -284.925791)
			(xy 338.426142 -284.933603) (xy 338.401152 -284.934152) (xy 338.377784 -284.933735) (xy 338.331552 -284.926884)
			(xy 338.286822 -284.913337) (xy 338.244558 -284.893386) (xy 338.205671 -284.86746) (xy 338.188046 -284.85211)
			(xy 338.184998 -284.84957) (xy 338.174584 -284.845506) (xy 338.15147 -284.836616) (xy 338.14706 -284.836714)
			(xy 338.138375 -284.838248) (xy 338.134198 -284.839664) (xy 338.084414 -284.861762) (xy 338.046314 -284.878526)
			(xy 338.038009 -284.88292) (xy 338.025191 -284.896639) (xy 338.018281 -284.914097) (xy 338.017866 -284.923484)
			(xy 338.017866 -285.084774) (xy 338.018321 -285.093958) (xy 338.024966 -285.111087) (xy 338.037282 -285.124721)
			(xy 338.045298 -285.129224) (xy 338.049616 -285.131002) (xy 338.072852 -285.140839) (xy 338.116129 -285.166777)
			(xy 338.154767 -285.199224) (xy 338.187796 -285.237366) (xy 338.214385 -285.280246) (xy 338.233868 -285.326787)
			(xy 338.245756 -285.375822) (xy 338.24975 -285.426119) (xy 338.249748 -285.42615) (xy 338.554817 -285.42615)
			(xy 338.558912 -285.375422) (xy 338.571091 -285.326008) (xy 338.591039 -285.279188) (xy 338.61824 -285.236174)
			(xy 338.651988 -285.19808) (xy 338.69141 -285.165893) (xy 338.735484 -285.140447) (xy 338.78307 -285.1224)
			(xy 338.832934 -285.11222) (xy 338.883786 -285.110171) (xy 338.934307 -285.116305) (xy 338.983191 -285.130465)
			(xy 339.02917 -285.152282) (xy 339.071054 -285.181192) (xy 339.107758 -285.216447) (xy 339.138331 -285.257133)
			(xy 339.161982 -285.302196) (xy 339.178098 -285.35047) (xy 339.186262 -285.400704) (xy 339.186774 -285.42615)
			(xy 339.186271 -285.451139) (xy 339.493588 -285.451139) (xy 339.493588 -285.401161) (xy 339.501407 -285.351798)
			(xy 339.516851 -285.304266) (xy 339.539541 -285.259734) (xy 339.568917 -285.219301) (xy 339.604257 -285.183961)
			(xy 339.64469 -285.154585) (xy 339.689222 -285.131895) (xy 339.736754 -285.116451) (xy 339.786117 -285.108632)
			(xy 339.836095 -285.108632) (xy 339.885458 -285.116451) (xy 339.93299 -285.131895) (xy 339.977522 -285.154585)
			(xy 340.017955 -285.183961) (xy 340.053295 -285.219301) (xy 340.082671 -285.259734) (xy 340.105361 -285.304266)
			(xy 340.120805 -285.351798) (xy 340.128624 -285.401161) (xy 340.129114 -285.42615) (xy 340.434925 -285.42615)
			(xy 340.43902 -285.375422) (xy 340.451199 -285.326008) (xy 340.471147 -285.279188) (xy 340.498348 -285.236174)
			(xy 340.532096 -285.19808) (xy 340.571518 -285.165893) (xy 340.615592 -285.140447) (xy 340.663178 -285.1224)
			(xy 340.713042 -285.11222) (xy 340.763894 -285.110171) (xy 340.814415 -285.116305) (xy 340.863299 -285.130465)
			(xy 340.909278 -285.152282) (xy 340.951162 -285.181192) (xy 340.987866 -285.216447) (xy 341.018439 -285.257133)
			(xy 341.04209 -285.302196) (xy 341.058206 -285.35047) (xy 341.06637 -285.400704) (xy 341.066882 -285.42615)
			(xy 342.314779 -285.42615) (xy 342.318874 -285.375422) (xy 342.331053 -285.326008) (xy 342.351001 -285.279188)
			(xy 342.378202 -285.236174) (xy 342.41195 -285.19808) (xy 342.451372 -285.165893) (xy 342.495446 -285.140447)
			(xy 342.543032 -285.1224) (xy 342.592896 -285.11222) (xy 342.643748 -285.110171) (xy 342.694269 -285.116305)
			(xy 342.743153 -285.130465) (xy 342.789132 -285.152282) (xy 342.831016 -285.181192) (xy 342.86772 -285.216447)
			(xy 342.898293 -285.257133) (xy 342.921944 -285.302196) (xy 342.93806 -285.35047) (xy 342.946224 -285.400704)
			(xy 342.946736 -285.42615) (xy 343.254833 -285.42615) (xy 343.258928 -285.375422) (xy 343.271107 -285.326008)
			(xy 343.291055 -285.279188) (xy 343.318256 -285.236174) (xy 343.352004 -285.19808) (xy 343.391426 -285.165893)
			(xy 343.4355 -285.140447) (xy 343.483086 -285.1224) (xy 343.53295 -285.11222) (xy 343.583802 -285.110171)
			(xy 343.634323 -285.116305) (xy 343.683207 -285.130465) (xy 343.729186 -285.152282) (xy 343.77107 -285.181192)
			(xy 343.807774 -285.216447) (xy 343.838347 -285.257133) (xy 343.861998 -285.302196) (xy 343.878114 -285.35047)
			(xy 343.886278 -285.400704) (xy 343.88679 -285.42615) (xy 343.886278 -285.451596) (xy 343.878114 -285.50183)
			(xy 343.861998 -285.550104) (xy 343.838347 -285.595167) (xy 343.807774 -285.635853) (xy 343.77107 -285.671108)
			(xy 343.729186 -285.700018) (xy 343.683207 -285.721835) (xy 343.634323 -285.735995) (xy 343.583802 -285.742129)
			(xy 343.53295 -285.74008) (xy 343.483086 -285.7299) (xy 343.4355 -285.711853) (xy 343.391426 -285.686407)
			(xy 343.352004 -285.65422) (xy 343.318256 -285.616126) (xy 343.291055 -285.573112) (xy 343.271107 -285.526292)
			(xy 343.258928 -285.476878) (xy 343.254833 -285.42615) (xy 342.946736 -285.42615) (xy 342.946224 -285.451596)
			(xy 342.93806 -285.50183) (xy 342.921944 -285.550104) (xy 342.898293 -285.595167) (xy 342.86772 -285.635853)
			(xy 342.831016 -285.671108) (xy 342.789132 -285.700018) (xy 342.743153 -285.721835) (xy 342.694269 -285.735995)
			(xy 342.643748 -285.742129) (xy 342.592896 -285.74008) (xy 342.543032 -285.7299) (xy 342.495446 -285.711853)
			(xy 342.451372 -285.686407) (xy 342.41195 -285.65422) (xy 342.378202 -285.616126) (xy 342.351001 -285.573112)
			(xy 342.331053 -285.526292) (xy 342.318874 -285.476878) (xy 342.314779 -285.42615) (xy 341.066882 -285.42615)
			(xy 341.06637 -285.451596) (xy 341.058206 -285.50183) (xy 341.04209 -285.550104) (xy 341.018439 -285.595167)
			(xy 340.987866 -285.635853) (xy 340.951162 -285.671108) (xy 340.909278 -285.700018) (xy 340.863299 -285.721835)
			(xy 340.814415 -285.735995) (xy 340.763894 -285.742129) (xy 340.713042 -285.74008) (xy 340.663178 -285.7299)
			(xy 340.615592 -285.711853) (xy 340.571518 -285.686407) (xy 340.532096 -285.65422) (xy 340.498348 -285.616126)
			(xy 340.471147 -285.573112) (xy 340.451199 -285.526292) (xy 340.43902 -285.476878) (xy 340.434925 -285.42615)
			(xy 340.129114 -285.42615) (xy 340.128624 -285.451139) (xy 340.120805 -285.500502) (xy 340.105361 -285.548034)
			(xy 340.082671 -285.592566) (xy 340.053295 -285.632999) (xy 340.017955 -285.668339) (xy 339.977522 -285.697715)
			(xy 339.93299 -285.720405) (xy 339.885458 -285.735849) (xy 339.836095 -285.743668) (xy 339.786117 -285.743668)
			(xy 339.736754 -285.735849) (xy 339.689222 -285.720405) (xy 339.64469 -285.697715) (xy 339.604257 -285.668339)
			(xy 339.568917 -285.632999) (xy 339.539541 -285.592566) (xy 339.516851 -285.548034) (xy 339.501407 -285.500502)
			(xy 339.493588 -285.451139) (xy 339.186271 -285.451139) (xy 339.186262 -285.451596) (xy 339.178098 -285.50183)
			(xy 339.161982 -285.550104) (xy 339.138331 -285.595167) (xy 339.107758 -285.635853) (xy 339.071054 -285.671108)
			(xy 339.02917 -285.700018) (xy 338.983191 -285.721835) (xy 338.934307 -285.735995) (xy 338.883786 -285.742129)
			(xy 338.832934 -285.74008) (xy 338.78307 -285.7299) (xy 338.735484 -285.711853) (xy 338.69141 -285.686407)
			(xy 338.651988 -285.65422) (xy 338.61824 -285.616126) (xy 338.591039 -285.573112) (xy 338.571091 -285.526292)
			(xy 338.558912 -285.476878) (xy 338.554817 -285.42615) (xy 338.249748 -285.42615) (xy 338.24575 -285.476415)
			(xy 338.233857 -285.525448) (xy 338.214368 -285.571987) (xy 338.187773 -285.614864) (xy 338.154741 -285.653003)
			(xy 338.116099 -285.685445) (xy 338.072818 -285.711377) (xy 338.049616 -285.721298) (xy 338.045298 -285.723076)
			(xy 338.037287 -285.727588) (xy 338.024959 -285.741206) (xy 338.01834 -285.758342) (xy 338.017866 -285.767526)
			(xy 338.017866 -285.928816) (xy 338.018308 -285.938194) (xy 338.025237 -285.95563) (xy 338.03803 -285.969354)
			(xy 338.046314 -285.973774) (xy 338.084414 -285.990538) (xy 338.134198 -286.012636) (xy 338.138372 -286.014066)
			(xy 338.147059 -286.015602) (xy 338.15147 -286.015684) (xy 338.174584 -286.006794) (xy 338.184998 -286.00273)
			(xy 338.188046 -286.00019) (xy 338.205658 -285.984823) (xy 338.244545 -285.958893) (xy 338.286812 -285.938941)
			(xy 338.331546 -285.925398) (xy 338.377782 -285.918556) (xy 338.401152 -285.918148) (xy 338.426149 -285.918609)
			(xy 338.475529 -285.926423) (xy 338.523078 -285.941866) (xy 338.567625 -285.964559) (xy 338.608074 -285.993941)
			(xy 338.643428 -286.029289) (xy 338.672816 -286.069734) (xy 338.695515 -286.114278) (xy 338.710966 -286.161824)
			(xy 338.718787 -286.211203) (xy 338.718787 -286.236156) (xy 339.024971 -286.236156) (xy 339.029066 -286.185428)
			(xy 339.041245 -286.136014) (xy 339.061193 -286.089194) (xy 339.088394 -286.04618) (xy 339.122142 -286.008086)
			(xy 339.161564 -285.975899) (xy 339.205638 -285.950453) (xy 339.253224 -285.932406) (xy 339.303088 -285.922226)
			(xy 339.35394 -285.920177) (xy 339.404461 -285.926311) (xy 339.453345 -285.940471) (xy 339.499324 -285.962288)
			(xy 339.541208 -285.991198) (xy 339.577912 -286.026453) (xy 339.608485 -286.067139) (xy 339.632136 -286.112202)
			(xy 339.648252 -286.160476) (xy 339.656416 -286.21071) (xy 339.656928 -286.236156) (xy 339.964771 -286.236156)
			(xy 339.968866 -286.185428) (xy 339.981045 -286.136014) (xy 340.000993 -286.089194) (xy 340.028194 -286.04618)
			(xy 340.061942 -286.008086) (xy 340.101364 -285.975899) (xy 340.145438 -285.950453) (xy 340.193024 -285.932406)
			(xy 340.242888 -285.922226) (xy 340.29374 -285.920177) (xy 340.344261 -285.926311) (xy 340.393145 -285.940471)
			(xy 340.439124 -285.962288) (xy 340.481008 -285.991198) (xy 340.517712 -286.026453) (xy 340.548285 -286.067139)
			(xy 340.571936 -286.112202) (xy 340.588052 -286.160476) (xy 340.596216 -286.21071) (xy 340.596728 -286.236156)
			(xy 340.596225 -286.261145) (xy 340.903542 -286.261145) (xy 340.903542 -286.211167) (xy 340.911361 -286.161804)
			(xy 340.926805 -286.114272) (xy 340.949495 -286.06974) (xy 340.978871 -286.029307) (xy 341.014211 -285.993967)
			(xy 341.054644 -285.964591) (xy 341.099176 -285.941901) (xy 341.146708 -285.926457) (xy 341.196071 -285.918638)
			(xy 341.246049 -285.918638) (xy 341.295412 -285.926457) (xy 341.342944 -285.941901) (xy 341.387476 -285.964591)
			(xy 341.427909 -285.993967) (xy 341.463249 -286.029307) (xy 341.492625 -286.06974) (xy 341.515315 -286.114272)
			(xy 341.530759 -286.161804) (xy 341.538578 -286.211167) (xy 341.539068 -286.236156) (xy 341.844879 -286.236156)
			(xy 341.848974 -286.185428) (xy 341.861153 -286.136014) (xy 341.881101 -286.089194) (xy 341.908302 -286.04618)
			(xy 341.94205 -286.008086) (xy 341.981472 -285.975899) (xy 342.025546 -285.950453) (xy 342.073132 -285.932406)
			(xy 342.122996 -285.922226) (xy 342.173848 -285.920177) (xy 342.224369 -285.926311) (xy 342.273253 -285.940471)
			(xy 342.319232 -285.962288) (xy 342.361116 -285.991198) (xy 342.39782 -286.026453) (xy 342.428393 -286.067139)
			(xy 342.452044 -286.112202) (xy 342.46816 -286.160476) (xy 342.476324 -286.21071) (xy 342.476836 -286.236156)
			(xy 342.476333 -286.261145) (xy 342.78365 -286.261145) (xy 342.78365 -286.211167) (xy 342.791469 -286.161804)
			(xy 342.806913 -286.114272) (xy 342.829603 -286.06974) (xy 342.858979 -286.029307) (xy 342.894319 -285.993967)
			(xy 342.934752 -285.964591) (xy 342.979284 -285.941901) (xy 343.026816 -285.926457) (xy 343.076179 -285.918638)
			(xy 343.126157 -285.918638) (xy 343.17552 -285.926457) (xy 343.223052 -285.941901) (xy 343.267584 -285.964591)
			(xy 343.308017 -285.993967) (xy 343.343357 -286.029307) (xy 343.372733 -286.06974) (xy 343.395423 -286.114272)
			(xy 343.410867 -286.161804) (xy 343.418686 -286.211167) (xy 343.419176 -286.236156) (xy 343.724987 -286.236156)
			(xy 343.729082 -286.185428) (xy 343.741261 -286.136014) (xy 343.761209 -286.089194) (xy 343.78841 -286.04618)
			(xy 343.822158 -286.008086) (xy 343.86158 -285.975899) (xy 343.905654 -285.950453) (xy 343.95324 -285.932406)
			(xy 344.003104 -285.922226) (xy 344.053956 -285.920177) (xy 344.104477 -285.926311) (xy 344.153361 -285.940471)
			(xy 344.19934 -285.962288) (xy 344.241224 -285.991198) (xy 344.277928 -286.026453) (xy 344.308501 -286.067139)
			(xy 344.332152 -286.112202) (xy 344.348268 -286.160476) (xy 344.356432 -286.21071) (xy 344.356944 -286.236156)
			(xy 344.356432 -286.261602) (xy 344.348268 -286.311836) (xy 344.332152 -286.36011) (xy 344.308501 -286.405173)
			(xy 344.277928 -286.445859) (xy 344.241224 -286.481114) (xy 344.19934 -286.510024) (xy 344.153361 -286.531841)
			(xy 344.104477 -286.546001) (xy 344.053956 -286.552135) (xy 344.003104 -286.550086) (xy 343.95324 -286.539906)
			(xy 343.905654 -286.521859) (xy 343.86158 -286.496413) (xy 343.822158 -286.464226) (xy 343.78841 -286.426132)
			(xy 343.761209 -286.383118) (xy 343.741261 -286.336298) (xy 343.729082 -286.286884) (xy 343.724987 -286.236156)
			(xy 343.419176 -286.236156) (xy 343.418686 -286.261145) (xy 343.410867 -286.310508) (xy 343.395423 -286.35804)
			(xy 343.372733 -286.402572) (xy 343.343357 -286.443005) (xy 343.308017 -286.478345) (xy 343.267584 -286.507721)
			(xy 343.223052 -286.530411) (xy 343.17552 -286.545855) (xy 343.126157 -286.553674) (xy 343.076179 -286.553674)
			(xy 343.026816 -286.545855) (xy 342.979284 -286.530411) (xy 342.934752 -286.507721) (xy 342.894319 -286.478345)
			(xy 342.858979 -286.443005) (xy 342.829603 -286.402572) (xy 342.806913 -286.35804) (xy 342.791469 -286.310508)
			(xy 342.78365 -286.261145) (xy 342.476333 -286.261145) (xy 342.476324 -286.261602) (xy 342.46816 -286.311836)
			(xy 342.452044 -286.36011) (xy 342.428393 -286.405173) (xy 342.39782 -286.445859) (xy 342.361116 -286.481114)
			(xy 342.319232 -286.510024) (xy 342.273253 -286.531841) (xy 342.224369 -286.546001) (xy 342.173848 -286.552135)
			(xy 342.122996 -286.550086) (xy 342.073132 -286.539906) (xy 342.025546 -286.521859) (xy 341.981472 -286.496413)
			(xy 341.94205 -286.464226) (xy 341.908302 -286.426132) (xy 341.881101 -286.383118) (xy 341.861153 -286.336298)
			(xy 341.848974 -286.286884) (xy 341.844879 -286.236156) (xy 341.539068 -286.236156) (xy 341.538578 -286.261145)
			(xy 341.530759 -286.310508) (xy 341.515315 -286.35804) (xy 341.492625 -286.402572) (xy 341.463249 -286.443005)
			(xy 341.427909 -286.478345) (xy 341.387476 -286.507721) (xy 341.342944 -286.530411) (xy 341.295412 -286.545855)
			(xy 341.246049 -286.553674) (xy 341.196071 -286.553674) (xy 341.146708 -286.545855) (xy 341.099176 -286.530411)
			(xy 341.054644 -286.507721) (xy 341.014211 -286.478345) (xy 340.978871 -286.443005) (xy 340.949495 -286.402572)
			(xy 340.926805 -286.35804) (xy 340.911361 -286.310508) (xy 340.903542 -286.261145) (xy 340.596225 -286.261145)
			(xy 340.596216 -286.261602) (xy 340.588052 -286.311836) (xy 340.571936 -286.36011) (xy 340.548285 -286.405173)
			(xy 340.517712 -286.445859) (xy 340.481008 -286.481114) (xy 340.439124 -286.510024) (xy 340.393145 -286.531841)
			(xy 340.344261 -286.546001) (xy 340.29374 -286.552135) (xy 340.242888 -286.550086) (xy 340.193024 -286.539906)
			(xy 340.145438 -286.521859) (xy 340.101364 -286.496413) (xy 340.061942 -286.464226) (xy 340.028194 -286.426132)
			(xy 340.000993 -286.383118) (xy 339.981045 -286.336298) (xy 339.968866 -286.286884) (xy 339.964771 -286.236156)
			(xy 339.656928 -286.236156) (xy 339.656416 -286.261602) (xy 339.648252 -286.311836) (xy 339.632136 -286.36011)
			(xy 339.608485 -286.405173) (xy 339.577912 -286.445859) (xy 339.541208 -286.481114) (xy 339.499324 -286.510024)
			(xy 339.453345 -286.531841) (xy 339.404461 -286.546001) (xy 339.35394 -286.552135) (xy 339.303088 -286.550086)
			(xy 339.253224 -286.539906) (xy 339.205638 -286.521859) (xy 339.161564 -286.496413) (xy 339.122142 -286.464226)
			(xy 339.088394 -286.426132) (xy 339.061193 -286.383118) (xy 339.041245 -286.336298) (xy 339.029066 -286.286884)
			(xy 339.024971 -286.236156) (xy 338.718787 -286.236156) (xy 338.718787 -286.261197) (xy 338.710966 -286.310576)
			(xy 338.695515 -286.358122) (xy 338.672816 -286.402666) (xy 338.643428 -286.443111) (xy 338.608074 -286.478459)
			(xy 338.567625 -286.507841) (xy 338.523078 -286.530534) (xy 338.475529 -286.545977) (xy 338.426149 -286.553791)
			(xy 338.401152 -286.554164) (xy 338.377784 -286.553747) (xy 338.331552 -286.546896) (xy 338.286821 -286.53335)
			(xy 338.244557 -286.513399) (xy 338.205669 -286.487474) (xy 338.188046 -286.472122) (xy 338.184998 -286.469582)
			(xy 338.174584 -286.465518) (xy 338.15147 -286.456628) (xy 338.14706 -286.456726) (xy 338.138376 -286.458261)
			(xy 338.134198 -286.459676) (xy 338.084414 -286.481774) (xy 338.046314 -286.498538) (xy 338.03801 -286.502932)
			(xy 338.025196 -286.516653) (xy 338.01829 -286.53411) (xy 338.017866 -286.543496) (xy 338.017866 -286.704532)
			(xy 338.018247 -286.713604) (xy 338.024665 -286.730573) (xy 338.036689 -286.744159) (xy 338.044536 -286.748728)
			(xy 338.04987 -286.75076) (xy 338.073106 -286.7606) (xy 338.116384 -286.786542) (xy 338.155022 -286.818994)
			(xy 338.18805 -286.85714) (xy 338.21464 -286.900023) (xy 338.234124 -286.946567) (xy 338.246014 -286.995604)
			(xy 338.25001 -287.045903) (xy 338.25001 -287.045908) (xy 338.554817 -287.045908) (xy 338.558912 -286.99518)
			(xy 338.571091 -286.945766) (xy 338.591039 -286.898946) (xy 338.61824 -286.855932) (xy 338.651988 -286.817838)
			(xy 338.69141 -286.785651) (xy 338.735484 -286.760205) (xy 338.78307 -286.742158) (xy 338.832934 -286.731978)
			(xy 338.883786 -286.729929) (xy 338.934307 -286.736063) (xy 338.983191 -286.750223) (xy 339.02917 -286.77204)
			(xy 339.071054 -286.80095) (xy 339.107758 -286.836205) (xy 339.138331 -286.876891) (xy 339.161982 -286.921954)
			(xy 339.178098 -286.970228) (xy 339.186262 -287.020462) (xy 339.186774 -287.045908) (xy 339.186271 -287.070897)
			(xy 339.493588 -287.070897) (xy 339.493588 -287.020919) (xy 339.501407 -286.971556) (xy 339.516851 -286.924024)
			(xy 339.539541 -286.879492) (xy 339.568917 -286.839059) (xy 339.604257 -286.803719) (xy 339.64469 -286.774343)
			(xy 339.689222 -286.751653) (xy 339.736754 -286.736209) (xy 339.786117 -286.72839) (xy 339.836095 -286.72839)
			(xy 339.885458 -286.736209) (xy 339.93299 -286.751653) (xy 339.977522 -286.774343) (xy 340.017955 -286.803719)
			(xy 340.053295 -286.839059) (xy 340.082671 -286.879492) (xy 340.105361 -286.924024) (xy 340.120805 -286.971556)
			(xy 340.128624 -287.020919) (xy 340.129114 -287.045908) (xy 340.434925 -287.045908) (xy 340.43902 -286.99518)
			(xy 340.451199 -286.945766) (xy 340.471147 -286.898946) (xy 340.498348 -286.855932) (xy 340.532096 -286.817838)
			(xy 340.571518 -286.785651) (xy 340.615592 -286.760205) (xy 340.663178 -286.742158) (xy 340.713042 -286.731978)
			(xy 340.763894 -286.729929) (xy 340.814415 -286.736063) (xy 340.863299 -286.750223) (xy 340.909278 -286.77204)
			(xy 340.951162 -286.80095) (xy 340.987866 -286.836205) (xy 341.018439 -286.876891) (xy 341.04209 -286.921954)
			(xy 341.058206 -286.970228) (xy 341.06637 -287.020462) (xy 341.066882 -287.045908) (xy 341.066379 -287.070897)
			(xy 341.373696 -287.070897) (xy 341.373696 -287.020919) (xy 341.381515 -286.971556) (xy 341.396959 -286.924024)
			(xy 341.419649 -286.879492) (xy 341.449025 -286.839059) (xy 341.484365 -286.803719) (xy 341.524798 -286.774343)
			(xy 341.56933 -286.751653) (xy 341.616862 -286.736209) (xy 341.666225 -286.72839) (xy 341.716203 -286.72839)
			(xy 341.765566 -286.736209) (xy 341.813098 -286.751653) (xy 341.85763 -286.774343) (xy 341.898063 -286.803719)
			(xy 341.933403 -286.839059) (xy 341.962779 -286.879492) (xy 341.985469 -286.924024) (xy 342.000913 -286.971556)
			(xy 342.008732 -287.020919) (xy 342.009222 -287.045908) (xy 342.314779 -287.045908) (xy 342.318874 -286.99518)
			(xy 342.331053 -286.945766) (xy 342.351001 -286.898946) (xy 342.378202 -286.855932) (xy 342.41195 -286.817838)
			(xy 342.451372 -286.785651) (xy 342.495446 -286.760205) (xy 342.543032 -286.742158) (xy 342.592896 -286.731978)
			(xy 342.643748 -286.729929) (xy 342.694269 -286.736063) (xy 342.743153 -286.750223) (xy 342.789132 -286.77204)
			(xy 342.831016 -286.80095) (xy 342.86772 -286.836205) (xy 342.898293 -286.876891) (xy 342.921944 -286.921954)
			(xy 342.93806 -286.970228) (xy 342.946224 -287.020462) (xy 342.946736 -287.045908) (xy 343.254833 -287.045908)
			(xy 343.258928 -286.99518) (xy 343.271107 -286.945766) (xy 343.291055 -286.898946) (xy 343.318256 -286.855932)
			(xy 343.352004 -286.817838) (xy 343.391426 -286.785651) (xy 343.4355 -286.760205) (xy 343.483086 -286.742158)
			(xy 343.53295 -286.731978) (xy 343.583802 -286.729929) (xy 343.634323 -286.736063) (xy 343.683207 -286.750223)
			(xy 343.729186 -286.77204) (xy 343.77107 -286.80095) (xy 343.807774 -286.836205) (xy 343.838347 -286.876891)
			(xy 343.861998 -286.921954) (xy 343.878114 -286.970228) (xy 343.886278 -287.020462) (xy 343.88679 -287.045908)
			(xy 343.886278 -287.071354) (xy 343.878114 -287.121588) (xy 343.861998 -287.169862) (xy 343.838347 -287.214925)
			(xy 343.807774 -287.255611) (xy 343.77107 -287.290866) (xy 343.729186 -287.319776) (xy 343.683207 -287.341593)
			(xy 343.634323 -287.355753) (xy 343.583802 -287.361887) (xy 343.53295 -287.359838) (xy 343.483086 -287.349658)
			(xy 343.4355 -287.331611) (xy 343.391426 -287.306165) (xy 343.352004 -287.273978) (xy 343.318256 -287.235884)
			(xy 343.291055 -287.19287) (xy 343.271107 -287.14605) (xy 343.258928 -287.096636) (xy 343.254833 -287.045908)
			(xy 342.946736 -287.045908) (xy 342.946224 -287.071354) (xy 342.93806 -287.121588) (xy 342.921944 -287.169862)
			(xy 342.898293 -287.214925) (xy 342.86772 -287.255611) (xy 342.831016 -287.290866) (xy 342.789132 -287.319776)
			(xy 342.743153 -287.341593) (xy 342.694269 -287.355753) (xy 342.643748 -287.361887) (xy 342.592896 -287.359838)
			(xy 342.543032 -287.349658) (xy 342.495446 -287.331611) (xy 342.451372 -287.306165) (xy 342.41195 -287.273978)
			(xy 342.378202 -287.235884) (xy 342.351001 -287.19287) (xy 342.331053 -287.14605) (xy 342.318874 -287.096636)
			(xy 342.314779 -287.045908) (xy 342.009222 -287.045908) (xy 342.008732 -287.070897) (xy 342.000913 -287.12026)
			(xy 341.985469 -287.167792) (xy 341.962779 -287.212324) (xy 341.933403 -287.252757) (xy 341.898063 -287.288097)
			(xy 341.85763 -287.317473) (xy 341.813098 -287.340163) (xy 341.765566 -287.355607) (xy 341.716203 -287.363426)
			(xy 341.666225 -287.363426) (xy 341.616862 -287.355607) (xy 341.56933 -287.340163) (xy 341.524798 -287.317473)
			(xy 341.484365 -287.288097) (xy 341.449025 -287.252757) (xy 341.419649 -287.212324) (xy 341.396959 -287.167792)
			(xy 341.381515 -287.12026) (xy 341.373696 -287.070897) (xy 341.066379 -287.070897) (xy 341.06637 -287.071354)
			(xy 341.058206 -287.121588) (xy 341.04209 -287.169862) (xy 341.018439 -287.214925) (xy 340.987866 -287.255611)
			(xy 340.951162 -287.290866) (xy 340.909278 -287.319776) (xy 340.863299 -287.341593) (xy 340.814415 -287.355753)
			(xy 340.763894 -287.361887) (xy 340.713042 -287.359838) (xy 340.663178 -287.349658) (xy 340.615592 -287.331611)
			(xy 340.571518 -287.306165) (xy 340.532096 -287.273978) (xy 340.498348 -287.235884) (xy 340.471147 -287.19287)
			(xy 340.451199 -287.14605) (xy 340.43902 -287.096636) (xy 340.434925 -287.045908) (xy 340.129114 -287.045908)
			(xy 340.128624 -287.070897) (xy 340.120805 -287.12026) (xy 340.105361 -287.167792) (xy 340.082671 -287.212324)
			(xy 340.053295 -287.252757) (xy 340.017955 -287.288097) (xy 339.977522 -287.317473) (xy 339.93299 -287.340163)
			(xy 339.885458 -287.355607) (xy 339.836095 -287.363426) (xy 339.786117 -287.363426) (xy 339.736754 -287.355607)
			(xy 339.689222 -287.340163) (xy 339.64469 -287.317473) (xy 339.604257 -287.288097) (xy 339.568917 -287.252757)
			(xy 339.539541 -287.212324) (xy 339.516851 -287.167792) (xy 339.501407 -287.12026) (xy 339.493588 -287.070897)
			(xy 339.186271 -287.070897) (xy 339.186262 -287.071354) (xy 339.178098 -287.121588) (xy 339.161982 -287.169862)
			(xy 339.138331 -287.214925) (xy 339.107758 -287.255611) (xy 339.071054 -287.290866) (xy 339.02917 -287.319776)
			(xy 338.983191 -287.341593) (xy 338.934307 -287.355753) (xy 338.883786 -287.361887) (xy 338.832934 -287.359838)
			(xy 338.78307 -287.349658) (xy 338.735484 -287.331611) (xy 338.69141 -287.306165) (xy 338.651988 -287.273978)
			(xy 338.61824 -287.235884) (xy 338.591039 -287.19287) (xy 338.571091 -287.14605) (xy 338.558912 -287.096636)
			(xy 338.554817 -287.045908) (xy 338.25001 -287.045908) (xy 338.246013 -287.096202) (xy 338.234122 -287.145239)
			(xy 338.214637 -287.191783) (xy 338.188047 -287.234665) (xy 338.155017 -287.272811) (xy 338.116379 -287.305261)
			(xy 338.073101 -287.331203) (xy 338.04987 -287.341056) (xy 338.044536 -287.343088) (xy 338.036703 -287.347671)
			(xy 338.024701 -287.361265) (xy 338.018265 -287.378218) (xy 338.017866 -287.387284) (xy 338.017866 -287.548828)
			(xy 338.01831 -287.558205) (xy 338.025242 -287.575637) (xy 338.038035 -287.589358) (xy 338.046314 -287.593786)
			(xy 338.084414 -287.61055) (xy 338.134198 -287.632648) (xy 338.138372 -287.634078) (xy 338.147059 -287.635613)
			(xy 338.15147 -287.635696) (xy 338.174584 -287.626806) (xy 338.184998 -287.622742) (xy 338.188046 -287.620202)
			(xy 338.205657 -287.604834) (xy 338.244544 -287.578903) (xy 338.286811 -287.55895) (xy 338.331546 -287.545407)
			(xy 338.377782 -287.538565) (xy 338.401152 -287.53816) (xy 338.426148 -287.538621) (xy 338.475526 -287.546435)
			(xy 338.523073 -287.561877) (xy 338.567619 -287.584569) (xy 338.608066 -287.61395) (xy 338.643419 -287.649297)
			(xy 338.672806 -287.68974) (xy 338.695504 -287.734282) (xy 338.710954 -287.781827) (xy 338.718775 -287.831204)
			(xy 338.718775 -287.856168) (xy 339.024971 -287.856168) (xy 339.029066 -287.80544) (xy 339.041245 -287.756026)
			(xy 339.061193 -287.709206) (xy 339.088394 -287.666192) (xy 339.122142 -287.628098) (xy 339.161564 -287.595911)
			(xy 339.205638 -287.570465) (xy 339.253224 -287.552418) (xy 339.303088 -287.542238) (xy 339.35394 -287.540189)
			(xy 339.404461 -287.546323) (xy 339.453345 -287.560483) (xy 339.499324 -287.5823) (xy 339.541208 -287.61121)
			(xy 339.577912 -287.646465) (xy 339.608485 -287.687151) (xy 339.632136 -287.732214) (xy 339.648252 -287.780488)
			(xy 339.656416 -287.830722) (xy 339.656928 -287.856168) (xy 339.964771 -287.856168) (xy 339.968866 -287.80544)
			(xy 339.981045 -287.756026) (xy 340.000993 -287.709206) (xy 340.028194 -287.666192) (xy 340.061942 -287.628098)
			(xy 340.101364 -287.595911) (xy 340.145438 -287.570465) (xy 340.193024 -287.552418) (xy 340.242888 -287.542238)
			(xy 340.29374 -287.540189) (xy 340.344261 -287.546323) (xy 340.393145 -287.560483) (xy 340.439124 -287.5823)
			(xy 340.481008 -287.61121) (xy 340.517712 -287.646465) (xy 340.548285 -287.687151) (xy 340.571936 -287.732214)
			(xy 340.588052 -287.780488) (xy 340.596216 -287.830722) (xy 340.596728 -287.856168) (xy 341.844879 -287.856168)
			(xy 341.848974 -287.80544) (xy 341.861153 -287.756026) (xy 341.881101 -287.709206) (xy 341.908302 -287.666192)
			(xy 341.94205 -287.628098) (xy 341.981472 -287.595911) (xy 342.025546 -287.570465) (xy 342.073132 -287.552418)
			(xy 342.122996 -287.542238) (xy 342.173848 -287.540189) (xy 342.224369 -287.546323) (xy 342.273253 -287.560483)
			(xy 342.319232 -287.5823) (xy 342.361116 -287.61121) (xy 342.39782 -287.646465) (xy 342.428393 -287.687151)
			(xy 342.452044 -287.732214) (xy 342.46816 -287.780488) (xy 342.476324 -287.830722) (xy 342.476836 -287.856168)
			(xy 342.476333 -287.881157) (xy 342.78365 -287.881157) (xy 342.78365 -287.831179) (xy 342.791469 -287.781816)
			(xy 342.806913 -287.734284) (xy 342.829603 -287.689752) (xy 342.858979 -287.649319) (xy 342.894319 -287.613979)
			(xy 342.934752 -287.584603) (xy 342.979284 -287.561913) (xy 343.026816 -287.546469) (xy 343.076179 -287.53865)
			(xy 343.126157 -287.53865) (xy 343.17552 -287.546469) (xy 343.223052 -287.561913) (xy 343.267584 -287.584603)
			(xy 343.308017 -287.613979) (xy 343.343357 -287.649319) (xy 343.372733 -287.689752) (xy 343.395423 -287.734284)
			(xy 343.410867 -287.781816) (xy 343.418686 -287.831179) (xy 343.419176 -287.856168) (xy 343.724987 -287.856168)
			(xy 343.729082 -287.80544) (xy 343.741261 -287.756026) (xy 343.761209 -287.709206) (xy 343.78841 -287.666192)
			(xy 343.822158 -287.628098) (xy 343.86158 -287.595911) (xy 343.905654 -287.570465) (xy 343.95324 -287.552418)
			(xy 344.003104 -287.542238) (xy 344.053956 -287.540189) (xy 344.104477 -287.546323) (xy 344.153361 -287.560483)
			(xy 344.19934 -287.5823) (xy 344.241224 -287.61121) (xy 344.277928 -287.646465) (xy 344.308501 -287.687151)
			(xy 344.332152 -287.732214) (xy 344.348268 -287.780488) (xy 344.356432 -287.830722) (xy 344.356944 -287.856168)
			(xy 344.356432 -287.881614) (xy 344.348268 -287.931848) (xy 344.332152 -287.980122) (xy 344.308501 -288.025185)
			(xy 344.277928 -288.065871) (xy 344.241224 -288.101126) (xy 344.19934 -288.130036) (xy 344.153361 -288.151853)
			(xy 344.104477 -288.166013) (xy 344.053956 -288.172147) (xy 344.003104 -288.170098) (xy 343.95324 -288.159918)
			(xy 343.905654 -288.141871) (xy 343.86158 -288.116425) (xy 343.822158 -288.084238) (xy 343.78841 -288.046144)
			(xy 343.761209 -288.00313) (xy 343.741261 -287.95631) (xy 343.729082 -287.906896) (xy 343.724987 -287.856168)
			(xy 343.419176 -287.856168) (xy 343.418686 -287.881157) (xy 343.410867 -287.93052) (xy 343.395423 -287.978052)
			(xy 343.372733 -288.022584) (xy 343.343357 -288.063017) (xy 343.308017 -288.098357) (xy 343.267584 -288.127733)
			(xy 343.223052 -288.150423) (xy 343.17552 -288.165867) (xy 343.126157 -288.173686) (xy 343.076179 -288.173686)
			(xy 343.026816 -288.165867) (xy 342.979284 -288.150423) (xy 342.934752 -288.127733) (xy 342.894319 -288.098357)
			(xy 342.858979 -288.063017) (xy 342.829603 -288.022584) (xy 342.806913 -287.978052) (xy 342.791469 -287.93052)
			(xy 342.78365 -287.881157) (xy 342.476333 -287.881157) (xy 342.476324 -287.881614) (xy 342.46816 -287.931848)
			(xy 342.452044 -287.980122) (xy 342.428393 -288.025185) (xy 342.39782 -288.065871) (xy 342.361116 -288.101126)
			(xy 342.319232 -288.130036) (xy 342.273253 -288.151853) (xy 342.224369 -288.166013) (xy 342.173848 -288.172147)
			(xy 342.122996 -288.170098) (xy 342.073132 -288.159918) (xy 342.025546 -288.141871) (xy 341.981472 -288.116425)
			(xy 341.94205 -288.084238) (xy 341.908302 -288.046144) (xy 341.881101 -288.00313) (xy 341.861153 -287.95631)
			(xy 341.848974 -287.906896) (xy 341.844879 -287.856168) (xy 340.596728 -287.856168) (xy 340.596216 -287.881614)
			(xy 340.588052 -287.931848) (xy 340.571936 -287.980122) (xy 340.548285 -288.025185) (xy 340.517712 -288.065871)
			(xy 340.481008 -288.101126) (xy 340.439124 -288.130036) (xy 340.393145 -288.151853) (xy 340.344261 -288.166013)
			(xy 340.29374 -288.172147) (xy 340.242888 -288.170098) (xy 340.193024 -288.159918) (xy 340.145438 -288.141871)
			(xy 340.101364 -288.116425) (xy 340.061942 -288.084238) (xy 340.028194 -288.046144) (xy 340.000993 -288.00313)
			(xy 339.981045 -287.95631) (xy 339.968866 -287.906896) (xy 339.964771 -287.856168) (xy 339.656928 -287.856168)
			(xy 339.656416 -287.881614) (xy 339.648252 -287.931848) (xy 339.632136 -287.980122) (xy 339.608485 -288.025185)
			(xy 339.577912 -288.065871) (xy 339.541208 -288.101126) (xy 339.499324 -288.130036) (xy 339.453345 -288.151853)
			(xy 339.404461 -288.166013) (xy 339.35394 -288.172147) (xy 339.303088 -288.170098) (xy 339.253224 -288.159918)
			(xy 339.205638 -288.141871) (xy 339.161564 -288.116425) (xy 339.122142 -288.084238) (xy 339.088394 -288.046144)
			(xy 339.061193 -288.00313) (xy 339.041245 -287.95631) (xy 339.029066 -287.906896) (xy 339.024971 -287.856168)
			(xy 338.718775 -287.856168) (xy 338.718775 -287.881196) (xy 338.710954 -287.930573) (xy 338.695504 -287.978118)
			(xy 338.672806 -288.02266) (xy 338.643419 -288.063103) (xy 338.608066 -288.09845) (xy 338.567619 -288.127831)
			(xy 338.523073 -288.150523) (xy 338.475526 -288.165965) (xy 338.426148 -288.173779) (xy 338.401152 -288.174176)
			(xy 338.377784 -288.173759) (xy 338.331551 -288.166909) (xy 338.286821 -288.153362) (xy 338.244556 -288.133412)
			(xy 338.205667 -288.107488) (xy 338.188046 -288.092134) (xy 338.184998 -288.089594) (xy 338.174584 -288.08553)
			(xy 338.15147 -288.07664) (xy 338.14706 -288.076738) (xy 338.138376 -288.078273) (xy 338.134198 -288.079688)
			(xy 338.084414 -288.101786) (xy 338.046314 -288.11855) (xy 338.038011 -288.122945) (xy 338.0252 -288.136666)
			(xy 338.018299 -288.154123) (xy 338.017866 -288.163508) (xy 338.017866 -288.324544) (xy 338.018332 -288.333721)
			(xy 338.024993 -288.350831) (xy 338.037313 -288.364444) (xy 338.045298 -288.368994) (xy 338.049616 -288.370772)
			(xy 338.072854 -288.380609) (xy 338.116136 -288.406547) (xy 338.154779 -288.438996) (xy 338.187811 -288.47714)
			(xy 338.214405 -288.520023) (xy 338.233891 -288.566568) (xy 338.245782 -288.615607) (xy 338.249778 -288.665907)
			(xy 338.249777 -288.66592) (xy 338.554817 -288.66592) (xy 338.558912 -288.615192) (xy 338.571091 -288.565778)
			(xy 338.591039 -288.518958) (xy 338.61824 -288.475944) (xy 338.651988 -288.43785) (xy 338.69141 -288.405663)
			(xy 338.735484 -288.380217) (xy 338.78307 -288.36217) (xy 338.832934 -288.35199) (xy 338.883786 -288.349941)
			(xy 338.934307 -288.356075) (xy 338.983191 -288.370235) (xy 339.02917 -288.392052) (xy 339.071054 -288.420962)
			(xy 339.107758 -288.456217) (xy 339.138331 -288.496903) (xy 339.161982 -288.541966) (xy 339.178098 -288.59024)
			(xy 339.186262 -288.640474) (xy 339.186774 -288.66592) (xy 339.186271 -288.690909) (xy 339.493588 -288.690909)
			(xy 339.493588 -288.640931) (xy 339.501407 -288.591568) (xy 339.516851 -288.544036) (xy 339.539541 -288.499504)
			(xy 339.568917 -288.459071) (xy 339.604257 -288.423731) (xy 339.64469 -288.394355) (xy 339.689222 -288.371665)
			(xy 339.736754 -288.356221) (xy 339.786117 -288.348402) (xy 339.836095 -288.348402) (xy 339.885458 -288.356221)
			(xy 339.93299 -288.371665) (xy 339.977522 -288.394355) (xy 340.017955 -288.423731) (xy 340.053295 -288.459071)
			(xy 340.082671 -288.499504) (xy 340.105361 -288.544036) (xy 340.120805 -288.591568) (xy 340.128624 -288.640931)
			(xy 340.129114 -288.66592) (xy 340.434925 -288.66592) (xy 340.43902 -288.615192) (xy 340.451199 -288.565778)
			(xy 340.471147 -288.518958) (xy 340.498348 -288.475944) (xy 340.532096 -288.43785) (xy 340.571518 -288.405663)
			(xy 340.615592 -288.380217) (xy 340.663178 -288.36217) (xy 340.713042 -288.35199) (xy 340.763894 -288.349941)
			(xy 340.814415 -288.356075) (xy 340.863299 -288.370235) (xy 340.909278 -288.392052) (xy 340.951162 -288.420962)
			(xy 340.987866 -288.456217) (xy 341.018439 -288.496903) (xy 341.04209 -288.541966) (xy 341.058206 -288.59024)
			(xy 341.06637 -288.640474) (xy 341.066882 -288.66592) (xy 341.066379 -288.690909) (xy 341.373696 -288.690909)
			(xy 341.373696 -288.640931) (xy 341.381515 -288.591568) (xy 341.396959 -288.544036) (xy 341.419649 -288.499504)
			(xy 341.449025 -288.459071) (xy 341.484365 -288.423731) (xy 341.524798 -288.394355) (xy 341.56933 -288.371665)
			(xy 341.616862 -288.356221) (xy 341.666225 -288.348402) (xy 341.716203 -288.348402) (xy 341.765566 -288.356221)
			(xy 341.813098 -288.371665) (xy 341.85763 -288.394355) (xy 341.898063 -288.423731) (xy 341.933403 -288.459071)
			(xy 341.962779 -288.499504) (xy 341.985469 -288.544036) (xy 342.000913 -288.591568) (xy 342.008732 -288.640931)
			(xy 342.009222 -288.66592) (xy 342.314779 -288.66592) (xy 342.318874 -288.615192) (xy 342.331053 -288.565778)
			(xy 342.351001 -288.518958) (xy 342.378202 -288.475944) (xy 342.41195 -288.43785) (xy 342.451372 -288.405663)
			(xy 342.495446 -288.380217) (xy 342.543032 -288.36217) (xy 342.592896 -288.35199) (xy 342.643748 -288.349941)
			(xy 342.694269 -288.356075) (xy 342.743153 -288.370235) (xy 342.789132 -288.392052) (xy 342.831016 -288.420962)
			(xy 342.86772 -288.456217) (xy 342.898293 -288.496903) (xy 342.921944 -288.541966) (xy 342.93806 -288.59024)
			(xy 342.946224 -288.640474) (xy 342.946736 -288.66592) (xy 343.254833 -288.66592) (xy 343.258928 -288.615192)
			(xy 343.271107 -288.565778) (xy 343.291055 -288.518958) (xy 343.318256 -288.475944) (xy 343.352004 -288.43785)
			(xy 343.391426 -288.405663) (xy 343.4355 -288.380217) (xy 343.483086 -288.36217) (xy 343.53295 -288.35199)
			(xy 343.583802 -288.349941) (xy 343.634323 -288.356075) (xy 343.683207 -288.370235) (xy 343.729186 -288.392052)
			(xy 343.77107 -288.420962) (xy 343.807774 -288.456217) (xy 343.838347 -288.496903) (xy 343.861998 -288.541966)
			(xy 343.878114 -288.59024) (xy 343.886278 -288.640474) (xy 343.88679 -288.66592) (xy 343.886278 -288.691366)
			(xy 343.878114 -288.7416) (xy 343.861998 -288.789874) (xy 343.838347 -288.834937) (xy 343.807774 -288.875623)
			(xy 343.77107 -288.910878) (xy 343.729186 -288.939788) (xy 343.683207 -288.961605) (xy 343.634323 -288.975765)
			(xy 343.583802 -288.981899) (xy 343.53295 -288.97985) (xy 343.483086 -288.96967) (xy 343.4355 -288.951623)
			(xy 343.391426 -288.926177) (xy 343.352004 -288.89399) (xy 343.318256 -288.855896) (xy 343.291055 -288.812882)
			(xy 343.271107 -288.766062) (xy 343.258928 -288.716648) (xy 343.254833 -288.66592) (xy 342.946736 -288.66592)
			(xy 342.946224 -288.691366) (xy 342.93806 -288.7416) (xy 342.921944 -288.789874) (xy 342.898293 -288.834937)
			(xy 342.86772 -288.875623) (xy 342.831016 -288.910878) (xy 342.789132 -288.939788) (xy 342.743153 -288.961605)
			(xy 342.694269 -288.975765) (xy 342.643748 -288.981899) (xy 342.592896 -288.97985) (xy 342.543032 -288.96967)
			(xy 342.495446 -288.951623) (xy 342.451372 -288.926177) (xy 342.41195 -288.89399) (xy 342.378202 -288.855896)
			(xy 342.351001 -288.812882) (xy 342.331053 -288.766062) (xy 342.318874 -288.716648) (xy 342.314779 -288.66592)
			(xy 342.009222 -288.66592) (xy 342.008732 -288.690909) (xy 342.000913 -288.740272) (xy 341.985469 -288.787804)
			(xy 341.962779 -288.832336) (xy 341.933403 -288.872769) (xy 341.898063 -288.908109) (xy 341.85763 -288.937485)
			(xy 341.813098 -288.960175) (xy 341.765566 -288.975619) (xy 341.716203 -288.983438) (xy 341.666225 -288.983438)
			(xy 341.616862 -288.975619) (xy 341.56933 -288.960175) (xy 341.524798 -288.937485) (xy 341.484365 -288.908109)
			(xy 341.449025 -288.872769) (xy 341.419649 -288.832336) (xy 341.396959 -288.787804) (xy 341.381515 -288.740272)
			(xy 341.373696 -288.690909) (xy 341.066379 -288.690909) (xy 341.06637 -288.691366) (xy 341.058206 -288.7416)
			(xy 341.04209 -288.789874) (xy 341.018439 -288.834937) (xy 340.987866 -288.875623) (xy 340.951162 -288.910878)
			(xy 340.909278 -288.939788) (xy 340.863299 -288.961605) (xy 340.814415 -288.975765) (xy 340.763894 -288.981899)
			(xy 340.713042 -288.97985) (xy 340.663178 -288.96967) (xy 340.615592 -288.951623) (xy 340.571518 -288.926177)
			(xy 340.532096 -288.89399) (xy 340.498348 -288.855896) (xy 340.471147 -288.812882) (xy 340.451199 -288.766062)
			(xy 340.43902 -288.716648) (xy 340.434925 -288.66592) (xy 340.129114 -288.66592) (xy 340.128624 -288.690909)
			(xy 340.120805 -288.740272) (xy 340.105361 -288.787804) (xy 340.082671 -288.832336) (xy 340.053295 -288.872769)
			(xy 340.017955 -288.908109) (xy 339.977522 -288.937485) (xy 339.93299 -288.960175) (xy 339.885458 -288.975619)
			(xy 339.836095 -288.983438) (xy 339.786117 -288.983438) (xy 339.736754 -288.975619) (xy 339.689222 -288.960175)
			(xy 339.64469 -288.937485) (xy 339.604257 -288.908109) (xy 339.568917 -288.872769) (xy 339.539541 -288.832336)
			(xy 339.516851 -288.787804) (xy 339.501407 -288.740272) (xy 339.493588 -288.690909) (xy 339.186271 -288.690909)
			(xy 339.186262 -288.691366) (xy 339.178098 -288.7416) (xy 339.161982 -288.789874) (xy 339.138331 -288.834937)
			(xy 339.107758 -288.875623) (xy 339.071054 -288.910878) (xy 339.02917 -288.939788) (xy 338.983191 -288.961605)
			(xy 338.934307 -288.975765) (xy 338.883786 -288.981899) (xy 338.832934 -288.97985) (xy 338.78307 -288.96967)
			(xy 338.735484 -288.951623) (xy 338.69141 -288.926177) (xy 338.651988 -288.89399) (xy 338.61824 -288.855896)
			(xy 338.591039 -288.812882) (xy 338.571091 -288.766062) (xy 338.558912 -288.716648) (xy 338.554817 -288.66592)
			(xy 338.249777 -288.66592) (xy 338.245779 -288.716208) (xy 338.233887 -288.765246) (xy 338.214398 -288.81179)
			(xy 338.187802 -288.854672) (xy 338.154768 -288.892815) (xy 338.116124 -288.925261) (xy 338.072841 -288.951197)
			(xy 338.049616 -288.961068) (xy 338.045298 -288.962846) (xy 338.037284 -288.967356) (xy 338.024947 -288.980973)
			(xy 338.018318 -288.99811) (xy 338.017866 -289.007296) (xy 338.017866 -289.168586) (xy 338.018303 -289.177967)
			(xy 338.025226 -289.195411) (xy 338.038018 -289.209144) (xy 338.046314 -289.213544) (xy 338.084414 -289.230308)
			(xy 338.134198 -289.252406) (xy 338.138372 -289.253837) (xy 338.147059 -289.255373) (xy 338.15147 -289.255454)
			(xy 338.174584 -289.246564) (xy 338.184998 -289.2425) (xy 338.188046 -289.23996) (xy 338.205658 -289.224594)
			(xy 338.244546 -289.198666) (xy 338.286813 -289.178716) (xy 338.331547 -289.165175) (xy 338.377783 -289.158334)
			(xy 338.401152 -289.157918) (xy 338.426144 -289.158379) (xy 338.475512 -289.166192) (xy 338.523051 -289.181631)
			(xy 338.567589 -289.204319) (xy 338.608028 -289.233694) (xy 338.643374 -289.269035) (xy 338.672756 -289.30947)
			(xy 338.69545 -289.354005) (xy 338.710897 -289.401541) (xy 338.718717 -289.450908) (xy 338.718717 -289.475926)
			(xy 339.024971 -289.475926) (xy 339.029066 -289.425198) (xy 339.041245 -289.375784) (xy 339.061193 -289.328964)
			(xy 339.088394 -289.28595) (xy 339.122142 -289.247856) (xy 339.161564 -289.215669) (xy 339.205638 -289.190223)
			(xy 339.253224 -289.172176) (xy 339.303088 -289.161996) (xy 339.35394 -289.159947) (xy 339.404461 -289.166081)
			(xy 339.453345 -289.180241) (xy 339.499324 -289.202058) (xy 339.541208 -289.230968) (xy 339.577912 -289.266223)
			(xy 339.608485 -289.306909) (xy 339.632136 -289.351972) (xy 339.648252 -289.400246) (xy 339.656416 -289.45048)
			(xy 339.656928 -289.475926) (xy 339.964771 -289.475926) (xy 339.968866 -289.425198) (xy 339.981045 -289.375784)
			(xy 340.000993 -289.328964) (xy 340.028194 -289.28595) (xy 340.061942 -289.247856) (xy 340.101364 -289.215669)
			(xy 340.145438 -289.190223) (xy 340.193024 -289.172176) (xy 340.242888 -289.161996) (xy 340.29374 -289.159947)
			(xy 340.344261 -289.166081) (xy 340.393145 -289.180241) (xy 340.439124 -289.202058) (xy 340.481008 -289.230968)
			(xy 340.517712 -289.266223) (xy 340.548285 -289.306909) (xy 340.571936 -289.351972) (xy 340.588052 -289.400246)
			(xy 340.596216 -289.45048) (xy 340.596728 -289.475926) (xy 340.596225 -289.500915) (xy 340.903542 -289.500915)
			(xy 340.903542 -289.450937) (xy 340.911361 -289.401574) (xy 340.926805 -289.354042) (xy 340.949495 -289.30951)
			(xy 340.978871 -289.269077) (xy 341.014211 -289.233737) (xy 341.054644 -289.204361) (xy 341.099176 -289.181671)
			(xy 341.146708 -289.166227) (xy 341.196071 -289.158408) (xy 341.246049 -289.158408) (xy 341.295412 -289.166227)
			(xy 341.342944 -289.181671) (xy 341.387476 -289.204361) (xy 341.427909 -289.233737) (xy 341.463249 -289.269077)
			(xy 341.492625 -289.30951) (xy 341.515315 -289.354042) (xy 341.530759 -289.401574) (xy 341.538578 -289.450937)
			(xy 341.539068 -289.475926) (xy 341.844879 -289.475926) (xy 341.848974 -289.425198) (xy 341.861153 -289.375784)
			(xy 341.881101 -289.328964) (xy 341.908302 -289.28595) (xy 341.94205 -289.247856) (xy 341.981472 -289.215669)
			(xy 342.025546 -289.190223) (xy 342.073132 -289.172176) (xy 342.122996 -289.161996) (xy 342.173848 -289.159947)
			(xy 342.224369 -289.166081) (xy 342.273253 -289.180241) (xy 342.319232 -289.202058) (xy 342.361116 -289.230968)
			(xy 342.39782 -289.266223) (xy 342.428393 -289.306909) (xy 342.452044 -289.351972) (xy 342.46816 -289.400246)
			(xy 342.476324 -289.45048) (xy 342.476836 -289.475926) (xy 342.476333 -289.500915) (xy 342.78365 -289.500915)
			(xy 342.78365 -289.450937) (xy 342.791469 -289.401574) (xy 342.806913 -289.354042) (xy 342.829603 -289.30951)
			(xy 342.858979 -289.269077) (xy 342.894319 -289.233737) (xy 342.934752 -289.204361) (xy 342.979284 -289.181671)
			(xy 343.026816 -289.166227) (xy 343.076179 -289.158408) (xy 343.126157 -289.158408) (xy 343.17552 -289.166227)
			(xy 343.223052 -289.181671) (xy 343.267584 -289.204361) (xy 343.308017 -289.233737) (xy 343.343357 -289.269077)
			(xy 343.372733 -289.30951) (xy 343.395423 -289.354042) (xy 343.410867 -289.401574) (xy 343.418686 -289.450937)
			(xy 343.419176 -289.475926) (xy 343.418686 -289.500915) (xy 343.410867 -289.550278) (xy 343.395423 -289.59781)
			(xy 343.372733 -289.642342) (xy 343.343357 -289.682775) (xy 343.308017 -289.718115) (xy 343.267584 -289.747491)
			(xy 343.223052 -289.770181) (xy 343.17552 -289.785625) (xy 343.126157 -289.793444) (xy 343.076179 -289.793444)
			(xy 343.026816 -289.785625) (xy 342.979284 -289.770181) (xy 342.934752 -289.747491) (xy 342.894319 -289.718115)
			(xy 342.858979 -289.682775) (xy 342.829603 -289.642342) (xy 342.806913 -289.59781) (xy 342.791469 -289.550278)
			(xy 342.78365 -289.500915) (xy 342.476333 -289.500915) (xy 342.476324 -289.501372) (xy 342.46816 -289.551606)
			(xy 342.452044 -289.59988) (xy 342.428393 -289.644943) (xy 342.39782 -289.685629) (xy 342.361116 -289.720884)
			(xy 342.319232 -289.749794) (xy 342.273253 -289.771611) (xy 342.224369 -289.785771) (xy 342.173848 -289.791905)
			(xy 342.122996 -289.789856) (xy 342.073132 -289.779676) (xy 342.025546 -289.761629) (xy 341.981472 -289.736183)
			(xy 341.94205 -289.703996) (xy 341.908302 -289.665902) (xy 341.881101 -289.622888) (xy 341.861153 -289.576068)
			(xy 341.848974 -289.526654) (xy 341.844879 -289.475926) (xy 341.539068 -289.475926) (xy 341.538578 -289.500915)
			(xy 341.530759 -289.550278) (xy 341.515315 -289.59781) (xy 341.492625 -289.642342) (xy 341.463249 -289.682775)
			(xy 341.427909 -289.718115) (xy 341.387476 -289.747491) (xy 341.342944 -289.770181) (xy 341.295412 -289.785625)
			(xy 341.246049 -289.793444) (xy 341.196071 -289.793444) (xy 341.146708 -289.785625) (xy 341.099176 -289.770181)
			(xy 341.054644 -289.747491) (xy 341.014211 -289.718115) (xy 340.978871 -289.682775) (xy 340.949495 -289.642342)
			(xy 340.926805 -289.59781) (xy 340.911361 -289.550278) (xy 340.903542 -289.500915) (xy 340.596225 -289.500915)
			(xy 340.596216 -289.501372) (xy 340.588052 -289.551606) (xy 340.571936 -289.59988) (xy 340.548285 -289.644943)
			(xy 340.517712 -289.685629) (xy 340.481008 -289.720884) (xy 340.439124 -289.749794) (xy 340.393145 -289.771611)
			(xy 340.344261 -289.785771) (xy 340.29374 -289.791905) (xy 340.242888 -289.789856) (xy 340.193024 -289.779676)
			(xy 340.145438 -289.761629) (xy 340.101364 -289.736183) (xy 340.061942 -289.703996) (xy 340.028194 -289.665902)
			(xy 340.000993 -289.622888) (xy 339.981045 -289.576068) (xy 339.968866 -289.526654) (xy 339.964771 -289.475926)
			(xy 339.656928 -289.475926) (xy 339.656416 -289.501372) (xy 339.648252 -289.551606) (xy 339.632136 -289.59988)
			(xy 339.608485 -289.644943) (xy 339.577912 -289.685629) (xy 339.541208 -289.720884) (xy 339.499324 -289.749794)
			(xy 339.453345 -289.771611) (xy 339.404461 -289.785771) (xy 339.35394 -289.791905) (xy 339.303088 -289.789856)
			(xy 339.253224 -289.779676) (xy 339.205638 -289.761629) (xy 339.161564 -289.736183) (xy 339.122142 -289.703996)
			(xy 339.088394 -289.665902) (xy 339.061193 -289.622888) (xy 339.041245 -289.576068) (xy 339.029066 -289.526654)
			(xy 339.024971 -289.475926) (xy 338.718717 -289.475926) (xy 338.718717 -289.500892) (xy 338.710897 -289.550259)
			(xy 338.69545 -289.597795) (xy 338.672756 -289.64233) (xy 338.643374 -289.682765) (xy 338.608028 -289.718106)
			(xy 338.567589 -289.747481) (xy 338.523051 -289.770169) (xy 338.475512 -289.785608) (xy 338.426144 -289.793421)
			(xy 338.401152 -289.793934) (xy 338.377784 -289.793517) (xy 338.331552 -289.786666) (xy 338.286823 -289.773118)
			(xy 338.244559 -289.753166) (xy 338.205673 -289.72724) (xy 338.188046 -289.711892) (xy 338.184998 -289.709352)
			(xy 338.174584 -289.705288) (xy 338.15147 -289.696398) (xy 338.14706 -289.696496) (xy 338.138375 -289.69803)
			(xy 338.134198 -289.699446) (xy 338.084414 -289.721544) (xy 338.046314 -289.738308) (xy 338.038007 -289.742701)
			(xy 338.025184 -289.75642) (xy 338.018268 -289.773878) (xy 338.017866 -289.783266) (xy 338.017866 -289.944556)
			(xy 338.018334 -289.953732) (xy 338.024997 -289.970839) (xy 338.037318 -289.984448) (xy 338.045298 -289.989006)
			(xy 338.049616 -289.990784) (xy 338.072853 -290.000621) (xy 338.116133 -290.026559) (xy 338.154774 -290.059007)
			(xy 338.187805 -290.097151) (xy 338.214397 -290.140032) (xy 338.233882 -290.186576) (xy 338.245772 -290.235613)
			(xy 338.249767 -290.285912) (xy 338.249765 -290.285932) (xy 338.554817 -290.285932) (xy 338.558912 -290.235204)
			(xy 338.571091 -290.18579) (xy 338.591039 -290.13897) (xy 338.61824 -290.095956) (xy 338.651988 -290.057862)
			(xy 338.69141 -290.025675) (xy 338.735484 -290.000229) (xy 338.78307 -289.982182) (xy 338.832934 -289.972002)
			(xy 338.883786 -289.969953) (xy 338.934307 -289.976087) (xy 338.983191 -289.990247) (xy 339.02917 -290.012064)
			(xy 339.071054 -290.040974) (xy 339.107758 -290.076229) (xy 339.138331 -290.116915) (xy 339.161982 -290.161978)
			(xy 339.178098 -290.210252) (xy 339.186262 -290.260486) (xy 339.186774 -290.285932) (xy 339.186271 -290.310921)
			(xy 339.493588 -290.310921) (xy 339.493588 -290.260943) (xy 339.501407 -290.21158) (xy 339.516851 -290.164048)
			(xy 339.539541 -290.119516) (xy 339.568917 -290.079083) (xy 339.604257 -290.043743) (xy 339.64469 -290.014367)
			(xy 339.689222 -289.991677) (xy 339.736754 -289.976233) (xy 339.786117 -289.968414) (xy 339.836095 -289.968414)
			(xy 339.885458 -289.976233) (xy 339.93299 -289.991677) (xy 339.977522 -290.014367) (xy 340.017955 -290.043743)
			(xy 340.053295 -290.079083) (xy 340.082671 -290.119516) (xy 340.105361 -290.164048) (xy 340.120805 -290.21158)
			(xy 340.128624 -290.260943) (xy 340.129114 -290.285932) (xy 340.434925 -290.285932) (xy 340.43902 -290.235204)
			(xy 340.451199 -290.18579) (xy 340.471147 -290.13897) (xy 340.498348 -290.095956) (xy 340.532096 -290.057862)
			(xy 340.571518 -290.025675) (xy 340.615592 -290.000229) (xy 340.663178 -289.982182) (xy 340.713042 -289.972002)
			(xy 340.763894 -289.969953) (xy 340.814415 -289.976087) (xy 340.863299 -289.990247) (xy 340.909278 -290.012064)
			(xy 340.951162 -290.040974) (xy 340.987866 -290.076229) (xy 341.018439 -290.116915) (xy 341.04209 -290.161978)
			(xy 341.058206 -290.210252) (xy 341.06637 -290.260486) (xy 341.066882 -290.285932) (xy 341.06637 -290.311378)
			(xy 341.058206 -290.361612) (xy 341.04209 -290.409886) (xy 341.018439 -290.454949) (xy 340.987866 -290.495635)
			(xy 340.951162 -290.53089) (xy 340.909278 -290.5598) (xy 340.863299 -290.581617) (xy 340.814415 -290.595777)
			(xy 340.763894 -290.601911) (xy 340.713042 -290.599862) (xy 340.663178 -290.589682) (xy 340.615592 -290.571635)
			(xy 340.571518 -290.546189) (xy 340.532096 -290.514002) (xy 340.498348 -290.475908) (xy 340.471147 -290.432894)
			(xy 340.451199 -290.386074) (xy 340.43902 -290.33666) (xy 340.434925 -290.285932) (xy 340.129114 -290.285932)
			(xy 340.128624 -290.310921) (xy 340.120805 -290.360284) (xy 340.105361 -290.407816) (xy 340.082671 -290.452348)
			(xy 340.053295 -290.492781) (xy 340.017955 -290.528121) (xy 339.977522 -290.557497) (xy 339.93299 -290.580187)
			(xy 339.885458 -290.595631) (xy 339.836095 -290.60345) (xy 339.786117 -290.60345) (xy 339.736754 -290.595631)
			(xy 339.689222 -290.580187) (xy 339.64469 -290.557497) (xy 339.604257 -290.528121) (xy 339.568917 -290.492781)
			(xy 339.539541 -290.452348) (xy 339.516851 -290.407816) (xy 339.501407 -290.360284) (xy 339.493588 -290.310921)
			(xy 339.186271 -290.310921) (xy 339.186262 -290.311378) (xy 339.178098 -290.361612) (xy 339.161982 -290.409886)
			(xy 339.138331 -290.454949) (xy 339.107758 -290.495635) (xy 339.071054 -290.53089) (xy 339.02917 -290.5598)
			(xy 338.983191 -290.581617) (xy 338.934307 -290.595777) (xy 338.883786 -290.601911) (xy 338.832934 -290.599862)
			(xy 338.78307 -290.589682) (xy 338.735484 -290.571635) (xy 338.69141 -290.546189) (xy 338.651988 -290.514002)
			(xy 338.61824 -290.475908) (xy 338.591039 -290.432894) (xy 338.571091 -290.386074) (xy 338.558912 -290.33666)
			(xy 338.554817 -290.285932) (xy 338.249765 -290.285932) (xy 338.245768 -290.336211) (xy 338.233875 -290.385247)
			(xy 338.214386 -290.431789) (xy 338.187791 -290.474669) (xy 338.154757 -290.51281) (xy 338.116114 -290.545255)
			(xy 338.072832 -290.571189) (xy 338.049616 -290.58108) (xy 338.045298 -290.582858) (xy 338.037285 -290.587369)
			(xy 338.024952 -290.600986) (xy 338.018327 -290.618123) (xy 338.017866 -290.627308) (xy 338.017866 -290.788598)
			(xy 338.018305 -290.797978) (xy 338.025231 -290.815419) (xy 338.038023 -290.829148) (xy 338.046314 -290.833556)
			(xy 338.084414 -290.85032) (xy 338.134198 -290.872418) (xy 338.138372 -290.873848) (xy 338.147059 -290.875385)
			(xy 338.15147 -290.875466) (xy 338.174584 -290.866576) (xy 338.184998 -290.862512) (xy 338.188046 -290.859972)
			(xy 338.205658 -290.844606) (xy 338.244545 -290.818677) (xy 338.286812 -290.798726) (xy 338.331547 -290.785184)
			(xy 338.377782 -290.778343) (xy 338.401152 -290.77793) (xy 338.426143 -290.778391) (xy 338.47551 -290.786203)
			(xy 338.523046 -290.801643) (xy 338.567582 -290.824329) (xy 338.608021 -290.853703) (xy 338.643365 -290.889043)
			(xy 338.672746 -290.929477) (xy 338.695439 -290.974009) (xy 338.710885 -291.021544) (xy 338.718705 -291.070909)
			(xy 338.718705 -291.095938) (xy 339.024971 -291.095938) (xy 339.029066 -291.04521) (xy 339.041245 -290.995796)
			(xy 339.061193 -290.948976) (xy 339.088394 -290.905962) (xy 339.122142 -290.867868) (xy 339.161564 -290.835681)
			(xy 339.205638 -290.810235) (xy 339.253224 -290.792188) (xy 339.303088 -290.782008) (xy 339.35394 -290.779959)
			(xy 339.404461 -290.786093) (xy 339.453345 -290.800253) (xy 339.499324 -290.82207) (xy 339.541208 -290.85098)
			(xy 339.577912 -290.886235) (xy 339.608485 -290.926921) (xy 339.632136 -290.971984) (xy 339.648252 -291.020258)
			(xy 339.656416 -291.070492) (xy 339.656928 -291.095938) (xy 339.964771 -291.095938) (xy 339.968866 -291.04521)
			(xy 339.981045 -290.995796) (xy 340.000993 -290.948976) (xy 340.028194 -290.905962) (xy 340.061942 -290.867868)
			(xy 340.101364 -290.835681) (xy 340.145438 -290.810235) (xy 340.193024 -290.792188) (xy 340.242888 -290.782008)
			(xy 340.29374 -290.779959) (xy 340.344261 -290.786093) (xy 340.393145 -290.800253) (xy 340.439124 -290.82207)
			(xy 340.481008 -290.85098) (xy 340.517712 -290.886235) (xy 340.548285 -290.926921) (xy 340.571936 -290.971984)
			(xy 340.588052 -291.020258) (xy 340.596216 -291.070492) (xy 340.596728 -291.095938) (xy 340.596225 -291.120927)
			(xy 340.903542 -291.120927) (xy 340.903542 -291.070949) (xy 340.911361 -291.021586) (xy 340.926805 -290.974054)
			(xy 340.949495 -290.929522) (xy 340.978871 -290.889089) (xy 341.014211 -290.853749) (xy 341.054644 -290.824373)
			(xy 341.099176 -290.801683) (xy 341.146708 -290.786239) (xy 341.196071 -290.77842) (xy 341.246049 -290.77842)
			(xy 341.295412 -290.786239) (xy 341.342944 -290.801683) (xy 341.387476 -290.824373) (xy 341.427909 -290.853749)
			(xy 341.463249 -290.889089) (xy 341.492625 -290.929522) (xy 341.515315 -290.974054) (xy 341.530759 -291.021586)
			(xy 341.538578 -291.070949) (xy 341.539068 -291.095938) (xy 341.538578 -291.120927) (xy 341.530759 -291.17029)
			(xy 341.515315 -291.217822) (xy 341.492625 -291.262354) (xy 341.463249 -291.302787) (xy 341.427909 -291.338127)
			(xy 341.387476 -291.367503) (xy 341.342944 -291.390193) (xy 341.295412 -291.405637) (xy 341.246049 -291.413456)
			(xy 341.196071 -291.413456) (xy 341.146708 -291.405637) (xy 341.099176 -291.390193) (xy 341.054644 -291.367503)
			(xy 341.014211 -291.338127) (xy 340.978871 -291.302787) (xy 340.949495 -291.262354) (xy 340.926805 -291.217822)
			(xy 340.911361 -291.17029) (xy 340.903542 -291.120927) (xy 340.596225 -291.120927) (xy 340.596216 -291.121384)
			(xy 340.588052 -291.171618) (xy 340.571936 -291.219892) (xy 340.548285 -291.264955) (xy 340.517712 -291.305641)
			(xy 340.481008 -291.340896) (xy 340.439124 -291.369806) (xy 340.393145 -291.391623) (xy 340.344261 -291.405783)
			(xy 340.29374 -291.411917) (xy 340.242888 -291.409868) (xy 340.193024 -291.399688) (xy 340.145438 -291.381641)
			(xy 340.101364 -291.356195) (xy 340.061942 -291.324008) (xy 340.028194 -291.285914) (xy 340.000993 -291.2429)
			(xy 339.981045 -291.19608) (xy 339.968866 -291.146666) (xy 339.964771 -291.095938) (xy 339.656928 -291.095938)
			(xy 339.656416 -291.121384) (xy 339.648252 -291.171618) (xy 339.632136 -291.219892) (xy 339.608485 -291.264955)
			(xy 339.577912 -291.305641) (xy 339.541208 -291.340896) (xy 339.499324 -291.369806) (xy 339.453345 -291.391623)
			(xy 339.404461 -291.405783) (xy 339.35394 -291.411917) (xy 339.303088 -291.409868) (xy 339.253224 -291.399688)
			(xy 339.205638 -291.381641) (xy 339.161564 -291.356195) (xy 339.122142 -291.324008) (xy 339.088394 -291.285914)
			(xy 339.061193 -291.2429) (xy 339.041245 -291.19608) (xy 339.029066 -291.146666) (xy 339.024971 -291.095938)
			(xy 338.718705 -291.095938) (xy 338.718705 -291.120891) (xy 338.710886 -291.170256) (xy 338.695439 -291.217791)
			(xy 338.672746 -291.262323) (xy 338.643365 -291.302757) (xy 338.608021 -291.338097) (xy 338.567582 -291.367471)
			(xy 338.523046 -291.390157) (xy 338.47551 -291.405597) (xy 338.426143 -291.413409) (xy 338.401152 -291.413946)
			(xy 338.377784 -291.413529) (xy 338.331552 -291.406678) (xy 338.286822 -291.393131) (xy 338.244558 -291.373179)
			(xy 338.205671 -291.347253) (xy 338.188046 -291.331904) (xy 338.184998 -291.329364) (xy 338.174584 -291.3253)
			(xy 338.15147 -291.31641) (xy 338.14706 -291.316508) (xy 338.138375 -291.318042) (xy 338.134198 -291.319458)
			(xy 338.084414 -291.341556) (xy 338.046314 -291.35832) (xy 338.038008 -291.362714) (xy 338.025189 -291.376433)
			(xy 338.018277 -291.393891) (xy 338.017866 -291.403278) (xy 338.017866 -291.564568) (xy 338.01832 -291.573753)
			(xy 338.024964 -291.590883) (xy 338.03728 -291.604519) (xy 338.045298 -291.609018) (xy 338.049616 -291.610796)
			(xy 338.074346 -291.621367) (xy 338.120138 -291.649563) (xy 338.160543 -291.685052) (xy 338.194411 -291.726824)
			(xy 338.22078 -291.773692) (xy 338.2389 -291.824325) (xy 338.248256 -291.877282) (xy 338.249006 -291.904166)
			(xy 338.249006 -291.905944) (xy 338.554817 -291.905944) (xy 338.558912 -291.855216) (xy 338.571091 -291.805802)
			(xy 338.591039 -291.758982) (xy 338.61824 -291.715968) (xy 338.651988 -291.677874) (xy 338.69141 -291.645687)
			(xy 338.735484 -291.620241) (xy 338.78307 -291.602194) (xy 338.832934 -291.592014) (xy 338.883786 -291.589965)
			(xy 338.934307 -291.596099) (xy 338.983191 -291.610259) (xy 339.02917 -291.632076) (xy 339.071054 -291.660986)
			(xy 339.107758 -291.696241) (xy 339.138331 -291.736927) (xy 339.161982 -291.78199) (xy 339.178098 -291.830264)
			(xy 339.186262 -291.880498) (xy 339.186774 -291.905944) (xy 339.186271 -291.930933) (xy 339.493588 -291.930933)
			(xy 339.493588 -291.880955) (xy 339.501407 -291.831592) (xy 339.516851 -291.78406) (xy 339.539541 -291.739528)
			(xy 339.568917 -291.699095) (xy 339.604257 -291.663755) (xy 339.64469 -291.634379) (xy 339.689222 -291.611689)
			(xy 339.736754 -291.596245) (xy 339.786117 -291.588426) (xy 339.836095 -291.588426) (xy 339.885458 -291.596245)
			(xy 339.93299 -291.611689) (xy 339.977522 -291.634379) (xy 340.017955 -291.663755) (xy 340.053295 -291.699095)
			(xy 340.082671 -291.739528) (xy 340.105361 -291.78406) (xy 340.120805 -291.831592) (xy 340.128624 -291.880955)
			(xy 340.129114 -291.905944) (xy 340.434925 -291.905944) (xy 340.43902 -291.855216) (xy 340.451199 -291.805802)
			(xy 340.471147 -291.758982) (xy 340.498348 -291.715968) (xy 340.532096 -291.677874) (xy 340.571518 -291.645687)
			(xy 340.615592 -291.620241) (xy 340.663178 -291.602194) (xy 340.713042 -291.592014) (xy 340.763894 -291.589965)
			(xy 340.814415 -291.596099) (xy 340.863299 -291.610259) (xy 340.909278 -291.632076) (xy 340.951162 -291.660986)
			(xy 340.987866 -291.696241) (xy 341.018439 -291.736927) (xy 341.04209 -291.78199) (xy 341.058206 -291.830264)
			(xy 341.06637 -291.880498) (xy 341.066882 -291.905944) (xy 341.06637 -291.93139) (xy 341.058206 -291.981624)
			(xy 341.04209 -292.029898) (xy 341.018439 -292.074961) (xy 340.987866 -292.115647) (xy 340.951162 -292.150902)
			(xy 340.909278 -292.179812) (xy 340.863299 -292.201629) (xy 340.814415 -292.215789) (xy 340.763894 -292.221923)
			(xy 340.713042 -292.219874) (xy 340.663178 -292.209694) (xy 340.615592 -292.191647) (xy 340.571518 -292.166201)
			(xy 340.532096 -292.134014) (xy 340.498348 -292.09592) (xy 340.471147 -292.052906) (xy 340.451199 -292.006086)
			(xy 340.43902 -291.956672) (xy 340.434925 -291.905944) (xy 340.129114 -291.905944) (xy 340.128624 -291.930933)
			(xy 340.120805 -291.980296) (xy 340.105361 -292.027828) (xy 340.082671 -292.07236) (xy 340.053295 -292.112793)
			(xy 340.017955 -292.148133) (xy 339.977522 -292.177509) (xy 339.93299 -292.200199) (xy 339.885458 -292.215643)
			(xy 339.836095 -292.223462) (xy 339.786117 -292.223462) (xy 339.736754 -292.215643) (xy 339.689222 -292.200199)
			(xy 339.64469 -292.177509) (xy 339.604257 -292.148133) (xy 339.568917 -292.112793) (xy 339.539541 -292.07236)
			(xy 339.516851 -292.027828) (xy 339.501407 -291.980296) (xy 339.493588 -291.930933) (xy 339.186271 -291.930933)
			(xy 339.186262 -291.93139) (xy 339.178098 -291.981624) (xy 339.161982 -292.029898) (xy 339.138331 -292.074961)
			(xy 339.107758 -292.115647) (xy 339.071054 -292.150902) (xy 339.02917 -292.179812) (xy 338.983191 -292.201629)
			(xy 338.934307 -292.215789) (xy 338.883786 -292.221923) (xy 338.832934 -292.219874) (xy 338.78307 -292.209694)
			(xy 338.735484 -292.191647) (xy 338.69141 -292.166201) (xy 338.651988 -292.134014) (xy 338.61824 -292.09592)
			(xy 338.591039 -292.052906) (xy 338.571091 -292.006086) (xy 338.558912 -291.956672) (xy 338.554817 -291.905944)
			(xy 338.249006 -291.905944) (xy 338.249006 -291.906198) (xy 338.248909 -291.918245) (xy 338.247127 -291.942274)
			(xy 338.24545 -291.954204) (xy 338.245196 -291.95522) (xy 338.245196 -291.956744) (xy 338.24029 -291.983572)
			(xy 338.222533 -292.035135) (xy 338.196241 -292.082914) (xy 338.179664 -292.104572) (xy 338.173568 -292.112192)
			(xy 338.171028 -292.119558) (xy 338.169696 -292.123876) (xy 338.168412 -292.13282) (xy 338.168488 -292.137338)
			(xy 338.168742 -292.14572) (xy 338.169758 -292.171374) (xy 338.171035 -292.179642) (xy 338.178297 -292.194702)
			(xy 338.183982 -292.200838) (xy 338.366354 -292.38321) (xy 338.369972 -292.386643) (xy 338.37829 -292.392143)
			(xy 338.382864 -292.394132) (xy 338.391754 -292.397942) (xy 338.401914 -292.397942) (xy 338.42683 -292.398482)
			(xy 338.476036 -292.406365) (xy 338.523411 -292.421825) (xy 338.567796 -292.444485) (xy 338.608103 -292.47379)
			(xy 338.643346 -292.509023) (xy 338.672663 -292.549321) (xy 338.695337 -292.593698) (xy 338.710812 -292.641068)
			(xy 338.71871 -292.690272) (xy 338.71916 -292.715188) (xy 338.71916 -292.71595) (xy 339.024971 -292.71595)
			(xy 339.029066 -292.665222) (xy 339.041245 -292.615808) (xy 339.061193 -292.568988) (xy 339.088394 -292.525974)
			(xy 339.122142 -292.48788) (xy 339.161564 -292.455693) (xy 339.205638 -292.430247) (xy 339.253224 -292.4122)
			(xy 339.303088 -292.40202) (xy 339.35394 -292.399971) (xy 339.404461 -292.406105) (xy 339.453345 -292.420265)
			(xy 339.499324 -292.442082) (xy 339.541208 -292.470992) (xy 339.577912 -292.506247) (xy 339.608485 -292.546933)
			(xy 339.632136 -292.591996) (xy 339.648252 -292.64027) (xy 339.656416 -292.690504) (xy 339.656928 -292.71595)
			(xy 339.656416 -292.741396) (xy 339.648252 -292.79163) (xy 339.632136 -292.839904) (xy 339.608485 -292.884967)
			(xy 339.577912 -292.925653) (xy 339.541208 -292.960908) (xy 339.499324 -292.989818) (xy 339.453345 -293.011635)
			(xy 339.404461 -293.025795) (xy 339.35394 -293.031929) (xy 339.303088 -293.02988) (xy 339.253224 -293.0197)
			(xy 339.205638 -293.001653) (xy 339.161564 -292.976207) (xy 339.122142 -292.94402) (xy 339.088394 -292.905926)
			(xy 339.061193 -292.862912) (xy 339.041245 -292.816092) (xy 339.029066 -292.766678) (xy 339.024971 -292.71595)
			(xy 338.71916 -292.71595) (xy 338.71916 -292.725348) (xy 338.72297 -292.734238) (xy 338.724978 -292.738801)
			(xy 338.730477 -292.747116) (xy 338.733892 -292.750748) (xy 339.278976 -293.295832) (xy 339.286223 -293.302388)
			(xy 339.304267 -293.309839) (xy 339.314028 -293.31031) (xy 339.547454 -293.31031) (xy 339.550502 -293.31031)
		)
		(stroke
			(width 0)
			(type solid)
		)
		(fill yes)
		(layer "B.Cu")
		(net "PVDDIO_P0")
	)
	(gr_poly
		(pts
			(xy 207.32496 -325.965312) (xy 207.334799 -325.964778) (xy 207.352963 -325.957195) (xy 207.360266 -325.95058)
			(xy 207.548988 -325.761858) (xy 207.555829 -325.754458) (xy 207.56355 -325.73586) (xy 207.563974 -325.72579)
			(xy 207.563974 -198.861934) (xy 207.56356 -198.85191) (xy 207.555895 -198.833386) (xy 207.541721 -198.81921)
			(xy 207.523198 -198.811542) (xy 207.513174 -198.811134) (xy 206.702152 -198.811134) (xy 206.688815 -198.811525)
			(xy 206.66305 -198.818424) (xy 206.639953 -198.831764) (xy 206.621102 -198.850634) (xy 206.607785 -198.873744)
			(xy 206.600912 -198.899516) (xy 206.600952 -198.926188) (xy 206.604108 -198.93915) (xy 206.610068 -198.962768)
			(xy 206.61644 -199.01106) (xy 206.616808 -199.035416) (xy 206.616292 -199.063016) (xy 206.608065 -199.117599)
			(xy 206.591795 -199.170346) (xy 206.567845 -199.220079) (xy 206.53675 -199.265686) (xy 206.499205 -199.30615)
			(xy 206.456048 -199.340567) (xy 206.408244 -199.368166) (xy 206.35686 -199.388333) (xy 206.303045 -199.400616)
			(xy 206.248 -199.404741) (xy 206.192955 -199.400616) (xy 206.13914 -199.388333) (xy 206.087756 -199.368166)
			(xy 206.039952 -199.340567) (xy 205.996795 -199.30615) (xy 205.95925 -199.265686) (xy 205.928155 -199.220079)
			(xy 205.904205 -199.170346) (xy 205.887935 -199.117599) (xy 205.879708 -199.063016) (xy 205.879192 -199.035416)
			(xy 205.879567 -199.011061) (xy 205.885939 -198.962769) (xy 205.891892 -198.93915) (xy 205.894966 -198.926182)
			(xy 205.894982 -198.899541) (xy 205.888102 -198.873802) (xy 205.874794 -198.850722) (xy 205.855965 -198.831874)
			(xy 205.832899 -198.818541) (xy 205.807169 -198.811632) (xy 205.793848 -198.811134) (xy 199.158352 -198.811134)
			(xy 199.145015 -198.811525) (xy 199.11925 -198.818424) (xy 199.096153 -198.831764) (xy 199.077302 -198.850634)
			(xy 199.063985 -198.873744) (xy 199.057112 -198.899516) (xy 199.057152 -198.926188) (xy 199.060308 -198.93915)
			(xy 199.066268 -198.962768) (xy 199.07264 -199.01106) (xy 199.073008 -199.035416) (xy 199.072492 -199.063016)
			(xy 199.064265 -199.117599) (xy 199.047995 -199.170346) (xy 199.024045 -199.220079) (xy 198.99295 -199.265686)
			(xy 198.955405 -199.30615) (xy 198.912248 -199.340567) (xy 198.864444 -199.368166) (xy 198.81306 -199.388333)
			(xy 198.759245 -199.400616) (xy 198.7042 -199.404741) (xy 198.649155 -199.400616) (xy 198.59534 -199.388333)
			(xy 198.543956 -199.368166) (xy 198.496152 -199.340567) (xy 198.452995 -199.30615) (xy 198.41545 -199.265686)
			(xy 198.384355 -199.220079) (xy 198.360405 -199.170346) (xy 198.344135 -199.117599) (xy 198.335908 -199.063016)
			(xy 198.335392 -199.035416) (xy 198.335767 -199.011061) (xy 198.342139 -198.962769) (xy 198.348092 -198.93915)
			(xy 198.351166 -198.926182) (xy 198.351182 -198.899541) (xy 198.344302 -198.873802) (xy 198.330994 -198.850722)
			(xy 198.312165 -198.831874) (xy 198.289099 -198.818541) (xy 198.263369 -198.811632) (xy 198.250048 -198.811134)
			(xy 191.614298 -198.811134) (xy 191.600967 -198.811531) (xy 191.575214 -198.818439) (xy 191.55213 -198.831782)
			(xy 191.53329 -198.850649) (xy 191.519981 -198.873753) (xy 191.513112 -198.899516) (xy 191.513151 -198.926179)
			(xy 191.516254 -198.93915) (xy 191.522214 -198.962768) (xy 191.528588 -199.01106) (xy 191.528954 -199.035416)
			(xy 191.528438 -199.063016) (xy 191.520211 -199.117599) (xy 191.503941 -199.170346) (xy 191.479991 -199.220079)
			(xy 191.448896 -199.265686) (xy 191.411351 -199.30615) (xy 191.368194 -199.340567) (xy 191.32039 -199.368166)
			(xy 191.269006 -199.388333) (xy 191.215191 -199.400616) (xy 191.160146 -199.404741) (xy 191.105101 -199.400616)
			(xy 191.051286 -199.388333) (xy 190.999902 -199.368166) (xy 190.952098 -199.340567) (xy 190.908941 -199.30615)
			(xy 190.871396 -199.265686) (xy 190.840301 -199.220079) (xy 190.816351 -199.170346) (xy 190.800081 -199.117599)
			(xy 190.791854 -199.063016) (xy 190.791338 -199.035416) (xy 190.791713 -199.011061) (xy 190.798086 -198.96277)
			(xy 190.804038 -198.93915) (xy 190.807072 -198.926175) (xy 190.807087 -198.89954) (xy 190.80021 -198.873808)
			(xy 190.786908 -198.850733) (xy 190.768089 -198.831885) (xy 190.745033 -198.818549) (xy 190.719311 -198.811633)
			(xy 190.705994 -198.811134) (xy 184.070244 -198.811134) (xy 184.056908 -198.811526) (xy 184.031145 -198.818426)
			(xy 184.00805 -198.831766) (xy 183.9892 -198.850636) (xy 183.975885 -198.873745) (xy 183.969012 -198.899516)
			(xy 183.969052 -198.926187) (xy 183.9722 -198.93915) (xy 183.97816 -198.962768) (xy 183.984533 -199.01106)
			(xy 183.9849 -199.035416) (xy 183.984384 -199.063016) (xy 183.976157 -199.117599) (xy 183.959887 -199.170346)
			(xy 183.935937 -199.220079) (xy 183.904842 -199.265686) (xy 183.867297 -199.30615) (xy 183.82414 -199.340567)
			(xy 183.776336 -199.368166) (xy 183.724952 -199.388333) (xy 183.671137 -199.400616) (xy 183.616092 -199.404741)
			(xy 183.561047 -199.400616) (xy 183.507232 -199.388333) (xy 183.455848 -199.368166) (xy 183.408044 -199.340567)
			(xy 183.364887 -199.30615) (xy 183.327342 -199.265686) (xy 183.296247 -199.220079) (xy 183.272297 -199.170346)
			(xy 183.256027 -199.117599) (xy 183.2478 -199.063016) (xy 183.247284 -199.035416) (xy 183.247659 -199.011061)
			(xy 183.254031 -198.962769) (xy 183.259984 -198.93915) (xy 183.263058 -198.926183) (xy 183.263074 -198.899541)
			(xy 183.256194 -198.873804) (xy 183.242886 -198.850725) (xy 183.224057 -198.831877) (xy 183.200991 -198.818546)
			(xy 183.17526 -198.811639) (xy 183.16194 -198.811134) (xy 177.932334 -198.811134) (xy 177.922311 -198.811548)
			(xy 177.903788 -198.819213) (xy 177.889613 -198.833388) (xy 177.881948 -198.851911) (xy 177.881534 -198.861934)
			(xy 177.881534 -199.8853) (xy 179.146723 -199.8853) (xy 179.150658 -199.831529) (xy 179.162381 -199.778905)
			(xy 179.181641 -199.728548) (xy 179.208027 -199.681531) (xy 179.240979 -199.638858) (xy 179.279792 -199.601437)
			(xy 179.32364 -199.570067) (xy 179.371588 -199.545415) (xy 179.422615 -199.528007) (xy 179.475633 -199.518214)
			(xy 179.529512 -199.516245) (xy 179.583103 -199.522142) (xy 179.635264 -199.535778) (xy 179.684884 -199.556865)
			(xy 179.730905 -199.584951) (xy 179.772347 -199.619439) (xy 179.808325 -199.659593) (xy 179.838073 -199.704557)
			(xy 179.860958 -199.753374) (xy 179.87649 -199.805003) (xy 179.88434 -199.858343) (xy 179.884832 -199.8853)
			(xy 186.690777 -199.8853) (xy 186.694712 -199.831529) (xy 186.706435 -199.778905) (xy 186.725695 -199.728548)
			(xy 186.752081 -199.681531) (xy 186.785033 -199.638858) (xy 186.823846 -199.601437) (xy 186.867694 -199.570067)
			(xy 186.915642 -199.545415) (xy 186.966669 -199.528007) (xy 187.019687 -199.518214) (xy 187.073566 -199.516245)
			(xy 187.127157 -199.522142) (xy 187.179318 -199.535778) (xy 187.228938 -199.556865) (xy 187.274959 -199.584951)
			(xy 187.316401 -199.619439) (xy 187.352379 -199.659593) (xy 187.382127 -199.704557) (xy 187.405012 -199.753374)
			(xy 187.420544 -199.805003) (xy 187.428394 -199.858343) (xy 187.428886 -199.8853) (xy 194.234831 -199.8853)
			(xy 194.238766 -199.831529) (xy 194.250489 -199.778905) (xy 194.269749 -199.728548) (xy 194.296135 -199.681531)
			(xy 194.329087 -199.638858) (xy 194.3679 -199.601437) (xy 194.411748 -199.570067) (xy 194.459696 -199.545415)
			(xy 194.510723 -199.528007) (xy 194.563741 -199.518214) (xy 194.61762 -199.516245) (xy 194.671211 -199.522142)
			(xy 194.723372 -199.535778) (xy 194.772992 -199.556865) (xy 194.819013 -199.584951) (xy 194.860455 -199.619439)
			(xy 194.896433 -199.659593) (xy 194.926181 -199.704557) (xy 194.949066 -199.753374) (xy 194.964598 -199.805003)
			(xy 194.972448 -199.858343) (xy 194.97294 -199.8853) (xy 201.778631 -199.8853) (xy 201.782566 -199.831529)
			(xy 201.794289 -199.778905) (xy 201.813549 -199.728548) (xy 201.839935 -199.681531) (xy 201.872887 -199.638858)
			(xy 201.9117 -199.601437) (xy 201.955548 -199.570067) (xy 202.003496 -199.545415) (xy 202.054523 -199.528007)
			(xy 202.107541 -199.518214) (xy 202.16142 -199.516245) (xy 202.215011 -199.522142) (xy 202.267172 -199.535778)
			(xy 202.316792 -199.556865) (xy 202.362813 -199.584951) (xy 202.404255 -199.619439) (xy 202.440233 -199.659593)
			(xy 202.469981 -199.704557) (xy 202.492866 -199.753374) (xy 202.508398 -199.805003) (xy 202.516248 -199.858343)
			(xy 202.51674 -199.8853) (xy 202.516248 -199.912257) (xy 202.508398 -199.965597) (xy 202.492866 -200.017226)
			(xy 202.469981 -200.066043) (xy 202.440233 -200.111007) (xy 202.404255 -200.151161) (xy 202.362813 -200.185649)
			(xy 202.316792 -200.213735) (xy 202.267172 -200.234822) (xy 202.215011 -200.248458) (xy 202.16142 -200.254355)
			(xy 202.107541 -200.252386) (xy 202.054523 -200.242593) (xy 202.003496 -200.225185) (xy 201.955548 -200.200533)
			(xy 201.9117 -200.169163) (xy 201.872887 -200.131742) (xy 201.839935 -200.089069) (xy 201.813549 -200.042052)
			(xy 201.794289 -199.991695) (xy 201.782566 -199.939071) (xy 201.778631 -199.8853) (xy 194.97294 -199.8853)
			(xy 194.972448 -199.912257) (xy 194.964598 -199.965597) (xy 194.949066 -200.017226) (xy 194.926181 -200.066043)
			(xy 194.896433 -200.111007) (xy 194.860455 -200.151161) (xy 194.819013 -200.185649) (xy 194.772992 -200.213735)
			(xy 194.723372 -200.234822) (xy 194.671211 -200.248458) (xy 194.61762 -200.254355) (xy 194.563741 -200.252386)
			(xy 194.510723 -200.242593) (xy 194.459696 -200.225185) (xy 194.411748 -200.200533) (xy 194.3679 -200.169163)
			(xy 194.329087 -200.131742) (xy 194.296135 -200.089069) (xy 194.269749 -200.042052) (xy 194.250489 -199.991695)
			(xy 194.238766 -199.939071) (xy 194.234831 -199.8853) (xy 187.428886 -199.8853) (xy 187.428394 -199.912257)
			(xy 187.420544 -199.965597) (xy 187.405012 -200.017226) (xy 187.382127 -200.066043) (xy 187.352379 -200.111007)
			(xy 187.316401 -200.151161) (xy 187.274959 -200.185649) (xy 187.228938 -200.213735) (xy 187.179318 -200.234822)
			(xy 187.127157 -200.248458) (xy 187.073566 -200.254355) (xy 187.019687 -200.252386) (xy 186.966669 -200.242593)
			(xy 186.915642 -200.225185) (xy 186.867694 -200.200533) (xy 186.823846 -200.169163) (xy 186.785033 -200.131742)
			(xy 186.752081 -200.089069) (xy 186.725695 -200.042052) (xy 186.706435 -199.991695) (xy 186.694712 -199.939071)
			(xy 186.690777 -199.8853) (xy 179.884832 -199.8853) (xy 179.88434 -199.912257) (xy 179.87649 -199.965597)
			(xy 179.860958 -200.017226) (xy 179.838073 -200.066043) (xy 179.808325 -200.111007) (xy 179.772347 -200.151161)
			(xy 179.730905 -200.185649) (xy 179.684884 -200.213735) (xy 179.635264 -200.234822) (xy 179.583103 -200.248458)
			(xy 179.529512 -200.254355) (xy 179.475633 -200.252386) (xy 179.422615 -200.242593) (xy 179.371588 -200.225185)
			(xy 179.32364 -200.200533) (xy 179.279792 -200.169163) (xy 179.240979 -200.131742) (xy 179.208027 -200.089069)
			(xy 179.181641 -200.042052) (xy 179.162381 -199.991695) (xy 179.150658 -199.939071) (xy 179.146723 -199.8853)
			(xy 177.881534 -199.8853) (xy 177.881534 -200.735438) (xy 183.246791 -200.735438) (xy 183.250726 -200.681667)
			(xy 183.262449 -200.629043) (xy 183.281709 -200.578686) (xy 183.308095 -200.531669) (xy 183.341047 -200.488996)
			(xy 183.37986 -200.451575) (xy 183.423708 -200.420205) (xy 183.471656 -200.395553) (xy 183.522683 -200.378145)
			(xy 183.575701 -200.368352) (xy 183.62958 -200.366383) (xy 183.683171 -200.37228) (xy 183.735332 -200.385916)
			(xy 183.784952 -200.407003) (xy 183.830973 -200.435089) (xy 183.872415 -200.469577) (xy 183.908393 -200.509731)
			(xy 183.938141 -200.554695) (xy 183.961026 -200.603512) (xy 183.976558 -200.655141) (xy 183.984408 -200.708481)
			(xy 183.9849 -200.735438) (xy 190.790845 -200.735438) (xy 190.79478 -200.681667) (xy 190.806503 -200.629043)
			(xy 190.825763 -200.578686) (xy 190.852149 -200.531669) (xy 190.885101 -200.488996) (xy 190.923914 -200.451575)
			(xy 190.967762 -200.420205) (xy 191.01571 -200.395553) (xy 191.066737 -200.378145) (xy 191.119755 -200.368352)
			(xy 191.173634 -200.366383) (xy 191.227225 -200.37228) (xy 191.279386 -200.385916) (xy 191.329006 -200.407003)
			(xy 191.375027 -200.435089) (xy 191.416469 -200.469577) (xy 191.452447 -200.509731) (xy 191.482195 -200.554695)
			(xy 191.50508 -200.603512) (xy 191.520612 -200.655141) (xy 191.528462 -200.708481) (xy 191.528954 -200.735438)
			(xy 198.334899 -200.735438) (xy 198.338834 -200.681667) (xy 198.350557 -200.629043) (xy 198.369817 -200.578686)
			(xy 198.396203 -200.531669) (xy 198.429155 -200.488996) (xy 198.467968 -200.451575) (xy 198.511816 -200.420205)
			(xy 198.559764 -200.395553) (xy 198.610791 -200.378145) (xy 198.663809 -200.368352) (xy 198.717688 -200.366383)
			(xy 198.771279 -200.37228) (xy 198.82344 -200.385916) (xy 198.87306 -200.407003) (xy 198.919081 -200.435089)
			(xy 198.960523 -200.469577) (xy 198.996501 -200.509731) (xy 199.026249 -200.554695) (xy 199.049134 -200.603512)
			(xy 199.064666 -200.655141) (xy 199.072516 -200.708481) (xy 199.073008 -200.735438) (xy 205.878699 -200.735438)
			(xy 205.882634 -200.681667) (xy 205.894357 -200.629043) (xy 205.913617 -200.578686) (xy 205.940003 -200.531669)
			(xy 205.972955 -200.488996) (xy 206.011768 -200.451575) (xy 206.055616 -200.420205) (xy 206.103564 -200.395553)
			(xy 206.154591 -200.378145) (xy 206.207609 -200.368352) (xy 206.261488 -200.366383) (xy 206.315079 -200.37228)
			(xy 206.36724 -200.385916) (xy 206.41686 -200.407003) (xy 206.462881 -200.435089) (xy 206.504323 -200.469577)
			(xy 206.540301 -200.509731) (xy 206.570049 -200.554695) (xy 206.592934 -200.603512) (xy 206.608466 -200.655141)
			(xy 206.616316 -200.708481) (xy 206.616808 -200.735438) (xy 206.616316 -200.762395) (xy 206.608466 -200.815735)
			(xy 206.592934 -200.867364) (xy 206.570049 -200.916181) (xy 206.540301 -200.961145) (xy 206.504323 -201.001299)
			(xy 206.462881 -201.035787) (xy 206.41686 -201.063873) (xy 206.36724 -201.08496) (xy 206.315079 -201.098596)
			(xy 206.261488 -201.104493) (xy 206.207609 -201.102524) (xy 206.154591 -201.092731) (xy 206.103564 -201.075323)
			(xy 206.055616 -201.050671) (xy 206.011768 -201.019301) (xy 205.972955 -200.98188) (xy 205.940003 -200.939207)
			(xy 205.913617 -200.89219) (xy 205.894357 -200.841833) (xy 205.882634 -200.789209) (xy 205.878699 -200.735438)
			(xy 199.073008 -200.735438) (xy 199.072516 -200.762395) (xy 199.064666 -200.815735) (xy 199.049134 -200.867364)
			(xy 199.026249 -200.916181) (xy 198.996501 -200.961145) (xy 198.960523 -201.001299) (xy 198.919081 -201.035787)
			(xy 198.87306 -201.063873) (xy 198.82344 -201.08496) (xy 198.771279 -201.098596) (xy 198.717688 -201.104493)
			(xy 198.663809 -201.102524) (xy 198.610791 -201.092731) (xy 198.559764 -201.075323) (xy 198.511816 -201.050671)
			(xy 198.467968 -201.019301) (xy 198.429155 -200.98188) (xy 198.396203 -200.939207) (xy 198.369817 -200.89219)
			(xy 198.350557 -200.841833) (xy 198.338834 -200.789209) (xy 198.334899 -200.735438) (xy 191.528954 -200.735438)
			(xy 191.528462 -200.762395) (xy 191.520612 -200.815735) (xy 191.50508 -200.867364) (xy 191.482195 -200.916181)
			(xy 191.452447 -200.961145) (xy 191.416469 -201.001299) (xy 191.375027 -201.035787) (xy 191.329006 -201.063873)
			(xy 191.279386 -201.08496) (xy 191.227225 -201.098596) (xy 191.173634 -201.104493) (xy 191.119755 -201.102524)
			(xy 191.066737 -201.092731) (xy 191.01571 -201.075323) (xy 190.967762 -201.050671) (xy 190.923914 -201.019301)
			(xy 190.885101 -200.98188) (xy 190.852149 -200.939207) (xy 190.825763 -200.89219) (xy 190.806503 -200.841833)
			(xy 190.79478 -200.789209) (xy 190.790845 -200.735438) (xy 183.9849 -200.735438) (xy 183.984408 -200.762395)
			(xy 183.976558 -200.815735) (xy 183.961026 -200.867364) (xy 183.938141 -200.916181) (xy 183.908393 -200.961145)
			(xy 183.872415 -201.001299) (xy 183.830973 -201.035787) (xy 183.784952 -201.063873) (xy 183.735332 -201.08496)
			(xy 183.683171 -201.098596) (xy 183.62958 -201.104493) (xy 183.575701 -201.102524) (xy 183.522683 -201.092731)
			(xy 183.471656 -201.075323) (xy 183.423708 -201.050671) (xy 183.37986 -201.019301) (xy 183.341047 -200.98188)
			(xy 183.308095 -200.939207) (xy 183.281709 -200.89219) (xy 183.262449 -200.841833) (xy 183.250726 -200.789209)
			(xy 183.246791 -200.735438) (xy 177.881534 -200.735438) (xy 177.881534 -201.585322) (xy 179.146723 -201.585322)
			(xy 179.150658 -201.531551) (xy 179.162381 -201.478927) (xy 179.181641 -201.42857) (xy 179.208027 -201.381553)
			(xy 179.240979 -201.33888) (xy 179.279792 -201.301459) (xy 179.32364 -201.270089) (xy 179.371588 -201.245437)
			(xy 179.422615 -201.228029) (xy 179.475633 -201.218236) (xy 179.529512 -201.216267) (xy 179.583103 -201.222164)
			(xy 179.635264 -201.2358) (xy 179.684884 -201.256887) (xy 179.730905 -201.284973) (xy 179.772347 -201.319461)
			(xy 179.808325 -201.359615) (xy 179.838073 -201.404579) (xy 179.860958 -201.453396) (xy 179.87649 -201.505025)
			(xy 179.88434 -201.558365) (xy 179.884832 -201.585322) (xy 183.246791 -201.585322) (xy 183.250726 -201.531551)
			(xy 183.262449 -201.478927) (xy 183.281709 -201.42857) (xy 183.308095 -201.381553) (xy 183.341047 -201.33888)
			(xy 183.37986 -201.301459) (xy 183.423708 -201.270089) (xy 183.471656 -201.245437) (xy 183.522683 -201.228029)
			(xy 183.575701 -201.218236) (xy 183.62958 -201.216267) (xy 183.683171 -201.222164) (xy 183.735332 -201.2358)
			(xy 183.784952 -201.256887) (xy 183.830973 -201.284973) (xy 183.872415 -201.319461) (xy 183.908393 -201.359615)
			(xy 183.938141 -201.404579) (xy 183.961026 -201.453396) (xy 183.976558 -201.505025) (xy 183.984408 -201.558365)
			(xy 183.9849 -201.585322) (xy 186.690777 -201.585322) (xy 186.694712 -201.531551) (xy 186.706435 -201.478927)
			(xy 186.725695 -201.42857) (xy 186.752081 -201.381553) (xy 186.785033 -201.33888) (xy 186.823846 -201.301459)
			(xy 186.867694 -201.270089) (xy 186.915642 -201.245437) (xy 186.966669 -201.228029) (xy 187.019687 -201.218236)
			(xy 187.073566 -201.216267) (xy 187.127157 -201.222164) (xy 187.179318 -201.2358) (xy 187.228938 -201.256887)
			(xy 187.274959 -201.284973) (xy 187.316401 -201.319461) (xy 187.352379 -201.359615) (xy 187.382127 -201.404579)
			(xy 187.405012 -201.453396) (xy 187.420544 -201.505025) (xy 187.428394 -201.558365) (xy 187.428886 -201.585322)
			(xy 190.790845 -201.585322) (xy 190.79478 -201.531551) (xy 190.806503 -201.478927) (xy 190.825763 -201.42857)
			(xy 190.852149 -201.381553) (xy 190.885101 -201.33888) (xy 190.923914 -201.301459) (xy 190.967762 -201.270089)
			(xy 191.01571 -201.245437) (xy 191.066737 -201.228029) (xy 191.119755 -201.218236) (xy 191.173634 -201.216267)
			(xy 191.227225 -201.222164) (xy 191.279386 -201.2358) (xy 191.329006 -201.256887) (xy 191.375027 -201.284973)
			(xy 191.416469 -201.319461) (xy 191.452447 -201.359615) (xy 191.482195 -201.404579) (xy 191.50508 -201.453396)
			(xy 191.520612 -201.505025) (xy 191.528462 -201.558365) (xy 191.528954 -201.585322) (xy 194.234831 -201.585322)
			(xy 194.238766 -201.531551) (xy 194.250489 -201.478927) (xy 194.269749 -201.42857) (xy 194.296135 -201.381553)
			(xy 194.329087 -201.33888) (xy 194.3679 -201.301459) (xy 194.411748 -201.270089) (xy 194.459696 -201.245437)
			(xy 194.510723 -201.228029) (xy 194.563741 -201.218236) (xy 194.61762 -201.216267) (xy 194.671211 -201.222164)
			(xy 194.723372 -201.2358) (xy 194.772992 -201.256887) (xy 194.819013 -201.284973) (xy 194.860455 -201.319461)
			(xy 194.896433 -201.359615) (xy 194.926181 -201.404579) (xy 194.949066 -201.453396) (xy 194.964598 -201.505025)
			(xy 194.972448 -201.558365) (xy 194.97294 -201.585322) (xy 198.334899 -201.585322) (xy 198.338834 -201.531551)
			(xy 198.350557 -201.478927) (xy 198.369817 -201.42857) (xy 198.396203 -201.381553) (xy 198.429155 -201.33888)
			(xy 198.467968 -201.301459) (xy 198.511816 -201.270089) (xy 198.559764 -201.245437) (xy 198.610791 -201.228029)
			(xy 198.663809 -201.218236) (xy 198.717688 -201.216267) (xy 198.771279 -201.222164) (xy 198.82344 -201.2358)
			(xy 198.87306 -201.256887) (xy 198.919081 -201.284973) (xy 198.960523 -201.319461) (xy 198.996501 -201.359615)
			(xy 199.026249 -201.404579) (xy 199.049134 -201.453396) (xy 199.064666 -201.505025) (xy 199.072516 -201.558365)
			(xy 199.073008 -201.585322) (xy 201.778631 -201.585322) (xy 201.782566 -201.531551) (xy 201.794289 -201.478927)
			(xy 201.813549 -201.42857) (xy 201.839935 -201.381553) (xy 201.872887 -201.33888) (xy 201.9117 -201.301459)
			(xy 201.955548 -201.270089) (xy 202.003496 -201.245437) (xy 202.054523 -201.228029) (xy 202.107541 -201.218236)
			(xy 202.16142 -201.216267) (xy 202.215011 -201.222164) (xy 202.267172 -201.2358) (xy 202.316792 -201.256887)
			(xy 202.362813 -201.284973) (xy 202.404255 -201.319461) (xy 202.440233 -201.359615) (xy 202.469981 -201.404579)
			(xy 202.492866 -201.453396) (xy 202.508398 -201.505025) (xy 202.516248 -201.558365) (xy 202.51674 -201.585322)
			(xy 205.878699 -201.585322) (xy 205.882634 -201.531551) (xy 205.894357 -201.478927) (xy 205.913617 -201.42857)
			(xy 205.940003 -201.381553) (xy 205.972955 -201.33888) (xy 206.011768 -201.301459) (xy 206.055616 -201.270089)
			(xy 206.103564 -201.245437) (xy 206.154591 -201.228029) (xy 206.207609 -201.218236) (xy 206.261488 -201.216267)
			(xy 206.315079 -201.222164) (xy 206.36724 -201.2358) (xy 206.41686 -201.256887) (xy 206.462881 -201.284973)
			(xy 206.504323 -201.319461) (xy 206.540301 -201.359615) (xy 206.570049 -201.404579) (xy 206.592934 -201.453396)
			(xy 206.608466 -201.505025) (xy 206.616316 -201.558365) (xy 206.616808 -201.585322) (xy 206.616316 -201.612279)
			(xy 206.608466 -201.665619) (xy 206.592934 -201.717248) (xy 206.570049 -201.766065) (xy 206.540301 -201.811029)
			(xy 206.504323 -201.851183) (xy 206.462881 -201.885671) (xy 206.41686 -201.913757) (xy 206.36724 -201.934844)
			(xy 206.315079 -201.94848) (xy 206.261488 -201.954377) (xy 206.207609 -201.952408) (xy 206.154591 -201.942615)
			(xy 206.103564 -201.925207) (xy 206.055616 -201.900555) (xy 206.011768 -201.869185) (xy 205.972955 -201.831764)
			(xy 205.940003 -201.789091) (xy 205.913617 -201.742074) (xy 205.894357 -201.691717) (xy 205.882634 -201.639093)
			(xy 205.878699 -201.585322) (xy 202.51674 -201.585322) (xy 202.516248 -201.612279) (xy 202.508398 -201.665619)
			(xy 202.492866 -201.717248) (xy 202.469981 -201.766065) (xy 202.440233 -201.811029) (xy 202.404255 -201.851183)
			(xy 202.362813 -201.885671) (xy 202.316792 -201.913757) (xy 202.267172 -201.934844) (xy 202.215011 -201.94848)
			(xy 202.16142 -201.954377) (xy 202.107541 -201.952408) (xy 202.054523 -201.942615) (xy 202.003496 -201.925207)
			(xy 201.955548 -201.900555) (xy 201.9117 -201.869185) (xy 201.872887 -201.831764) (xy 201.839935 -201.789091)
			(xy 201.813549 -201.742074) (xy 201.794289 -201.691717) (xy 201.782566 -201.639093) (xy 201.778631 -201.585322)
			(xy 199.073008 -201.585322) (xy 199.072516 -201.612279) (xy 199.064666 -201.665619) (xy 199.049134 -201.717248)
			(xy 199.026249 -201.766065) (xy 198.996501 -201.811029) (xy 198.960523 -201.851183) (xy 198.919081 -201.885671)
			(xy 198.87306 -201.913757) (xy 198.82344 -201.934844) (xy 198.771279 -201.94848) (xy 198.717688 -201.954377)
			(xy 198.663809 -201.952408) (xy 198.610791 -201.942615) (xy 198.559764 -201.925207) (xy 198.511816 -201.900555)
			(xy 198.467968 -201.869185) (xy 198.429155 -201.831764) (xy 198.396203 -201.789091) (xy 198.369817 -201.742074)
			(xy 198.350557 -201.691717) (xy 198.338834 -201.639093) (xy 198.334899 -201.585322) (xy 194.97294 -201.585322)
			(xy 194.972448 -201.612279) (xy 194.964598 -201.665619) (xy 194.949066 -201.717248) (xy 194.926181 -201.766065)
			(xy 194.896433 -201.811029) (xy 194.860455 -201.851183) (xy 194.819013 -201.885671) (xy 194.772992 -201.913757)
			(xy 194.723372 -201.934844) (xy 194.671211 -201.94848) (xy 194.61762 -201.954377) (xy 194.563741 -201.952408)
			(xy 194.510723 -201.942615) (xy 194.459696 -201.925207) (xy 194.411748 -201.900555) (xy 194.3679 -201.869185)
			(xy 194.329087 -201.831764) (xy 194.296135 -201.789091) (xy 194.269749 -201.742074) (xy 194.250489 -201.691717)
			(xy 194.238766 -201.639093) (xy 194.234831 -201.585322) (xy 191.528954 -201.585322) (xy 191.528462 -201.612279)
			(xy 191.520612 -201.665619) (xy 191.50508 -201.717248) (xy 191.482195 -201.766065) (xy 191.452447 -201.811029)
			(xy 191.416469 -201.851183) (xy 191.375027 -201.885671) (xy 191.329006 -201.913757) (xy 191.279386 -201.934844)
			(xy 191.227225 -201.94848) (xy 191.173634 -201.954377) (xy 191.119755 -201.952408) (xy 191.066737 -201.942615)
			(xy 191.01571 -201.925207) (xy 190.967762 -201.900555) (xy 190.923914 -201.869185) (xy 190.885101 -201.831764)
			(xy 190.852149 -201.789091) (xy 190.825763 -201.742074) (xy 190.806503 -201.691717) (xy 190.79478 -201.639093)
			(xy 190.790845 -201.585322) (xy 187.428886 -201.585322) (xy 187.428394 -201.612279) (xy 187.420544 -201.665619)
			(xy 187.405012 -201.717248) (xy 187.382127 -201.766065) (xy 187.352379 -201.811029) (xy 187.316401 -201.851183)
			(xy 187.274959 -201.885671) (xy 187.228938 -201.913757) (xy 187.179318 -201.934844) (xy 187.127157 -201.94848)
			(xy 187.073566 -201.954377) (xy 187.019687 -201.952408) (xy 186.966669 -201.942615) (xy 186.915642 -201.925207)
			(xy 186.867694 -201.900555) (xy 186.823846 -201.869185) (xy 186.785033 -201.831764) (xy 186.752081 -201.789091)
			(xy 186.725695 -201.742074) (xy 186.706435 -201.691717) (xy 186.694712 -201.639093) (xy 186.690777 -201.585322)
			(xy 183.9849 -201.585322) (xy 183.984408 -201.612279) (xy 183.976558 -201.665619) (xy 183.961026 -201.717248)
			(xy 183.938141 -201.766065) (xy 183.908393 -201.811029) (xy 183.872415 -201.851183) (xy 183.830973 -201.885671)
			(xy 183.784952 -201.913757) (xy 183.735332 -201.934844) (xy 183.683171 -201.94848) (xy 183.62958 -201.954377)
			(xy 183.575701 -201.952408) (xy 183.522683 -201.942615) (xy 183.471656 -201.925207) (xy 183.423708 -201.900555)
			(xy 183.37986 -201.869185) (xy 183.341047 -201.831764) (xy 183.308095 -201.789091) (xy 183.281709 -201.742074)
			(xy 183.262449 -201.691717) (xy 183.250726 -201.639093) (xy 183.246791 -201.585322) (xy 179.884832 -201.585322)
			(xy 179.88434 -201.612279) (xy 179.87649 -201.665619) (xy 179.860958 -201.717248) (xy 179.838073 -201.766065)
			(xy 179.808325 -201.811029) (xy 179.772347 -201.851183) (xy 179.730905 -201.885671) (xy 179.684884 -201.913757)
			(xy 179.635264 -201.934844) (xy 179.583103 -201.94848) (xy 179.529512 -201.954377) (xy 179.475633 -201.952408)
			(xy 179.422615 -201.942615) (xy 179.371588 -201.925207) (xy 179.32364 -201.900555) (xy 179.279792 -201.869185)
			(xy 179.240979 -201.831764) (xy 179.208027 -201.789091) (xy 179.181641 -201.742074) (xy 179.162381 -201.691717)
			(xy 179.150658 -201.639093) (xy 179.146723 -201.585322) (xy 177.881534 -201.585322) (xy 177.881534 -202.435206)
			(xy 179.146723 -202.435206) (xy 179.150658 -202.381435) (xy 179.162381 -202.328811) (xy 179.181641 -202.278454)
			(xy 179.208027 -202.231437) (xy 179.240979 -202.188764) (xy 179.279792 -202.151343) (xy 179.32364 -202.119973)
			(xy 179.371588 -202.095321) (xy 179.422615 -202.077913) (xy 179.475633 -202.06812) (xy 179.529512 -202.066151)
			(xy 179.583103 -202.072048) (xy 179.635264 -202.085684) (xy 179.684884 -202.106771) (xy 179.730905 -202.134857)
			(xy 179.772347 -202.169345) (xy 179.808325 -202.209499) (xy 179.838073 -202.254463) (xy 179.860958 -202.30328)
			(xy 179.87649 -202.354909) (xy 179.88434 -202.408249) (xy 179.884832 -202.435206) (xy 186.690777 -202.435206)
			(xy 186.694712 -202.381435) (xy 186.706435 -202.328811) (xy 186.725695 -202.278454) (xy 186.752081 -202.231437)
			(xy 186.785033 -202.188764) (xy 186.823846 -202.151343) (xy 186.867694 -202.119973) (xy 186.915642 -202.095321)
			(xy 186.966669 -202.077913) (xy 187.019687 -202.06812) (xy 187.073566 -202.066151) (xy 187.127157 -202.072048)
			(xy 187.179318 -202.085684) (xy 187.228938 -202.106771) (xy 187.274959 -202.134857) (xy 187.316401 -202.169345)
			(xy 187.352379 -202.209499) (xy 187.382127 -202.254463) (xy 187.405012 -202.30328) (xy 187.420544 -202.354909)
			(xy 187.428394 -202.408249) (xy 187.428886 -202.435206) (xy 194.234831 -202.435206) (xy 194.238766 -202.381435)
			(xy 194.250489 -202.328811) (xy 194.269749 -202.278454) (xy 194.296135 -202.231437) (xy 194.329087 -202.188764)
			(xy 194.3679 -202.151343) (xy 194.411748 -202.119973) (xy 194.459696 -202.095321) (xy 194.510723 -202.077913)
			(xy 194.563741 -202.06812) (xy 194.61762 -202.066151) (xy 194.671211 -202.072048) (xy 194.723372 -202.085684)
			(xy 194.772992 -202.106771) (xy 194.819013 -202.134857) (xy 194.860455 -202.169345) (xy 194.896433 -202.209499)
			(xy 194.926181 -202.254463) (xy 194.949066 -202.30328) (xy 194.964598 -202.354909) (xy 194.972448 -202.408249)
			(xy 194.97294 -202.435206) (xy 201.778631 -202.435206) (xy 201.782566 -202.381435) (xy 201.794289 -202.328811)
			(xy 201.813549 -202.278454) (xy 201.839935 -202.231437) (xy 201.872887 -202.188764) (xy 201.9117 -202.151343)
			(xy 201.955548 -202.119973) (xy 202.003496 -202.095321) (xy 202.054523 -202.077913) (xy 202.107541 -202.06812)
			(xy 202.16142 -202.066151) (xy 202.215011 -202.072048) (xy 202.267172 -202.085684) (xy 202.316792 -202.106771)
			(xy 202.362813 -202.134857) (xy 202.404255 -202.169345) (xy 202.440233 -202.209499) (xy 202.469981 -202.254463)
			(xy 202.492866 -202.30328) (xy 202.508398 -202.354909) (xy 202.516248 -202.408249) (xy 202.51674 -202.435206)
			(xy 202.516248 -202.462163) (xy 202.508398 -202.515503) (xy 202.492866 -202.567132) (xy 202.469981 -202.615949)
			(xy 202.440233 -202.660913) (xy 202.404255 -202.701067) (xy 202.362813 -202.735555) (xy 202.316792 -202.763641)
			(xy 202.267172 -202.784728) (xy 202.215011 -202.798364) (xy 202.16142 -202.804261) (xy 202.107541 -202.802292)
			(xy 202.054523 -202.792499) (xy 202.003496 -202.775091) (xy 201.955548 -202.750439) (xy 201.9117 -202.719069)
			(xy 201.872887 -202.681648) (xy 201.839935 -202.638975) (xy 201.813549 -202.591958) (xy 201.794289 -202.541601)
			(xy 201.782566 -202.488977) (xy 201.778631 -202.435206) (xy 194.97294 -202.435206) (xy 194.972448 -202.462163)
			(xy 194.964598 -202.515503) (xy 194.949066 -202.567132) (xy 194.926181 -202.615949) (xy 194.896433 -202.660913)
			(xy 194.860455 -202.701067) (xy 194.819013 -202.735555) (xy 194.772992 -202.763641) (xy 194.723372 -202.784728)
			(xy 194.671211 -202.798364) (xy 194.61762 -202.804261) (xy 194.563741 -202.802292) (xy 194.510723 -202.792499)
			(xy 194.459696 -202.775091) (xy 194.411748 -202.750439) (xy 194.3679 -202.719069) (xy 194.329087 -202.681648)
			(xy 194.296135 -202.638975) (xy 194.269749 -202.591958) (xy 194.250489 -202.541601) (xy 194.238766 -202.488977)
			(xy 194.234831 -202.435206) (xy 187.428886 -202.435206) (xy 187.428394 -202.462163) (xy 187.420544 -202.515503)
			(xy 187.405012 -202.567132) (xy 187.382127 -202.615949) (xy 187.352379 -202.660913) (xy 187.316401 -202.701067)
			(xy 187.274959 -202.735555) (xy 187.228938 -202.763641) (xy 187.179318 -202.784728) (xy 187.127157 -202.798364)
			(xy 187.073566 -202.804261) (xy 187.019687 -202.802292) (xy 186.966669 -202.792499) (xy 186.915642 -202.775091)
			(xy 186.867694 -202.750439) (xy 186.823846 -202.719069) (xy 186.785033 -202.681648) (xy 186.752081 -202.638975)
			(xy 186.725695 -202.591958) (xy 186.706435 -202.541601) (xy 186.694712 -202.488977) (xy 186.690777 -202.435206)
			(xy 179.884832 -202.435206) (xy 179.88434 -202.462163) (xy 179.87649 -202.515503) (xy 179.860958 -202.567132)
			(xy 179.838073 -202.615949) (xy 179.808325 -202.660913) (xy 179.772347 -202.701067) (xy 179.730905 -202.735555)
			(xy 179.684884 -202.763641) (xy 179.635264 -202.784728) (xy 179.583103 -202.798364) (xy 179.529512 -202.804261)
			(xy 179.475633 -202.802292) (xy 179.422615 -202.792499) (xy 179.371588 -202.775091) (xy 179.32364 -202.750439)
			(xy 179.279792 -202.719069) (xy 179.240979 -202.681648) (xy 179.208027 -202.638975) (xy 179.181641 -202.591958)
			(xy 179.162381 -202.541601) (xy 179.150658 -202.488977) (xy 179.146723 -202.435206) (xy 177.881534 -202.435206)
			(xy 177.881534 -203.285344) (xy 183.246791 -203.285344) (xy 183.250726 -203.231573) (xy 183.262449 -203.178949)
			(xy 183.281709 -203.128592) (xy 183.308095 -203.081575) (xy 183.341047 -203.038902) (xy 183.37986 -203.001481)
			(xy 183.423708 -202.970111) (xy 183.471656 -202.945459) (xy 183.522683 -202.928051) (xy 183.575701 -202.918258)
			(xy 183.62958 -202.916289) (xy 183.683171 -202.922186) (xy 183.735332 -202.935822) (xy 183.784952 -202.956909)
			(xy 183.830973 -202.984995) (xy 183.872415 -203.019483) (xy 183.908393 -203.059637) (xy 183.938141 -203.104601)
			(xy 183.961026 -203.153418) (xy 183.976558 -203.205047) (xy 183.984408 -203.258387) (xy 183.9849 -203.285344)
			(xy 190.790845 -203.285344) (xy 190.79478 -203.231573) (xy 190.806503 -203.178949) (xy 190.825763 -203.128592)
			(xy 190.852149 -203.081575) (xy 190.885101 -203.038902) (xy 190.923914 -203.001481) (xy 190.967762 -202.970111)
			(xy 191.01571 -202.945459) (xy 191.066737 -202.928051) (xy 191.119755 -202.918258) (xy 191.173634 -202.916289)
			(xy 191.227225 -202.922186) (xy 191.279386 -202.935822) (xy 191.329006 -202.956909) (xy 191.375027 -202.984995)
			(xy 191.416469 -203.019483) (xy 191.452447 -203.059637) (xy 191.482195 -203.104601) (xy 191.50508 -203.153418)
			(xy 191.520612 -203.205047) (xy 191.528462 -203.258387) (xy 191.528954 -203.285344) (xy 198.334899 -203.285344)
			(xy 198.338834 -203.231573) (xy 198.350557 -203.178949) (xy 198.369817 -203.128592) (xy 198.396203 -203.081575)
			(xy 198.429155 -203.038902) (xy 198.467968 -203.001481) (xy 198.511816 -202.970111) (xy 198.559764 -202.945459)
			(xy 198.610791 -202.928051) (xy 198.663809 -202.918258) (xy 198.717688 -202.916289) (xy 198.771279 -202.922186)
			(xy 198.82344 -202.935822) (xy 198.87306 -202.956909) (xy 198.919081 -202.984995) (xy 198.960523 -203.019483)
			(xy 198.996501 -203.059637) (xy 199.026249 -203.104601) (xy 199.049134 -203.153418) (xy 199.064666 -203.205047)
			(xy 199.072516 -203.258387) (xy 199.073008 -203.285344) (xy 205.878699 -203.285344) (xy 205.882634 -203.231573)
			(xy 205.894357 -203.178949) (xy 205.913617 -203.128592) (xy 205.940003 -203.081575) (xy 205.972955 -203.038902)
			(xy 206.011768 -203.001481) (xy 206.055616 -202.970111) (xy 206.103564 -202.945459) (xy 206.154591 -202.928051)
			(xy 206.207609 -202.918258) (xy 206.261488 -202.916289) (xy 206.315079 -202.922186) (xy 206.36724 -202.935822)
			(xy 206.41686 -202.956909) (xy 206.462881 -202.984995) (xy 206.504323 -203.019483) (xy 206.540301 -203.059637)
			(xy 206.570049 -203.104601) (xy 206.592934 -203.153418) (xy 206.608466 -203.205047) (xy 206.616316 -203.258387)
			(xy 206.616808 -203.285344) (xy 206.616316 -203.312301) (xy 206.608466 -203.365641) (xy 206.592934 -203.41727)
			(xy 206.570049 -203.466087) (xy 206.540301 -203.511051) (xy 206.504323 -203.551205) (xy 206.462881 -203.585693)
			(xy 206.41686 -203.613779) (xy 206.36724 -203.634866) (xy 206.315079 -203.648502) (xy 206.261488 -203.654399)
			(xy 206.207609 -203.65243) (xy 206.154591 -203.642637) (xy 206.103564 -203.625229) (xy 206.055616 -203.600577)
			(xy 206.011768 -203.569207) (xy 205.972955 -203.531786) (xy 205.940003 -203.489113) (xy 205.913617 -203.442096)
			(xy 205.894357 -203.391739) (xy 205.882634 -203.339115) (xy 205.878699 -203.285344) (xy 199.073008 -203.285344)
			(xy 199.072516 -203.312301) (xy 199.064666 -203.365641) (xy 199.049134 -203.41727) (xy 199.026249 -203.466087)
			(xy 198.996501 -203.511051) (xy 198.960523 -203.551205) (xy 198.919081 -203.585693) (xy 198.87306 -203.613779)
			(xy 198.82344 -203.634866) (xy 198.771279 -203.648502) (xy 198.717688 -203.654399) (xy 198.663809 -203.65243)
			(xy 198.610791 -203.642637) (xy 198.559764 -203.625229) (xy 198.511816 -203.600577) (xy 198.467968 -203.569207)
			(xy 198.429155 -203.531786) (xy 198.396203 -203.489113) (xy 198.369817 -203.442096) (xy 198.350557 -203.391739)
			(xy 198.338834 -203.339115) (xy 198.334899 -203.285344) (xy 191.528954 -203.285344) (xy 191.528462 -203.312301)
			(xy 191.520612 -203.365641) (xy 191.50508 -203.41727) (xy 191.482195 -203.466087) (xy 191.452447 -203.511051)
			(xy 191.416469 -203.551205) (xy 191.375027 -203.585693) (xy 191.329006 -203.613779) (xy 191.279386 -203.634866)
			(xy 191.227225 -203.648502) (xy 191.173634 -203.654399) (xy 191.119755 -203.65243) (xy 191.066737 -203.642637)
			(xy 191.01571 -203.625229) (xy 190.967762 -203.600577) (xy 190.923914 -203.569207) (xy 190.885101 -203.531786)
			(xy 190.852149 -203.489113) (xy 190.825763 -203.442096) (xy 190.806503 -203.391739) (xy 190.79478 -203.339115)
			(xy 190.790845 -203.285344) (xy 183.9849 -203.285344) (xy 183.984408 -203.312301) (xy 183.976558 -203.365641)
			(xy 183.961026 -203.41727) (xy 183.938141 -203.466087) (xy 183.908393 -203.511051) (xy 183.872415 -203.551205)
			(xy 183.830973 -203.585693) (xy 183.784952 -203.613779) (xy 183.735332 -203.634866) (xy 183.683171 -203.648502)
			(xy 183.62958 -203.654399) (xy 183.575701 -203.65243) (xy 183.522683 -203.642637) (xy 183.471656 -203.625229)
			(xy 183.423708 -203.600577) (xy 183.37986 -203.569207) (xy 183.341047 -203.531786) (xy 183.308095 -203.489113)
			(xy 183.281709 -203.442096) (xy 183.262449 -203.391739) (xy 183.250726 -203.339115) (xy 183.246791 -203.285344)
			(xy 177.881534 -203.285344) (xy 177.881534 -204.135228) (xy 179.146723 -204.135228) (xy 179.150658 -204.081457)
			(xy 179.162381 -204.028833) (xy 179.181641 -203.978476) (xy 179.208027 -203.931459) (xy 179.240979 -203.888786)
			(xy 179.279792 -203.851365) (xy 179.32364 -203.819995) (xy 179.371588 -203.795343) (xy 179.422615 -203.777935)
			(xy 179.475633 -203.768142) (xy 179.529512 -203.766173) (xy 179.583103 -203.77207) (xy 179.635264 -203.785706)
			(xy 179.684884 -203.806793) (xy 179.730905 -203.834879) (xy 179.772347 -203.869367) (xy 179.808325 -203.909521)
			(xy 179.838073 -203.954485) (xy 179.860958 -204.003302) (xy 179.87649 -204.054931) (xy 179.88434 -204.108271)
			(xy 179.884832 -204.135228) (xy 186.690777 -204.135228) (xy 186.694712 -204.081457) (xy 186.706435 -204.028833)
			(xy 186.725695 -203.978476) (xy 186.752081 -203.931459) (xy 186.785033 -203.888786) (xy 186.823846 -203.851365)
			(xy 186.867694 -203.819995) (xy 186.915642 -203.795343) (xy 186.966669 -203.777935) (xy 187.019687 -203.768142)
			(xy 187.073566 -203.766173) (xy 187.127157 -203.77207) (xy 187.179318 -203.785706) (xy 187.228938 -203.806793)
			(xy 187.274959 -203.834879) (xy 187.316401 -203.869367) (xy 187.352379 -203.909521) (xy 187.382127 -203.954485)
			(xy 187.405012 -204.003302) (xy 187.420544 -204.054931) (xy 187.428394 -204.108271) (xy 187.428886 -204.135228)
			(xy 194.234831 -204.135228) (xy 194.238766 -204.081457) (xy 194.250489 -204.028833) (xy 194.269749 -203.978476)
			(xy 194.296135 -203.931459) (xy 194.329087 -203.888786) (xy 194.3679 -203.851365) (xy 194.411748 -203.819995)
			(xy 194.459696 -203.795343) (xy 194.510723 -203.777935) (xy 194.563741 -203.768142) (xy 194.61762 -203.766173)
			(xy 194.671211 -203.77207) (xy 194.723372 -203.785706) (xy 194.772992 -203.806793) (xy 194.819013 -203.834879)
			(xy 194.860455 -203.869367) (xy 194.896433 -203.909521) (xy 194.926181 -203.954485) (xy 194.949066 -204.003302)
			(xy 194.964598 -204.054931) (xy 194.972448 -204.108271) (xy 194.97294 -204.135228) (xy 201.778631 -204.135228)
			(xy 201.782566 -204.081457) (xy 201.794289 -204.028833) (xy 201.813549 -203.978476) (xy 201.839935 -203.931459)
			(xy 201.872887 -203.888786) (xy 201.9117 -203.851365) (xy 201.955548 -203.819995) (xy 202.003496 -203.795343)
			(xy 202.054523 -203.777935) (xy 202.107541 -203.768142) (xy 202.16142 -203.766173) (xy 202.215011 -203.77207)
			(xy 202.267172 -203.785706) (xy 202.316792 -203.806793) (xy 202.362813 -203.834879) (xy 202.404255 -203.869367)
			(xy 202.440233 -203.909521) (xy 202.469981 -203.954485) (xy 202.492866 -204.003302) (xy 202.508398 -204.054931)
			(xy 202.516248 -204.108271) (xy 202.51674 -204.135228) (xy 202.516248 -204.162185) (xy 202.508398 -204.215525)
			(xy 202.492866 -204.267154) (xy 202.469981 -204.315971) (xy 202.440233 -204.360935) (xy 202.404255 -204.401089)
			(xy 202.362813 -204.435577) (xy 202.316792 -204.463663) (xy 202.267172 -204.48475) (xy 202.215011 -204.498386)
			(xy 202.16142 -204.504283) (xy 202.107541 -204.502314) (xy 202.054523 -204.492521) (xy 202.003496 -204.475113)
			(xy 201.955548 -204.450461) (xy 201.9117 -204.419091) (xy 201.872887 -204.38167) (xy 201.839935 -204.338997)
			(xy 201.813549 -204.29198) (xy 201.794289 -204.241623) (xy 201.782566 -204.188999) (xy 201.778631 -204.135228)
			(xy 194.97294 -204.135228) (xy 194.972448 -204.162185) (xy 194.964598 -204.215525) (xy 194.949066 -204.267154)
			(xy 194.926181 -204.315971) (xy 194.896433 -204.360935) (xy 194.860455 -204.401089) (xy 194.819013 -204.435577)
			(xy 194.772992 -204.463663) (xy 194.723372 -204.48475) (xy 194.671211 -204.498386) (xy 194.61762 -204.504283)
			(xy 194.563741 -204.502314) (xy 194.510723 -204.492521) (xy 194.459696 -204.475113) (xy 194.411748 -204.450461)
			(xy 194.3679 -204.419091) (xy 194.329087 -204.38167) (xy 194.296135 -204.338997) (xy 194.269749 -204.29198)
			(xy 194.250489 -204.241623) (xy 194.238766 -204.188999) (xy 194.234831 -204.135228) (xy 187.428886 -204.135228)
			(xy 187.428394 -204.162185) (xy 187.420544 -204.215525) (xy 187.405012 -204.267154) (xy 187.382127 -204.315971)
			(xy 187.352379 -204.360935) (xy 187.316401 -204.401089) (xy 187.274959 -204.435577) (xy 187.228938 -204.463663)
			(xy 187.179318 -204.48475) (xy 187.127157 -204.498386) (xy 187.073566 -204.504283) (xy 187.019687 -204.502314)
			(xy 186.966669 -204.492521) (xy 186.915642 -204.475113) (xy 186.867694 -204.450461) (xy 186.823846 -204.419091)
			(xy 186.785033 -204.38167) (xy 186.752081 -204.338997) (xy 186.725695 -204.29198) (xy 186.706435 -204.241623)
			(xy 186.694712 -204.188999) (xy 186.690777 -204.135228) (xy 179.884832 -204.135228) (xy 179.88434 -204.162185)
			(xy 179.87649 -204.215525) (xy 179.860958 -204.267154) (xy 179.838073 -204.315971) (xy 179.808325 -204.360935)
			(xy 179.772347 -204.401089) (xy 179.730905 -204.435577) (xy 179.684884 -204.463663) (xy 179.635264 -204.48475)
			(xy 179.583103 -204.498386) (xy 179.529512 -204.504283) (xy 179.475633 -204.502314) (xy 179.422615 -204.492521)
			(xy 179.371588 -204.475113) (xy 179.32364 -204.450461) (xy 179.279792 -204.419091) (xy 179.240979 -204.38167)
			(xy 179.208027 -204.338997) (xy 179.181641 -204.29198) (xy 179.162381 -204.241623) (xy 179.150658 -204.188999)
			(xy 179.146723 -204.135228) (xy 177.881534 -204.135228) (xy 177.881534 -204.985366) (xy 183.246791 -204.985366)
			(xy 183.250726 -204.931595) (xy 183.262449 -204.878971) (xy 183.281709 -204.828614) (xy 183.308095 -204.781597)
			(xy 183.341047 -204.738924) (xy 183.37986 -204.701503) (xy 183.423708 -204.670133) (xy 183.471656 -204.645481)
			(xy 183.522683 -204.628073) (xy 183.575701 -204.61828) (xy 183.62958 -204.616311) (xy 183.683171 -204.622208)
			(xy 183.735332 -204.635844) (xy 183.784952 -204.656931) (xy 183.830973 -204.685017) (xy 183.872415 -204.719505)
			(xy 183.908393 -204.759659) (xy 183.938141 -204.804623) (xy 183.961026 -204.85344) (xy 183.976558 -204.905069)
			(xy 183.984408 -204.958409) (xy 183.9849 -204.985366) (xy 190.790845 -204.985366) (xy 190.79478 -204.931595)
			(xy 190.806503 -204.878971) (xy 190.825763 -204.828614) (xy 190.852149 -204.781597) (xy 190.885101 -204.738924)
			(xy 190.923914 -204.701503) (xy 190.967762 -204.670133) (xy 191.01571 -204.645481) (xy 191.066737 -204.628073)
			(xy 191.119755 -204.61828) (xy 191.173634 -204.616311) (xy 191.227225 -204.622208) (xy 191.279386 -204.635844)
			(xy 191.329006 -204.656931) (xy 191.375027 -204.685017) (xy 191.416469 -204.719505) (xy 191.452447 -204.759659)
			(xy 191.482195 -204.804623) (xy 191.50508 -204.85344) (xy 191.520612 -204.905069) (xy 191.528462 -204.958409)
			(xy 191.528954 -204.985366) (xy 198.334899 -204.985366) (xy 198.338834 -204.931595) (xy 198.350557 -204.878971)
			(xy 198.369817 -204.828614) (xy 198.396203 -204.781597) (xy 198.429155 -204.738924) (xy 198.467968 -204.701503)
			(xy 198.511816 -204.670133) (xy 198.559764 -204.645481) (xy 198.610791 -204.628073) (xy 198.663809 -204.61828)
			(xy 198.717688 -204.616311) (xy 198.771279 -204.622208) (xy 198.82344 -204.635844) (xy 198.87306 -204.656931)
			(xy 198.919081 -204.685017) (xy 198.960523 -204.719505) (xy 198.996501 -204.759659) (xy 199.026249 -204.804623)
			(xy 199.049134 -204.85344) (xy 199.064666 -204.905069) (xy 199.072516 -204.958409) (xy 199.073008 -204.985366)
			(xy 205.878699 -204.985366) (xy 205.882634 -204.931595) (xy 205.894357 -204.878971) (xy 205.913617 -204.828614)
			(xy 205.940003 -204.781597) (xy 205.972955 -204.738924) (xy 206.011768 -204.701503) (xy 206.055616 -204.670133)
			(xy 206.103564 -204.645481) (xy 206.154591 -204.628073) (xy 206.207609 -204.61828) (xy 206.261488 -204.616311)
			(xy 206.315079 -204.622208) (xy 206.36724 -204.635844) (xy 206.41686 -204.656931) (xy 206.462881 -204.685017)
			(xy 206.504323 -204.719505) (xy 206.540301 -204.759659) (xy 206.570049 -204.804623) (xy 206.592934 -204.85344)
			(xy 206.608466 -204.905069) (xy 206.616316 -204.958409) (xy 206.616808 -204.985366) (xy 206.616316 -205.012323)
			(xy 206.608466 -205.065663) (xy 206.592934 -205.117292) (xy 206.570049 -205.166109) (xy 206.540301 -205.211073)
			(xy 206.504323 -205.251227) (xy 206.462881 -205.285715) (xy 206.41686 -205.313801) (xy 206.36724 -205.334888)
			(xy 206.315079 -205.348524) (xy 206.261488 -205.354421) (xy 206.207609 -205.352452) (xy 206.154591 -205.342659)
			(xy 206.103564 -205.325251) (xy 206.055616 -205.300599) (xy 206.011768 -205.269229) (xy 205.972955 -205.231808)
			(xy 205.940003 -205.189135) (xy 205.913617 -205.142118) (xy 205.894357 -205.091761) (xy 205.882634 -205.039137)
			(xy 205.878699 -204.985366) (xy 199.073008 -204.985366) (xy 199.072516 -205.012323) (xy 199.064666 -205.065663)
			(xy 199.049134 -205.117292) (xy 199.026249 -205.166109) (xy 198.996501 -205.211073) (xy 198.960523 -205.251227)
			(xy 198.919081 -205.285715) (xy 198.87306 -205.313801) (xy 198.82344 -205.334888) (xy 198.771279 -205.348524)
			(xy 198.717688 -205.354421) (xy 198.663809 -205.352452) (xy 198.610791 -205.342659) (xy 198.559764 -205.325251)
			(xy 198.511816 -205.300599) (xy 198.467968 -205.269229) (xy 198.429155 -205.231808) (xy 198.396203 -205.189135)
			(xy 198.369817 -205.142118) (xy 198.350557 -205.091761) (xy 198.338834 -205.039137) (xy 198.334899 -204.985366)
			(xy 191.528954 -204.985366) (xy 191.528462 -205.012323) (xy 191.520612 -205.065663) (xy 191.50508 -205.117292)
			(xy 191.482195 -205.166109) (xy 191.452447 -205.211073) (xy 191.416469 -205.251227) (xy 191.375027 -205.285715)
			(xy 191.329006 -205.313801) (xy 191.279386 -205.334888) (xy 191.227225 -205.348524) (xy 191.173634 -205.354421)
			(xy 191.119755 -205.352452) (xy 191.066737 -205.342659) (xy 191.01571 -205.325251) (xy 190.967762 -205.300599)
			(xy 190.923914 -205.269229) (xy 190.885101 -205.231808) (xy 190.852149 -205.189135) (xy 190.825763 -205.142118)
			(xy 190.806503 -205.091761) (xy 190.79478 -205.039137) (xy 190.790845 -204.985366) (xy 183.9849 -204.985366)
			(xy 183.984408 -205.012323) (xy 183.976558 -205.065663) (xy 183.961026 -205.117292) (xy 183.938141 -205.166109)
			(xy 183.908393 -205.211073) (xy 183.872415 -205.251227) (xy 183.830973 -205.285715) (xy 183.784952 -205.313801)
			(xy 183.735332 -205.334888) (xy 183.683171 -205.348524) (xy 183.62958 -205.354421) (xy 183.575701 -205.352452)
			(xy 183.522683 -205.342659) (xy 183.471656 -205.325251) (xy 183.423708 -205.300599) (xy 183.37986 -205.269229)
			(xy 183.341047 -205.231808) (xy 183.308095 -205.189135) (xy 183.281709 -205.142118) (xy 183.262449 -205.091761)
			(xy 183.250726 -205.039137) (xy 183.246791 -204.985366) (xy 177.881534 -204.985366) (xy 177.881534 -205.83525)
			(xy 179.146723 -205.83525) (xy 179.150658 -205.781479) (xy 179.162381 -205.728855) (xy 179.181641 -205.678498)
			(xy 179.208027 -205.631481) (xy 179.240979 -205.588808) (xy 179.279792 -205.551387) (xy 179.32364 -205.520017)
			(xy 179.371588 -205.495365) (xy 179.422615 -205.477957) (xy 179.475633 -205.468164) (xy 179.529512 -205.466195)
			(xy 179.583103 -205.472092) (xy 179.635264 -205.485728) (xy 179.684884 -205.506815) (xy 179.730905 -205.534901)
			(xy 179.772347 -205.569389) (xy 179.808325 -205.609543) (xy 179.838073 -205.654507) (xy 179.860958 -205.703324)
			(xy 179.87649 -205.754953) (xy 179.88434 -205.808293) (xy 179.884832 -205.83525) (xy 186.690777 -205.83525)
			(xy 186.694712 -205.781479) (xy 186.706435 -205.728855) (xy 186.725695 -205.678498) (xy 186.752081 -205.631481)
			(xy 186.785033 -205.588808) (xy 186.823846 -205.551387) (xy 186.867694 -205.520017) (xy 186.915642 -205.495365)
			(xy 186.966669 -205.477957) (xy 187.019687 -205.468164) (xy 187.073566 -205.466195) (xy 187.127157 -205.472092)
			(xy 187.179318 -205.485728) (xy 187.228938 -205.506815) (xy 187.274959 -205.534901) (xy 187.316401 -205.569389)
			(xy 187.352379 -205.609543) (xy 187.382127 -205.654507) (xy 187.405012 -205.703324) (xy 187.420544 -205.754953)
			(xy 187.428394 -205.808293) (xy 187.428886 -205.83525) (xy 194.234831 -205.83525) (xy 194.238766 -205.781479)
			(xy 194.250489 -205.728855) (xy 194.269749 -205.678498) (xy 194.296135 -205.631481) (xy 194.329087 -205.588808)
			(xy 194.3679 -205.551387) (xy 194.411748 -205.520017) (xy 194.459696 -205.495365) (xy 194.510723 -205.477957)
			(xy 194.563741 -205.468164) (xy 194.61762 -205.466195) (xy 194.671211 -205.472092) (xy 194.723372 -205.485728)
			(xy 194.772992 -205.506815) (xy 194.819013 -205.534901) (xy 194.860455 -205.569389) (xy 194.896433 -205.609543)
			(xy 194.926181 -205.654507) (xy 194.949066 -205.703324) (xy 194.964598 -205.754953) (xy 194.972448 -205.808293)
			(xy 194.97294 -205.83525) (xy 201.778631 -205.83525) (xy 201.782566 -205.781479) (xy 201.794289 -205.728855)
			(xy 201.813549 -205.678498) (xy 201.839935 -205.631481) (xy 201.872887 -205.588808) (xy 201.9117 -205.551387)
			(xy 201.955548 -205.520017) (xy 202.003496 -205.495365) (xy 202.054523 -205.477957) (xy 202.107541 -205.468164)
			(xy 202.16142 -205.466195) (xy 202.215011 -205.472092) (xy 202.267172 -205.485728) (xy 202.316792 -205.506815)
			(xy 202.362813 -205.534901) (xy 202.404255 -205.569389) (xy 202.440233 -205.609543) (xy 202.469981 -205.654507)
			(xy 202.492866 -205.703324) (xy 202.508398 -205.754953) (xy 202.516248 -205.808293) (xy 202.51674 -205.83525)
			(xy 202.516248 -205.862207) (xy 202.508398 -205.915547) (xy 202.492866 -205.967176) (xy 202.469981 -206.015993)
			(xy 202.440233 -206.060957) (xy 202.404255 -206.101111) (xy 202.362813 -206.135599) (xy 202.316792 -206.163685)
			(xy 202.267172 -206.184772) (xy 202.215011 -206.198408) (xy 202.16142 -206.204305) (xy 202.107541 -206.202336)
			(xy 202.054523 -206.192543) (xy 202.003496 -206.175135) (xy 201.955548 -206.150483) (xy 201.9117 -206.119113)
			(xy 201.872887 -206.081692) (xy 201.839935 -206.039019) (xy 201.813549 -205.992002) (xy 201.794289 -205.941645)
			(xy 201.782566 -205.889021) (xy 201.778631 -205.83525) (xy 194.97294 -205.83525) (xy 194.972448 -205.862207)
			(xy 194.964598 -205.915547) (xy 194.949066 -205.967176) (xy 194.926181 -206.015993) (xy 194.896433 -206.060957)
			(xy 194.860455 -206.101111) (xy 194.819013 -206.135599) (xy 194.772992 -206.163685) (xy 194.723372 -206.184772)
			(xy 194.671211 -206.198408) (xy 194.61762 -206.204305) (xy 194.563741 -206.202336) (xy 194.510723 -206.192543)
			(xy 194.459696 -206.175135) (xy 194.411748 -206.150483) (xy 194.3679 -206.119113) (xy 194.329087 -206.081692)
			(xy 194.296135 -206.039019) (xy 194.269749 -205.992002) (xy 194.250489 -205.941645) (xy 194.238766 -205.889021)
			(xy 194.234831 -205.83525) (xy 187.428886 -205.83525) (xy 187.428394 -205.862207) (xy 187.420544 -205.915547)
			(xy 187.405012 -205.967176) (xy 187.382127 -206.015993) (xy 187.352379 -206.060957) (xy 187.316401 -206.101111)
			(xy 187.274959 -206.135599) (xy 187.228938 -206.163685) (xy 187.179318 -206.184772) (xy 187.127157 -206.198408)
			(xy 187.073566 -206.204305) (xy 187.019687 -206.202336) (xy 186.966669 -206.192543) (xy 186.915642 -206.175135)
			(xy 186.867694 -206.150483) (xy 186.823846 -206.119113) (xy 186.785033 -206.081692) (xy 186.752081 -206.039019)
			(xy 186.725695 -205.992002) (xy 186.706435 -205.941645) (xy 186.694712 -205.889021) (xy 186.690777 -205.83525)
			(xy 179.884832 -205.83525) (xy 179.88434 -205.862207) (xy 179.87649 -205.915547) (xy 179.860958 -205.967176)
			(xy 179.838073 -206.015993) (xy 179.808325 -206.060957) (xy 179.772347 -206.101111) (xy 179.730905 -206.135599)
			(xy 179.684884 -206.163685) (xy 179.635264 -206.184772) (xy 179.583103 -206.198408) (xy 179.529512 -206.204305)
			(xy 179.475633 -206.202336) (xy 179.422615 -206.192543) (xy 179.371588 -206.175135) (xy 179.32364 -206.150483)
			(xy 179.279792 -206.119113) (xy 179.240979 -206.081692) (xy 179.208027 -206.039019) (xy 179.181641 -205.992002)
			(xy 179.162381 -205.941645) (xy 179.150658 -205.889021) (xy 179.146723 -205.83525) (xy 177.881534 -205.83525)
			(xy 177.881534 -206.685388) (xy 183.246791 -206.685388) (xy 183.250726 -206.631617) (xy 183.262449 -206.578993)
			(xy 183.281709 -206.528636) (xy 183.308095 -206.481619) (xy 183.341047 -206.438946) (xy 183.37986 -206.401525)
			(xy 183.423708 -206.370155) (xy 183.471656 -206.345503) (xy 183.522683 -206.328095) (xy 183.575701 -206.318302)
			(xy 183.62958 -206.316333) (xy 183.683171 -206.32223) (xy 183.735332 -206.335866) (xy 183.784952 -206.356953)
			(xy 183.830973 -206.385039) (xy 183.872415 -206.419527) (xy 183.908393 -206.459681) (xy 183.938141 -206.504645)
			(xy 183.961026 -206.553462) (xy 183.976558 -206.605091) (xy 183.984408 -206.658431) (xy 183.9849 -206.685388)
			(xy 190.790845 -206.685388) (xy 190.79478 -206.631617) (xy 190.806503 -206.578993) (xy 190.825763 -206.528636)
			(xy 190.852149 -206.481619) (xy 190.885101 -206.438946) (xy 190.923914 -206.401525) (xy 190.967762 -206.370155)
			(xy 191.01571 -206.345503) (xy 191.066737 -206.328095) (xy 191.119755 -206.318302) (xy 191.173634 -206.316333)
			(xy 191.227225 -206.32223) (xy 191.279386 -206.335866) (xy 191.329006 -206.356953) (xy 191.375027 -206.385039)
			(xy 191.416469 -206.419527) (xy 191.452447 -206.459681) (xy 191.482195 -206.504645) (xy 191.50508 -206.553462)
			(xy 191.520612 -206.605091) (xy 191.528462 -206.658431) (xy 191.528954 -206.685388) (xy 198.334899 -206.685388)
			(xy 198.338834 -206.631617) (xy 198.350557 -206.578993) (xy 198.369817 -206.528636) (xy 198.396203 -206.481619)
			(xy 198.429155 -206.438946) (xy 198.467968 -206.401525) (xy 198.511816 -206.370155) (xy 198.559764 -206.345503)
			(xy 198.610791 -206.328095) (xy 198.663809 -206.318302) (xy 198.717688 -206.316333) (xy 198.771279 -206.32223)
			(xy 198.82344 -206.335866) (xy 198.87306 -206.356953) (xy 198.919081 -206.385039) (xy 198.960523 -206.419527)
			(xy 198.996501 -206.459681) (xy 199.026249 -206.504645) (xy 199.049134 -206.553462) (xy 199.064666 -206.605091)
			(xy 199.072516 -206.658431) (xy 199.073008 -206.685388) (xy 205.878699 -206.685388) (xy 205.882634 -206.631617)
			(xy 205.894357 -206.578993) (xy 205.913617 -206.528636) (xy 205.940003 -206.481619) (xy 205.972955 -206.438946)
			(xy 206.011768 -206.401525) (xy 206.055616 -206.370155) (xy 206.103564 -206.345503) (xy 206.154591 -206.328095)
			(xy 206.207609 -206.318302) (xy 206.261488 -206.316333) (xy 206.315079 -206.32223) (xy 206.36724 -206.335866)
			(xy 206.41686 -206.356953) (xy 206.462881 -206.385039) (xy 206.504323 -206.419527) (xy 206.540301 -206.459681)
			(xy 206.570049 -206.504645) (xy 206.592934 -206.553462) (xy 206.608466 -206.605091) (xy 206.616316 -206.658431)
			(xy 206.616808 -206.685388) (xy 206.616316 -206.712345) (xy 206.608466 -206.765685) (xy 206.592934 -206.817314)
			(xy 206.570049 -206.866131) (xy 206.540301 -206.911095) (xy 206.504323 -206.951249) (xy 206.462881 -206.985737)
			(xy 206.41686 -207.013823) (xy 206.36724 -207.03491) (xy 206.315079 -207.048546) (xy 206.261488 -207.054443)
			(xy 206.207609 -207.052474) (xy 206.154591 -207.042681) (xy 206.103564 -207.025273) (xy 206.055616 -207.000621)
			(xy 206.011768 -206.969251) (xy 205.972955 -206.93183) (xy 205.940003 -206.889157) (xy 205.913617 -206.84214)
			(xy 205.894357 -206.791783) (xy 205.882634 -206.739159) (xy 205.878699 -206.685388) (xy 199.073008 -206.685388)
			(xy 199.072516 -206.712345) (xy 199.064666 -206.765685) (xy 199.049134 -206.817314) (xy 199.026249 -206.866131)
			(xy 198.996501 -206.911095) (xy 198.960523 -206.951249) (xy 198.919081 -206.985737) (xy 198.87306 -207.013823)
			(xy 198.82344 -207.03491) (xy 198.771279 -207.048546) (xy 198.717688 -207.054443) (xy 198.663809 -207.052474)
			(xy 198.610791 -207.042681) (xy 198.559764 -207.025273) (xy 198.511816 -207.000621) (xy 198.467968 -206.969251)
			(xy 198.429155 -206.93183) (xy 198.396203 -206.889157) (xy 198.369817 -206.84214) (xy 198.350557 -206.791783)
			(xy 198.338834 -206.739159) (xy 198.334899 -206.685388) (xy 191.528954 -206.685388) (xy 191.528462 -206.712345)
			(xy 191.520612 -206.765685) (xy 191.50508 -206.817314) (xy 191.482195 -206.866131) (xy 191.452447 -206.911095)
			(xy 191.416469 -206.951249) (xy 191.375027 -206.985737) (xy 191.329006 -207.013823) (xy 191.279386 -207.03491)
			(xy 191.227225 -207.048546) (xy 191.173634 -207.054443) (xy 191.119755 -207.052474) (xy 191.066737 -207.042681)
			(xy 191.01571 -207.025273) (xy 190.967762 -207.000621) (xy 190.923914 -206.969251) (xy 190.885101 -206.93183)
			(xy 190.852149 -206.889157) (xy 190.825763 -206.84214) (xy 190.806503 -206.791783) (xy 190.79478 -206.739159)
			(xy 190.790845 -206.685388) (xy 183.9849 -206.685388) (xy 183.984408 -206.712345) (xy 183.976558 -206.765685)
			(xy 183.961026 -206.817314) (xy 183.938141 -206.866131) (xy 183.908393 -206.911095) (xy 183.872415 -206.951249)
			(xy 183.830973 -206.985737) (xy 183.784952 -207.013823) (xy 183.735332 -207.03491) (xy 183.683171 -207.048546)
			(xy 183.62958 -207.054443) (xy 183.575701 -207.052474) (xy 183.522683 -207.042681) (xy 183.471656 -207.025273)
			(xy 183.423708 -207.000621) (xy 183.37986 -206.969251) (xy 183.341047 -206.93183) (xy 183.308095 -206.889157)
			(xy 183.281709 -206.84214) (xy 183.262449 -206.791783) (xy 183.250726 -206.739159) (xy 183.246791 -206.685388)
			(xy 177.881534 -206.685388) (xy 177.881534 -207.535272) (xy 179.146723 -207.535272) (xy 179.150658 -207.481501)
			(xy 179.162381 -207.428877) (xy 179.181641 -207.37852) (xy 179.208027 -207.331503) (xy 179.240979 -207.28883)
			(xy 179.279792 -207.251409) (xy 179.32364 -207.220039) (xy 179.371588 -207.195387) (xy 179.422615 -207.177979)
			(xy 179.475633 -207.168186) (xy 179.529512 -207.166217) (xy 179.583103 -207.172114) (xy 179.635264 -207.18575)
			(xy 179.684884 -207.206837) (xy 179.730905 -207.234923) (xy 179.772347 -207.269411) (xy 179.808325 -207.309565)
			(xy 179.838073 -207.354529) (xy 179.860958 -207.403346) (xy 179.87649 -207.454975) (xy 179.88434 -207.508315)
			(xy 179.884832 -207.535272) (xy 186.690777 -207.535272) (xy 186.694712 -207.481501) (xy 186.706435 -207.428877)
			(xy 186.725695 -207.37852) (xy 186.752081 -207.331503) (xy 186.785033 -207.28883) (xy 186.823846 -207.251409)
			(xy 186.867694 -207.220039) (xy 186.915642 -207.195387) (xy 186.966669 -207.177979) (xy 187.019687 -207.168186)
			(xy 187.073566 -207.166217) (xy 187.127157 -207.172114) (xy 187.179318 -207.18575) (xy 187.228938 -207.206837)
			(xy 187.274959 -207.234923) (xy 187.316401 -207.269411) (xy 187.352379 -207.309565) (xy 187.382127 -207.354529)
			(xy 187.405012 -207.403346) (xy 187.420544 -207.454975) (xy 187.428394 -207.508315) (xy 187.428886 -207.535272)
			(xy 194.234831 -207.535272) (xy 194.238766 -207.481501) (xy 194.250489 -207.428877) (xy 194.269749 -207.37852)
			(xy 194.296135 -207.331503) (xy 194.329087 -207.28883) (xy 194.3679 -207.251409) (xy 194.411748 -207.220039)
			(xy 194.459696 -207.195387) (xy 194.510723 -207.177979) (xy 194.563741 -207.168186) (xy 194.61762 -207.166217)
			(xy 194.671211 -207.172114) (xy 194.723372 -207.18575) (xy 194.772992 -207.206837) (xy 194.819013 -207.234923)
			(xy 194.860455 -207.269411) (xy 194.896433 -207.309565) (xy 194.926181 -207.354529) (xy 194.949066 -207.403346)
			(xy 194.964598 -207.454975) (xy 194.972448 -207.508315) (xy 194.97294 -207.535272) (xy 201.778631 -207.535272)
			(xy 201.782566 -207.481501) (xy 201.794289 -207.428877) (xy 201.813549 -207.37852) (xy 201.839935 -207.331503)
			(xy 201.872887 -207.28883) (xy 201.9117 -207.251409) (xy 201.955548 -207.220039) (xy 202.003496 -207.195387)
			(xy 202.054523 -207.177979) (xy 202.107541 -207.168186) (xy 202.16142 -207.166217) (xy 202.215011 -207.172114)
			(xy 202.267172 -207.18575) (xy 202.316792 -207.206837) (xy 202.362813 -207.234923) (xy 202.404255 -207.269411)
			(xy 202.440233 -207.309565) (xy 202.469981 -207.354529) (xy 202.492866 -207.403346) (xy 202.508398 -207.454975)
			(xy 202.516248 -207.508315) (xy 202.51674 -207.535272) (xy 202.516248 -207.562229) (xy 202.508398 -207.615569)
			(xy 202.492866 -207.667198) (xy 202.469981 -207.716015) (xy 202.440233 -207.760979) (xy 202.404255 -207.801133)
			(xy 202.362813 -207.835621) (xy 202.316792 -207.863707) (xy 202.267172 -207.884794) (xy 202.215011 -207.89843)
			(xy 202.16142 -207.904327) (xy 202.107541 -207.902358) (xy 202.054523 -207.892565) (xy 202.003496 -207.875157)
			(xy 201.955548 -207.850505) (xy 201.9117 -207.819135) (xy 201.872887 -207.781714) (xy 201.839935 -207.739041)
			(xy 201.813549 -207.692024) (xy 201.794289 -207.641667) (xy 201.782566 -207.589043) (xy 201.778631 -207.535272)
			(xy 194.97294 -207.535272) (xy 194.972448 -207.562229) (xy 194.964598 -207.615569) (xy 194.949066 -207.667198)
			(xy 194.926181 -207.716015) (xy 194.896433 -207.760979) (xy 194.860455 -207.801133) (xy 194.819013 -207.835621)
			(xy 194.772992 -207.863707) (xy 194.723372 -207.884794) (xy 194.671211 -207.89843) (xy 194.61762 -207.904327)
			(xy 194.563741 -207.902358) (xy 194.510723 -207.892565) (xy 194.459696 -207.875157) (xy 194.411748 -207.850505)
			(xy 194.3679 -207.819135) (xy 194.329087 -207.781714) (xy 194.296135 -207.739041) (xy 194.269749 -207.692024)
			(xy 194.250489 -207.641667) (xy 194.238766 -207.589043) (xy 194.234831 -207.535272) (xy 187.428886 -207.535272)
			(xy 187.428394 -207.562229) (xy 187.420544 -207.615569) (xy 187.405012 -207.667198) (xy 187.382127 -207.716015)
			(xy 187.352379 -207.760979) (xy 187.316401 -207.801133) (xy 187.274959 -207.835621) (xy 187.228938 -207.863707)
			(xy 187.179318 -207.884794) (xy 187.127157 -207.89843) (xy 187.073566 -207.904327) (xy 187.019687 -207.902358)
			(xy 186.966669 -207.892565) (xy 186.915642 -207.875157) (xy 186.867694 -207.850505) (xy 186.823846 -207.819135)
			(xy 186.785033 -207.781714) (xy 186.752081 -207.739041) (xy 186.725695 -207.692024) (xy 186.706435 -207.641667)
			(xy 186.694712 -207.589043) (xy 186.690777 -207.535272) (xy 179.884832 -207.535272) (xy 179.88434 -207.562229)
			(xy 179.87649 -207.615569) (xy 179.860958 -207.667198) (xy 179.838073 -207.716015) (xy 179.808325 -207.760979)
			(xy 179.772347 -207.801133) (xy 179.730905 -207.835621) (xy 179.684884 -207.863707) (xy 179.635264 -207.884794)
			(xy 179.583103 -207.89843) (xy 179.529512 -207.904327) (xy 179.475633 -207.902358) (xy 179.422615 -207.892565)
			(xy 179.371588 -207.875157) (xy 179.32364 -207.850505) (xy 179.279792 -207.819135) (xy 179.240979 -207.781714)
			(xy 179.208027 -207.739041) (xy 179.181641 -207.692024) (xy 179.162381 -207.641667) (xy 179.150658 -207.589043)
			(xy 179.146723 -207.535272) (xy 177.881534 -207.535272) (xy 177.881534 -208.38541) (xy 183.246791 -208.38541)
			(xy 183.250726 -208.331639) (xy 183.262449 -208.279015) (xy 183.281709 -208.228658) (xy 183.308095 -208.181641)
			(xy 183.341047 -208.138968) (xy 183.37986 -208.101547) (xy 183.423708 -208.070177) (xy 183.471656 -208.045525)
			(xy 183.522683 -208.028117) (xy 183.575701 -208.018324) (xy 183.62958 -208.016355) (xy 183.683171 -208.022252)
			(xy 183.735332 -208.035888) (xy 183.784952 -208.056975) (xy 183.830973 -208.085061) (xy 183.872415 -208.119549)
			(xy 183.908393 -208.159703) (xy 183.938141 -208.204667) (xy 183.961026 -208.253484) (xy 183.976558 -208.305113)
			(xy 183.984408 -208.358453) (xy 183.9849 -208.38541) (xy 190.790845 -208.38541) (xy 190.79478 -208.331639)
			(xy 190.806503 -208.279015) (xy 190.825763 -208.228658) (xy 190.852149 -208.181641) (xy 190.885101 -208.138968)
			(xy 190.923914 -208.101547) (xy 190.967762 -208.070177) (xy 191.01571 -208.045525) (xy 191.066737 -208.028117)
			(xy 191.119755 -208.018324) (xy 191.173634 -208.016355) (xy 191.227225 -208.022252) (xy 191.279386 -208.035888)
			(xy 191.329006 -208.056975) (xy 191.375027 -208.085061) (xy 191.416469 -208.119549) (xy 191.452447 -208.159703)
			(xy 191.482195 -208.204667) (xy 191.50508 -208.253484) (xy 191.520612 -208.305113) (xy 191.528462 -208.358453)
			(xy 191.528954 -208.38541) (xy 198.334899 -208.38541) (xy 198.338834 -208.331639) (xy 198.350557 -208.279015)
			(xy 198.369817 -208.228658) (xy 198.396203 -208.181641) (xy 198.429155 -208.138968) (xy 198.467968 -208.101547)
			(xy 198.511816 -208.070177) (xy 198.559764 -208.045525) (xy 198.610791 -208.028117) (xy 198.663809 -208.018324)
			(xy 198.717688 -208.016355) (xy 198.771279 -208.022252) (xy 198.82344 -208.035888) (xy 198.87306 -208.056975)
			(xy 198.919081 -208.085061) (xy 198.960523 -208.119549) (xy 198.996501 -208.159703) (xy 199.026249 -208.204667)
			(xy 199.049134 -208.253484) (xy 199.064666 -208.305113) (xy 199.072516 -208.358453) (xy 199.073008 -208.38541)
			(xy 205.878699 -208.38541) (xy 205.882634 -208.331639) (xy 205.894357 -208.279015) (xy 205.913617 -208.228658)
			(xy 205.940003 -208.181641) (xy 205.972955 -208.138968) (xy 206.011768 -208.101547) (xy 206.055616 -208.070177)
			(xy 206.103564 -208.045525) (xy 206.154591 -208.028117) (xy 206.207609 -208.018324) (xy 206.261488 -208.016355)
			(xy 206.315079 -208.022252) (xy 206.36724 -208.035888) (xy 206.41686 -208.056975) (xy 206.462881 -208.085061)
			(xy 206.504323 -208.119549) (xy 206.540301 -208.159703) (xy 206.570049 -208.204667) (xy 206.592934 -208.253484)
			(xy 206.608466 -208.305113) (xy 206.616316 -208.358453) (xy 206.616808 -208.38541) (xy 206.616316 -208.412367)
			(xy 206.608466 -208.465707) (xy 206.592934 -208.517336) (xy 206.570049 -208.566153) (xy 206.540301 -208.611117)
			(xy 206.504323 -208.651271) (xy 206.462881 -208.685759) (xy 206.41686 -208.713845) (xy 206.36724 -208.734932)
			(xy 206.315079 -208.748568) (xy 206.261488 -208.754465) (xy 206.207609 -208.752496) (xy 206.154591 -208.742703)
			(xy 206.103564 -208.725295) (xy 206.055616 -208.700643) (xy 206.011768 -208.669273) (xy 205.972955 -208.631852)
			(xy 205.940003 -208.589179) (xy 205.913617 -208.542162) (xy 205.894357 -208.491805) (xy 205.882634 -208.439181)
			(xy 205.878699 -208.38541) (xy 199.073008 -208.38541) (xy 199.072516 -208.412367) (xy 199.064666 -208.465707)
			(xy 199.049134 -208.517336) (xy 199.026249 -208.566153) (xy 198.996501 -208.611117) (xy 198.960523 -208.651271)
			(xy 198.919081 -208.685759) (xy 198.87306 -208.713845) (xy 198.82344 -208.734932) (xy 198.771279 -208.748568)
			(xy 198.717688 -208.754465) (xy 198.663809 -208.752496) (xy 198.610791 -208.742703) (xy 198.559764 -208.725295)
			(xy 198.511816 -208.700643) (xy 198.467968 -208.669273) (xy 198.429155 -208.631852) (xy 198.396203 -208.589179)
			(xy 198.369817 -208.542162) (xy 198.350557 -208.491805) (xy 198.338834 -208.439181) (xy 198.334899 -208.38541)
			(xy 191.528954 -208.38541) (xy 191.528462 -208.412367) (xy 191.520612 -208.465707) (xy 191.50508 -208.517336)
			(xy 191.482195 -208.566153) (xy 191.452447 -208.611117) (xy 191.416469 -208.651271) (xy 191.375027 -208.685759)
			(xy 191.329006 -208.713845) (xy 191.279386 -208.734932) (xy 191.227225 -208.748568) (xy 191.173634 -208.754465)
			(xy 191.119755 -208.752496) (xy 191.066737 -208.742703) (xy 191.01571 -208.725295) (xy 190.967762 -208.700643)
			(xy 190.923914 -208.669273) (xy 190.885101 -208.631852) (xy 190.852149 -208.589179) (xy 190.825763 -208.542162)
			(xy 190.806503 -208.491805) (xy 190.79478 -208.439181) (xy 190.790845 -208.38541) (xy 183.9849 -208.38541)
			(xy 183.984408 -208.412367) (xy 183.976558 -208.465707) (xy 183.961026 -208.517336) (xy 183.938141 -208.566153)
			(xy 183.908393 -208.611117) (xy 183.872415 -208.651271) (xy 183.830973 -208.685759) (xy 183.784952 -208.713845)
			(xy 183.735332 -208.734932) (xy 183.683171 -208.748568) (xy 183.62958 -208.754465) (xy 183.575701 -208.752496)
			(xy 183.522683 -208.742703) (xy 183.471656 -208.725295) (xy 183.423708 -208.700643) (xy 183.37986 -208.669273)
			(xy 183.341047 -208.631852) (xy 183.308095 -208.589179) (xy 183.281709 -208.542162) (xy 183.262449 -208.491805)
			(xy 183.250726 -208.439181) (xy 183.246791 -208.38541) (xy 177.881534 -208.38541) (xy 177.881534 -209.235294)
			(xy 179.146723 -209.235294) (xy 179.150658 -209.181523) (xy 179.162381 -209.128899) (xy 179.181641 -209.078542)
			(xy 179.208027 -209.031525) (xy 179.240979 -208.988852) (xy 179.279792 -208.951431) (xy 179.32364 -208.920061)
			(xy 179.371588 -208.895409) (xy 179.422615 -208.878001) (xy 179.475633 -208.868208) (xy 179.529512 -208.866239)
			(xy 179.583103 -208.872136) (xy 179.635264 -208.885772) (xy 179.684884 -208.906859) (xy 179.730905 -208.934945)
			(xy 179.772347 -208.969433) (xy 179.808325 -209.009587) (xy 179.838073 -209.054551) (xy 179.860958 -209.103368)
			(xy 179.87649 -209.154997) (xy 179.88434 -209.208337) (xy 179.884832 -209.235294) (xy 186.690777 -209.235294)
			(xy 186.694712 -209.181523) (xy 186.706435 -209.128899) (xy 186.725695 -209.078542) (xy 186.752081 -209.031525)
			(xy 186.785033 -208.988852) (xy 186.823846 -208.951431) (xy 186.867694 -208.920061) (xy 186.915642 -208.895409)
			(xy 186.966669 -208.878001) (xy 187.019687 -208.868208) (xy 187.073566 -208.866239) (xy 187.127157 -208.872136)
			(xy 187.179318 -208.885772) (xy 187.228938 -208.906859) (xy 187.274959 -208.934945) (xy 187.316401 -208.969433)
			(xy 187.352379 -209.009587) (xy 187.382127 -209.054551) (xy 187.405012 -209.103368) (xy 187.420544 -209.154997)
			(xy 187.428394 -209.208337) (xy 187.428886 -209.235294) (xy 194.234831 -209.235294) (xy 194.238766 -209.181523)
			(xy 194.250489 -209.128899) (xy 194.269749 -209.078542) (xy 194.296135 -209.031525) (xy 194.329087 -208.988852)
			(xy 194.3679 -208.951431) (xy 194.411748 -208.920061) (xy 194.459696 -208.895409) (xy 194.510723 -208.878001)
			(xy 194.563741 -208.868208) (xy 194.61762 -208.866239) (xy 194.671211 -208.872136) (xy 194.723372 -208.885772)
			(xy 194.772992 -208.906859) (xy 194.819013 -208.934945) (xy 194.860455 -208.969433) (xy 194.896433 -209.009587)
			(xy 194.926181 -209.054551) (xy 194.949066 -209.103368) (xy 194.964598 -209.154997) (xy 194.972448 -209.208337)
			(xy 194.97294 -209.235294) (xy 201.778631 -209.235294) (xy 201.782566 -209.181523) (xy 201.794289 -209.128899)
			(xy 201.813549 -209.078542) (xy 201.839935 -209.031525) (xy 201.872887 -208.988852) (xy 201.9117 -208.951431)
			(xy 201.955548 -208.920061) (xy 202.003496 -208.895409) (xy 202.054523 -208.878001) (xy 202.107541 -208.868208)
			(xy 202.16142 -208.866239) (xy 202.215011 -208.872136) (xy 202.267172 -208.885772) (xy 202.316792 -208.906859)
			(xy 202.362813 -208.934945) (xy 202.404255 -208.969433) (xy 202.440233 -209.009587) (xy 202.469981 -209.054551)
			(xy 202.492866 -209.103368) (xy 202.508398 -209.154997) (xy 202.516248 -209.208337) (xy 202.51674 -209.235294)
			(xy 202.516248 -209.262251) (xy 202.508398 -209.315591) (xy 202.492866 -209.36722) (xy 202.469981 -209.416037)
			(xy 202.440233 -209.461001) (xy 202.404255 -209.501155) (xy 202.362813 -209.535643) (xy 202.316792 -209.563729)
			(xy 202.267172 -209.584816) (xy 202.215011 -209.598452) (xy 202.16142 -209.604349) (xy 202.107541 -209.60238)
			(xy 202.054523 -209.592587) (xy 202.003496 -209.575179) (xy 201.955548 -209.550527) (xy 201.9117 -209.519157)
			(xy 201.872887 -209.481736) (xy 201.839935 -209.439063) (xy 201.813549 -209.392046) (xy 201.794289 -209.341689)
			(xy 201.782566 -209.289065) (xy 201.778631 -209.235294) (xy 194.97294 -209.235294) (xy 194.972448 -209.262251)
			(xy 194.964598 -209.315591) (xy 194.949066 -209.36722) (xy 194.926181 -209.416037) (xy 194.896433 -209.461001)
			(xy 194.860455 -209.501155) (xy 194.819013 -209.535643) (xy 194.772992 -209.563729) (xy 194.723372 -209.584816)
			(xy 194.671211 -209.598452) (xy 194.61762 -209.604349) (xy 194.563741 -209.60238) (xy 194.510723 -209.592587)
			(xy 194.459696 -209.575179) (xy 194.411748 -209.550527) (xy 194.3679 -209.519157) (xy 194.329087 -209.481736)
			(xy 194.296135 -209.439063) (xy 194.269749 -209.392046) (xy 194.250489 -209.341689) (xy 194.238766 -209.289065)
			(xy 194.234831 -209.235294) (xy 187.428886 -209.235294) (xy 187.428394 -209.262251) (xy 187.420544 -209.315591)
			(xy 187.405012 -209.36722) (xy 187.382127 -209.416037) (xy 187.352379 -209.461001) (xy 187.316401 -209.501155)
			(xy 187.274959 -209.535643) (xy 187.228938 -209.563729) (xy 187.179318 -209.584816) (xy 187.127157 -209.598452)
			(xy 187.073566 -209.604349) (xy 187.019687 -209.60238) (xy 186.966669 -209.592587) (xy 186.915642 -209.575179)
			(xy 186.867694 -209.550527) (xy 186.823846 -209.519157) (xy 186.785033 -209.481736) (xy 186.752081 -209.439063)
			(xy 186.725695 -209.392046) (xy 186.706435 -209.341689) (xy 186.694712 -209.289065) (xy 186.690777 -209.235294)
			(xy 179.884832 -209.235294) (xy 179.88434 -209.262251) (xy 179.87649 -209.315591) (xy 179.860958 -209.36722)
			(xy 179.838073 -209.416037) (xy 179.808325 -209.461001) (xy 179.772347 -209.501155) (xy 179.730905 -209.535643)
			(xy 179.684884 -209.563729) (xy 179.635264 -209.584816) (xy 179.583103 -209.598452) (xy 179.529512 -209.604349)
			(xy 179.475633 -209.60238) (xy 179.422615 -209.592587) (xy 179.371588 -209.575179) (xy 179.32364 -209.550527)
			(xy 179.279792 -209.519157) (xy 179.240979 -209.481736) (xy 179.208027 -209.439063) (xy 179.181641 -209.392046)
			(xy 179.162381 -209.341689) (xy 179.150658 -209.289065) (xy 179.146723 -209.235294) (xy 177.881534 -209.235294)
			(xy 177.881534 -210.085432) (xy 183.246791 -210.085432) (xy 183.250726 -210.031661) (xy 183.262449 -209.979037)
			(xy 183.281709 -209.92868) (xy 183.308095 -209.881663) (xy 183.341047 -209.83899) (xy 183.37986 -209.801569)
			(xy 183.423708 -209.770199) (xy 183.471656 -209.745547) (xy 183.522683 -209.728139) (xy 183.575701 -209.718346)
			(xy 183.62958 -209.716377) (xy 183.683171 -209.722274) (xy 183.735332 -209.73591) (xy 183.784952 -209.756997)
			(xy 183.830973 -209.785083) (xy 183.872415 -209.819571) (xy 183.908393 -209.859725) (xy 183.938141 -209.904689)
			(xy 183.961026 -209.953506) (xy 183.976558 -210.005135) (xy 183.984408 -210.058475) (xy 183.9849 -210.085432)
			(xy 190.790845 -210.085432) (xy 190.79478 -210.031661) (xy 190.806503 -209.979037) (xy 190.825763 -209.92868)
			(xy 190.852149 -209.881663) (xy 190.885101 -209.83899) (xy 190.923914 -209.801569) (xy 190.967762 -209.770199)
			(xy 191.01571 -209.745547) (xy 191.066737 -209.728139) (xy 191.119755 -209.718346) (xy 191.173634 -209.716377)
			(xy 191.227225 -209.722274) (xy 191.279386 -209.73591) (xy 191.329006 -209.756997) (xy 191.375027 -209.785083)
			(xy 191.416469 -209.819571) (xy 191.452447 -209.859725) (xy 191.482195 -209.904689) (xy 191.50508 -209.953506)
			(xy 191.520612 -210.005135) (xy 191.528462 -210.058475) (xy 191.528954 -210.085432) (xy 198.334899 -210.085432)
			(xy 198.338834 -210.031661) (xy 198.350557 -209.979037) (xy 198.369817 -209.92868) (xy 198.396203 -209.881663)
			(xy 198.429155 -209.83899) (xy 198.467968 -209.801569) (xy 198.511816 -209.770199) (xy 198.559764 -209.745547)
			(xy 198.610791 -209.728139) (xy 198.663809 -209.718346) (xy 198.717688 -209.716377) (xy 198.771279 -209.722274)
			(xy 198.82344 -209.73591) (xy 198.87306 -209.756997) (xy 198.919081 -209.785083) (xy 198.960523 -209.819571)
			(xy 198.996501 -209.859725) (xy 199.026249 -209.904689) (xy 199.049134 -209.953506) (xy 199.064666 -210.005135)
			(xy 199.072516 -210.058475) (xy 199.073008 -210.085432) (xy 205.878699 -210.085432) (xy 205.882634 -210.031661)
			(xy 205.894357 -209.979037) (xy 205.913617 -209.92868) (xy 205.940003 -209.881663) (xy 205.972955 -209.83899)
			(xy 206.011768 -209.801569) (xy 206.055616 -209.770199) (xy 206.103564 -209.745547) (xy 206.154591 -209.728139)
			(xy 206.207609 -209.718346) (xy 206.261488 -209.716377) (xy 206.315079 -209.722274) (xy 206.36724 -209.73591)
			(xy 206.41686 -209.756997) (xy 206.462881 -209.785083) (xy 206.504323 -209.819571) (xy 206.540301 -209.859725)
			(xy 206.570049 -209.904689) (xy 206.592934 -209.953506) (xy 206.608466 -210.005135) (xy 206.616316 -210.058475)
			(xy 206.616808 -210.085432) (xy 206.616316 -210.112389) (xy 206.608466 -210.165729) (xy 206.592934 -210.217358)
			(xy 206.570049 -210.266175) (xy 206.540301 -210.311139) (xy 206.504323 -210.351293) (xy 206.462881 -210.385781)
			(xy 206.41686 -210.413867) (xy 206.36724 -210.434954) (xy 206.315079 -210.44859) (xy 206.261488 -210.454487)
			(xy 206.207609 -210.452518) (xy 206.154591 -210.442725) (xy 206.103564 -210.425317) (xy 206.055616 -210.400665)
			(xy 206.011768 -210.369295) (xy 205.972955 -210.331874) (xy 205.940003 -210.289201) (xy 205.913617 -210.242184)
			(xy 205.894357 -210.191827) (xy 205.882634 -210.139203) (xy 205.878699 -210.085432) (xy 199.073008 -210.085432)
			(xy 199.072516 -210.112389) (xy 199.064666 -210.165729) (xy 199.049134 -210.217358) (xy 199.026249 -210.266175)
			(xy 198.996501 -210.311139) (xy 198.960523 -210.351293) (xy 198.919081 -210.385781) (xy 198.87306 -210.413867)
			(xy 198.82344 -210.434954) (xy 198.771279 -210.44859) (xy 198.717688 -210.454487) (xy 198.663809 -210.452518)
			(xy 198.610791 -210.442725) (xy 198.559764 -210.425317) (xy 198.511816 -210.400665) (xy 198.467968 -210.369295)
			(xy 198.429155 -210.331874) (xy 198.396203 -210.289201) (xy 198.369817 -210.242184) (xy 198.350557 -210.191827)
			(xy 198.338834 -210.139203) (xy 198.334899 -210.085432) (xy 191.528954 -210.085432) (xy 191.528462 -210.112389)
			(xy 191.520612 -210.165729) (xy 191.50508 -210.217358) (xy 191.482195 -210.266175) (xy 191.452447 -210.311139)
			(xy 191.416469 -210.351293) (xy 191.375027 -210.385781) (xy 191.329006 -210.413867) (xy 191.279386 -210.434954)
			(xy 191.227225 -210.44859) (xy 191.173634 -210.454487) (xy 191.119755 -210.452518) (xy 191.066737 -210.442725)
			(xy 191.01571 -210.425317) (xy 190.967762 -210.400665) (xy 190.923914 -210.369295) (xy 190.885101 -210.331874)
			(xy 190.852149 -210.289201) (xy 190.825763 -210.242184) (xy 190.806503 -210.191827) (xy 190.79478 -210.139203)
			(xy 190.790845 -210.085432) (xy 183.9849 -210.085432) (xy 183.984408 -210.112389) (xy 183.976558 -210.165729)
			(xy 183.961026 -210.217358) (xy 183.938141 -210.266175) (xy 183.908393 -210.311139) (xy 183.872415 -210.351293)
			(xy 183.830973 -210.385781) (xy 183.784952 -210.413867) (xy 183.735332 -210.434954) (xy 183.683171 -210.44859)
			(xy 183.62958 -210.454487) (xy 183.575701 -210.452518) (xy 183.522683 -210.442725) (xy 183.471656 -210.425317)
			(xy 183.423708 -210.400665) (xy 183.37986 -210.369295) (xy 183.341047 -210.331874) (xy 183.308095 -210.289201)
			(xy 183.281709 -210.242184) (xy 183.262449 -210.191827) (xy 183.250726 -210.139203) (xy 183.246791 -210.085432)
			(xy 177.881534 -210.085432) (xy 177.881534 -210.935316) (xy 179.146723 -210.935316) (xy 179.150658 -210.881545)
			(xy 179.162381 -210.828921) (xy 179.181641 -210.778564) (xy 179.208027 -210.731547) (xy 179.240979 -210.688874)
			(xy 179.279792 -210.651453) (xy 179.32364 -210.620083) (xy 179.371588 -210.595431) (xy 179.422615 -210.578023)
			(xy 179.475633 -210.56823) (xy 179.529512 -210.566261) (xy 179.583103 -210.572158) (xy 179.635264 -210.585794)
			(xy 179.684884 -210.606881) (xy 179.730905 -210.634967) (xy 179.772347 -210.669455) (xy 179.808325 -210.709609)
			(xy 179.838073 -210.754573) (xy 179.860958 -210.80339) (xy 179.87649 -210.855019) (xy 179.88434 -210.908359)
			(xy 179.884832 -210.935316) (xy 183.246791 -210.935316) (xy 183.250726 -210.881545) (xy 183.262449 -210.828921)
			(xy 183.281709 -210.778564) (xy 183.308095 -210.731547) (xy 183.341047 -210.688874) (xy 183.37986 -210.651453)
			(xy 183.423708 -210.620083) (xy 183.471656 -210.595431) (xy 183.522683 -210.578023) (xy 183.575701 -210.56823)
			(xy 183.62958 -210.566261) (xy 183.683171 -210.572158) (xy 183.735332 -210.585794) (xy 183.784952 -210.606881)
			(xy 183.830973 -210.634967) (xy 183.872415 -210.669455) (xy 183.908393 -210.709609) (xy 183.938141 -210.754573)
			(xy 183.961026 -210.80339) (xy 183.976558 -210.855019) (xy 183.984408 -210.908359) (xy 183.9849 -210.935316)
			(xy 186.690777 -210.935316) (xy 186.694712 -210.881545) (xy 186.706435 -210.828921) (xy 186.725695 -210.778564)
			(xy 186.752081 -210.731547) (xy 186.785033 -210.688874) (xy 186.823846 -210.651453) (xy 186.867694 -210.620083)
			(xy 186.915642 -210.595431) (xy 186.966669 -210.578023) (xy 187.019687 -210.56823) (xy 187.073566 -210.566261)
			(xy 187.127157 -210.572158) (xy 187.179318 -210.585794) (xy 187.228938 -210.606881) (xy 187.274959 -210.634967)
			(xy 187.316401 -210.669455) (xy 187.352379 -210.709609) (xy 187.382127 -210.754573) (xy 187.405012 -210.80339)
			(xy 187.420544 -210.855019) (xy 187.428394 -210.908359) (xy 187.428886 -210.935316) (xy 190.790845 -210.935316)
			(xy 190.79478 -210.881545) (xy 190.806503 -210.828921) (xy 190.825763 -210.778564) (xy 190.852149 -210.731547)
			(xy 190.885101 -210.688874) (xy 190.923914 -210.651453) (xy 190.967762 -210.620083) (xy 191.01571 -210.595431)
			(xy 191.066737 -210.578023) (xy 191.119755 -210.56823) (xy 191.173634 -210.566261) (xy 191.227225 -210.572158)
			(xy 191.279386 -210.585794) (xy 191.329006 -210.606881) (xy 191.375027 -210.634967) (xy 191.416469 -210.669455)
			(xy 191.452447 -210.709609) (xy 191.482195 -210.754573) (xy 191.50508 -210.80339) (xy 191.520612 -210.855019)
			(xy 191.528462 -210.908359) (xy 191.528954 -210.935316) (xy 194.234831 -210.935316) (xy 194.238766 -210.881545)
			(xy 194.250489 -210.828921) (xy 194.269749 -210.778564) (xy 194.296135 -210.731547) (xy 194.329087 -210.688874)
			(xy 194.3679 -210.651453) (xy 194.411748 -210.620083) (xy 194.459696 -210.595431) (xy 194.510723 -210.578023)
			(xy 194.563741 -210.56823) (xy 194.61762 -210.566261) (xy 194.671211 -210.572158) (xy 194.723372 -210.585794)
			(xy 194.772992 -210.606881) (xy 194.819013 -210.634967) (xy 194.860455 -210.669455) (xy 194.896433 -210.709609)
			(xy 194.926181 -210.754573) (xy 194.949066 -210.80339) (xy 194.964598 -210.855019) (xy 194.972448 -210.908359)
			(xy 194.97294 -210.935316) (xy 198.334899 -210.935316) (xy 198.338834 -210.881545) (xy 198.350557 -210.828921)
			(xy 198.369817 -210.778564) (xy 198.396203 -210.731547) (xy 198.429155 -210.688874) (xy 198.467968 -210.651453)
			(xy 198.511816 -210.620083) (xy 198.559764 -210.595431) (xy 198.610791 -210.578023) (xy 198.663809 -210.56823)
			(xy 198.717688 -210.566261) (xy 198.771279 -210.572158) (xy 198.82344 -210.585794) (xy 198.87306 -210.606881)
			(xy 198.919081 -210.634967) (xy 198.960523 -210.669455) (xy 198.996501 -210.709609) (xy 199.026249 -210.754573)
			(xy 199.049134 -210.80339) (xy 199.064666 -210.855019) (xy 199.072516 -210.908359) (xy 199.073008 -210.935316)
			(xy 201.778631 -210.935316) (xy 201.782566 -210.881545) (xy 201.794289 -210.828921) (xy 201.813549 -210.778564)
			(xy 201.839935 -210.731547) (xy 201.872887 -210.688874) (xy 201.9117 -210.651453) (xy 201.955548 -210.620083)
			(xy 202.003496 -210.595431) (xy 202.054523 -210.578023) (xy 202.107541 -210.56823) (xy 202.16142 -210.566261)
			(xy 202.215011 -210.572158) (xy 202.267172 -210.585794) (xy 202.316792 -210.606881) (xy 202.362813 -210.634967)
			(xy 202.404255 -210.669455) (xy 202.440233 -210.709609) (xy 202.469981 -210.754573) (xy 202.492866 -210.80339)
			(xy 202.508398 -210.855019) (xy 202.516248 -210.908359) (xy 202.51674 -210.935316) (xy 205.878699 -210.935316)
			(xy 205.882634 -210.881545) (xy 205.894357 -210.828921) (xy 205.913617 -210.778564) (xy 205.940003 -210.731547)
			(xy 205.972955 -210.688874) (xy 206.011768 -210.651453) (xy 206.055616 -210.620083) (xy 206.103564 -210.595431)
			(xy 206.154591 -210.578023) (xy 206.207609 -210.56823) (xy 206.261488 -210.566261) (xy 206.315079 -210.572158)
			(xy 206.36724 -210.585794) (xy 206.41686 -210.606881) (xy 206.462881 -210.634967) (xy 206.504323 -210.669455)
			(xy 206.540301 -210.709609) (xy 206.570049 -210.754573) (xy 206.592934 -210.80339) (xy 206.608466 -210.855019)
			(xy 206.616316 -210.908359) (xy 206.616808 -210.935316) (xy 206.616316 -210.962273) (xy 206.608466 -211.015613)
			(xy 206.592934 -211.067242) (xy 206.570049 -211.116059) (xy 206.540301 -211.161023) (xy 206.504323 -211.201177)
			(xy 206.462881 -211.235665) (xy 206.41686 -211.263751) (xy 206.36724 -211.284838) (xy 206.315079 -211.298474)
			(xy 206.261488 -211.304371) (xy 206.207609 -211.302402) (xy 206.154591 -211.292609) (xy 206.103564 -211.275201)
			(xy 206.055616 -211.250549) (xy 206.011768 -211.219179) (xy 205.972955 -211.181758) (xy 205.940003 -211.139085)
			(xy 205.913617 -211.092068) (xy 205.894357 -211.041711) (xy 205.882634 -210.989087) (xy 205.878699 -210.935316)
			(xy 202.51674 -210.935316) (xy 202.516248 -210.962273) (xy 202.508398 -211.015613) (xy 202.492866 -211.067242)
			(xy 202.469981 -211.116059) (xy 202.440233 -211.161023) (xy 202.404255 -211.201177) (xy 202.362813 -211.235665)
			(xy 202.316792 -211.263751) (xy 202.267172 -211.284838) (xy 202.215011 -211.298474) (xy 202.16142 -211.304371)
			(xy 202.107541 -211.302402) (xy 202.054523 -211.292609) (xy 202.003496 -211.275201) (xy 201.955548 -211.250549)
			(xy 201.9117 -211.219179) (xy 201.872887 -211.181758) (xy 201.839935 -211.139085) (xy 201.813549 -211.092068)
			(xy 201.794289 -211.041711) (xy 201.782566 -210.989087) (xy 201.778631 -210.935316) (xy 199.073008 -210.935316)
			(xy 199.072516 -210.962273) (xy 199.064666 -211.015613) (xy 199.049134 -211.067242) (xy 199.026249 -211.116059)
			(xy 198.996501 -211.161023) (xy 198.960523 -211.201177) (xy 198.919081 -211.235665) (xy 198.87306 -211.263751)
			(xy 198.82344 -211.284838) (xy 198.771279 -211.298474) (xy 198.717688 -211.304371) (xy 198.663809 -211.302402)
			(xy 198.610791 -211.292609) (xy 198.559764 -211.275201) (xy 198.511816 -211.250549) (xy 198.467968 -211.219179)
			(xy 198.429155 -211.181758) (xy 198.396203 -211.139085) (xy 198.369817 -211.092068) (xy 198.350557 -211.041711)
			(xy 198.338834 -210.989087) (xy 198.334899 -210.935316) (xy 194.97294 -210.935316) (xy 194.972448 -210.962273)
			(xy 194.964598 -211.015613) (xy 194.949066 -211.067242) (xy 194.926181 -211.116059) (xy 194.896433 -211.161023)
			(xy 194.860455 -211.201177) (xy 194.819013 -211.235665) (xy 194.772992 -211.263751) (xy 194.723372 -211.284838)
			(xy 194.671211 -211.298474) (xy 194.61762 -211.304371) (xy 194.563741 -211.302402) (xy 194.510723 -211.292609)
			(xy 194.459696 -211.275201) (xy 194.411748 -211.250549) (xy 194.3679 -211.219179) (xy 194.329087 -211.181758)
			(xy 194.296135 -211.139085) (xy 194.269749 -211.092068) (xy 194.250489 -211.041711) (xy 194.238766 -210.989087)
			(xy 194.234831 -210.935316) (xy 191.528954 -210.935316) (xy 191.528462 -210.962273) (xy 191.520612 -211.015613)
			(xy 191.50508 -211.067242) (xy 191.482195 -211.116059) (xy 191.452447 -211.161023) (xy 191.416469 -211.201177)
			(xy 191.375027 -211.235665) (xy 191.329006 -211.263751) (xy 191.279386 -211.284838) (xy 191.227225 -211.298474)
			(xy 191.173634 -211.304371) (xy 191.119755 -211.302402) (xy 191.066737 -211.292609) (xy 191.01571 -211.275201)
			(xy 190.967762 -211.250549) (xy 190.923914 -211.219179) (xy 190.885101 -211.181758) (xy 190.852149 -211.139085)
			(xy 190.825763 -211.092068) (xy 190.806503 -211.041711) (xy 190.79478 -210.989087) (xy 190.790845 -210.935316)
			(xy 187.428886 -210.935316) (xy 187.428394 -210.962273) (xy 187.420544 -211.015613) (xy 187.405012 -211.067242)
			(xy 187.382127 -211.116059) (xy 187.352379 -211.161023) (xy 187.316401 -211.201177) (xy 187.274959 -211.235665)
			(xy 187.228938 -211.263751) (xy 187.179318 -211.284838) (xy 187.127157 -211.298474) (xy 187.073566 -211.304371)
			(xy 187.019687 -211.302402) (xy 186.966669 -211.292609) (xy 186.915642 -211.275201) (xy 186.867694 -211.250549)
			(xy 186.823846 -211.219179) (xy 186.785033 -211.181758) (xy 186.752081 -211.139085) (xy 186.725695 -211.092068)
			(xy 186.706435 -211.041711) (xy 186.694712 -210.989087) (xy 186.690777 -210.935316) (xy 183.9849 -210.935316)
			(xy 183.984408 -210.962273) (xy 183.976558 -211.015613) (xy 183.961026 -211.067242) (xy 183.938141 -211.116059)
			(xy 183.908393 -211.161023) (xy 183.872415 -211.201177) (xy 183.830973 -211.235665) (xy 183.784952 -211.263751)
			(xy 183.735332 -211.284838) (xy 183.683171 -211.298474) (xy 183.62958 -211.304371) (xy 183.575701 -211.302402)
			(xy 183.522683 -211.292609) (xy 183.471656 -211.275201) (xy 183.423708 -211.250549) (xy 183.37986 -211.219179)
			(xy 183.341047 -211.181758) (xy 183.308095 -211.139085) (xy 183.281709 -211.092068) (xy 183.262449 -211.041711)
			(xy 183.250726 -210.989087) (xy 183.246791 -210.935316) (xy 179.884832 -210.935316) (xy 179.88434 -210.962273)
			(xy 179.87649 -211.015613) (xy 179.860958 -211.067242) (xy 179.838073 -211.116059) (xy 179.808325 -211.161023)
			(xy 179.772347 -211.201177) (xy 179.730905 -211.235665) (xy 179.684884 -211.263751) (xy 179.635264 -211.284838)
			(xy 179.583103 -211.298474) (xy 179.529512 -211.304371) (xy 179.475633 -211.302402) (xy 179.422615 -211.292609)
			(xy 179.371588 -211.275201) (xy 179.32364 -211.250549) (xy 179.279792 -211.219179) (xy 179.240979 -211.181758)
			(xy 179.208027 -211.139085) (xy 179.181641 -211.092068) (xy 179.162381 -211.041711) (xy 179.150658 -210.989087)
			(xy 179.146723 -210.935316) (xy 177.881534 -210.935316) (xy 177.881534 -211.7852) (xy 179.146723 -211.7852)
			(xy 179.150658 -211.731429) (xy 179.162381 -211.678805) (xy 179.181641 -211.628448) (xy 179.208027 -211.581431)
			(xy 179.240979 -211.538758) (xy 179.279792 -211.501337) (xy 179.32364 -211.469967) (xy 179.371588 -211.445315)
			(xy 179.422615 -211.427907) (xy 179.475633 -211.418114) (xy 179.529512 -211.416145) (xy 179.583103 -211.422042)
			(xy 179.635264 -211.435678) (xy 179.684884 -211.456765) (xy 179.730905 -211.484851) (xy 179.772347 -211.519339)
			(xy 179.808325 -211.559493) (xy 179.838073 -211.604457) (xy 179.860958 -211.653274) (xy 179.87649 -211.704903)
			(xy 179.88434 -211.758243) (xy 179.884832 -211.7852) (xy 186.690777 -211.7852) (xy 186.694712 -211.731429)
			(xy 186.706435 -211.678805) (xy 186.725695 -211.628448) (xy 186.752081 -211.581431) (xy 186.785033 -211.538758)
			(xy 186.823846 -211.501337) (xy 186.867694 -211.469967) (xy 186.915642 -211.445315) (xy 186.966669 -211.427907)
			(xy 187.019687 -211.418114) (xy 187.073566 -211.416145) (xy 187.127157 -211.422042) (xy 187.179318 -211.435678)
			(xy 187.228938 -211.456765) (xy 187.274959 -211.484851) (xy 187.316401 -211.519339) (xy 187.352379 -211.559493)
			(xy 187.382127 -211.604457) (xy 187.405012 -211.653274) (xy 187.420544 -211.704903) (xy 187.428394 -211.758243)
			(xy 187.428886 -211.7852) (xy 194.234831 -211.7852) (xy 194.238766 -211.731429) (xy 194.250489 -211.678805)
			(xy 194.269749 -211.628448) (xy 194.296135 -211.581431) (xy 194.329087 -211.538758) (xy 194.3679 -211.501337)
			(xy 194.411748 -211.469967) (xy 194.459696 -211.445315) (xy 194.510723 -211.427907) (xy 194.563741 -211.418114)
			(xy 194.61762 -211.416145) (xy 194.671211 -211.422042) (xy 194.723372 -211.435678) (xy 194.772992 -211.456765)
			(xy 194.819013 -211.484851) (xy 194.860455 -211.519339) (xy 194.896433 -211.559493) (xy 194.926181 -211.604457)
			(xy 194.949066 -211.653274) (xy 194.964598 -211.704903) (xy 194.972448 -211.758243) (xy 194.97294 -211.7852)
			(xy 201.778631 -211.7852) (xy 201.782566 -211.731429) (xy 201.794289 -211.678805) (xy 201.813549 -211.628448)
			(xy 201.839935 -211.581431) (xy 201.872887 -211.538758) (xy 201.9117 -211.501337) (xy 201.955548 -211.469967)
			(xy 202.003496 -211.445315) (xy 202.054523 -211.427907) (xy 202.107541 -211.418114) (xy 202.16142 -211.416145)
			(xy 202.215011 -211.422042) (xy 202.267172 -211.435678) (xy 202.316792 -211.456765) (xy 202.362813 -211.484851)
			(xy 202.404255 -211.519339) (xy 202.440233 -211.559493) (xy 202.469981 -211.604457) (xy 202.492866 -211.653274)
			(xy 202.508398 -211.704903) (xy 202.516248 -211.758243) (xy 202.51674 -211.7852) (xy 202.516248 -211.812157)
			(xy 202.508398 -211.865497) (xy 202.492866 -211.917126) (xy 202.469981 -211.965943) (xy 202.440233 -212.010907)
			(xy 202.404255 -212.051061) (xy 202.362813 -212.085549) (xy 202.316792 -212.113635) (xy 202.267172 -212.134722)
			(xy 202.215011 -212.148358) (xy 202.16142 -212.154255) (xy 202.107541 -212.152286) (xy 202.054523 -212.142493)
			(xy 202.003496 -212.125085) (xy 201.955548 -212.100433) (xy 201.9117 -212.069063) (xy 201.872887 -212.031642)
			(xy 201.839935 -211.988969) (xy 201.813549 -211.941952) (xy 201.794289 -211.891595) (xy 201.782566 -211.838971)
			(xy 201.778631 -211.7852) (xy 194.97294 -211.7852) (xy 194.972448 -211.812157) (xy 194.964598 -211.865497)
			(xy 194.949066 -211.917126) (xy 194.926181 -211.965943) (xy 194.896433 -212.010907) (xy 194.860455 -212.051061)
			(xy 194.819013 -212.085549) (xy 194.772992 -212.113635) (xy 194.723372 -212.134722) (xy 194.671211 -212.148358)
			(xy 194.61762 -212.154255) (xy 194.563741 -212.152286) (xy 194.510723 -212.142493) (xy 194.459696 -212.125085)
			(xy 194.411748 -212.100433) (xy 194.3679 -212.069063) (xy 194.329087 -212.031642) (xy 194.296135 -211.988969)
			(xy 194.269749 -211.941952) (xy 194.250489 -211.891595) (xy 194.238766 -211.838971) (xy 194.234831 -211.7852)
			(xy 187.428886 -211.7852) (xy 187.428394 -211.812157) (xy 187.420544 -211.865497) (xy 187.405012 -211.917126)
			(xy 187.382127 -211.965943) (xy 187.352379 -212.010907) (xy 187.316401 -212.051061) (xy 187.274959 -212.085549)
			(xy 187.228938 -212.113635) (xy 187.179318 -212.134722) (xy 187.127157 -212.148358) (xy 187.073566 -212.154255)
			(xy 187.019687 -212.152286) (xy 186.966669 -212.142493) (xy 186.915642 -212.125085) (xy 186.867694 -212.100433)
			(xy 186.823846 -212.069063) (xy 186.785033 -212.031642) (xy 186.752081 -211.988969) (xy 186.725695 -211.941952)
			(xy 186.706435 -211.891595) (xy 186.694712 -211.838971) (xy 186.690777 -211.7852) (xy 179.884832 -211.7852)
			(xy 179.88434 -211.812157) (xy 179.87649 -211.865497) (xy 179.860958 -211.917126) (xy 179.838073 -211.965943)
			(xy 179.808325 -212.010907) (xy 179.772347 -212.051061) (xy 179.730905 -212.085549) (xy 179.684884 -212.113635)
			(xy 179.635264 -212.134722) (xy 179.583103 -212.148358) (xy 179.529512 -212.154255) (xy 179.475633 -212.152286)
			(xy 179.422615 -212.142493) (xy 179.371588 -212.125085) (xy 179.32364 -212.100433) (xy 179.279792 -212.069063)
			(xy 179.240979 -212.031642) (xy 179.208027 -211.988969) (xy 179.181641 -211.941952) (xy 179.162381 -211.891595)
			(xy 179.150658 -211.838971) (xy 179.146723 -211.7852) (xy 177.881534 -211.7852) (xy 177.881534 -212.635338)
			(xy 183.246791 -212.635338) (xy 183.250726 -212.581567) (xy 183.262449 -212.528943) (xy 183.281709 -212.478586)
			(xy 183.308095 -212.431569) (xy 183.341047 -212.388896) (xy 183.37986 -212.351475) (xy 183.423708 -212.320105)
			(xy 183.471656 -212.295453) (xy 183.522683 -212.278045) (xy 183.575701 -212.268252) (xy 183.62958 -212.266283)
			(xy 183.683171 -212.27218) (xy 183.735332 -212.285816) (xy 183.784952 -212.306903) (xy 183.830973 -212.334989)
			(xy 183.872415 -212.369477) (xy 183.908393 -212.409631) (xy 183.938141 -212.454595) (xy 183.961026 -212.503412)
			(xy 183.976558 -212.555041) (xy 183.984408 -212.608381) (xy 183.9849 -212.635338) (xy 190.790845 -212.635338)
			(xy 190.79478 -212.581567) (xy 190.806503 -212.528943) (xy 190.825763 -212.478586) (xy 190.852149 -212.431569)
			(xy 190.885101 -212.388896) (xy 190.923914 -212.351475) (xy 190.967762 -212.320105) (xy 191.01571 -212.295453)
			(xy 191.066737 -212.278045) (xy 191.119755 -212.268252) (xy 191.173634 -212.266283) (xy 191.227225 -212.27218)
			(xy 191.279386 -212.285816) (xy 191.329006 -212.306903) (xy 191.375027 -212.334989) (xy 191.416469 -212.369477)
			(xy 191.452447 -212.409631) (xy 191.482195 -212.454595) (xy 191.50508 -212.503412) (xy 191.520612 -212.555041)
			(xy 191.528462 -212.608381) (xy 191.528954 -212.635338) (xy 198.334899 -212.635338) (xy 198.338834 -212.581567)
			(xy 198.350557 -212.528943) (xy 198.369817 -212.478586) (xy 198.396203 -212.431569) (xy 198.429155 -212.388896)
			(xy 198.467968 -212.351475) (xy 198.511816 -212.320105) (xy 198.559764 -212.295453) (xy 198.610791 -212.278045)
			(xy 198.663809 -212.268252) (xy 198.717688 -212.266283) (xy 198.771279 -212.27218) (xy 198.82344 -212.285816)
			(xy 198.87306 -212.306903) (xy 198.919081 -212.334989) (xy 198.960523 -212.369477) (xy 198.996501 -212.409631)
			(xy 199.026249 -212.454595) (xy 199.049134 -212.503412) (xy 199.064666 -212.555041) (xy 199.072516 -212.608381)
			(xy 199.073008 -212.635338) (xy 205.878699 -212.635338) (xy 205.882634 -212.581567) (xy 205.894357 -212.528943)
			(xy 205.913617 -212.478586) (xy 205.940003 -212.431569) (xy 205.972955 -212.388896) (xy 206.011768 -212.351475)
			(xy 206.055616 -212.320105) (xy 206.103564 -212.295453) (xy 206.154591 -212.278045) (xy 206.207609 -212.268252)
			(xy 206.261488 -212.266283) (xy 206.315079 -212.27218) (xy 206.36724 -212.285816) (xy 206.41686 -212.306903)
			(xy 206.462881 -212.334989) (xy 206.504323 -212.369477) (xy 206.540301 -212.409631) (xy 206.570049 -212.454595)
			(xy 206.592934 -212.503412) (xy 206.608466 -212.555041) (xy 206.616316 -212.608381) (xy 206.616808 -212.635338)
			(xy 206.616316 -212.662295) (xy 206.608466 -212.715635) (xy 206.592934 -212.767264) (xy 206.570049 -212.816081)
			(xy 206.540301 -212.861045) (xy 206.504323 -212.901199) (xy 206.462881 -212.935687) (xy 206.41686 -212.963773)
			(xy 206.36724 -212.98486) (xy 206.315079 -212.998496) (xy 206.261488 -213.004393) (xy 206.207609 -213.002424)
			(xy 206.154591 -212.992631) (xy 206.103564 -212.975223) (xy 206.055616 -212.950571) (xy 206.011768 -212.919201)
			(xy 205.972955 -212.88178) (xy 205.940003 -212.839107) (xy 205.913617 -212.79209) (xy 205.894357 -212.741733)
			(xy 205.882634 -212.689109) (xy 205.878699 -212.635338) (xy 199.073008 -212.635338) (xy 199.072516 -212.662295)
			(xy 199.064666 -212.715635) (xy 199.049134 -212.767264) (xy 199.026249 -212.816081) (xy 198.996501 -212.861045)
			(xy 198.960523 -212.901199) (xy 198.919081 -212.935687) (xy 198.87306 -212.963773) (xy 198.82344 -212.98486)
			(xy 198.771279 -212.998496) (xy 198.717688 -213.004393) (xy 198.663809 -213.002424) (xy 198.610791 -212.992631)
			(xy 198.559764 -212.975223) (xy 198.511816 -212.950571) (xy 198.467968 -212.919201) (xy 198.429155 -212.88178)
			(xy 198.396203 -212.839107) (xy 198.369817 -212.79209) (xy 198.350557 -212.741733) (xy 198.338834 -212.689109)
			(xy 198.334899 -212.635338) (xy 191.528954 -212.635338) (xy 191.528462 -212.662295) (xy 191.520612 -212.715635)
			(xy 191.50508 -212.767264) (xy 191.482195 -212.816081) (xy 191.452447 -212.861045) (xy 191.416469 -212.901199)
			(xy 191.375027 -212.935687) (xy 191.329006 -212.963773) (xy 191.279386 -212.98486) (xy 191.227225 -212.998496)
			(xy 191.173634 -213.004393) (xy 191.119755 -213.002424) (xy 191.066737 -212.992631) (xy 191.01571 -212.975223)
			(xy 190.967762 -212.950571) (xy 190.923914 -212.919201) (xy 190.885101 -212.88178) (xy 190.852149 -212.839107)
			(xy 190.825763 -212.79209) (xy 190.806503 -212.741733) (xy 190.79478 -212.689109) (xy 190.790845 -212.635338)
			(xy 183.9849 -212.635338) (xy 183.984408 -212.662295) (xy 183.976558 -212.715635) (xy 183.961026 -212.767264)
			(xy 183.938141 -212.816081) (xy 183.908393 -212.861045) (xy 183.872415 -212.901199) (xy 183.830973 -212.935687)
			(xy 183.784952 -212.963773) (xy 183.735332 -212.98486) (xy 183.683171 -212.998496) (xy 183.62958 -213.004393)
			(xy 183.575701 -213.002424) (xy 183.522683 -212.992631) (xy 183.471656 -212.975223) (xy 183.423708 -212.950571)
			(xy 183.37986 -212.919201) (xy 183.341047 -212.88178) (xy 183.308095 -212.839107) (xy 183.281709 -212.79209)
			(xy 183.262449 -212.741733) (xy 183.250726 -212.689109) (xy 183.246791 -212.635338) (xy 177.881534 -212.635338)
			(xy 177.881534 -213.485222) (xy 179.146723 -213.485222) (xy 179.150658 -213.431451) (xy 179.162381 -213.378827)
			(xy 179.181641 -213.32847) (xy 179.208027 -213.281453) (xy 179.240979 -213.23878) (xy 179.279792 -213.201359)
			(xy 179.32364 -213.169989) (xy 179.371588 -213.145337) (xy 179.422615 -213.127929) (xy 179.475633 -213.118136)
			(xy 179.529512 -213.116167) (xy 179.583103 -213.122064) (xy 179.635264 -213.1357) (xy 179.684884 -213.156787)
			(xy 179.730905 -213.184873) (xy 179.772347 -213.219361) (xy 179.808325 -213.259515) (xy 179.838073 -213.304479)
			(xy 179.860958 -213.353296) (xy 179.87649 -213.404925) (xy 179.88434 -213.458265) (xy 179.884832 -213.485222)
			(xy 186.690777 -213.485222) (xy 186.694712 -213.431451) (xy 186.706435 -213.378827) (xy 186.725695 -213.32847)
			(xy 186.752081 -213.281453) (xy 186.785033 -213.23878) (xy 186.823846 -213.201359) (xy 186.867694 -213.169989)
			(xy 186.915642 -213.145337) (xy 186.966669 -213.127929) (xy 187.019687 -213.118136) (xy 187.073566 -213.116167)
			(xy 187.127157 -213.122064) (xy 187.179318 -213.1357) (xy 187.228938 -213.156787) (xy 187.274959 -213.184873)
			(xy 187.316401 -213.219361) (xy 187.352379 -213.259515) (xy 187.382127 -213.304479) (xy 187.405012 -213.353296)
			(xy 187.420544 -213.404925) (xy 187.428394 -213.458265) (xy 187.428886 -213.485222) (xy 194.234831 -213.485222)
			(xy 194.238766 -213.431451) (xy 194.250489 -213.378827) (xy 194.269749 -213.32847) (xy 194.296135 -213.281453)
			(xy 194.329087 -213.23878) (xy 194.3679 -213.201359) (xy 194.411748 -213.169989) (xy 194.459696 -213.145337)
			(xy 194.510723 -213.127929) (xy 194.563741 -213.118136) (xy 194.61762 -213.116167) (xy 194.671211 -213.122064)
			(xy 194.723372 -213.1357) (xy 194.772992 -213.156787) (xy 194.819013 -213.184873) (xy 194.860455 -213.219361)
			(xy 194.896433 -213.259515) (xy 194.926181 -213.304479) (xy 194.949066 -213.353296) (xy 194.964598 -213.404925)
			(xy 194.972448 -213.458265) (xy 194.97294 -213.485222) (xy 201.778631 -213.485222) (xy 201.782566 -213.431451)
			(xy 201.794289 -213.378827) (xy 201.813549 -213.32847) (xy 201.839935 -213.281453) (xy 201.872887 -213.23878)
			(xy 201.9117 -213.201359) (xy 201.955548 -213.169989) (xy 202.003496 -213.145337) (xy 202.054523 -213.127929)
			(xy 202.107541 -213.118136) (xy 202.16142 -213.116167) (xy 202.215011 -213.122064) (xy 202.267172 -213.1357)
			(xy 202.316792 -213.156787) (xy 202.362813 -213.184873) (xy 202.404255 -213.219361) (xy 202.440233 -213.259515)
			(xy 202.469981 -213.304479) (xy 202.492866 -213.353296) (xy 202.508398 -213.404925) (xy 202.516248 -213.458265)
			(xy 202.51674 -213.485222) (xy 202.516248 -213.512179) (xy 202.508398 -213.565519) (xy 202.492866 -213.617148)
			(xy 202.469981 -213.665965) (xy 202.440233 -213.710929) (xy 202.404255 -213.751083) (xy 202.362813 -213.785571)
			(xy 202.316792 -213.813657) (xy 202.267172 -213.834744) (xy 202.215011 -213.84838) (xy 202.16142 -213.854277)
			(xy 202.107541 -213.852308) (xy 202.054523 -213.842515) (xy 202.003496 -213.825107) (xy 201.955548 -213.800455)
			(xy 201.9117 -213.769085) (xy 201.872887 -213.731664) (xy 201.839935 -213.688991) (xy 201.813549 -213.641974)
			(xy 201.794289 -213.591617) (xy 201.782566 -213.538993) (xy 201.778631 -213.485222) (xy 194.97294 -213.485222)
			(xy 194.972448 -213.512179) (xy 194.964598 -213.565519) (xy 194.949066 -213.617148) (xy 194.926181 -213.665965)
			(xy 194.896433 -213.710929) (xy 194.860455 -213.751083) (xy 194.819013 -213.785571) (xy 194.772992 -213.813657)
			(xy 194.723372 -213.834744) (xy 194.671211 -213.84838) (xy 194.61762 -213.854277) (xy 194.563741 -213.852308)
			(xy 194.510723 -213.842515) (xy 194.459696 -213.825107) (xy 194.411748 -213.800455) (xy 194.3679 -213.769085)
			(xy 194.329087 -213.731664) (xy 194.296135 -213.688991) (xy 194.269749 -213.641974) (xy 194.250489 -213.591617)
			(xy 194.238766 -213.538993) (xy 194.234831 -213.485222) (xy 187.428886 -213.485222) (xy 187.428394 -213.512179)
			(xy 187.420544 -213.565519) (xy 187.405012 -213.617148) (xy 187.382127 -213.665965) (xy 187.352379 -213.710929)
			(xy 187.316401 -213.751083) (xy 187.274959 -213.785571) (xy 187.228938 -213.813657) (xy 187.179318 -213.834744)
			(xy 187.127157 -213.84838) (xy 187.073566 -213.854277) (xy 187.019687 -213.852308) (xy 186.966669 -213.842515)
			(xy 186.915642 -213.825107) (xy 186.867694 -213.800455) (xy 186.823846 -213.769085) (xy 186.785033 -213.731664)
			(xy 186.752081 -213.688991) (xy 186.725695 -213.641974) (xy 186.706435 -213.591617) (xy 186.694712 -213.538993)
			(xy 186.690777 -213.485222) (xy 179.884832 -213.485222) (xy 179.88434 -213.512179) (xy 179.87649 -213.565519)
			(xy 179.860958 -213.617148) (xy 179.838073 -213.665965) (xy 179.808325 -213.710929) (xy 179.772347 -213.751083)
			(xy 179.730905 -213.785571) (xy 179.684884 -213.813657) (xy 179.635264 -213.834744) (xy 179.583103 -213.84838)
			(xy 179.529512 -213.854277) (xy 179.475633 -213.852308) (xy 179.422615 -213.842515) (xy 179.371588 -213.825107)
			(xy 179.32364 -213.800455) (xy 179.279792 -213.769085) (xy 179.240979 -213.731664) (xy 179.208027 -213.688991)
			(xy 179.181641 -213.641974) (xy 179.162381 -213.591617) (xy 179.150658 -213.538993) (xy 179.146723 -213.485222)
			(xy 177.881534 -213.485222) (xy 177.881534 -214.33536) (xy 183.246791 -214.33536) (xy 183.250726 -214.281589)
			(xy 183.262449 -214.228965) (xy 183.281709 -214.178608) (xy 183.308095 -214.131591) (xy 183.341047 -214.088918)
			(xy 183.37986 -214.051497) (xy 183.423708 -214.020127) (xy 183.471656 -213.995475) (xy 183.522683 -213.978067)
			(xy 183.575701 -213.968274) (xy 183.62958 -213.966305) (xy 183.683171 -213.972202) (xy 183.735332 -213.985838)
			(xy 183.784952 -214.006925) (xy 183.830973 -214.035011) (xy 183.872415 -214.069499) (xy 183.908393 -214.109653)
			(xy 183.938141 -214.154617) (xy 183.961026 -214.203434) (xy 183.976558 -214.255063) (xy 183.984408 -214.308403)
			(xy 183.9849 -214.33536) (xy 190.790845 -214.33536) (xy 190.79478 -214.281589) (xy 190.806503 -214.228965)
			(xy 190.825763 -214.178608) (xy 190.852149 -214.131591) (xy 190.885101 -214.088918) (xy 190.923914 -214.051497)
			(xy 190.967762 -214.020127) (xy 191.01571 -213.995475) (xy 191.066737 -213.978067) (xy 191.119755 -213.968274)
			(xy 191.173634 -213.966305) (xy 191.227225 -213.972202) (xy 191.279386 -213.985838) (xy 191.329006 -214.006925)
			(xy 191.375027 -214.035011) (xy 191.416469 -214.069499) (xy 191.452447 -214.109653) (xy 191.482195 -214.154617)
			(xy 191.50508 -214.203434) (xy 191.520612 -214.255063) (xy 191.528462 -214.308403) (xy 191.528954 -214.33536)
			(xy 198.334899 -214.33536) (xy 198.338834 -214.281589) (xy 198.350557 -214.228965) (xy 198.369817 -214.178608)
			(xy 198.396203 -214.131591) (xy 198.429155 -214.088918) (xy 198.467968 -214.051497) (xy 198.511816 -214.020127)
			(xy 198.559764 -213.995475) (xy 198.610791 -213.978067) (xy 198.663809 -213.968274) (xy 198.717688 -213.966305)
			(xy 198.771279 -213.972202) (xy 198.82344 -213.985838) (xy 198.87306 -214.006925) (xy 198.919081 -214.035011)
			(xy 198.960523 -214.069499) (xy 198.996501 -214.109653) (xy 199.026249 -214.154617) (xy 199.049134 -214.203434)
			(xy 199.064666 -214.255063) (xy 199.072516 -214.308403) (xy 199.073008 -214.33536) (xy 205.878699 -214.33536)
			(xy 205.882634 -214.281589) (xy 205.894357 -214.228965) (xy 205.913617 -214.178608) (xy 205.940003 -214.131591)
			(xy 205.972955 -214.088918) (xy 206.011768 -214.051497) (xy 206.055616 -214.020127) (xy 206.103564 -213.995475)
			(xy 206.154591 -213.978067) (xy 206.207609 -213.968274) (xy 206.261488 -213.966305) (xy 206.315079 -213.972202)
			(xy 206.36724 -213.985838) (xy 206.41686 -214.006925) (xy 206.462881 -214.035011) (xy 206.504323 -214.069499)
			(xy 206.540301 -214.109653) (xy 206.570049 -214.154617) (xy 206.592934 -214.203434) (xy 206.608466 -214.255063)
			(xy 206.616316 -214.308403) (xy 206.616808 -214.33536) (xy 206.616316 -214.362317) (xy 206.608466 -214.415657)
			(xy 206.592934 -214.467286) (xy 206.570049 -214.516103) (xy 206.540301 -214.561067) (xy 206.504323 -214.601221)
			(xy 206.462881 -214.635709) (xy 206.41686 -214.663795) (xy 206.36724 -214.684882) (xy 206.315079 -214.698518)
			(xy 206.261488 -214.704415) (xy 206.207609 -214.702446) (xy 206.154591 -214.692653) (xy 206.103564 -214.675245)
			(xy 206.055616 -214.650593) (xy 206.011768 -214.619223) (xy 205.972955 -214.581802) (xy 205.940003 -214.539129)
			(xy 205.913617 -214.492112) (xy 205.894357 -214.441755) (xy 205.882634 -214.389131) (xy 205.878699 -214.33536)
			(xy 199.073008 -214.33536) (xy 199.072516 -214.362317) (xy 199.064666 -214.415657) (xy 199.049134 -214.467286)
			(xy 199.026249 -214.516103) (xy 198.996501 -214.561067) (xy 198.960523 -214.601221) (xy 198.919081 -214.635709)
			(xy 198.87306 -214.663795) (xy 198.82344 -214.684882) (xy 198.771279 -214.698518) (xy 198.717688 -214.704415)
			(xy 198.663809 -214.702446) (xy 198.610791 -214.692653) (xy 198.559764 -214.675245) (xy 198.511816 -214.650593)
			(xy 198.467968 -214.619223) (xy 198.429155 -214.581802) (xy 198.396203 -214.539129) (xy 198.369817 -214.492112)
			(xy 198.350557 -214.441755) (xy 198.338834 -214.389131) (xy 198.334899 -214.33536) (xy 191.528954 -214.33536)
			(xy 191.528462 -214.362317) (xy 191.520612 -214.415657) (xy 191.50508 -214.467286) (xy 191.482195 -214.516103)
			(xy 191.452447 -214.561067) (xy 191.416469 -214.601221) (xy 191.375027 -214.635709) (xy 191.329006 -214.663795)
			(xy 191.279386 -214.684882) (xy 191.227225 -214.698518) (xy 191.173634 -214.704415) (xy 191.119755 -214.702446)
			(xy 191.066737 -214.692653) (xy 191.01571 -214.675245) (xy 190.967762 -214.650593) (xy 190.923914 -214.619223)
			(xy 190.885101 -214.581802) (xy 190.852149 -214.539129) (xy 190.825763 -214.492112) (xy 190.806503 -214.441755)
			(xy 190.79478 -214.389131) (xy 190.790845 -214.33536) (xy 183.9849 -214.33536) (xy 183.984408 -214.362317)
			(xy 183.976558 -214.415657) (xy 183.961026 -214.467286) (xy 183.938141 -214.516103) (xy 183.908393 -214.561067)
			(xy 183.872415 -214.601221) (xy 183.830973 -214.635709) (xy 183.784952 -214.663795) (xy 183.735332 -214.684882)
			(xy 183.683171 -214.698518) (xy 183.62958 -214.704415) (xy 183.575701 -214.702446) (xy 183.522683 -214.692653)
			(xy 183.471656 -214.675245) (xy 183.423708 -214.650593) (xy 183.37986 -214.619223) (xy 183.341047 -214.581802)
			(xy 183.308095 -214.539129) (xy 183.281709 -214.492112) (xy 183.262449 -214.441755) (xy 183.250726 -214.389131)
			(xy 183.246791 -214.33536) (xy 177.881534 -214.33536) (xy 177.881534 -215.185244) (xy 179.146723 -215.185244)
			(xy 179.150658 -215.131473) (xy 179.162381 -215.078849) (xy 179.181641 -215.028492) (xy 179.208027 -214.981475)
			(xy 179.240979 -214.938802) (xy 179.279792 -214.901381) (xy 179.32364 -214.870011) (xy 179.371588 -214.845359)
			(xy 179.422615 -214.827951) (xy 179.475633 -214.818158) (xy 179.529512 -214.816189) (xy 179.583103 -214.822086)
			(xy 179.635264 -214.835722) (xy 179.684884 -214.856809) (xy 179.730905 -214.884895) (xy 179.772347 -214.919383)
			(xy 179.808325 -214.959537) (xy 179.838073 -215.004501) (xy 179.860958 -215.053318) (xy 179.87649 -215.104947)
			(xy 179.88434 -215.158287) (xy 179.884832 -215.185244) (xy 186.690777 -215.185244) (xy 186.694712 -215.131473)
			(xy 186.706435 -215.078849) (xy 186.725695 -215.028492) (xy 186.752081 -214.981475) (xy 186.785033 -214.938802)
			(xy 186.823846 -214.901381) (xy 186.867694 -214.870011) (xy 186.915642 -214.845359) (xy 186.966669 -214.827951)
			(xy 187.019687 -214.818158) (xy 187.073566 -214.816189) (xy 187.127157 -214.822086) (xy 187.179318 -214.835722)
			(xy 187.228938 -214.856809) (xy 187.274959 -214.884895) (xy 187.316401 -214.919383) (xy 187.352379 -214.959537)
			(xy 187.382127 -215.004501) (xy 187.405012 -215.053318) (xy 187.420544 -215.104947) (xy 187.428394 -215.158287)
			(xy 187.428886 -215.185244) (xy 194.234831 -215.185244) (xy 194.238766 -215.131473) (xy 194.250489 -215.078849)
			(xy 194.269749 -215.028492) (xy 194.296135 -214.981475) (xy 194.329087 -214.938802) (xy 194.3679 -214.901381)
			(xy 194.411748 -214.870011) (xy 194.459696 -214.845359) (xy 194.510723 -214.827951) (xy 194.563741 -214.818158)
			(xy 194.61762 -214.816189) (xy 194.671211 -214.822086) (xy 194.723372 -214.835722) (xy 194.772992 -214.856809)
			(xy 194.819013 -214.884895) (xy 194.860455 -214.919383) (xy 194.896433 -214.959537) (xy 194.926181 -215.004501)
			(xy 194.949066 -215.053318) (xy 194.964598 -215.104947) (xy 194.972448 -215.158287) (xy 194.97294 -215.185244)
			(xy 201.778631 -215.185244) (xy 201.782566 -215.131473) (xy 201.794289 -215.078849) (xy 201.813549 -215.028492)
			(xy 201.839935 -214.981475) (xy 201.872887 -214.938802) (xy 201.9117 -214.901381) (xy 201.955548 -214.870011)
			(xy 202.003496 -214.845359) (xy 202.054523 -214.827951) (xy 202.107541 -214.818158) (xy 202.16142 -214.816189)
			(xy 202.215011 -214.822086) (xy 202.267172 -214.835722) (xy 202.316792 -214.856809) (xy 202.362813 -214.884895)
			(xy 202.404255 -214.919383) (xy 202.440233 -214.959537) (xy 202.469981 -215.004501) (xy 202.492866 -215.053318)
			(xy 202.508398 -215.104947) (xy 202.516248 -215.158287) (xy 202.51674 -215.185244) (xy 202.516248 -215.212201)
			(xy 202.508398 -215.265541) (xy 202.492866 -215.31717) (xy 202.469981 -215.365987) (xy 202.440233 -215.410951)
			(xy 202.404255 -215.451105) (xy 202.362813 -215.485593) (xy 202.316792 -215.513679) (xy 202.267172 -215.534766)
			(xy 202.215011 -215.548402) (xy 202.16142 -215.554299) (xy 202.107541 -215.55233) (xy 202.054523 -215.542537)
			(xy 202.003496 -215.525129) (xy 201.955548 -215.500477) (xy 201.9117 -215.469107) (xy 201.872887 -215.431686)
			(xy 201.839935 -215.389013) (xy 201.813549 -215.341996) (xy 201.794289 -215.291639) (xy 201.782566 -215.239015)
			(xy 201.778631 -215.185244) (xy 194.97294 -215.185244) (xy 194.972448 -215.212201) (xy 194.964598 -215.265541)
			(xy 194.949066 -215.31717) (xy 194.926181 -215.365987) (xy 194.896433 -215.410951) (xy 194.860455 -215.451105)
			(xy 194.819013 -215.485593) (xy 194.772992 -215.513679) (xy 194.723372 -215.534766) (xy 194.671211 -215.548402)
			(xy 194.61762 -215.554299) (xy 194.563741 -215.55233) (xy 194.510723 -215.542537) (xy 194.459696 -215.525129)
			(xy 194.411748 -215.500477) (xy 194.3679 -215.469107) (xy 194.329087 -215.431686) (xy 194.296135 -215.389013)
			(xy 194.269749 -215.341996) (xy 194.250489 -215.291639) (xy 194.238766 -215.239015) (xy 194.234831 -215.185244)
			(xy 187.428886 -215.185244) (xy 187.428394 -215.212201) (xy 187.420544 -215.265541) (xy 187.405012 -215.31717)
			(xy 187.382127 -215.365987) (xy 187.352379 -215.410951) (xy 187.316401 -215.451105) (xy 187.274959 -215.485593)
			(xy 187.228938 -215.513679) (xy 187.179318 -215.534766) (xy 187.127157 -215.548402) (xy 187.073566 -215.554299)
			(xy 187.019687 -215.55233) (xy 186.966669 -215.542537) (xy 186.915642 -215.525129) (xy 186.867694 -215.500477)
			(xy 186.823846 -215.469107) (xy 186.785033 -215.431686) (xy 186.752081 -215.389013) (xy 186.725695 -215.341996)
			(xy 186.706435 -215.291639) (xy 186.694712 -215.239015) (xy 186.690777 -215.185244) (xy 179.884832 -215.185244)
			(xy 179.88434 -215.212201) (xy 179.87649 -215.265541) (xy 179.860958 -215.31717) (xy 179.838073 -215.365987)
			(xy 179.808325 -215.410951) (xy 179.772347 -215.451105) (xy 179.730905 -215.485593) (xy 179.684884 -215.513679)
			(xy 179.635264 -215.534766) (xy 179.583103 -215.548402) (xy 179.529512 -215.554299) (xy 179.475633 -215.55233)
			(xy 179.422615 -215.542537) (xy 179.371588 -215.525129) (xy 179.32364 -215.500477) (xy 179.279792 -215.469107)
			(xy 179.240979 -215.431686) (xy 179.208027 -215.389013) (xy 179.181641 -215.341996) (xy 179.162381 -215.291639)
			(xy 179.150658 -215.239015) (xy 179.146723 -215.185244) (xy 177.881534 -215.185244) (xy 177.881534 -216.035382)
			(xy 183.246791 -216.035382) (xy 183.250726 -215.981611) (xy 183.262449 -215.928987) (xy 183.281709 -215.87863)
			(xy 183.308095 -215.831613) (xy 183.341047 -215.78894) (xy 183.37986 -215.751519) (xy 183.423708 -215.720149)
			(xy 183.471656 -215.695497) (xy 183.522683 -215.678089) (xy 183.575701 -215.668296) (xy 183.62958 -215.666327)
			(xy 183.683171 -215.672224) (xy 183.735332 -215.68586) (xy 183.784952 -215.706947) (xy 183.830973 -215.735033)
			(xy 183.872415 -215.769521) (xy 183.908393 -215.809675) (xy 183.938141 -215.854639) (xy 183.961026 -215.903456)
			(xy 183.976558 -215.955085) (xy 183.984408 -216.008425) (xy 183.9849 -216.035382) (xy 190.790845 -216.035382)
			(xy 190.79478 -215.981611) (xy 190.806503 -215.928987) (xy 190.825763 -215.87863) (xy 190.852149 -215.831613)
			(xy 190.885101 -215.78894) (xy 190.923914 -215.751519) (xy 190.967762 -215.720149) (xy 191.01571 -215.695497)
			(xy 191.066737 -215.678089) (xy 191.119755 -215.668296) (xy 191.173634 -215.666327) (xy 191.227225 -215.672224)
			(xy 191.279386 -215.68586) (xy 191.329006 -215.706947) (xy 191.375027 -215.735033) (xy 191.416469 -215.769521)
			(xy 191.452447 -215.809675) (xy 191.482195 -215.854639) (xy 191.50508 -215.903456) (xy 191.520612 -215.955085)
			(xy 191.528462 -216.008425) (xy 191.528954 -216.035382) (xy 198.334899 -216.035382) (xy 198.338834 -215.981611)
			(xy 198.350557 -215.928987) (xy 198.369817 -215.87863) (xy 198.396203 -215.831613) (xy 198.429155 -215.78894)
			(xy 198.467968 -215.751519) (xy 198.511816 -215.720149) (xy 198.559764 -215.695497) (xy 198.610791 -215.678089)
			(xy 198.663809 -215.668296) (xy 198.717688 -215.666327) (xy 198.771279 -215.672224) (xy 198.82344 -215.68586)
			(xy 198.87306 -215.706947) (xy 198.919081 -215.735033) (xy 198.960523 -215.769521) (xy 198.996501 -215.809675)
			(xy 199.026249 -215.854639) (xy 199.049134 -215.903456) (xy 199.064666 -215.955085) (xy 199.072516 -216.008425)
			(xy 199.073008 -216.035382) (xy 205.878699 -216.035382) (xy 205.882634 -215.981611) (xy 205.894357 -215.928987)
			(xy 205.913617 -215.87863) (xy 205.940003 -215.831613) (xy 205.972955 -215.78894) (xy 206.011768 -215.751519)
			(xy 206.055616 -215.720149) (xy 206.103564 -215.695497) (xy 206.154591 -215.678089) (xy 206.207609 -215.668296)
			(xy 206.261488 -215.666327) (xy 206.315079 -215.672224) (xy 206.36724 -215.68586) (xy 206.41686 -215.706947)
			(xy 206.462881 -215.735033) (xy 206.504323 -215.769521) (xy 206.540301 -215.809675) (xy 206.570049 -215.854639)
			(xy 206.592934 -215.903456) (xy 206.608466 -215.955085) (xy 206.616316 -216.008425) (xy 206.616808 -216.035382)
			(xy 206.616316 -216.062339) (xy 206.608466 -216.115679) (xy 206.592934 -216.167308) (xy 206.570049 -216.216125)
			(xy 206.540301 -216.261089) (xy 206.504323 -216.301243) (xy 206.462881 -216.335731) (xy 206.41686 -216.363817)
			(xy 206.36724 -216.384904) (xy 206.315079 -216.39854) (xy 206.261488 -216.404437) (xy 206.207609 -216.402468)
			(xy 206.154591 -216.392675) (xy 206.103564 -216.375267) (xy 206.055616 -216.350615) (xy 206.011768 -216.319245)
			(xy 205.972955 -216.281824) (xy 205.940003 -216.239151) (xy 205.913617 -216.192134) (xy 205.894357 -216.141777)
			(xy 205.882634 -216.089153) (xy 205.878699 -216.035382) (xy 199.073008 -216.035382) (xy 199.072516 -216.062339)
			(xy 199.064666 -216.115679) (xy 199.049134 -216.167308) (xy 199.026249 -216.216125) (xy 198.996501 -216.261089)
			(xy 198.960523 -216.301243) (xy 198.919081 -216.335731) (xy 198.87306 -216.363817) (xy 198.82344 -216.384904)
			(xy 198.771279 -216.39854) (xy 198.717688 -216.404437) (xy 198.663809 -216.402468) (xy 198.610791 -216.392675)
			(xy 198.559764 -216.375267) (xy 198.511816 -216.350615) (xy 198.467968 -216.319245) (xy 198.429155 -216.281824)
			(xy 198.396203 -216.239151) (xy 198.369817 -216.192134) (xy 198.350557 -216.141777) (xy 198.338834 -216.089153)
			(xy 198.334899 -216.035382) (xy 191.528954 -216.035382) (xy 191.528462 -216.062339) (xy 191.520612 -216.115679)
			(xy 191.50508 -216.167308) (xy 191.482195 -216.216125) (xy 191.452447 -216.261089) (xy 191.416469 -216.301243)
			(xy 191.375027 -216.335731) (xy 191.329006 -216.363817) (xy 191.279386 -216.384904) (xy 191.227225 -216.39854)
			(xy 191.173634 -216.404437) (xy 191.119755 -216.402468) (xy 191.066737 -216.392675) (xy 191.01571 -216.375267)
			(xy 190.967762 -216.350615) (xy 190.923914 -216.319245) (xy 190.885101 -216.281824) (xy 190.852149 -216.239151)
			(xy 190.825763 -216.192134) (xy 190.806503 -216.141777) (xy 190.79478 -216.089153) (xy 190.790845 -216.035382)
			(xy 183.9849 -216.035382) (xy 183.984408 -216.062339) (xy 183.976558 -216.115679) (xy 183.961026 -216.167308)
			(xy 183.938141 -216.216125) (xy 183.908393 -216.261089) (xy 183.872415 -216.301243) (xy 183.830973 -216.335731)
			(xy 183.784952 -216.363817) (xy 183.735332 -216.384904) (xy 183.683171 -216.39854) (xy 183.62958 -216.404437)
			(xy 183.575701 -216.402468) (xy 183.522683 -216.392675) (xy 183.471656 -216.375267) (xy 183.423708 -216.350615)
			(xy 183.37986 -216.319245) (xy 183.341047 -216.281824) (xy 183.308095 -216.239151) (xy 183.281709 -216.192134)
			(xy 183.262449 -216.141777) (xy 183.250726 -216.089153) (xy 183.246791 -216.035382) (xy 177.881534 -216.035382)
			(xy 177.881534 -216.885266) (xy 179.146723 -216.885266) (xy 179.150658 -216.831495) (xy 179.162381 -216.778871)
			(xy 179.181641 -216.728514) (xy 179.208027 -216.681497) (xy 179.240979 -216.638824) (xy 179.279792 -216.601403)
			(xy 179.32364 -216.570033) (xy 179.371588 -216.545381) (xy 179.422615 -216.527973) (xy 179.475633 -216.51818)
			(xy 179.529512 -216.516211) (xy 179.583103 -216.522108) (xy 179.635264 -216.535744) (xy 179.684884 -216.556831)
			(xy 179.730905 -216.584917) (xy 179.772347 -216.619405) (xy 179.808325 -216.659559) (xy 179.838073 -216.704523)
			(xy 179.860958 -216.75334) (xy 179.87649 -216.804969) (xy 179.88434 -216.858309) (xy 179.884832 -216.885266)
			(xy 186.690777 -216.885266) (xy 186.694712 -216.831495) (xy 186.706435 -216.778871) (xy 186.725695 -216.728514)
			(xy 186.752081 -216.681497) (xy 186.785033 -216.638824) (xy 186.823846 -216.601403) (xy 186.867694 -216.570033)
			(xy 186.915642 -216.545381) (xy 186.966669 -216.527973) (xy 187.019687 -216.51818) (xy 187.073566 -216.516211)
			(xy 187.127157 -216.522108) (xy 187.179318 -216.535744) (xy 187.228938 -216.556831) (xy 187.274959 -216.584917)
			(xy 187.316401 -216.619405) (xy 187.352379 -216.659559) (xy 187.382127 -216.704523) (xy 187.405012 -216.75334)
			(xy 187.420544 -216.804969) (xy 187.428394 -216.858309) (xy 187.428886 -216.885266) (xy 194.234831 -216.885266)
			(xy 194.238766 -216.831495) (xy 194.250489 -216.778871) (xy 194.269749 -216.728514) (xy 194.296135 -216.681497)
			(xy 194.329087 -216.638824) (xy 194.3679 -216.601403) (xy 194.411748 -216.570033) (xy 194.459696 -216.545381)
			(xy 194.510723 -216.527973) (xy 194.563741 -216.51818) (xy 194.61762 -216.516211) (xy 194.671211 -216.522108)
			(xy 194.723372 -216.535744) (xy 194.772992 -216.556831) (xy 194.819013 -216.584917) (xy 194.860455 -216.619405)
			(xy 194.896433 -216.659559) (xy 194.926181 -216.704523) (xy 194.949066 -216.75334) (xy 194.964598 -216.804969)
			(xy 194.972448 -216.858309) (xy 194.97294 -216.885266) (xy 201.778631 -216.885266) (xy 201.782566 -216.831495)
			(xy 201.794289 -216.778871) (xy 201.813549 -216.728514) (xy 201.839935 -216.681497) (xy 201.872887 -216.638824)
			(xy 201.9117 -216.601403) (xy 201.955548 -216.570033) (xy 202.003496 -216.545381) (xy 202.054523 -216.527973)
			(xy 202.107541 -216.51818) (xy 202.16142 -216.516211) (xy 202.215011 -216.522108) (xy 202.267172 -216.535744)
			(xy 202.316792 -216.556831) (xy 202.362813 -216.584917) (xy 202.404255 -216.619405) (xy 202.440233 -216.659559)
			(xy 202.469981 -216.704523) (xy 202.492866 -216.75334) (xy 202.508398 -216.804969) (xy 202.516248 -216.858309)
			(xy 202.51674 -216.885266) (xy 202.516248 -216.912223) (xy 202.508398 -216.965563) (xy 202.492866 -217.017192)
			(xy 202.469981 -217.066009) (xy 202.440233 -217.110973) (xy 202.404255 -217.151127) (xy 202.362813 -217.185615)
			(xy 202.316792 -217.213701) (xy 202.267172 -217.234788) (xy 202.215011 -217.248424) (xy 202.16142 -217.254321)
			(xy 202.107541 -217.252352) (xy 202.054523 -217.242559) (xy 202.003496 -217.225151) (xy 201.955548 -217.200499)
			(xy 201.9117 -217.169129) (xy 201.872887 -217.131708) (xy 201.839935 -217.089035) (xy 201.813549 -217.042018)
			(xy 201.794289 -216.991661) (xy 201.782566 -216.939037) (xy 201.778631 -216.885266) (xy 194.97294 -216.885266)
			(xy 194.972448 -216.912223) (xy 194.964598 -216.965563) (xy 194.949066 -217.017192) (xy 194.926181 -217.066009)
			(xy 194.896433 -217.110973) (xy 194.860455 -217.151127) (xy 194.819013 -217.185615) (xy 194.772992 -217.213701)
			(xy 194.723372 -217.234788) (xy 194.671211 -217.248424) (xy 194.61762 -217.254321) (xy 194.563741 -217.252352)
			(xy 194.510723 -217.242559) (xy 194.459696 -217.225151) (xy 194.411748 -217.200499) (xy 194.3679 -217.169129)
			(xy 194.329087 -217.131708) (xy 194.296135 -217.089035) (xy 194.269749 -217.042018) (xy 194.250489 -216.991661)
			(xy 194.238766 -216.939037) (xy 194.234831 -216.885266) (xy 187.428886 -216.885266) (xy 187.428394 -216.912223)
			(xy 187.420544 -216.965563) (xy 187.405012 -217.017192) (xy 187.382127 -217.066009) (xy 187.352379 -217.110973)
			(xy 187.316401 -217.151127) (xy 187.274959 -217.185615) (xy 187.228938 -217.213701) (xy 187.179318 -217.234788)
			(xy 187.127157 -217.248424) (xy 187.073566 -217.254321) (xy 187.019687 -217.252352) (xy 186.966669 -217.242559)
			(xy 186.915642 -217.225151) (xy 186.867694 -217.200499) (xy 186.823846 -217.169129) (xy 186.785033 -217.131708)
			(xy 186.752081 -217.089035) (xy 186.725695 -217.042018) (xy 186.706435 -216.991661) (xy 186.694712 -216.939037)
			(xy 186.690777 -216.885266) (xy 179.884832 -216.885266) (xy 179.88434 -216.912223) (xy 179.87649 -216.965563)
			(xy 179.860958 -217.017192) (xy 179.838073 -217.066009) (xy 179.808325 -217.110973) (xy 179.772347 -217.151127)
			(xy 179.730905 -217.185615) (xy 179.684884 -217.213701) (xy 179.635264 -217.234788) (xy 179.583103 -217.248424)
			(xy 179.529512 -217.254321) (xy 179.475633 -217.252352) (xy 179.422615 -217.242559) (xy 179.371588 -217.225151)
			(xy 179.32364 -217.200499) (xy 179.279792 -217.169129) (xy 179.240979 -217.131708) (xy 179.208027 -217.089035)
			(xy 179.181641 -217.042018) (xy 179.162381 -216.991661) (xy 179.150658 -216.939037) (xy 179.146723 -216.885266)
			(xy 177.881534 -216.885266) (xy 177.881534 -217.735404) (xy 183.246791 -217.735404) (xy 183.250726 -217.681633)
			(xy 183.262449 -217.629009) (xy 183.281709 -217.578652) (xy 183.308095 -217.531635) (xy 183.341047 -217.488962)
			(xy 183.37986 -217.451541) (xy 183.423708 -217.420171) (xy 183.471656 -217.395519) (xy 183.522683 -217.378111)
			(xy 183.575701 -217.368318) (xy 183.62958 -217.366349) (xy 183.683171 -217.372246) (xy 183.735332 -217.385882)
			(xy 183.784952 -217.406969) (xy 183.830973 -217.435055) (xy 183.872415 -217.469543) (xy 183.908393 -217.509697)
			(xy 183.938141 -217.554661) (xy 183.961026 -217.603478) (xy 183.976558 -217.655107) (xy 183.984408 -217.708447)
			(xy 183.9849 -217.735404) (xy 190.790845 -217.735404) (xy 190.79478 -217.681633) (xy 190.806503 -217.629009)
			(xy 190.825763 -217.578652) (xy 190.852149 -217.531635) (xy 190.885101 -217.488962) (xy 190.923914 -217.451541)
			(xy 190.967762 -217.420171) (xy 191.01571 -217.395519) (xy 191.066737 -217.378111) (xy 191.119755 -217.368318)
			(xy 191.173634 -217.366349) (xy 191.227225 -217.372246) (xy 191.279386 -217.385882) (xy 191.329006 -217.406969)
			(xy 191.375027 -217.435055) (xy 191.416469 -217.469543) (xy 191.452447 -217.509697) (xy 191.482195 -217.554661)
			(xy 191.50508 -217.603478) (xy 191.520612 -217.655107) (xy 191.528462 -217.708447) (xy 191.528954 -217.735404)
			(xy 198.334899 -217.735404) (xy 198.338834 -217.681633) (xy 198.350557 -217.629009) (xy 198.369817 -217.578652)
			(xy 198.396203 -217.531635) (xy 198.429155 -217.488962) (xy 198.467968 -217.451541) (xy 198.511816 -217.420171)
			(xy 198.559764 -217.395519) (xy 198.610791 -217.378111) (xy 198.663809 -217.368318) (xy 198.717688 -217.366349)
			(xy 198.771279 -217.372246) (xy 198.82344 -217.385882) (xy 198.87306 -217.406969) (xy 198.919081 -217.435055)
			(xy 198.960523 -217.469543) (xy 198.996501 -217.509697) (xy 199.026249 -217.554661) (xy 199.049134 -217.603478)
			(xy 199.064666 -217.655107) (xy 199.072516 -217.708447) (xy 199.073008 -217.735404) (xy 205.878699 -217.735404)
			(xy 205.882634 -217.681633) (xy 205.894357 -217.629009) (xy 205.913617 -217.578652) (xy 205.940003 -217.531635)
			(xy 205.972955 -217.488962) (xy 206.011768 -217.451541) (xy 206.055616 -217.420171) (xy 206.103564 -217.395519)
			(xy 206.154591 -217.378111) (xy 206.207609 -217.368318) (xy 206.261488 -217.366349) (xy 206.315079 -217.372246)
			(xy 206.36724 -217.385882) (xy 206.41686 -217.406969) (xy 206.462881 -217.435055) (xy 206.504323 -217.469543)
			(xy 206.540301 -217.509697) (xy 206.570049 -217.554661) (xy 206.592934 -217.603478) (xy 206.608466 -217.655107)
			(xy 206.616316 -217.708447) (xy 206.616808 -217.735404) (xy 206.616316 -217.762361) (xy 206.608466 -217.815701)
			(xy 206.592934 -217.86733) (xy 206.570049 -217.916147) (xy 206.540301 -217.961111) (xy 206.504323 -218.001265)
			(xy 206.462881 -218.035753) (xy 206.41686 -218.063839) (xy 206.36724 -218.084926) (xy 206.315079 -218.098562)
			(xy 206.261488 -218.104459) (xy 206.207609 -218.10249) (xy 206.154591 -218.092697) (xy 206.103564 -218.075289)
			(xy 206.055616 -218.050637) (xy 206.011768 -218.019267) (xy 205.972955 -217.981846) (xy 205.940003 -217.939173)
			(xy 205.913617 -217.892156) (xy 205.894357 -217.841799) (xy 205.882634 -217.789175) (xy 205.878699 -217.735404)
			(xy 199.073008 -217.735404) (xy 199.072516 -217.762361) (xy 199.064666 -217.815701) (xy 199.049134 -217.86733)
			(xy 199.026249 -217.916147) (xy 198.996501 -217.961111) (xy 198.960523 -218.001265) (xy 198.919081 -218.035753)
			(xy 198.87306 -218.063839) (xy 198.82344 -218.084926) (xy 198.771279 -218.098562) (xy 198.717688 -218.104459)
			(xy 198.663809 -218.10249) (xy 198.610791 -218.092697) (xy 198.559764 -218.075289) (xy 198.511816 -218.050637)
			(xy 198.467968 -218.019267) (xy 198.429155 -217.981846) (xy 198.396203 -217.939173) (xy 198.369817 -217.892156)
			(xy 198.350557 -217.841799) (xy 198.338834 -217.789175) (xy 198.334899 -217.735404) (xy 191.528954 -217.735404)
			(xy 191.528462 -217.762361) (xy 191.520612 -217.815701) (xy 191.50508 -217.86733) (xy 191.482195 -217.916147)
			(xy 191.452447 -217.961111) (xy 191.416469 -218.001265) (xy 191.375027 -218.035753) (xy 191.329006 -218.063839)
			(xy 191.279386 -218.084926) (xy 191.227225 -218.098562) (xy 191.173634 -218.104459) (xy 191.119755 -218.10249)
			(xy 191.066737 -218.092697) (xy 191.01571 -218.075289) (xy 190.967762 -218.050637) (xy 190.923914 -218.019267)
			(xy 190.885101 -217.981846) (xy 190.852149 -217.939173) (xy 190.825763 -217.892156) (xy 190.806503 -217.841799)
			(xy 190.79478 -217.789175) (xy 190.790845 -217.735404) (xy 183.9849 -217.735404) (xy 183.984408 -217.762361)
			(xy 183.976558 -217.815701) (xy 183.961026 -217.86733) (xy 183.938141 -217.916147) (xy 183.908393 -217.961111)
			(xy 183.872415 -218.001265) (xy 183.830973 -218.035753) (xy 183.784952 -218.063839) (xy 183.735332 -218.084926)
			(xy 183.683171 -218.098562) (xy 183.62958 -218.104459) (xy 183.575701 -218.10249) (xy 183.522683 -218.092697)
			(xy 183.471656 -218.075289) (xy 183.423708 -218.050637) (xy 183.37986 -218.019267) (xy 183.341047 -217.981846)
			(xy 183.308095 -217.939173) (xy 183.281709 -217.892156) (xy 183.262449 -217.841799) (xy 183.250726 -217.789175)
			(xy 183.246791 -217.735404) (xy 177.881534 -217.735404) (xy 177.881534 -218.585288) (xy 179.146723 -218.585288)
			(xy 179.150658 -218.531517) (xy 179.162381 -218.478893) (xy 179.181641 -218.428536) (xy 179.208027 -218.381519)
			(xy 179.240979 -218.338846) (xy 179.279792 -218.301425) (xy 179.32364 -218.270055) (xy 179.371588 -218.245403)
			(xy 179.422615 -218.227995) (xy 179.475633 -218.218202) (xy 179.529512 -218.216233) (xy 179.583103 -218.22213)
			(xy 179.635264 -218.235766) (xy 179.684884 -218.256853) (xy 179.730905 -218.284939) (xy 179.772347 -218.319427)
			(xy 179.808325 -218.359581) (xy 179.838073 -218.404545) (xy 179.860958 -218.453362) (xy 179.87649 -218.504991)
			(xy 179.88434 -218.558331) (xy 179.884832 -218.585288) (xy 186.690777 -218.585288) (xy 186.694712 -218.531517)
			(xy 186.706435 -218.478893) (xy 186.725695 -218.428536) (xy 186.752081 -218.381519) (xy 186.785033 -218.338846)
			(xy 186.823846 -218.301425) (xy 186.867694 -218.270055) (xy 186.915642 -218.245403) (xy 186.966669 -218.227995)
			(xy 187.019687 -218.218202) (xy 187.073566 -218.216233) (xy 187.127157 -218.22213) (xy 187.179318 -218.235766)
			(xy 187.228938 -218.256853) (xy 187.274959 -218.284939) (xy 187.316401 -218.319427) (xy 187.352379 -218.359581)
			(xy 187.382127 -218.404545) (xy 187.405012 -218.453362) (xy 187.420544 -218.504991) (xy 187.428394 -218.558331)
			(xy 187.428886 -218.585288) (xy 194.234831 -218.585288) (xy 194.238766 -218.531517) (xy 194.250489 -218.478893)
			(xy 194.269749 -218.428536) (xy 194.296135 -218.381519) (xy 194.329087 -218.338846) (xy 194.3679 -218.301425)
			(xy 194.411748 -218.270055) (xy 194.459696 -218.245403) (xy 194.510723 -218.227995) (xy 194.563741 -218.218202)
			(xy 194.61762 -218.216233) (xy 194.671211 -218.22213) (xy 194.723372 -218.235766) (xy 194.772992 -218.256853)
			(xy 194.819013 -218.284939) (xy 194.860455 -218.319427) (xy 194.896433 -218.359581) (xy 194.926181 -218.404545)
			(xy 194.949066 -218.453362) (xy 194.964598 -218.504991) (xy 194.972448 -218.558331) (xy 194.97294 -218.585288)
			(xy 201.778631 -218.585288) (xy 201.782566 -218.531517) (xy 201.794289 -218.478893) (xy 201.813549 -218.428536)
			(xy 201.839935 -218.381519) (xy 201.872887 -218.338846) (xy 201.9117 -218.301425) (xy 201.955548 -218.270055)
			(xy 202.003496 -218.245403) (xy 202.054523 -218.227995) (xy 202.107541 -218.218202) (xy 202.16142 -218.216233)
			(xy 202.215011 -218.22213) (xy 202.267172 -218.235766) (xy 202.316792 -218.256853) (xy 202.362813 -218.284939)
			(xy 202.404255 -218.319427) (xy 202.440233 -218.359581) (xy 202.469981 -218.404545) (xy 202.492866 -218.453362)
			(xy 202.508398 -218.504991) (xy 202.516248 -218.558331) (xy 202.51674 -218.585288) (xy 202.516248 -218.612245)
			(xy 202.508398 -218.665585) (xy 202.492866 -218.717214) (xy 202.469981 -218.766031) (xy 202.440233 -218.810995)
			(xy 202.404255 -218.851149) (xy 202.362813 -218.885637) (xy 202.316792 -218.913723) (xy 202.267172 -218.93481)
			(xy 202.215011 -218.948446) (xy 202.16142 -218.954343) (xy 202.107541 -218.952374) (xy 202.054523 -218.942581)
			(xy 202.003496 -218.925173) (xy 201.955548 -218.900521) (xy 201.9117 -218.869151) (xy 201.872887 -218.83173)
			(xy 201.839935 -218.789057) (xy 201.813549 -218.74204) (xy 201.794289 -218.691683) (xy 201.782566 -218.639059)
			(xy 201.778631 -218.585288) (xy 194.97294 -218.585288) (xy 194.972448 -218.612245) (xy 194.964598 -218.665585)
			(xy 194.949066 -218.717214) (xy 194.926181 -218.766031) (xy 194.896433 -218.810995) (xy 194.860455 -218.851149)
			(xy 194.819013 -218.885637) (xy 194.772992 -218.913723) (xy 194.723372 -218.93481) (xy 194.671211 -218.948446)
			(xy 194.61762 -218.954343) (xy 194.563741 -218.952374) (xy 194.510723 -218.942581) (xy 194.459696 -218.925173)
			(xy 194.411748 -218.900521) (xy 194.3679 -218.869151) (xy 194.329087 -218.83173) (xy 194.296135 -218.789057)
			(xy 194.269749 -218.74204) (xy 194.250489 -218.691683) (xy 194.238766 -218.639059) (xy 194.234831 -218.585288)
			(xy 187.428886 -218.585288) (xy 187.428394 -218.612245) (xy 187.420544 -218.665585) (xy 187.405012 -218.717214)
			(xy 187.382127 -218.766031) (xy 187.352379 -218.810995) (xy 187.316401 -218.851149) (xy 187.274959 -218.885637)
			(xy 187.228938 -218.913723) (xy 187.179318 -218.93481) (xy 187.127157 -218.948446) (xy 187.073566 -218.954343)
			(xy 187.019687 -218.952374) (xy 186.966669 -218.942581) (xy 186.915642 -218.925173) (xy 186.867694 -218.900521)
			(xy 186.823846 -218.869151) (xy 186.785033 -218.83173) (xy 186.752081 -218.789057) (xy 186.725695 -218.74204)
			(xy 186.706435 -218.691683) (xy 186.694712 -218.639059) (xy 186.690777 -218.585288) (xy 179.884832 -218.585288)
			(xy 179.88434 -218.612245) (xy 179.87649 -218.665585) (xy 179.860958 -218.717214) (xy 179.838073 -218.766031)
			(xy 179.808325 -218.810995) (xy 179.772347 -218.851149) (xy 179.730905 -218.885637) (xy 179.684884 -218.913723)
			(xy 179.635264 -218.93481) (xy 179.583103 -218.948446) (xy 179.529512 -218.954343) (xy 179.475633 -218.952374)
			(xy 179.422615 -218.942581) (xy 179.371588 -218.925173) (xy 179.32364 -218.900521) (xy 179.279792 -218.869151)
			(xy 179.240979 -218.83173) (xy 179.208027 -218.789057) (xy 179.181641 -218.74204) (xy 179.162381 -218.691683)
			(xy 179.150658 -218.639059) (xy 179.146723 -218.585288) (xy 177.881534 -218.585288) (xy 177.881534 -219.435426)
			(xy 183.246791 -219.435426) (xy 183.250726 -219.381655) (xy 183.262449 -219.329031) (xy 183.281709 -219.278674)
			(xy 183.308095 -219.231657) (xy 183.341047 -219.188984) (xy 183.37986 -219.151563) (xy 183.423708 -219.120193)
			(xy 183.471656 -219.095541) (xy 183.522683 -219.078133) (xy 183.575701 -219.06834) (xy 183.62958 -219.066371)
			(xy 183.683171 -219.072268) (xy 183.735332 -219.085904) (xy 183.784952 -219.106991) (xy 183.830973 -219.135077)
			(xy 183.872415 -219.169565) (xy 183.908393 -219.209719) (xy 183.938141 -219.254683) (xy 183.961026 -219.3035)
			(xy 183.976558 -219.355129) (xy 183.984408 -219.408469) (xy 183.9849 -219.435426) (xy 190.790845 -219.435426)
			(xy 190.79478 -219.381655) (xy 190.806503 -219.329031) (xy 190.825763 -219.278674) (xy 190.852149 -219.231657)
			(xy 190.885101 -219.188984) (xy 190.923914 -219.151563) (xy 190.967762 -219.120193) (xy 191.01571 -219.095541)
			(xy 191.066737 -219.078133) (xy 191.119755 -219.06834) (xy 191.173634 -219.066371) (xy 191.227225 -219.072268)
			(xy 191.279386 -219.085904) (xy 191.329006 -219.106991) (xy 191.375027 -219.135077) (xy 191.416469 -219.169565)
			(xy 191.452447 -219.209719) (xy 191.482195 -219.254683) (xy 191.50508 -219.3035) (xy 191.520612 -219.355129)
			(xy 191.528462 -219.408469) (xy 191.528954 -219.435426) (xy 198.334899 -219.435426) (xy 198.338834 -219.381655)
			(xy 198.350557 -219.329031) (xy 198.369817 -219.278674) (xy 198.396203 -219.231657) (xy 198.429155 -219.188984)
			(xy 198.467968 -219.151563) (xy 198.511816 -219.120193) (xy 198.559764 -219.095541) (xy 198.610791 -219.078133)
			(xy 198.663809 -219.06834) (xy 198.717688 -219.066371) (xy 198.771279 -219.072268) (xy 198.82344 -219.085904)
			(xy 198.87306 -219.106991) (xy 198.919081 -219.135077) (xy 198.960523 -219.169565) (xy 198.996501 -219.209719)
			(xy 199.026249 -219.254683) (xy 199.049134 -219.3035) (xy 199.064666 -219.355129) (xy 199.072516 -219.408469)
			(xy 199.073008 -219.435426) (xy 205.878699 -219.435426) (xy 205.882634 -219.381655) (xy 205.894357 -219.329031)
			(xy 205.913617 -219.278674) (xy 205.940003 -219.231657) (xy 205.972955 -219.188984) (xy 206.011768 -219.151563)
			(xy 206.055616 -219.120193) (xy 206.103564 -219.095541) (xy 206.154591 -219.078133) (xy 206.207609 -219.06834)
			(xy 206.261488 -219.066371) (xy 206.315079 -219.072268) (xy 206.36724 -219.085904) (xy 206.41686 -219.106991)
			(xy 206.462881 -219.135077) (xy 206.504323 -219.169565) (xy 206.540301 -219.209719) (xy 206.570049 -219.254683)
			(xy 206.592934 -219.3035) (xy 206.608466 -219.355129) (xy 206.616316 -219.408469) (xy 206.616808 -219.435426)
			(xy 206.616316 -219.462383) (xy 206.608466 -219.515723) (xy 206.592934 -219.567352) (xy 206.570049 -219.616169)
			(xy 206.540301 -219.661133) (xy 206.504323 -219.701287) (xy 206.462881 -219.735775) (xy 206.41686 -219.763861)
			(xy 206.36724 -219.784948) (xy 206.315079 -219.798584) (xy 206.261488 -219.804481) (xy 206.207609 -219.802512)
			(xy 206.154591 -219.792719) (xy 206.103564 -219.775311) (xy 206.055616 -219.750659) (xy 206.011768 -219.719289)
			(xy 205.972955 -219.681868) (xy 205.940003 -219.639195) (xy 205.913617 -219.592178) (xy 205.894357 -219.541821)
			(xy 205.882634 -219.489197) (xy 205.878699 -219.435426) (xy 199.073008 -219.435426) (xy 199.072516 -219.462383)
			(xy 199.064666 -219.515723) (xy 199.049134 -219.567352) (xy 199.026249 -219.616169) (xy 198.996501 -219.661133)
			(xy 198.960523 -219.701287) (xy 198.919081 -219.735775) (xy 198.87306 -219.763861) (xy 198.82344 -219.784948)
			(xy 198.771279 -219.798584) (xy 198.717688 -219.804481) (xy 198.663809 -219.802512) (xy 198.610791 -219.792719)
			(xy 198.559764 -219.775311) (xy 198.511816 -219.750659) (xy 198.467968 -219.719289) (xy 198.429155 -219.681868)
			(xy 198.396203 -219.639195) (xy 198.369817 -219.592178) (xy 198.350557 -219.541821) (xy 198.338834 -219.489197)
			(xy 198.334899 -219.435426) (xy 191.528954 -219.435426) (xy 191.528462 -219.462383) (xy 191.520612 -219.515723)
			(xy 191.50508 -219.567352) (xy 191.482195 -219.616169) (xy 191.452447 -219.661133) (xy 191.416469 -219.701287)
			(xy 191.375027 -219.735775) (xy 191.329006 -219.763861) (xy 191.279386 -219.784948) (xy 191.227225 -219.798584)
			(xy 191.173634 -219.804481) (xy 191.119755 -219.802512) (xy 191.066737 -219.792719) (xy 191.01571 -219.775311)
			(xy 190.967762 -219.750659) (xy 190.923914 -219.719289) (xy 190.885101 -219.681868) (xy 190.852149 -219.639195)
			(xy 190.825763 -219.592178) (xy 190.806503 -219.541821) (xy 190.79478 -219.489197) (xy 190.790845 -219.435426)
			(xy 183.9849 -219.435426) (xy 183.984408 -219.462383) (xy 183.976558 -219.515723) (xy 183.961026 -219.567352)
			(xy 183.938141 -219.616169) (xy 183.908393 -219.661133) (xy 183.872415 -219.701287) (xy 183.830973 -219.735775)
			(xy 183.784952 -219.763861) (xy 183.735332 -219.784948) (xy 183.683171 -219.798584) (xy 183.62958 -219.804481)
			(xy 183.575701 -219.802512) (xy 183.522683 -219.792719) (xy 183.471656 -219.775311) (xy 183.423708 -219.750659)
			(xy 183.37986 -219.719289) (xy 183.341047 -219.681868) (xy 183.308095 -219.639195) (xy 183.281709 -219.592178)
			(xy 183.262449 -219.541821) (xy 183.250726 -219.489197) (xy 183.246791 -219.435426) (xy 177.881534 -219.435426)
			(xy 177.881534 -220.28531) (xy 179.146723 -220.28531) (xy 179.150658 -220.231539) (xy 179.162381 -220.178915)
			(xy 179.181641 -220.128558) (xy 179.208027 -220.081541) (xy 179.240979 -220.038868) (xy 179.279792 -220.001447)
			(xy 179.32364 -219.970077) (xy 179.371588 -219.945425) (xy 179.422615 -219.928017) (xy 179.475633 -219.918224)
			(xy 179.529512 -219.916255) (xy 179.583103 -219.922152) (xy 179.635264 -219.935788) (xy 179.684884 -219.956875)
			(xy 179.730905 -219.984961) (xy 179.772347 -220.019449) (xy 179.808325 -220.059603) (xy 179.838073 -220.104567)
			(xy 179.860958 -220.153384) (xy 179.87649 -220.205013) (xy 179.88434 -220.258353) (xy 179.884832 -220.28531)
			(xy 183.246791 -220.28531) (xy 183.250726 -220.231539) (xy 183.262449 -220.178915) (xy 183.281709 -220.128558)
			(xy 183.308095 -220.081541) (xy 183.341047 -220.038868) (xy 183.37986 -220.001447) (xy 183.423708 -219.970077)
			(xy 183.471656 -219.945425) (xy 183.522683 -219.928017) (xy 183.575701 -219.918224) (xy 183.62958 -219.916255)
			(xy 183.683171 -219.922152) (xy 183.735332 -219.935788) (xy 183.784952 -219.956875) (xy 183.830973 -219.984961)
			(xy 183.872415 -220.019449) (xy 183.908393 -220.059603) (xy 183.938141 -220.104567) (xy 183.961026 -220.153384)
			(xy 183.976558 -220.205013) (xy 183.984408 -220.258353) (xy 183.9849 -220.28531) (xy 186.690777 -220.28531)
			(xy 186.694712 -220.231539) (xy 186.706435 -220.178915) (xy 186.725695 -220.128558) (xy 186.752081 -220.081541)
			(xy 186.785033 -220.038868) (xy 186.823846 -220.001447) (xy 186.867694 -219.970077) (xy 186.915642 -219.945425)
			(xy 186.966669 -219.928017) (xy 187.019687 -219.918224) (xy 187.073566 -219.916255) (xy 187.127157 -219.922152)
			(xy 187.179318 -219.935788) (xy 187.228938 -219.956875) (xy 187.274959 -219.984961) (xy 187.316401 -220.019449)
			(xy 187.352379 -220.059603) (xy 187.382127 -220.104567) (xy 187.405012 -220.153384) (xy 187.420544 -220.205013)
			(xy 187.428394 -220.258353) (xy 187.428886 -220.28531) (xy 190.790845 -220.28531) (xy 190.79478 -220.231539)
			(xy 190.806503 -220.178915) (xy 190.825763 -220.128558) (xy 190.852149 -220.081541) (xy 190.885101 -220.038868)
			(xy 190.923914 -220.001447) (xy 190.967762 -219.970077) (xy 191.01571 -219.945425) (xy 191.066737 -219.928017)
			(xy 191.119755 -219.918224) (xy 191.173634 -219.916255) (xy 191.227225 -219.922152) (xy 191.279386 -219.935788)
			(xy 191.329006 -219.956875) (xy 191.375027 -219.984961) (xy 191.416469 -220.019449) (xy 191.452447 -220.059603)
			(xy 191.482195 -220.104567) (xy 191.50508 -220.153384) (xy 191.520612 -220.205013) (xy 191.528462 -220.258353)
			(xy 191.528954 -220.28531) (xy 194.234831 -220.28531) (xy 194.238766 -220.231539) (xy 194.250489 -220.178915)
			(xy 194.269749 -220.128558) (xy 194.296135 -220.081541) (xy 194.329087 -220.038868) (xy 194.3679 -220.001447)
			(xy 194.411748 -219.970077) (xy 194.459696 -219.945425) (xy 194.510723 -219.928017) (xy 194.563741 -219.918224)
			(xy 194.61762 -219.916255) (xy 194.671211 -219.922152) (xy 194.723372 -219.935788) (xy 194.772992 -219.956875)
			(xy 194.819013 -219.984961) (xy 194.860455 -220.019449) (xy 194.896433 -220.059603) (xy 194.926181 -220.104567)
			(xy 194.949066 -220.153384) (xy 194.964598 -220.205013) (xy 194.972448 -220.258353) (xy 194.97294 -220.28531)
			(xy 198.334899 -220.28531) (xy 198.338834 -220.231539) (xy 198.350557 -220.178915) (xy 198.369817 -220.128558)
			(xy 198.396203 -220.081541) (xy 198.429155 -220.038868) (xy 198.467968 -220.001447) (xy 198.511816 -219.970077)
			(xy 198.559764 -219.945425) (xy 198.610791 -219.928017) (xy 198.663809 -219.918224) (xy 198.717688 -219.916255)
			(xy 198.771279 -219.922152) (xy 198.82344 -219.935788) (xy 198.87306 -219.956875) (xy 198.919081 -219.984961)
			(xy 198.960523 -220.019449) (xy 198.996501 -220.059603) (xy 199.026249 -220.104567) (xy 199.049134 -220.153384)
			(xy 199.064666 -220.205013) (xy 199.072516 -220.258353) (xy 199.073008 -220.28531) (xy 201.778631 -220.28531)
			(xy 201.782566 -220.231539) (xy 201.794289 -220.178915) (xy 201.813549 -220.128558) (xy 201.839935 -220.081541)
			(xy 201.872887 -220.038868) (xy 201.9117 -220.001447) (xy 201.955548 -219.970077) (xy 202.003496 -219.945425)
			(xy 202.054523 -219.928017) (xy 202.107541 -219.918224) (xy 202.16142 -219.916255) (xy 202.215011 -219.922152)
			(xy 202.267172 -219.935788) (xy 202.316792 -219.956875) (xy 202.362813 -219.984961) (xy 202.404255 -220.019449)
			(xy 202.440233 -220.059603) (xy 202.469981 -220.104567) (xy 202.492866 -220.153384) (xy 202.508398 -220.205013)
			(xy 202.516248 -220.258353) (xy 202.51674 -220.28531) (xy 205.878699 -220.28531) (xy 205.882634 -220.231539)
			(xy 205.894357 -220.178915) (xy 205.913617 -220.128558) (xy 205.940003 -220.081541) (xy 205.972955 -220.038868)
			(xy 206.011768 -220.001447) (xy 206.055616 -219.970077) (xy 206.103564 -219.945425) (xy 206.154591 -219.928017)
			(xy 206.207609 -219.918224) (xy 206.261488 -219.916255) (xy 206.315079 -219.922152) (xy 206.36724 -219.935788)
			(xy 206.41686 -219.956875) (xy 206.462881 -219.984961) (xy 206.504323 -220.019449) (xy 206.540301 -220.059603)
			(xy 206.570049 -220.104567) (xy 206.592934 -220.153384) (xy 206.608466 -220.205013) (xy 206.616316 -220.258353)
			(xy 206.616808 -220.28531) (xy 206.616316 -220.312267) (xy 206.608466 -220.365607) (xy 206.592934 -220.417236)
			(xy 206.570049 -220.466053) (xy 206.540301 -220.511017) (xy 206.504323 -220.551171) (xy 206.462881 -220.585659)
			(xy 206.41686 -220.613745) (xy 206.36724 -220.634832) (xy 206.315079 -220.648468) (xy 206.261488 -220.654365)
			(xy 206.207609 -220.652396) (xy 206.154591 -220.642603) (xy 206.103564 -220.625195) (xy 206.055616 -220.600543)
			(xy 206.011768 -220.569173) (xy 205.972955 -220.531752) (xy 205.940003 -220.489079) (xy 205.913617 -220.442062)
			(xy 205.894357 -220.391705) (xy 205.882634 -220.339081) (xy 205.878699 -220.28531) (xy 202.51674 -220.28531)
			(xy 202.516248 -220.312267) (xy 202.508398 -220.365607) (xy 202.492866 -220.417236) (xy 202.469981 -220.466053)
			(xy 202.440233 -220.511017) (xy 202.404255 -220.551171) (xy 202.362813 -220.585659) (xy 202.316792 -220.613745)
			(xy 202.267172 -220.634832) (xy 202.215011 -220.648468) (xy 202.16142 -220.654365) (xy 202.107541 -220.652396)
			(xy 202.054523 -220.642603) (xy 202.003496 -220.625195) (xy 201.955548 -220.600543) (xy 201.9117 -220.569173)
			(xy 201.872887 -220.531752) (xy 201.839935 -220.489079) (xy 201.813549 -220.442062) (xy 201.794289 -220.391705)
			(xy 201.782566 -220.339081) (xy 201.778631 -220.28531) (xy 199.073008 -220.28531) (xy 199.072516 -220.312267)
			(xy 199.064666 -220.365607) (xy 199.049134 -220.417236) (xy 199.026249 -220.466053) (xy 198.996501 -220.511017)
			(xy 198.960523 -220.551171) (xy 198.919081 -220.585659) (xy 198.87306 -220.613745) (xy 198.82344 -220.634832)
			(xy 198.771279 -220.648468) (xy 198.717688 -220.654365) (xy 198.663809 -220.652396) (xy 198.610791 -220.642603)
			(xy 198.559764 -220.625195) (xy 198.511816 -220.600543) (xy 198.467968 -220.569173) (xy 198.429155 -220.531752)
			(xy 198.396203 -220.489079) (xy 198.369817 -220.442062) (xy 198.350557 -220.391705) (xy 198.338834 -220.339081)
			(xy 198.334899 -220.28531) (xy 194.97294 -220.28531) (xy 194.972448 -220.312267) (xy 194.964598 -220.365607)
			(xy 194.949066 -220.417236) (xy 194.926181 -220.466053) (xy 194.896433 -220.511017) (xy 194.860455 -220.551171)
			(xy 194.819013 -220.585659) (xy 194.772992 -220.613745) (xy 194.723372 -220.634832) (xy 194.671211 -220.648468)
			(xy 194.61762 -220.654365) (xy 194.563741 -220.652396) (xy 194.510723 -220.642603) (xy 194.459696 -220.625195)
			(xy 194.411748 -220.600543) (xy 194.3679 -220.569173) (xy 194.329087 -220.531752) (xy 194.296135 -220.489079)
			(xy 194.269749 -220.442062) (xy 194.250489 -220.391705) (xy 194.238766 -220.339081) (xy 194.234831 -220.28531)
			(xy 191.528954 -220.28531) (xy 191.528462 -220.312267) (xy 191.520612 -220.365607) (xy 191.50508 -220.417236)
			(xy 191.482195 -220.466053) (xy 191.452447 -220.511017) (xy 191.416469 -220.551171) (xy 191.375027 -220.585659)
			(xy 191.329006 -220.613745) (xy 191.279386 -220.634832) (xy 191.227225 -220.648468) (xy 191.173634 -220.654365)
			(xy 191.119755 -220.652396) (xy 191.066737 -220.642603) (xy 191.01571 -220.625195) (xy 190.967762 -220.600543)
			(xy 190.923914 -220.569173) (xy 190.885101 -220.531752) (xy 190.852149 -220.489079) (xy 190.825763 -220.442062)
			(xy 190.806503 -220.391705) (xy 190.79478 -220.339081) (xy 190.790845 -220.28531) (xy 187.428886 -220.28531)
			(xy 187.428394 -220.312267) (xy 187.420544 -220.365607) (xy 187.405012 -220.417236) (xy 187.382127 -220.466053)
			(xy 187.352379 -220.511017) (xy 187.316401 -220.551171) (xy 187.274959 -220.585659) (xy 187.228938 -220.613745)
			(xy 187.179318 -220.634832) (xy 187.127157 -220.648468) (xy 187.073566 -220.654365) (xy 187.019687 -220.652396)
			(xy 186.966669 -220.642603) (xy 186.915642 -220.625195) (xy 186.867694 -220.600543) (xy 186.823846 -220.569173)
			(xy 186.785033 -220.531752) (xy 186.752081 -220.489079) (xy 186.725695 -220.442062) (xy 186.706435 -220.391705)
			(xy 186.694712 -220.339081) (xy 186.690777 -220.28531) (xy 183.9849 -220.28531) (xy 183.984408 -220.312267)
			(xy 183.976558 -220.365607) (xy 183.961026 -220.417236) (xy 183.938141 -220.466053) (xy 183.908393 -220.511017)
			(xy 183.872415 -220.551171) (xy 183.830973 -220.585659) (xy 183.784952 -220.613745) (xy 183.735332 -220.634832)
			(xy 183.683171 -220.648468) (xy 183.62958 -220.654365) (xy 183.575701 -220.652396) (xy 183.522683 -220.642603)
			(xy 183.471656 -220.625195) (xy 183.423708 -220.600543) (xy 183.37986 -220.569173) (xy 183.341047 -220.531752)
			(xy 183.308095 -220.489079) (xy 183.281709 -220.442062) (xy 183.262449 -220.391705) (xy 183.250726 -220.339081)
			(xy 183.246791 -220.28531) (xy 179.884832 -220.28531) (xy 179.88434 -220.312267) (xy 179.87649 -220.365607)
			(xy 179.860958 -220.417236) (xy 179.838073 -220.466053) (xy 179.808325 -220.511017) (xy 179.772347 -220.551171)
			(xy 179.730905 -220.585659) (xy 179.684884 -220.613745) (xy 179.635264 -220.634832) (xy 179.583103 -220.648468)
			(xy 179.529512 -220.654365) (xy 179.475633 -220.652396) (xy 179.422615 -220.642603) (xy 179.371588 -220.625195)
			(xy 179.32364 -220.600543) (xy 179.279792 -220.569173) (xy 179.240979 -220.531752) (xy 179.208027 -220.489079)
			(xy 179.181641 -220.442062) (xy 179.162381 -220.391705) (xy 179.150658 -220.339081) (xy 179.146723 -220.28531)
			(xy 177.881534 -220.28531) (xy 177.881534 -221.135194) (xy 179.146723 -221.135194) (xy 179.150658 -221.081423)
			(xy 179.162381 -221.028799) (xy 179.181641 -220.978442) (xy 179.208027 -220.931425) (xy 179.240979 -220.888752)
			(xy 179.279792 -220.851331) (xy 179.32364 -220.819961) (xy 179.371588 -220.795309) (xy 179.422615 -220.777901)
			(xy 179.475633 -220.768108) (xy 179.529512 -220.766139) (xy 179.583103 -220.772036) (xy 179.635264 -220.785672)
			(xy 179.684884 -220.806759) (xy 179.730905 -220.834845) (xy 179.772347 -220.869333) (xy 179.808325 -220.909487)
			(xy 179.838073 -220.954451) (xy 179.860958 -221.003268) (xy 179.87649 -221.054897) (xy 179.88434 -221.108237)
			(xy 179.884832 -221.135194) (xy 186.690777 -221.135194) (xy 186.694712 -221.081423) (xy 186.706435 -221.028799)
			(xy 186.725695 -220.978442) (xy 186.752081 -220.931425) (xy 186.785033 -220.888752) (xy 186.823846 -220.851331)
			(xy 186.867694 -220.819961) (xy 186.915642 -220.795309) (xy 186.966669 -220.777901) (xy 187.019687 -220.768108)
			(xy 187.073566 -220.766139) (xy 187.127157 -220.772036) (xy 187.179318 -220.785672) (xy 187.228938 -220.806759)
			(xy 187.274959 -220.834845) (xy 187.316401 -220.869333) (xy 187.352379 -220.909487) (xy 187.382127 -220.954451)
			(xy 187.405012 -221.003268) (xy 187.420544 -221.054897) (xy 187.428394 -221.108237) (xy 187.428886 -221.135194)
			(xy 194.234831 -221.135194) (xy 194.238766 -221.081423) (xy 194.250489 -221.028799) (xy 194.269749 -220.978442)
			(xy 194.296135 -220.931425) (xy 194.329087 -220.888752) (xy 194.3679 -220.851331) (xy 194.411748 -220.819961)
			(xy 194.459696 -220.795309) (xy 194.510723 -220.777901) (xy 194.563741 -220.768108) (xy 194.61762 -220.766139)
			(xy 194.671211 -220.772036) (xy 194.723372 -220.785672) (xy 194.772992 -220.806759) (xy 194.819013 -220.834845)
			(xy 194.860455 -220.869333) (xy 194.896433 -220.909487) (xy 194.926181 -220.954451) (xy 194.949066 -221.003268)
			(xy 194.964598 -221.054897) (xy 194.972448 -221.108237) (xy 194.97294 -221.135194) (xy 201.778631 -221.135194)
			(xy 201.782566 -221.081423) (xy 201.794289 -221.028799) (xy 201.813549 -220.978442) (xy 201.839935 -220.931425)
			(xy 201.872887 -220.888752) (xy 201.9117 -220.851331) (xy 201.955548 -220.819961) (xy 202.003496 -220.795309)
			(xy 202.054523 -220.777901) (xy 202.107541 -220.768108) (xy 202.16142 -220.766139) (xy 202.215011 -220.772036)
			(xy 202.267172 -220.785672) (xy 202.316792 -220.806759) (xy 202.362813 -220.834845) (xy 202.404255 -220.869333)
			(xy 202.440233 -220.909487) (xy 202.469981 -220.954451) (xy 202.492866 -221.003268) (xy 202.508398 -221.054897)
			(xy 202.516248 -221.108237) (xy 202.51674 -221.135194) (xy 202.516248 -221.162151) (xy 202.508398 -221.215491)
			(xy 202.492866 -221.26712) (xy 202.469981 -221.315937) (xy 202.440233 -221.360901) (xy 202.404255 -221.401055)
			(xy 202.362813 -221.435543) (xy 202.316792 -221.463629) (xy 202.267172 -221.484716) (xy 202.215011 -221.498352)
			(xy 202.16142 -221.504249) (xy 202.107541 -221.50228) (xy 202.054523 -221.492487) (xy 202.003496 -221.475079)
			(xy 201.955548 -221.450427) (xy 201.9117 -221.419057) (xy 201.872887 -221.381636) (xy 201.839935 -221.338963)
			(xy 201.813549 -221.291946) (xy 201.794289 -221.241589) (xy 201.782566 -221.188965) (xy 201.778631 -221.135194)
			(xy 194.97294 -221.135194) (xy 194.972448 -221.162151) (xy 194.964598 -221.215491) (xy 194.949066 -221.26712)
			(xy 194.926181 -221.315937) (xy 194.896433 -221.360901) (xy 194.860455 -221.401055) (xy 194.819013 -221.435543)
			(xy 194.772992 -221.463629) (xy 194.723372 -221.484716) (xy 194.671211 -221.498352) (xy 194.61762 -221.504249)
			(xy 194.563741 -221.50228) (xy 194.510723 -221.492487) (xy 194.459696 -221.475079) (xy 194.411748 -221.450427)
			(xy 194.3679 -221.419057) (xy 194.329087 -221.381636) (xy 194.296135 -221.338963) (xy 194.269749 -221.291946)
			(xy 194.250489 -221.241589) (xy 194.238766 -221.188965) (xy 194.234831 -221.135194) (xy 187.428886 -221.135194)
			(xy 187.428394 -221.162151) (xy 187.420544 -221.215491) (xy 187.405012 -221.26712) (xy 187.382127 -221.315937)
			(xy 187.352379 -221.360901) (xy 187.316401 -221.401055) (xy 187.274959 -221.435543) (xy 187.228938 -221.463629)
			(xy 187.179318 -221.484716) (xy 187.127157 -221.498352) (xy 187.073566 -221.504249) (xy 187.019687 -221.50228)
			(xy 186.966669 -221.492487) (xy 186.915642 -221.475079) (xy 186.867694 -221.450427) (xy 186.823846 -221.419057)
			(xy 186.785033 -221.381636) (xy 186.752081 -221.338963) (xy 186.725695 -221.291946) (xy 186.706435 -221.241589)
			(xy 186.694712 -221.188965) (xy 186.690777 -221.135194) (xy 179.884832 -221.135194) (xy 179.88434 -221.162151)
			(xy 179.87649 -221.215491) (xy 179.860958 -221.26712) (xy 179.838073 -221.315937) (xy 179.808325 -221.360901)
			(xy 179.772347 -221.401055) (xy 179.730905 -221.435543) (xy 179.684884 -221.463629) (xy 179.635264 -221.484716)
			(xy 179.583103 -221.498352) (xy 179.529512 -221.504249) (xy 179.475633 -221.50228) (xy 179.422615 -221.492487)
			(xy 179.371588 -221.475079) (xy 179.32364 -221.450427) (xy 179.279792 -221.419057) (xy 179.240979 -221.381636)
			(xy 179.208027 -221.338963) (xy 179.181641 -221.291946) (xy 179.162381 -221.241589) (xy 179.150658 -221.188965)
			(xy 179.146723 -221.135194) (xy 177.881534 -221.135194) (xy 177.881534 -221.985332) (xy 183.246791 -221.985332)
			(xy 183.250726 -221.931561) (xy 183.262449 -221.878937) (xy 183.281709 -221.82858) (xy 183.308095 -221.781563)
			(xy 183.341047 -221.73889) (xy 183.37986 -221.701469) (xy 183.423708 -221.670099) (xy 183.471656 -221.645447)
			(xy 183.522683 -221.628039) (xy 183.575701 -221.618246) (xy 183.62958 -221.616277) (xy 183.683171 -221.622174)
			(xy 183.735332 -221.63581) (xy 183.784952 -221.656897) (xy 183.830973 -221.684983) (xy 183.872415 -221.719471)
			(xy 183.908393 -221.759625) (xy 183.938141 -221.804589) (xy 183.961026 -221.853406) (xy 183.976558 -221.905035)
			(xy 183.984408 -221.958375) (xy 183.9849 -221.985332) (xy 190.790845 -221.985332) (xy 190.79478 -221.931561)
			(xy 190.806503 -221.878937) (xy 190.825763 -221.82858) (xy 190.852149 -221.781563) (xy 190.885101 -221.73889)
			(xy 190.923914 -221.701469) (xy 190.967762 -221.670099) (xy 191.01571 -221.645447) (xy 191.066737 -221.628039)
			(xy 191.119755 -221.618246) (xy 191.173634 -221.616277) (xy 191.227225 -221.622174) (xy 191.279386 -221.63581)
			(xy 191.329006 -221.656897) (xy 191.375027 -221.684983) (xy 191.416469 -221.719471) (xy 191.452447 -221.759625)
			(xy 191.482195 -221.804589) (xy 191.50508 -221.853406) (xy 191.520612 -221.905035) (xy 191.528462 -221.958375)
			(xy 191.528954 -221.985332) (xy 198.334899 -221.985332) (xy 198.338834 -221.931561) (xy 198.350557 -221.878937)
			(xy 198.369817 -221.82858) (xy 198.396203 -221.781563) (xy 198.429155 -221.73889) (xy 198.467968 -221.701469)
			(xy 198.511816 -221.670099) (xy 198.559764 -221.645447) (xy 198.610791 -221.628039) (xy 198.663809 -221.618246)
			(xy 198.717688 -221.616277) (xy 198.771279 -221.622174) (xy 198.82344 -221.63581) (xy 198.87306 -221.656897)
			(xy 198.919081 -221.684983) (xy 198.960523 -221.719471) (xy 198.996501 -221.759625) (xy 199.026249 -221.804589)
			(xy 199.049134 -221.853406) (xy 199.064666 -221.905035) (xy 199.072516 -221.958375) (xy 199.073008 -221.985332)
			(xy 205.878699 -221.985332) (xy 205.882634 -221.931561) (xy 205.894357 -221.878937) (xy 205.913617 -221.82858)
			(xy 205.940003 -221.781563) (xy 205.972955 -221.73889) (xy 206.011768 -221.701469) (xy 206.055616 -221.670099)
			(xy 206.103564 -221.645447) (xy 206.154591 -221.628039) (xy 206.207609 -221.618246) (xy 206.261488 -221.616277)
			(xy 206.315079 -221.622174) (xy 206.36724 -221.63581) (xy 206.41686 -221.656897) (xy 206.462881 -221.684983)
			(xy 206.504323 -221.719471) (xy 206.540301 -221.759625) (xy 206.570049 -221.804589) (xy 206.592934 -221.853406)
			(xy 206.608466 -221.905035) (xy 206.616316 -221.958375) (xy 206.616808 -221.985332) (xy 206.616316 -222.012289)
			(xy 206.608466 -222.065629) (xy 206.592934 -222.117258) (xy 206.570049 -222.166075) (xy 206.540301 -222.211039)
			(xy 206.504323 -222.251193) (xy 206.462881 -222.285681) (xy 206.41686 -222.313767) (xy 206.36724 -222.334854)
			(xy 206.315079 -222.34849) (xy 206.261488 -222.354387) (xy 206.207609 -222.352418) (xy 206.154591 -222.342625)
			(xy 206.103564 -222.325217) (xy 206.055616 -222.300565) (xy 206.011768 -222.269195) (xy 205.972955 -222.231774)
			(xy 205.940003 -222.189101) (xy 205.913617 -222.142084) (xy 205.894357 -222.091727) (xy 205.882634 -222.039103)
			(xy 205.878699 -221.985332) (xy 199.073008 -221.985332) (xy 199.072516 -222.012289) (xy 199.064666 -222.065629)
			(xy 199.049134 -222.117258) (xy 199.026249 -222.166075) (xy 198.996501 -222.211039) (xy 198.960523 -222.251193)
			(xy 198.919081 -222.285681) (xy 198.87306 -222.313767) (xy 198.82344 -222.334854) (xy 198.771279 -222.34849)
			(xy 198.717688 -222.354387) (xy 198.663809 -222.352418) (xy 198.610791 -222.342625) (xy 198.559764 -222.325217)
			(xy 198.511816 -222.300565) (xy 198.467968 -222.269195) (xy 198.429155 -222.231774) (xy 198.396203 -222.189101)
			(xy 198.369817 -222.142084) (xy 198.350557 -222.091727) (xy 198.338834 -222.039103) (xy 198.334899 -221.985332)
			(xy 191.528954 -221.985332) (xy 191.528462 -222.012289) (xy 191.520612 -222.065629) (xy 191.50508 -222.117258)
			(xy 191.482195 -222.166075) (xy 191.452447 -222.211039) (xy 191.416469 -222.251193) (xy 191.375027 -222.285681)
			(xy 191.329006 -222.313767) (xy 191.279386 -222.334854) (xy 191.227225 -222.34849) (xy 191.173634 -222.354387)
			(xy 191.119755 -222.352418) (xy 191.066737 -222.342625) (xy 191.01571 -222.325217) (xy 190.967762 -222.300565)
			(xy 190.923914 -222.269195) (xy 190.885101 -222.231774) (xy 190.852149 -222.189101) (xy 190.825763 -222.142084)
			(xy 190.806503 -222.091727) (xy 190.79478 -222.039103) (xy 190.790845 -221.985332) (xy 183.9849 -221.985332)
			(xy 183.984408 -222.012289) (xy 183.976558 -222.065629) (xy 183.961026 -222.117258) (xy 183.938141 -222.166075)
			(xy 183.908393 -222.211039) (xy 183.872415 -222.251193) (xy 183.830973 -222.285681) (xy 183.784952 -222.313767)
			(xy 183.735332 -222.334854) (xy 183.683171 -222.34849) (xy 183.62958 -222.354387) (xy 183.575701 -222.352418)
			(xy 183.522683 -222.342625) (xy 183.471656 -222.325217) (xy 183.423708 -222.300565) (xy 183.37986 -222.269195)
			(xy 183.341047 -222.231774) (xy 183.308095 -222.189101) (xy 183.281709 -222.142084) (xy 183.262449 -222.091727)
			(xy 183.250726 -222.039103) (xy 183.246791 -221.985332) (xy 177.881534 -221.985332) (xy 177.881534 -222.835216)
			(xy 179.146723 -222.835216) (xy 179.150658 -222.781445) (xy 179.162381 -222.728821) (xy 179.181641 -222.678464)
			(xy 179.208027 -222.631447) (xy 179.240979 -222.588774) (xy 179.279792 -222.551353) (xy 179.32364 -222.519983)
			(xy 179.371588 -222.495331) (xy 179.422615 -222.477923) (xy 179.475633 -222.46813) (xy 179.529512 -222.466161)
			(xy 179.583103 -222.472058) (xy 179.635264 -222.485694) (xy 179.684884 -222.506781) (xy 179.730905 -222.534867)
			(xy 179.772347 -222.569355) (xy 179.808325 -222.609509) (xy 179.838073 -222.654473) (xy 179.860958 -222.70329)
			(xy 179.87649 -222.754919) (xy 179.88434 -222.808259) (xy 179.884832 -222.835216) (xy 186.690777 -222.835216)
			(xy 186.694712 -222.781445) (xy 186.706435 -222.728821) (xy 186.725695 -222.678464) (xy 186.752081 -222.631447)
			(xy 186.785033 -222.588774) (xy 186.823846 -222.551353) (xy 186.867694 -222.519983) (xy 186.915642 -222.495331)
			(xy 186.966669 -222.477923) (xy 187.019687 -222.46813) (xy 187.073566 -222.466161) (xy 187.127157 -222.472058)
			(xy 187.179318 -222.485694) (xy 187.228938 -222.506781) (xy 187.274959 -222.534867) (xy 187.316401 -222.569355)
			(xy 187.352379 -222.609509) (xy 187.382127 -222.654473) (xy 187.405012 -222.70329) (xy 187.420544 -222.754919)
			(xy 187.428394 -222.808259) (xy 187.428886 -222.835216) (xy 194.234831 -222.835216) (xy 194.238766 -222.781445)
			(xy 194.250489 -222.728821) (xy 194.269749 -222.678464) (xy 194.296135 -222.631447) (xy 194.329087 -222.588774)
			(xy 194.3679 -222.551353) (xy 194.411748 -222.519983) (xy 194.459696 -222.495331) (xy 194.510723 -222.477923)
			(xy 194.563741 -222.46813) (xy 194.61762 -222.466161) (xy 194.671211 -222.472058) (xy 194.723372 -222.485694)
			(xy 194.772992 -222.506781) (xy 194.819013 -222.534867) (xy 194.860455 -222.569355) (xy 194.896433 -222.609509)
			(xy 194.926181 -222.654473) (xy 194.949066 -222.70329) (xy 194.964598 -222.754919) (xy 194.972448 -222.808259)
			(xy 194.97294 -222.835216) (xy 201.778631 -222.835216) (xy 201.782566 -222.781445) (xy 201.794289 -222.728821)
			(xy 201.813549 -222.678464) (xy 201.839935 -222.631447) (xy 201.872887 -222.588774) (xy 201.9117 -222.551353)
			(xy 201.955548 -222.519983) (xy 202.003496 -222.495331) (xy 202.054523 -222.477923) (xy 202.107541 -222.46813)
			(xy 202.16142 -222.466161) (xy 202.215011 -222.472058) (xy 202.267172 -222.485694) (xy 202.316792 -222.506781)
			(xy 202.362813 -222.534867) (xy 202.404255 -222.569355) (xy 202.440233 -222.609509) (xy 202.469981 -222.654473)
			(xy 202.492866 -222.70329) (xy 202.508398 -222.754919) (xy 202.516248 -222.808259) (xy 202.51674 -222.835216)
			(xy 202.516248 -222.862173) (xy 202.508398 -222.915513) (xy 202.492866 -222.967142) (xy 202.469981 -223.015959)
			(xy 202.440233 -223.060923) (xy 202.404255 -223.101077) (xy 202.362813 -223.135565) (xy 202.316792 -223.163651)
			(xy 202.267172 -223.184738) (xy 202.215011 -223.198374) (xy 202.16142 -223.204271) (xy 202.107541 -223.202302)
			(xy 202.054523 -223.192509) (xy 202.003496 -223.175101) (xy 201.955548 -223.150449) (xy 201.9117 -223.119079)
			(xy 201.872887 -223.081658) (xy 201.839935 -223.038985) (xy 201.813549 -222.991968) (xy 201.794289 -222.941611)
			(xy 201.782566 -222.888987) (xy 201.778631 -222.835216) (xy 194.97294 -222.835216) (xy 194.972448 -222.862173)
			(xy 194.964598 -222.915513) (xy 194.949066 -222.967142) (xy 194.926181 -223.015959) (xy 194.896433 -223.060923)
			(xy 194.860455 -223.101077) (xy 194.819013 -223.135565) (xy 194.772992 -223.163651) (xy 194.723372 -223.184738)
			(xy 194.671211 -223.198374) (xy 194.61762 -223.204271) (xy 194.563741 -223.202302) (xy 194.510723 -223.192509)
			(xy 194.459696 -223.175101) (xy 194.411748 -223.150449) (xy 194.3679 -223.119079) (xy 194.329087 -223.081658)
			(xy 194.296135 -223.038985) (xy 194.269749 -222.991968) (xy 194.250489 -222.941611) (xy 194.238766 -222.888987)
			(xy 194.234831 -222.835216) (xy 187.428886 -222.835216) (xy 187.428394 -222.862173) (xy 187.420544 -222.915513)
			(xy 187.405012 -222.967142) (xy 187.382127 -223.015959) (xy 187.352379 -223.060923) (xy 187.316401 -223.101077)
			(xy 187.274959 -223.135565) (xy 187.228938 -223.163651) (xy 187.179318 -223.184738) (xy 187.127157 -223.198374)
			(xy 187.073566 -223.204271) (xy 187.019687 -223.202302) (xy 186.966669 -223.192509) (xy 186.915642 -223.175101)
			(xy 186.867694 -223.150449) (xy 186.823846 -223.119079) (xy 186.785033 -223.081658) (xy 186.752081 -223.038985)
			(xy 186.725695 -222.991968) (xy 186.706435 -222.941611) (xy 186.694712 -222.888987) (xy 186.690777 -222.835216)
			(xy 179.884832 -222.835216) (xy 179.88434 -222.862173) (xy 179.87649 -222.915513) (xy 179.860958 -222.967142)
			(xy 179.838073 -223.015959) (xy 179.808325 -223.060923) (xy 179.772347 -223.101077) (xy 179.730905 -223.135565)
			(xy 179.684884 -223.163651) (xy 179.635264 -223.184738) (xy 179.583103 -223.198374) (xy 179.529512 -223.204271)
			(xy 179.475633 -223.202302) (xy 179.422615 -223.192509) (xy 179.371588 -223.175101) (xy 179.32364 -223.150449)
			(xy 179.279792 -223.119079) (xy 179.240979 -223.081658) (xy 179.208027 -223.038985) (xy 179.181641 -222.991968)
			(xy 179.162381 -222.941611) (xy 179.150658 -222.888987) (xy 179.146723 -222.835216) (xy 177.881534 -222.835216)
			(xy 177.881534 -223.685354) (xy 183.246791 -223.685354) (xy 183.250726 -223.631583) (xy 183.262449 -223.578959)
			(xy 183.281709 -223.528602) (xy 183.308095 -223.481585) (xy 183.341047 -223.438912) (xy 183.37986 -223.401491)
			(xy 183.423708 -223.370121) (xy 183.471656 -223.345469) (xy 183.522683 -223.328061) (xy 183.575701 -223.318268)
			(xy 183.62958 -223.316299) (xy 183.683171 -223.322196) (xy 183.735332 -223.335832) (xy 183.784952 -223.356919)
			(xy 183.830973 -223.385005) (xy 183.872415 -223.419493) (xy 183.908393 -223.459647) (xy 183.938141 -223.504611)
			(xy 183.961026 -223.553428) (xy 183.976558 -223.605057) (xy 183.984408 -223.658397) (xy 183.9849 -223.685354)
			(xy 190.790845 -223.685354) (xy 190.79478 -223.631583) (xy 190.806503 -223.578959) (xy 190.825763 -223.528602)
			(xy 190.852149 -223.481585) (xy 190.885101 -223.438912) (xy 190.923914 -223.401491) (xy 190.967762 -223.370121)
			(xy 191.01571 -223.345469) (xy 191.066737 -223.328061) (xy 191.119755 -223.318268) (xy 191.173634 -223.316299)
			(xy 191.227225 -223.322196) (xy 191.279386 -223.335832) (xy 191.329006 -223.356919) (xy 191.375027 -223.385005)
			(xy 191.416469 -223.419493) (xy 191.452447 -223.459647) (xy 191.482195 -223.504611) (xy 191.50508 -223.553428)
			(xy 191.520612 -223.605057) (xy 191.528462 -223.658397) (xy 191.528954 -223.685354) (xy 198.334899 -223.685354)
			(xy 198.338834 -223.631583) (xy 198.350557 -223.578959) (xy 198.369817 -223.528602) (xy 198.396203 -223.481585)
			(xy 198.429155 -223.438912) (xy 198.467968 -223.401491) (xy 198.511816 -223.370121) (xy 198.559764 -223.345469)
			(xy 198.610791 -223.328061) (xy 198.663809 -223.318268) (xy 198.717688 -223.316299) (xy 198.771279 -223.322196)
			(xy 198.82344 -223.335832) (xy 198.87306 -223.356919) (xy 198.919081 -223.385005) (xy 198.960523 -223.419493)
			(xy 198.996501 -223.459647) (xy 199.026249 -223.504611) (xy 199.049134 -223.553428) (xy 199.064666 -223.605057)
			(xy 199.072516 -223.658397) (xy 199.073008 -223.685354) (xy 205.878699 -223.685354) (xy 205.882634 -223.631583)
			(xy 205.894357 -223.578959) (xy 205.913617 -223.528602) (xy 205.940003 -223.481585) (xy 205.972955 -223.438912)
			(xy 206.011768 -223.401491) (xy 206.055616 -223.370121) (xy 206.103564 -223.345469) (xy 206.154591 -223.328061)
			(xy 206.207609 -223.318268) (xy 206.261488 -223.316299) (xy 206.315079 -223.322196) (xy 206.36724 -223.335832)
			(xy 206.41686 -223.356919) (xy 206.462881 -223.385005) (xy 206.504323 -223.419493) (xy 206.540301 -223.459647)
			(xy 206.570049 -223.504611) (xy 206.592934 -223.553428) (xy 206.608466 -223.605057) (xy 206.616316 -223.658397)
			(xy 206.616808 -223.685354) (xy 206.616316 -223.712311) (xy 206.608466 -223.765651) (xy 206.592934 -223.81728)
			(xy 206.570049 -223.866097) (xy 206.540301 -223.911061) (xy 206.504323 -223.951215) (xy 206.462881 -223.985703)
			(xy 206.41686 -224.013789) (xy 206.36724 -224.034876) (xy 206.315079 -224.048512) (xy 206.261488 -224.054409)
			(xy 206.207609 -224.05244) (xy 206.154591 -224.042647) (xy 206.103564 -224.025239) (xy 206.055616 -224.000587)
			(xy 206.011768 -223.969217) (xy 205.972955 -223.931796) (xy 205.940003 -223.889123) (xy 205.913617 -223.842106)
			(xy 205.894357 -223.791749) (xy 205.882634 -223.739125) (xy 205.878699 -223.685354) (xy 199.073008 -223.685354)
			(xy 199.072516 -223.712311) (xy 199.064666 -223.765651) (xy 199.049134 -223.81728) (xy 199.026249 -223.866097)
			(xy 198.996501 -223.911061) (xy 198.960523 -223.951215) (xy 198.919081 -223.985703) (xy 198.87306 -224.013789)
			(xy 198.82344 -224.034876) (xy 198.771279 -224.048512) (xy 198.717688 -224.054409) (xy 198.663809 -224.05244)
			(xy 198.610791 -224.042647) (xy 198.559764 -224.025239) (xy 198.511816 -224.000587) (xy 198.467968 -223.969217)
			(xy 198.429155 -223.931796) (xy 198.396203 -223.889123) (xy 198.369817 -223.842106) (xy 198.350557 -223.791749)
			(xy 198.338834 -223.739125) (xy 198.334899 -223.685354) (xy 191.528954 -223.685354) (xy 191.528462 -223.712311)
			(xy 191.520612 -223.765651) (xy 191.50508 -223.81728) (xy 191.482195 -223.866097) (xy 191.452447 -223.911061)
			(xy 191.416469 -223.951215) (xy 191.375027 -223.985703) (xy 191.329006 -224.013789) (xy 191.279386 -224.034876)
			(xy 191.227225 -224.048512) (xy 191.173634 -224.054409) (xy 191.119755 -224.05244) (xy 191.066737 -224.042647)
			(xy 191.01571 -224.025239) (xy 190.967762 -224.000587) (xy 190.923914 -223.969217) (xy 190.885101 -223.931796)
			(xy 190.852149 -223.889123) (xy 190.825763 -223.842106) (xy 190.806503 -223.791749) (xy 190.79478 -223.739125)
			(xy 190.790845 -223.685354) (xy 183.9849 -223.685354) (xy 183.984408 -223.712311) (xy 183.976558 -223.765651)
			(xy 183.961026 -223.81728) (xy 183.938141 -223.866097) (xy 183.908393 -223.911061) (xy 183.872415 -223.951215)
			(xy 183.830973 -223.985703) (xy 183.784952 -224.013789) (xy 183.735332 -224.034876) (xy 183.683171 -224.048512)
			(xy 183.62958 -224.054409) (xy 183.575701 -224.05244) (xy 183.522683 -224.042647) (xy 183.471656 -224.025239)
			(xy 183.423708 -224.000587) (xy 183.37986 -223.969217) (xy 183.341047 -223.931796) (xy 183.308095 -223.889123)
			(xy 183.281709 -223.842106) (xy 183.262449 -223.791749) (xy 183.250726 -223.739125) (xy 183.246791 -223.685354)
			(xy 177.881534 -223.685354) (xy 177.881534 -224.535238) (xy 179.146723 -224.535238) (xy 179.150658 -224.481467)
			(xy 179.162381 -224.428843) (xy 179.181641 -224.378486) (xy 179.208027 -224.331469) (xy 179.240979 -224.288796)
			(xy 179.279792 -224.251375) (xy 179.32364 -224.220005) (xy 179.371588 -224.195353) (xy 179.422615 -224.177945)
			(xy 179.475633 -224.168152) (xy 179.529512 -224.166183) (xy 179.583103 -224.17208) (xy 179.635264 -224.185716)
			(xy 179.684884 -224.206803) (xy 179.730905 -224.234889) (xy 179.772347 -224.269377) (xy 179.808325 -224.309531)
			(xy 179.838073 -224.354495) (xy 179.860958 -224.403312) (xy 179.87649 -224.454941) (xy 179.88434 -224.508281)
			(xy 179.884832 -224.535238) (xy 186.690777 -224.535238) (xy 186.694712 -224.481467) (xy 186.706435 -224.428843)
			(xy 186.725695 -224.378486) (xy 186.752081 -224.331469) (xy 186.785033 -224.288796) (xy 186.823846 -224.251375)
			(xy 186.867694 -224.220005) (xy 186.915642 -224.195353) (xy 186.966669 -224.177945) (xy 187.019687 -224.168152)
			(xy 187.073566 -224.166183) (xy 187.127157 -224.17208) (xy 187.179318 -224.185716) (xy 187.228938 -224.206803)
			(xy 187.274959 -224.234889) (xy 187.316401 -224.269377) (xy 187.352379 -224.309531) (xy 187.382127 -224.354495)
			(xy 187.405012 -224.403312) (xy 187.420544 -224.454941) (xy 187.428394 -224.508281) (xy 187.428886 -224.535238)
			(xy 194.234831 -224.535238) (xy 194.238766 -224.481467) (xy 194.250489 -224.428843) (xy 194.269749 -224.378486)
			(xy 194.296135 -224.331469) (xy 194.329087 -224.288796) (xy 194.3679 -224.251375) (xy 194.411748 -224.220005)
			(xy 194.459696 -224.195353) (xy 194.510723 -224.177945) (xy 194.563741 -224.168152) (xy 194.61762 -224.166183)
			(xy 194.671211 -224.17208) (xy 194.723372 -224.185716) (xy 194.772992 -224.206803) (xy 194.819013 -224.234889)
			(xy 194.860455 -224.269377) (xy 194.896433 -224.309531) (xy 194.926181 -224.354495) (xy 194.949066 -224.403312)
			(xy 194.964598 -224.454941) (xy 194.972448 -224.508281) (xy 194.97294 -224.535238) (xy 201.778631 -224.535238)
			(xy 201.782566 -224.481467) (xy 201.794289 -224.428843) (xy 201.813549 -224.378486) (xy 201.839935 -224.331469)
			(xy 201.872887 -224.288796) (xy 201.9117 -224.251375) (xy 201.955548 -224.220005) (xy 202.003496 -224.195353)
			(xy 202.054523 -224.177945) (xy 202.107541 -224.168152) (xy 202.16142 -224.166183) (xy 202.215011 -224.17208)
			(xy 202.267172 -224.185716) (xy 202.316792 -224.206803) (xy 202.362813 -224.234889) (xy 202.404255 -224.269377)
			(xy 202.440233 -224.309531) (xy 202.469981 -224.354495) (xy 202.492866 -224.403312) (xy 202.508398 -224.454941)
			(xy 202.516248 -224.508281) (xy 202.51674 -224.535238) (xy 202.516248 -224.562195) (xy 202.508398 -224.615535)
			(xy 202.492866 -224.667164) (xy 202.469981 -224.715981) (xy 202.440233 -224.760945) (xy 202.404255 -224.801099)
			(xy 202.362813 -224.835587) (xy 202.316792 -224.863673) (xy 202.267172 -224.88476) (xy 202.215011 -224.898396)
			(xy 202.16142 -224.904293) (xy 202.107541 -224.902324) (xy 202.054523 -224.892531) (xy 202.003496 -224.875123)
			(xy 201.955548 -224.850471) (xy 201.9117 -224.819101) (xy 201.872887 -224.78168) (xy 201.839935 -224.739007)
			(xy 201.813549 -224.69199) (xy 201.794289 -224.641633) (xy 201.782566 -224.589009) (xy 201.778631 -224.535238)
			(xy 194.97294 -224.535238) (xy 194.972448 -224.562195) (xy 194.964598 -224.615535) (xy 194.949066 -224.667164)
			(xy 194.926181 -224.715981) (xy 194.896433 -224.760945) (xy 194.860455 -224.801099) (xy 194.819013 -224.835587)
			(xy 194.772992 -224.863673) (xy 194.723372 -224.88476) (xy 194.671211 -224.898396) (xy 194.61762 -224.904293)
			(xy 194.563741 -224.902324) (xy 194.510723 -224.892531) (xy 194.459696 -224.875123) (xy 194.411748 -224.850471)
			(xy 194.3679 -224.819101) (xy 194.329087 -224.78168) (xy 194.296135 -224.739007) (xy 194.269749 -224.69199)
			(xy 194.250489 -224.641633) (xy 194.238766 -224.589009) (xy 194.234831 -224.535238) (xy 187.428886 -224.535238)
			(xy 187.428394 -224.562195) (xy 187.420544 -224.615535) (xy 187.405012 -224.667164) (xy 187.382127 -224.715981)
			(xy 187.352379 -224.760945) (xy 187.316401 -224.801099) (xy 187.274959 -224.835587) (xy 187.228938 -224.863673)
			(xy 187.179318 -224.88476) (xy 187.127157 -224.898396) (xy 187.073566 -224.904293) (xy 187.019687 -224.902324)
			(xy 186.966669 -224.892531) (xy 186.915642 -224.875123) (xy 186.867694 -224.850471) (xy 186.823846 -224.819101)
			(xy 186.785033 -224.78168) (xy 186.752081 -224.739007) (xy 186.725695 -224.69199) (xy 186.706435 -224.641633)
			(xy 186.694712 -224.589009) (xy 186.690777 -224.535238) (xy 179.884832 -224.535238) (xy 179.88434 -224.562195)
			(xy 179.87649 -224.615535) (xy 179.860958 -224.667164) (xy 179.838073 -224.715981) (xy 179.808325 -224.760945)
			(xy 179.772347 -224.801099) (xy 179.730905 -224.835587) (xy 179.684884 -224.863673) (xy 179.635264 -224.88476)
			(xy 179.583103 -224.898396) (xy 179.529512 -224.904293) (xy 179.475633 -224.902324) (xy 179.422615 -224.892531)
			(xy 179.371588 -224.875123) (xy 179.32364 -224.850471) (xy 179.279792 -224.819101) (xy 179.240979 -224.78168)
			(xy 179.208027 -224.739007) (xy 179.181641 -224.69199) (xy 179.162381 -224.641633) (xy 179.150658 -224.589009)
			(xy 179.146723 -224.535238) (xy 177.881534 -224.535238) (xy 177.881534 -225.385376) (xy 183.246791 -225.385376)
			(xy 183.250726 -225.331605) (xy 183.262449 -225.278981) (xy 183.281709 -225.228624) (xy 183.308095 -225.181607)
			(xy 183.341047 -225.138934) (xy 183.37986 -225.101513) (xy 183.423708 -225.070143) (xy 183.471656 -225.045491)
			(xy 183.522683 -225.028083) (xy 183.575701 -225.01829) (xy 183.62958 -225.016321) (xy 183.683171 -225.022218)
			(xy 183.735332 -225.035854) (xy 183.784952 -225.056941) (xy 183.830973 -225.085027) (xy 183.872415 -225.119515)
			(xy 183.908393 -225.159669) (xy 183.938141 -225.204633) (xy 183.961026 -225.25345) (xy 183.976558 -225.305079)
			(xy 183.984408 -225.358419) (xy 183.9849 -225.385376) (xy 190.790845 -225.385376) (xy 190.79478 -225.331605)
			(xy 190.806503 -225.278981) (xy 190.825763 -225.228624) (xy 190.852149 -225.181607) (xy 190.885101 -225.138934)
			(xy 190.923914 -225.101513) (xy 190.967762 -225.070143) (xy 191.01571 -225.045491) (xy 191.066737 -225.028083)
			(xy 191.119755 -225.01829) (xy 191.173634 -225.016321) (xy 191.227225 -225.022218) (xy 191.279386 -225.035854)
			(xy 191.329006 -225.056941) (xy 191.375027 -225.085027) (xy 191.416469 -225.119515) (xy 191.452447 -225.159669)
			(xy 191.482195 -225.204633) (xy 191.50508 -225.25345) (xy 191.520612 -225.305079) (xy 191.528462 -225.358419)
			(xy 191.528954 -225.385376) (xy 198.334899 -225.385376) (xy 198.338834 -225.331605) (xy 198.350557 -225.278981)
			(xy 198.369817 -225.228624) (xy 198.396203 -225.181607) (xy 198.429155 -225.138934) (xy 198.467968 -225.101513)
			(xy 198.511816 -225.070143) (xy 198.559764 -225.045491) (xy 198.610791 -225.028083) (xy 198.663809 -225.01829)
			(xy 198.717688 -225.016321) (xy 198.771279 -225.022218) (xy 198.82344 -225.035854) (xy 198.87306 -225.056941)
			(xy 198.919081 -225.085027) (xy 198.960523 -225.119515) (xy 198.996501 -225.159669) (xy 199.026249 -225.204633)
			(xy 199.049134 -225.25345) (xy 199.064666 -225.305079) (xy 199.072516 -225.358419) (xy 199.073008 -225.385376)
			(xy 205.878699 -225.385376) (xy 205.882634 -225.331605) (xy 205.894357 -225.278981) (xy 205.913617 -225.228624)
			(xy 205.940003 -225.181607) (xy 205.972955 -225.138934) (xy 206.011768 -225.101513) (xy 206.055616 -225.070143)
			(xy 206.103564 -225.045491) (xy 206.154591 -225.028083) (xy 206.207609 -225.01829) (xy 206.261488 -225.016321)
			(xy 206.315079 -225.022218) (xy 206.36724 -225.035854) (xy 206.41686 -225.056941) (xy 206.462881 -225.085027)
			(xy 206.504323 -225.119515) (xy 206.540301 -225.159669) (xy 206.570049 -225.204633) (xy 206.592934 -225.25345)
			(xy 206.608466 -225.305079) (xy 206.616316 -225.358419) (xy 206.616808 -225.385376) (xy 206.616316 -225.412333)
			(xy 206.608466 -225.465673) (xy 206.592934 -225.517302) (xy 206.570049 -225.566119) (xy 206.540301 -225.611083)
			(xy 206.504323 -225.651237) (xy 206.462881 -225.685725) (xy 206.41686 -225.713811) (xy 206.36724 -225.734898)
			(xy 206.315079 -225.748534) (xy 206.261488 -225.754431) (xy 206.207609 -225.752462) (xy 206.154591 -225.742669)
			(xy 206.103564 -225.725261) (xy 206.055616 -225.700609) (xy 206.011768 -225.669239) (xy 205.972955 -225.631818)
			(xy 205.940003 -225.589145) (xy 205.913617 -225.542128) (xy 205.894357 -225.491771) (xy 205.882634 -225.439147)
			(xy 205.878699 -225.385376) (xy 199.073008 -225.385376) (xy 199.072516 -225.412333) (xy 199.064666 -225.465673)
			(xy 199.049134 -225.517302) (xy 199.026249 -225.566119) (xy 198.996501 -225.611083) (xy 198.960523 -225.651237)
			(xy 198.919081 -225.685725) (xy 198.87306 -225.713811) (xy 198.82344 -225.734898) (xy 198.771279 -225.748534)
			(xy 198.717688 -225.754431) (xy 198.663809 -225.752462) (xy 198.610791 -225.742669) (xy 198.559764 -225.725261)
			(xy 198.511816 -225.700609) (xy 198.467968 -225.669239) (xy 198.429155 -225.631818) (xy 198.396203 -225.589145)
			(xy 198.369817 -225.542128) (xy 198.350557 -225.491771) (xy 198.338834 -225.439147) (xy 198.334899 -225.385376)
			(xy 191.528954 -225.385376) (xy 191.528462 -225.412333) (xy 191.520612 -225.465673) (xy 191.50508 -225.517302)
			(xy 191.482195 -225.566119) (xy 191.452447 -225.611083) (xy 191.416469 -225.651237) (xy 191.375027 -225.685725)
			(xy 191.329006 -225.713811) (xy 191.279386 -225.734898) (xy 191.227225 -225.748534) (xy 191.173634 -225.754431)
			(xy 191.119755 -225.752462) (xy 191.066737 -225.742669) (xy 191.01571 -225.725261) (xy 190.967762 -225.700609)
			(xy 190.923914 -225.669239) (xy 190.885101 -225.631818) (xy 190.852149 -225.589145) (xy 190.825763 -225.542128)
			(xy 190.806503 -225.491771) (xy 190.79478 -225.439147) (xy 190.790845 -225.385376) (xy 183.9849 -225.385376)
			(xy 183.984408 -225.412333) (xy 183.976558 -225.465673) (xy 183.961026 -225.517302) (xy 183.938141 -225.566119)
			(xy 183.908393 -225.611083) (xy 183.872415 -225.651237) (xy 183.830973 -225.685725) (xy 183.784952 -225.713811)
			(xy 183.735332 -225.734898) (xy 183.683171 -225.748534) (xy 183.62958 -225.754431) (xy 183.575701 -225.752462)
			(xy 183.522683 -225.742669) (xy 183.471656 -225.725261) (xy 183.423708 -225.700609) (xy 183.37986 -225.669239)
			(xy 183.341047 -225.631818) (xy 183.308095 -225.589145) (xy 183.281709 -225.542128) (xy 183.262449 -225.491771)
			(xy 183.250726 -225.439147) (xy 183.246791 -225.385376) (xy 177.881534 -225.385376) (xy 177.881534 -226.23526)
			(xy 179.146723 -226.23526) (xy 179.150658 -226.181489) (xy 179.162381 -226.128865) (xy 179.181641 -226.078508)
			(xy 179.208027 -226.031491) (xy 179.240979 -225.988818) (xy 179.279792 -225.951397) (xy 179.32364 -225.920027)
			(xy 179.371588 -225.895375) (xy 179.422615 -225.877967) (xy 179.475633 -225.868174) (xy 179.529512 -225.866205)
			(xy 179.583103 -225.872102) (xy 179.635264 -225.885738) (xy 179.684884 -225.906825) (xy 179.730905 -225.934911)
			(xy 179.772347 -225.969399) (xy 179.808325 -226.009553) (xy 179.838073 -226.054517) (xy 179.860958 -226.103334)
			(xy 179.87649 -226.154963) (xy 179.88434 -226.208303) (xy 179.884832 -226.23526) (xy 186.690777 -226.23526)
			(xy 186.694712 -226.181489) (xy 186.706435 -226.128865) (xy 186.725695 -226.078508) (xy 186.752081 -226.031491)
			(xy 186.785033 -225.988818) (xy 186.823846 -225.951397) (xy 186.867694 -225.920027) (xy 186.915642 -225.895375)
			(xy 186.966669 -225.877967) (xy 187.019687 -225.868174) (xy 187.073566 -225.866205) (xy 187.127157 -225.872102)
			(xy 187.179318 -225.885738) (xy 187.228938 -225.906825) (xy 187.274959 -225.934911) (xy 187.316401 -225.969399)
			(xy 187.352379 -226.009553) (xy 187.382127 -226.054517) (xy 187.405012 -226.103334) (xy 187.420544 -226.154963)
			(xy 187.428394 -226.208303) (xy 187.428886 -226.23526) (xy 194.234831 -226.23526) (xy 194.238766 -226.181489)
			(xy 194.250489 -226.128865) (xy 194.269749 -226.078508) (xy 194.296135 -226.031491) (xy 194.329087 -225.988818)
			(xy 194.3679 -225.951397) (xy 194.411748 -225.920027) (xy 194.459696 -225.895375) (xy 194.510723 -225.877967)
			(xy 194.563741 -225.868174) (xy 194.61762 -225.866205) (xy 194.671211 -225.872102) (xy 194.723372 -225.885738)
			(xy 194.772992 -225.906825) (xy 194.819013 -225.934911) (xy 194.860455 -225.969399) (xy 194.896433 -226.009553)
			(xy 194.926181 -226.054517) (xy 194.949066 -226.103334) (xy 194.964598 -226.154963) (xy 194.972448 -226.208303)
			(xy 194.97294 -226.23526) (xy 201.778631 -226.23526) (xy 201.782566 -226.181489) (xy 201.794289 -226.128865)
			(xy 201.813549 -226.078508) (xy 201.839935 -226.031491) (xy 201.872887 -225.988818) (xy 201.9117 -225.951397)
			(xy 201.955548 -225.920027) (xy 202.003496 -225.895375) (xy 202.054523 -225.877967) (xy 202.107541 -225.868174)
			(xy 202.16142 -225.866205) (xy 202.215011 -225.872102) (xy 202.267172 -225.885738) (xy 202.316792 -225.906825)
			(xy 202.362813 -225.934911) (xy 202.404255 -225.969399) (xy 202.440233 -226.009553) (xy 202.469981 -226.054517)
			(xy 202.492866 -226.103334) (xy 202.508398 -226.154963) (xy 202.516248 -226.208303) (xy 202.51674 -226.23526)
			(xy 202.516248 -226.262217) (xy 202.508398 -226.315557) (xy 202.492866 -226.367186) (xy 202.469981 -226.416003)
			(xy 202.440233 -226.460967) (xy 202.404255 -226.501121) (xy 202.362813 -226.535609) (xy 202.316792 -226.563695)
			(xy 202.267172 -226.584782) (xy 202.215011 -226.598418) (xy 202.16142 -226.604315) (xy 202.107541 -226.602346)
			(xy 202.054523 -226.592553) (xy 202.003496 -226.575145) (xy 201.955548 -226.550493) (xy 201.9117 -226.519123)
			(xy 201.872887 -226.481702) (xy 201.839935 -226.439029) (xy 201.813549 -226.392012) (xy 201.794289 -226.341655)
			(xy 201.782566 -226.289031) (xy 201.778631 -226.23526) (xy 194.97294 -226.23526) (xy 194.972448 -226.262217)
			(xy 194.964598 -226.315557) (xy 194.949066 -226.367186) (xy 194.926181 -226.416003) (xy 194.896433 -226.460967)
			(xy 194.860455 -226.501121) (xy 194.819013 -226.535609) (xy 194.772992 -226.563695) (xy 194.723372 -226.584782)
			(xy 194.671211 -226.598418) (xy 194.61762 -226.604315) (xy 194.563741 -226.602346) (xy 194.510723 -226.592553)
			(xy 194.459696 -226.575145) (xy 194.411748 -226.550493) (xy 194.3679 -226.519123) (xy 194.329087 -226.481702)
			(xy 194.296135 -226.439029) (xy 194.269749 -226.392012) (xy 194.250489 -226.341655) (xy 194.238766 -226.289031)
			(xy 194.234831 -226.23526) (xy 187.428886 -226.23526) (xy 187.428394 -226.262217) (xy 187.420544 -226.315557)
			(xy 187.405012 -226.367186) (xy 187.382127 -226.416003) (xy 187.352379 -226.460967) (xy 187.316401 -226.501121)
			(xy 187.274959 -226.535609) (xy 187.228938 -226.563695) (xy 187.179318 -226.584782) (xy 187.127157 -226.598418)
			(xy 187.073566 -226.604315) (xy 187.019687 -226.602346) (xy 186.966669 -226.592553) (xy 186.915642 -226.575145)
			(xy 186.867694 -226.550493) (xy 186.823846 -226.519123) (xy 186.785033 -226.481702) (xy 186.752081 -226.439029)
			(xy 186.725695 -226.392012) (xy 186.706435 -226.341655) (xy 186.694712 -226.289031) (xy 186.690777 -226.23526)
			(xy 179.884832 -226.23526) (xy 179.88434 -226.262217) (xy 179.87649 -226.315557) (xy 179.860958 -226.367186)
			(xy 179.838073 -226.416003) (xy 179.808325 -226.460967) (xy 179.772347 -226.501121) (xy 179.730905 -226.535609)
			(xy 179.684884 -226.563695) (xy 179.635264 -226.584782) (xy 179.583103 -226.598418) (xy 179.529512 -226.604315)
			(xy 179.475633 -226.602346) (xy 179.422615 -226.592553) (xy 179.371588 -226.575145) (xy 179.32364 -226.550493)
			(xy 179.279792 -226.519123) (xy 179.240979 -226.481702) (xy 179.208027 -226.439029) (xy 179.181641 -226.392012)
			(xy 179.162381 -226.341655) (xy 179.150658 -226.289031) (xy 179.146723 -226.23526) (xy 177.881534 -226.23526)
			(xy 177.881534 -227.085398) (xy 183.246791 -227.085398) (xy 183.250726 -227.031627) (xy 183.262449 -226.979003)
			(xy 183.281709 -226.928646) (xy 183.308095 -226.881629) (xy 183.341047 -226.838956) (xy 183.37986 -226.801535)
			(xy 183.423708 -226.770165) (xy 183.471656 -226.745513) (xy 183.522683 -226.728105) (xy 183.575701 -226.718312)
			(xy 183.62958 -226.716343) (xy 183.683171 -226.72224) (xy 183.735332 -226.735876) (xy 183.784952 -226.756963)
			(xy 183.830973 -226.785049) (xy 183.872415 -226.819537) (xy 183.908393 -226.859691) (xy 183.938141 -226.904655)
			(xy 183.961026 -226.953472) (xy 183.976558 -227.005101) (xy 183.984408 -227.058441) (xy 183.9849 -227.085398)
			(xy 190.790845 -227.085398) (xy 190.79478 -227.031627) (xy 190.806503 -226.979003) (xy 190.825763 -226.928646)
			(xy 190.852149 -226.881629) (xy 190.885101 -226.838956) (xy 190.923914 -226.801535) (xy 190.967762 -226.770165)
			(xy 191.01571 -226.745513) (xy 191.066737 -226.728105) (xy 191.119755 -226.718312) (xy 191.173634 -226.716343)
			(xy 191.227225 -226.72224) (xy 191.279386 -226.735876) (xy 191.329006 -226.756963) (xy 191.375027 -226.785049)
			(xy 191.416469 -226.819537) (xy 191.452447 -226.859691) (xy 191.482195 -226.904655) (xy 191.50508 -226.953472)
			(xy 191.520612 -227.005101) (xy 191.528462 -227.058441) (xy 191.528954 -227.085398) (xy 198.334899 -227.085398)
			(xy 198.338834 -227.031627) (xy 198.350557 -226.979003) (xy 198.369817 -226.928646) (xy 198.396203 -226.881629)
			(xy 198.429155 -226.838956) (xy 198.467968 -226.801535) (xy 198.511816 -226.770165) (xy 198.559764 -226.745513)
			(xy 198.610791 -226.728105) (xy 198.663809 -226.718312) (xy 198.717688 -226.716343) (xy 198.771279 -226.72224)
			(xy 198.82344 -226.735876) (xy 198.87306 -226.756963) (xy 198.919081 -226.785049) (xy 198.960523 -226.819537)
			(xy 198.996501 -226.859691) (xy 199.026249 -226.904655) (xy 199.049134 -226.953472) (xy 199.064666 -227.005101)
			(xy 199.072516 -227.058441) (xy 199.073008 -227.085398) (xy 205.878699 -227.085398) (xy 205.882634 -227.031627)
			(xy 205.894357 -226.979003) (xy 205.913617 -226.928646) (xy 205.940003 -226.881629) (xy 205.972955 -226.838956)
			(xy 206.011768 -226.801535) (xy 206.055616 -226.770165) (xy 206.103564 -226.745513) (xy 206.154591 -226.728105)
			(xy 206.207609 -226.718312) (xy 206.261488 -226.716343) (xy 206.315079 -226.72224) (xy 206.36724 -226.735876)
			(xy 206.41686 -226.756963) (xy 206.462881 -226.785049) (xy 206.504323 -226.819537) (xy 206.540301 -226.859691)
			(xy 206.570049 -226.904655) (xy 206.592934 -226.953472) (xy 206.608466 -227.005101) (xy 206.616316 -227.058441)
			(xy 206.616808 -227.085398) (xy 206.616316 -227.112355) (xy 206.608466 -227.165695) (xy 206.592934 -227.217324)
			(xy 206.570049 -227.266141) (xy 206.540301 -227.311105) (xy 206.504323 -227.351259) (xy 206.462881 -227.385747)
			(xy 206.41686 -227.413833) (xy 206.36724 -227.43492) (xy 206.315079 -227.448556) (xy 206.261488 -227.454453)
			(xy 206.207609 -227.452484) (xy 206.154591 -227.442691) (xy 206.103564 -227.425283) (xy 206.055616 -227.400631)
			(xy 206.011768 -227.369261) (xy 205.972955 -227.33184) (xy 205.940003 -227.289167) (xy 205.913617 -227.24215)
			(xy 205.894357 -227.191793) (xy 205.882634 -227.139169) (xy 205.878699 -227.085398) (xy 199.073008 -227.085398)
			(xy 199.072516 -227.112355) (xy 199.064666 -227.165695) (xy 199.049134 -227.217324) (xy 199.026249 -227.266141)
			(xy 198.996501 -227.311105) (xy 198.960523 -227.351259) (xy 198.919081 -227.385747) (xy 198.87306 -227.413833)
			(xy 198.82344 -227.43492) (xy 198.771279 -227.448556) (xy 198.717688 -227.454453) (xy 198.663809 -227.452484)
			(xy 198.610791 -227.442691) (xy 198.559764 -227.425283) (xy 198.511816 -227.400631) (xy 198.467968 -227.369261)
			(xy 198.429155 -227.33184) (xy 198.396203 -227.289167) (xy 198.369817 -227.24215) (xy 198.350557 -227.191793)
			(xy 198.338834 -227.139169) (xy 198.334899 -227.085398) (xy 191.528954 -227.085398) (xy 191.528462 -227.112355)
			(xy 191.520612 -227.165695) (xy 191.50508 -227.217324) (xy 191.482195 -227.266141) (xy 191.452447 -227.311105)
			(xy 191.416469 -227.351259) (xy 191.375027 -227.385747) (xy 191.329006 -227.413833) (xy 191.279386 -227.43492)
			(xy 191.227225 -227.448556) (xy 191.173634 -227.454453) (xy 191.119755 -227.452484) (xy 191.066737 -227.442691)
			(xy 191.01571 -227.425283) (xy 190.967762 -227.400631) (xy 190.923914 -227.369261) (xy 190.885101 -227.33184)
			(xy 190.852149 -227.289167) (xy 190.825763 -227.24215) (xy 190.806503 -227.191793) (xy 190.79478 -227.139169)
			(xy 190.790845 -227.085398) (xy 183.9849 -227.085398) (xy 183.984408 -227.112355) (xy 183.976558 -227.165695)
			(xy 183.961026 -227.217324) (xy 183.938141 -227.266141) (xy 183.908393 -227.311105) (xy 183.872415 -227.351259)
			(xy 183.830973 -227.385747) (xy 183.784952 -227.413833) (xy 183.735332 -227.43492) (xy 183.683171 -227.448556)
			(xy 183.62958 -227.454453) (xy 183.575701 -227.452484) (xy 183.522683 -227.442691) (xy 183.471656 -227.425283)
			(xy 183.423708 -227.400631) (xy 183.37986 -227.369261) (xy 183.341047 -227.33184) (xy 183.308095 -227.289167)
			(xy 183.281709 -227.24215) (xy 183.262449 -227.191793) (xy 183.250726 -227.139169) (xy 183.246791 -227.085398)
			(xy 177.881534 -227.085398) (xy 177.881534 -227.935282) (xy 179.146723 -227.935282) (xy 179.150658 -227.881511)
			(xy 179.162381 -227.828887) (xy 179.181641 -227.77853) (xy 179.208027 -227.731513) (xy 179.240979 -227.68884)
			(xy 179.279792 -227.651419) (xy 179.32364 -227.620049) (xy 179.371588 -227.595397) (xy 179.422615 -227.577989)
			(xy 179.475633 -227.568196) (xy 179.529512 -227.566227) (xy 179.583103 -227.572124) (xy 179.635264 -227.58576)
			(xy 179.684884 -227.606847) (xy 179.730905 -227.634933) (xy 179.772347 -227.669421) (xy 179.808325 -227.709575)
			(xy 179.838073 -227.754539) (xy 179.860958 -227.803356) (xy 179.87649 -227.854985) (xy 179.88434 -227.908325)
			(xy 179.884832 -227.935282) (xy 186.690777 -227.935282) (xy 186.694712 -227.881511) (xy 186.706435 -227.828887)
			(xy 186.725695 -227.77853) (xy 186.752081 -227.731513) (xy 186.785033 -227.68884) (xy 186.823846 -227.651419)
			(xy 186.867694 -227.620049) (xy 186.915642 -227.595397) (xy 186.966669 -227.577989) (xy 187.019687 -227.568196)
			(xy 187.073566 -227.566227) (xy 187.127157 -227.572124) (xy 187.179318 -227.58576) (xy 187.228938 -227.606847)
			(xy 187.274959 -227.634933) (xy 187.316401 -227.669421) (xy 187.352379 -227.709575) (xy 187.382127 -227.754539)
			(xy 187.405012 -227.803356) (xy 187.420544 -227.854985) (xy 187.428394 -227.908325) (xy 187.428886 -227.935282)
			(xy 194.234831 -227.935282) (xy 194.238766 -227.881511) (xy 194.250489 -227.828887) (xy 194.269749 -227.77853)
			(xy 194.296135 -227.731513) (xy 194.329087 -227.68884) (xy 194.3679 -227.651419) (xy 194.411748 -227.620049)
			(xy 194.459696 -227.595397) (xy 194.510723 -227.577989) (xy 194.563741 -227.568196) (xy 194.61762 -227.566227)
			(xy 194.671211 -227.572124) (xy 194.723372 -227.58576) (xy 194.772992 -227.606847) (xy 194.819013 -227.634933)
			(xy 194.860455 -227.669421) (xy 194.896433 -227.709575) (xy 194.926181 -227.754539) (xy 194.949066 -227.803356)
			(xy 194.964598 -227.854985) (xy 194.972448 -227.908325) (xy 194.97294 -227.935282) (xy 201.778631 -227.935282)
			(xy 201.782566 -227.881511) (xy 201.794289 -227.828887) (xy 201.813549 -227.77853) (xy 201.839935 -227.731513)
			(xy 201.872887 -227.68884) (xy 201.9117 -227.651419) (xy 201.955548 -227.620049) (xy 202.003496 -227.595397)
			(xy 202.054523 -227.577989) (xy 202.107541 -227.568196) (xy 202.16142 -227.566227) (xy 202.215011 -227.572124)
			(xy 202.267172 -227.58576) (xy 202.316792 -227.606847) (xy 202.362813 -227.634933) (xy 202.404255 -227.669421)
			(xy 202.440233 -227.709575) (xy 202.469981 -227.754539) (xy 202.492866 -227.803356) (xy 202.508398 -227.854985)
			(xy 202.516248 -227.908325) (xy 202.51674 -227.935282) (xy 202.516248 -227.962239) (xy 202.508398 -228.015579)
			(xy 202.492866 -228.067208) (xy 202.469981 -228.116025) (xy 202.440233 -228.160989) (xy 202.404255 -228.201143)
			(xy 202.362813 -228.235631) (xy 202.316792 -228.263717) (xy 202.267172 -228.284804) (xy 202.215011 -228.29844)
			(xy 202.16142 -228.304337) (xy 202.107541 -228.302368) (xy 202.054523 -228.292575) (xy 202.003496 -228.275167)
			(xy 201.955548 -228.250515) (xy 201.9117 -228.219145) (xy 201.872887 -228.181724) (xy 201.839935 -228.139051)
			(xy 201.813549 -228.092034) (xy 201.794289 -228.041677) (xy 201.782566 -227.989053) (xy 201.778631 -227.935282)
			(xy 194.97294 -227.935282) (xy 194.972448 -227.962239) (xy 194.964598 -228.015579) (xy 194.949066 -228.067208)
			(xy 194.926181 -228.116025) (xy 194.896433 -228.160989) (xy 194.860455 -228.201143) (xy 194.819013 -228.235631)
			(xy 194.772992 -228.263717) (xy 194.723372 -228.284804) (xy 194.671211 -228.29844) (xy 194.61762 -228.304337)
			(xy 194.563741 -228.302368) (xy 194.510723 -228.292575) (xy 194.459696 -228.275167) (xy 194.411748 -228.250515)
			(xy 194.3679 -228.219145) (xy 194.329087 -228.181724) (xy 194.296135 -228.139051) (xy 194.269749 -228.092034)
			(xy 194.250489 -228.041677) (xy 194.238766 -227.989053) (xy 194.234831 -227.935282) (xy 187.428886 -227.935282)
			(xy 187.428394 -227.962239) (xy 187.420544 -228.015579) (xy 187.405012 -228.067208) (xy 187.382127 -228.116025)
			(xy 187.352379 -228.160989) (xy 187.316401 -228.201143) (xy 187.274959 -228.235631) (xy 187.228938 -228.263717)
			(xy 187.179318 -228.284804) (xy 187.127157 -228.29844) (xy 187.073566 -228.304337) (xy 187.019687 -228.302368)
			(xy 186.966669 -228.292575) (xy 186.915642 -228.275167) (xy 186.867694 -228.250515) (xy 186.823846 -228.219145)
			(xy 186.785033 -228.181724) (xy 186.752081 -228.139051) (xy 186.725695 -228.092034) (xy 186.706435 -228.041677)
			(xy 186.694712 -227.989053) (xy 186.690777 -227.935282) (xy 179.884832 -227.935282) (xy 179.88434 -227.962239)
			(xy 179.87649 -228.015579) (xy 179.860958 -228.067208) (xy 179.838073 -228.116025) (xy 179.808325 -228.160989)
			(xy 179.772347 -228.201143) (xy 179.730905 -228.235631) (xy 179.684884 -228.263717) (xy 179.635264 -228.284804)
			(xy 179.583103 -228.29844) (xy 179.529512 -228.304337) (xy 179.475633 -228.302368) (xy 179.422615 -228.292575)
			(xy 179.371588 -228.275167) (xy 179.32364 -228.250515) (xy 179.279792 -228.219145) (xy 179.240979 -228.181724)
			(xy 179.208027 -228.139051) (xy 179.181641 -228.092034) (xy 179.162381 -228.041677) (xy 179.150658 -227.989053)
			(xy 179.146723 -227.935282) (xy 177.881534 -227.935282) (xy 177.881534 -228.78542) (xy 183.246791 -228.78542)
			(xy 183.250726 -228.731649) (xy 183.262449 -228.679025) (xy 183.281709 -228.628668) (xy 183.308095 -228.581651)
			(xy 183.341047 -228.538978) (xy 183.37986 -228.501557) (xy 183.423708 -228.470187) (xy 183.471656 -228.445535)
			(xy 183.522683 -228.428127) (xy 183.575701 -228.418334) (xy 183.62958 -228.416365) (xy 183.683171 -228.422262)
			(xy 183.735332 -228.435898) (xy 183.784952 -228.456985) (xy 183.830973 -228.485071) (xy 183.872415 -228.519559)
			(xy 183.908393 -228.559713) (xy 183.938141 -228.604677) (xy 183.961026 -228.653494) (xy 183.976558 -228.705123)
			(xy 183.984408 -228.758463) (xy 183.9849 -228.78542) (xy 190.790845 -228.78542) (xy 190.79478 -228.731649)
			(xy 190.806503 -228.679025) (xy 190.825763 -228.628668) (xy 190.852149 -228.581651) (xy 190.885101 -228.538978)
			(xy 190.923914 -228.501557) (xy 190.967762 -228.470187) (xy 191.01571 -228.445535) (xy 191.066737 -228.428127)
			(xy 191.119755 -228.418334) (xy 191.173634 -228.416365) (xy 191.227225 -228.422262) (xy 191.279386 -228.435898)
			(xy 191.329006 -228.456985) (xy 191.375027 -228.485071) (xy 191.416469 -228.519559) (xy 191.452447 -228.559713)
			(xy 191.482195 -228.604677) (xy 191.50508 -228.653494) (xy 191.520612 -228.705123) (xy 191.528462 -228.758463)
			(xy 191.528954 -228.78542) (xy 198.334899 -228.78542) (xy 198.338834 -228.731649) (xy 198.350557 -228.679025)
			(xy 198.369817 -228.628668) (xy 198.396203 -228.581651) (xy 198.429155 -228.538978) (xy 198.467968 -228.501557)
			(xy 198.511816 -228.470187) (xy 198.559764 -228.445535) (xy 198.610791 -228.428127) (xy 198.663809 -228.418334)
			(xy 198.717688 -228.416365) (xy 198.771279 -228.422262) (xy 198.82344 -228.435898) (xy 198.87306 -228.456985)
			(xy 198.919081 -228.485071) (xy 198.960523 -228.519559) (xy 198.996501 -228.559713) (xy 199.026249 -228.604677)
			(xy 199.049134 -228.653494) (xy 199.064666 -228.705123) (xy 199.072516 -228.758463) (xy 199.073008 -228.78542)
			(xy 205.878699 -228.78542) (xy 205.882634 -228.731649) (xy 205.894357 -228.679025) (xy 205.913617 -228.628668)
			(xy 205.940003 -228.581651) (xy 205.972955 -228.538978) (xy 206.011768 -228.501557) (xy 206.055616 -228.470187)
			(xy 206.103564 -228.445535) (xy 206.154591 -228.428127) (xy 206.207609 -228.418334) (xy 206.261488 -228.416365)
			(xy 206.315079 -228.422262) (xy 206.36724 -228.435898) (xy 206.41686 -228.456985) (xy 206.462881 -228.485071)
			(xy 206.504323 -228.519559) (xy 206.540301 -228.559713) (xy 206.570049 -228.604677) (xy 206.592934 -228.653494)
			(xy 206.608466 -228.705123) (xy 206.616316 -228.758463) (xy 206.616808 -228.78542) (xy 206.616316 -228.812377)
			(xy 206.608466 -228.865717) (xy 206.592934 -228.917346) (xy 206.570049 -228.966163) (xy 206.540301 -229.011127)
			(xy 206.504323 -229.051281) (xy 206.462881 -229.085769) (xy 206.41686 -229.113855) (xy 206.36724 -229.134942)
			(xy 206.315079 -229.148578) (xy 206.261488 -229.154475) (xy 206.207609 -229.152506) (xy 206.154591 -229.142713)
			(xy 206.103564 -229.125305) (xy 206.055616 -229.100653) (xy 206.011768 -229.069283) (xy 205.972955 -229.031862)
			(xy 205.940003 -228.989189) (xy 205.913617 -228.942172) (xy 205.894357 -228.891815) (xy 205.882634 -228.839191)
			(xy 205.878699 -228.78542) (xy 199.073008 -228.78542) (xy 199.072516 -228.812377) (xy 199.064666 -228.865717)
			(xy 199.049134 -228.917346) (xy 199.026249 -228.966163) (xy 198.996501 -229.011127) (xy 198.960523 -229.051281)
			(xy 198.919081 -229.085769) (xy 198.87306 -229.113855) (xy 198.82344 -229.134942) (xy 198.771279 -229.148578)
			(xy 198.717688 -229.154475) (xy 198.663809 -229.152506) (xy 198.610791 -229.142713) (xy 198.559764 -229.125305)
			(xy 198.511816 -229.100653) (xy 198.467968 -229.069283) (xy 198.429155 -229.031862) (xy 198.396203 -228.989189)
			(xy 198.369817 -228.942172) (xy 198.350557 -228.891815) (xy 198.338834 -228.839191) (xy 198.334899 -228.78542)
			(xy 191.528954 -228.78542) (xy 191.528462 -228.812377) (xy 191.520612 -228.865717) (xy 191.50508 -228.917346)
			(xy 191.482195 -228.966163) (xy 191.452447 -229.011127) (xy 191.416469 -229.051281) (xy 191.375027 -229.085769)
			(xy 191.329006 -229.113855) (xy 191.279386 -229.134942) (xy 191.227225 -229.148578) (xy 191.173634 -229.154475)
			(xy 191.119755 -229.152506) (xy 191.066737 -229.142713) (xy 191.01571 -229.125305) (xy 190.967762 -229.100653)
			(xy 190.923914 -229.069283) (xy 190.885101 -229.031862) (xy 190.852149 -228.989189) (xy 190.825763 -228.942172)
			(xy 190.806503 -228.891815) (xy 190.79478 -228.839191) (xy 190.790845 -228.78542) (xy 183.9849 -228.78542)
			(xy 183.984408 -228.812377) (xy 183.976558 -228.865717) (xy 183.961026 -228.917346) (xy 183.938141 -228.966163)
			(xy 183.908393 -229.011127) (xy 183.872415 -229.051281) (xy 183.830973 -229.085769) (xy 183.784952 -229.113855)
			(xy 183.735332 -229.134942) (xy 183.683171 -229.148578) (xy 183.62958 -229.154475) (xy 183.575701 -229.152506)
			(xy 183.522683 -229.142713) (xy 183.471656 -229.125305) (xy 183.423708 -229.100653) (xy 183.37986 -229.069283)
			(xy 183.341047 -229.031862) (xy 183.308095 -228.989189) (xy 183.281709 -228.942172) (xy 183.262449 -228.891815)
			(xy 183.250726 -228.839191) (xy 183.246791 -228.78542) (xy 177.881534 -228.78542) (xy 177.881534 -229.635304)
			(xy 179.146723 -229.635304) (xy 179.150658 -229.581533) (xy 179.162381 -229.528909) (xy 179.181641 -229.478552)
			(xy 179.208027 -229.431535) (xy 179.240979 -229.388862) (xy 179.279792 -229.351441) (xy 179.32364 -229.320071)
			(xy 179.371588 -229.295419) (xy 179.422615 -229.278011) (xy 179.475633 -229.268218) (xy 179.529512 -229.266249)
			(xy 179.583103 -229.272146) (xy 179.635264 -229.285782) (xy 179.684884 -229.306869) (xy 179.730905 -229.334955)
			(xy 179.772347 -229.369443) (xy 179.808325 -229.409597) (xy 179.838073 -229.454561) (xy 179.860958 -229.503378)
			(xy 179.87649 -229.555007) (xy 179.88434 -229.608347) (xy 179.884832 -229.635304) (xy 183.246791 -229.635304)
			(xy 183.250726 -229.581533) (xy 183.262449 -229.528909) (xy 183.281709 -229.478552) (xy 183.308095 -229.431535)
			(xy 183.341047 -229.388862) (xy 183.37986 -229.351441) (xy 183.423708 -229.320071) (xy 183.471656 -229.295419)
			(xy 183.522683 -229.278011) (xy 183.575701 -229.268218) (xy 183.62958 -229.266249) (xy 183.683171 -229.272146)
			(xy 183.735332 -229.285782) (xy 183.784952 -229.306869) (xy 183.830973 -229.334955) (xy 183.872415 -229.369443)
			(xy 183.908393 -229.409597) (xy 183.938141 -229.454561) (xy 183.961026 -229.503378) (xy 183.976558 -229.555007)
			(xy 183.984408 -229.608347) (xy 183.9849 -229.635304) (xy 186.690777 -229.635304) (xy 186.694712 -229.581533)
			(xy 186.706435 -229.528909) (xy 186.725695 -229.478552) (xy 186.752081 -229.431535) (xy 186.785033 -229.388862)
			(xy 186.823846 -229.351441) (xy 186.867694 -229.320071) (xy 186.915642 -229.295419) (xy 186.966669 -229.278011)
			(xy 187.019687 -229.268218) (xy 187.073566 -229.266249) (xy 187.127157 -229.272146) (xy 187.179318 -229.285782)
			(xy 187.228938 -229.306869) (xy 187.274959 -229.334955) (xy 187.316401 -229.369443) (xy 187.352379 -229.409597)
			(xy 187.382127 -229.454561) (xy 187.405012 -229.503378) (xy 187.420544 -229.555007) (xy 187.428394 -229.608347)
			(xy 187.428886 -229.635304) (xy 190.790845 -229.635304) (xy 190.79478 -229.581533) (xy 190.806503 -229.528909)
			(xy 190.825763 -229.478552) (xy 190.852149 -229.431535) (xy 190.885101 -229.388862) (xy 190.923914 -229.351441)
			(xy 190.967762 -229.320071) (xy 191.01571 -229.295419) (xy 191.066737 -229.278011) (xy 191.119755 -229.268218)
			(xy 191.173634 -229.266249) (xy 191.227225 -229.272146) (xy 191.279386 -229.285782) (xy 191.329006 -229.306869)
			(xy 191.375027 -229.334955) (xy 191.416469 -229.369443) (xy 191.452447 -229.409597) (xy 191.482195 -229.454561)
			(xy 191.50508 -229.503378) (xy 191.520612 -229.555007) (xy 191.528462 -229.608347) (xy 191.528954 -229.635304)
			(xy 194.234831 -229.635304) (xy 194.238766 -229.581533) (xy 194.250489 -229.528909) (xy 194.269749 -229.478552)
			(xy 194.296135 -229.431535) (xy 194.329087 -229.388862) (xy 194.3679 -229.351441) (xy 194.411748 -229.320071)
			(xy 194.459696 -229.295419) (xy 194.510723 -229.278011) (xy 194.563741 -229.268218) (xy 194.61762 -229.266249)
			(xy 194.671211 -229.272146) (xy 194.723372 -229.285782) (xy 194.772992 -229.306869) (xy 194.819013 -229.334955)
			(xy 194.860455 -229.369443) (xy 194.896433 -229.409597) (xy 194.926181 -229.454561) (xy 194.949066 -229.503378)
			(xy 194.964598 -229.555007) (xy 194.972448 -229.608347) (xy 194.97294 -229.635304) (xy 198.334899 -229.635304)
			(xy 198.338834 -229.581533) (xy 198.350557 -229.528909) (xy 198.369817 -229.478552) (xy 198.396203 -229.431535)
			(xy 198.429155 -229.388862) (xy 198.467968 -229.351441) (xy 198.511816 -229.320071) (xy 198.559764 -229.295419)
			(xy 198.610791 -229.278011) (xy 198.663809 -229.268218) (xy 198.717688 -229.266249) (xy 198.771279 -229.272146)
			(xy 198.82344 -229.285782) (xy 198.87306 -229.306869) (xy 198.919081 -229.334955) (xy 198.960523 -229.369443)
			(xy 198.996501 -229.409597) (xy 199.026249 -229.454561) (xy 199.049134 -229.503378) (xy 199.064666 -229.555007)
			(xy 199.072516 -229.608347) (xy 199.073008 -229.635304) (xy 201.778631 -229.635304) (xy 201.782566 -229.581533)
			(xy 201.794289 -229.528909) (xy 201.813549 -229.478552) (xy 201.839935 -229.431535) (xy 201.872887 -229.388862)
			(xy 201.9117 -229.351441) (xy 201.955548 -229.320071) (xy 202.003496 -229.295419) (xy 202.054523 -229.278011)
			(xy 202.107541 -229.268218) (xy 202.16142 -229.266249) (xy 202.215011 -229.272146) (xy 202.267172 -229.285782)
			(xy 202.316792 -229.306869) (xy 202.362813 -229.334955) (xy 202.404255 -229.369443) (xy 202.440233 -229.409597)
			(xy 202.469981 -229.454561) (xy 202.492866 -229.503378) (xy 202.508398 -229.555007) (xy 202.516248 -229.608347)
			(xy 202.51674 -229.635304) (xy 205.878699 -229.635304) (xy 205.882634 -229.581533) (xy 205.894357 -229.528909)
			(xy 205.913617 -229.478552) (xy 205.940003 -229.431535) (xy 205.972955 -229.388862) (xy 206.011768 -229.351441)
			(xy 206.055616 -229.320071) (xy 206.103564 -229.295419) (xy 206.154591 -229.278011) (xy 206.207609 -229.268218)
			(xy 206.261488 -229.266249) (xy 206.315079 -229.272146) (xy 206.36724 -229.285782) (xy 206.41686 -229.306869)
			(xy 206.462881 -229.334955) (xy 206.504323 -229.369443) (xy 206.540301 -229.409597) (xy 206.570049 -229.454561)
			(xy 206.592934 -229.503378) (xy 206.608466 -229.555007) (xy 206.616316 -229.608347) (xy 206.616808 -229.635304)
			(xy 206.616316 -229.662261) (xy 206.608466 -229.715601) (xy 206.592934 -229.76723) (xy 206.570049 -229.816047)
			(xy 206.540301 -229.861011) (xy 206.504323 -229.901165) (xy 206.462881 -229.935653) (xy 206.41686 -229.963739)
			(xy 206.36724 -229.984826) (xy 206.315079 -229.998462) (xy 206.261488 -230.004359) (xy 206.207609 -230.00239)
			(xy 206.154591 -229.992597) (xy 206.103564 -229.975189) (xy 206.055616 -229.950537) (xy 206.011768 -229.919167)
			(xy 205.972955 -229.881746) (xy 205.940003 -229.839073) (xy 205.913617 -229.792056) (xy 205.894357 -229.741699)
			(xy 205.882634 -229.689075) (xy 205.878699 -229.635304) (xy 202.51674 -229.635304) (xy 202.516248 -229.662261)
			(xy 202.508398 -229.715601) (xy 202.492866 -229.76723) (xy 202.469981 -229.816047) (xy 202.440233 -229.861011)
			(xy 202.404255 -229.901165) (xy 202.362813 -229.935653) (xy 202.316792 -229.963739) (xy 202.267172 -229.984826)
			(xy 202.215011 -229.998462) (xy 202.16142 -230.004359) (xy 202.107541 -230.00239) (xy 202.054523 -229.992597)
			(xy 202.003496 -229.975189) (xy 201.955548 -229.950537) (xy 201.9117 -229.919167) (xy 201.872887 -229.881746)
			(xy 201.839935 -229.839073) (xy 201.813549 -229.792056) (xy 201.794289 -229.741699) (xy 201.782566 -229.689075)
			(xy 201.778631 -229.635304) (xy 199.073008 -229.635304) (xy 199.072516 -229.662261) (xy 199.064666 -229.715601)
			(xy 199.049134 -229.76723) (xy 199.026249 -229.816047) (xy 198.996501 -229.861011) (xy 198.960523 -229.901165)
			(xy 198.919081 -229.935653) (xy 198.87306 -229.963739) (xy 198.82344 -229.984826) (xy 198.771279 -229.998462)
			(xy 198.717688 -230.004359) (xy 198.663809 -230.00239) (xy 198.610791 -229.992597) (xy 198.559764 -229.975189)
			(xy 198.511816 -229.950537) (xy 198.467968 -229.919167) (xy 198.429155 -229.881746) (xy 198.396203 -229.839073)
			(xy 198.369817 -229.792056) (xy 198.350557 -229.741699) (xy 198.338834 -229.689075) (xy 198.334899 -229.635304)
			(xy 194.97294 -229.635304) (xy 194.972448 -229.662261) (xy 194.964598 -229.715601) (xy 194.949066 -229.76723)
			(xy 194.926181 -229.816047) (xy 194.896433 -229.861011) (xy 194.860455 -229.901165) (xy 194.819013 -229.935653)
			(xy 194.772992 -229.963739) (xy 194.723372 -229.984826) (xy 194.671211 -229.998462) (xy 194.61762 -230.004359)
			(xy 194.563741 -230.00239) (xy 194.510723 -229.992597) (xy 194.459696 -229.975189) (xy 194.411748 -229.950537)
			(xy 194.3679 -229.919167) (xy 194.329087 -229.881746) (xy 194.296135 -229.839073) (xy 194.269749 -229.792056)
			(xy 194.250489 -229.741699) (xy 194.238766 -229.689075) (xy 194.234831 -229.635304) (xy 191.528954 -229.635304)
			(xy 191.528462 -229.662261) (xy 191.520612 -229.715601) (xy 191.50508 -229.76723) (xy 191.482195 -229.816047)
			(xy 191.452447 -229.861011) (xy 191.416469 -229.901165) (xy 191.375027 -229.935653) (xy 191.329006 -229.963739)
			(xy 191.279386 -229.984826) (xy 191.227225 -229.998462) (xy 191.173634 -230.004359) (xy 191.119755 -230.00239)
			(xy 191.066737 -229.992597) (xy 191.01571 -229.975189) (xy 190.967762 -229.950537) (xy 190.923914 -229.919167)
			(xy 190.885101 -229.881746) (xy 190.852149 -229.839073) (xy 190.825763 -229.792056) (xy 190.806503 -229.741699)
			(xy 190.79478 -229.689075) (xy 190.790845 -229.635304) (xy 187.428886 -229.635304) (xy 187.428394 -229.662261)
			(xy 187.420544 -229.715601) (xy 187.405012 -229.76723) (xy 187.382127 -229.816047) (xy 187.352379 -229.861011)
			(xy 187.316401 -229.901165) (xy 187.274959 -229.935653) (xy 187.228938 -229.963739) (xy 187.179318 -229.984826)
			(xy 187.127157 -229.998462) (xy 187.073566 -230.004359) (xy 187.019687 -230.00239) (xy 186.966669 -229.992597)
			(xy 186.915642 -229.975189) (xy 186.867694 -229.950537) (xy 186.823846 -229.919167) (xy 186.785033 -229.881746)
			(xy 186.752081 -229.839073) (xy 186.725695 -229.792056) (xy 186.706435 -229.741699) (xy 186.694712 -229.689075)
			(xy 186.690777 -229.635304) (xy 183.9849 -229.635304) (xy 183.984408 -229.662261) (xy 183.976558 -229.715601)
			(xy 183.961026 -229.76723) (xy 183.938141 -229.816047) (xy 183.908393 -229.861011) (xy 183.872415 -229.901165)
			(xy 183.830973 -229.935653) (xy 183.784952 -229.963739) (xy 183.735332 -229.984826) (xy 183.683171 -229.998462)
			(xy 183.62958 -230.004359) (xy 183.575701 -230.00239) (xy 183.522683 -229.992597) (xy 183.471656 -229.975189)
			(xy 183.423708 -229.950537) (xy 183.37986 -229.919167) (xy 183.341047 -229.881746) (xy 183.308095 -229.839073)
			(xy 183.281709 -229.792056) (xy 183.262449 -229.741699) (xy 183.250726 -229.689075) (xy 183.246791 -229.635304)
			(xy 179.884832 -229.635304) (xy 179.88434 -229.662261) (xy 179.87649 -229.715601) (xy 179.860958 -229.76723)
			(xy 179.838073 -229.816047) (xy 179.808325 -229.861011) (xy 179.772347 -229.901165) (xy 179.730905 -229.935653)
			(xy 179.684884 -229.963739) (xy 179.635264 -229.984826) (xy 179.583103 -229.998462) (xy 179.529512 -230.004359)
			(xy 179.475633 -230.00239) (xy 179.422615 -229.992597) (xy 179.371588 -229.975189) (xy 179.32364 -229.950537)
			(xy 179.279792 -229.919167) (xy 179.240979 -229.881746) (xy 179.208027 -229.839073) (xy 179.181641 -229.792056)
			(xy 179.162381 -229.741699) (xy 179.150658 -229.689075) (xy 179.146723 -229.635304) (xy 177.881534 -229.635304)
			(xy 177.881534 -230.485442) (xy 179.146723 -230.485442) (xy 179.150658 -230.431671) (xy 179.162381 -230.379047)
			(xy 179.181641 -230.32869) (xy 179.208027 -230.281673) (xy 179.240979 -230.239) (xy 179.279792 -230.201579)
			(xy 179.32364 -230.170209) (xy 179.371588 -230.145557) (xy 179.422615 -230.128149) (xy 179.475633 -230.118356)
			(xy 179.529512 -230.116387) (xy 179.583103 -230.122284) (xy 179.635264 -230.13592) (xy 179.684884 -230.157007)
			(xy 179.730905 -230.185093) (xy 179.772347 -230.219581) (xy 179.808325 -230.259735) (xy 179.838073 -230.304699)
			(xy 179.860958 -230.353516) (xy 179.87649 -230.405145) (xy 179.88434 -230.458485) (xy 179.884832 -230.485442)
			(xy 186.690777 -230.485442) (xy 186.694712 -230.431671) (xy 186.706435 -230.379047) (xy 186.725695 -230.32869)
			(xy 186.752081 -230.281673) (xy 186.785033 -230.239) (xy 186.823846 -230.201579) (xy 186.867694 -230.170209)
			(xy 186.915642 -230.145557) (xy 186.966669 -230.128149) (xy 187.019687 -230.118356) (xy 187.073566 -230.116387)
			(xy 187.127157 -230.122284) (xy 187.179318 -230.13592) (xy 187.228938 -230.157007) (xy 187.274959 -230.185093)
			(xy 187.316401 -230.219581) (xy 187.352379 -230.259735) (xy 187.382127 -230.304699) (xy 187.405012 -230.353516)
			(xy 187.420544 -230.405145) (xy 187.428394 -230.458485) (xy 187.428886 -230.485442) (xy 194.234831 -230.485442)
			(xy 194.238766 -230.431671) (xy 194.250489 -230.379047) (xy 194.269749 -230.32869) (xy 194.296135 -230.281673)
			(xy 194.329087 -230.239) (xy 194.3679 -230.201579) (xy 194.411748 -230.170209) (xy 194.459696 -230.145557)
			(xy 194.510723 -230.128149) (xy 194.563741 -230.118356) (xy 194.61762 -230.116387) (xy 194.671211 -230.122284)
			(xy 194.723372 -230.13592) (xy 194.772992 -230.157007) (xy 194.819013 -230.185093) (xy 194.860455 -230.219581)
			(xy 194.896433 -230.259735) (xy 194.926181 -230.304699) (xy 194.949066 -230.353516) (xy 194.964598 -230.405145)
			(xy 194.972448 -230.458485) (xy 194.97294 -230.485442) (xy 201.778631 -230.485442) (xy 201.782566 -230.431671)
			(xy 201.794289 -230.379047) (xy 201.813549 -230.32869) (xy 201.839935 -230.281673) (xy 201.872887 -230.239)
			(xy 201.9117 -230.201579) (xy 201.955548 -230.170209) (xy 202.003496 -230.145557) (xy 202.054523 -230.128149)
			(xy 202.107541 -230.118356) (xy 202.16142 -230.116387) (xy 202.215011 -230.122284) (xy 202.267172 -230.13592)
			(xy 202.316792 -230.157007) (xy 202.362813 -230.185093) (xy 202.404255 -230.219581) (xy 202.440233 -230.259735)
			(xy 202.469981 -230.304699) (xy 202.492866 -230.353516) (xy 202.508398 -230.405145) (xy 202.516248 -230.458485)
			(xy 202.51674 -230.485442) (xy 202.516248 -230.512399) (xy 202.508398 -230.565739) (xy 202.492866 -230.617368)
			(xy 202.469981 -230.666185) (xy 202.440233 -230.711149) (xy 202.404255 -230.751303) (xy 202.362813 -230.785791)
			(xy 202.316792 -230.813877) (xy 202.267172 -230.834964) (xy 202.215011 -230.8486) (xy 202.16142 -230.854497)
			(xy 202.107541 -230.852528) (xy 202.054523 -230.842735) (xy 202.003496 -230.825327) (xy 201.955548 -230.800675)
			(xy 201.9117 -230.769305) (xy 201.872887 -230.731884) (xy 201.839935 -230.689211) (xy 201.813549 -230.642194)
			(xy 201.794289 -230.591837) (xy 201.782566 -230.539213) (xy 201.778631 -230.485442) (xy 194.97294 -230.485442)
			(xy 194.972448 -230.512399) (xy 194.964598 -230.565739) (xy 194.949066 -230.617368) (xy 194.926181 -230.666185)
			(xy 194.896433 -230.711149) (xy 194.860455 -230.751303) (xy 194.819013 -230.785791) (xy 194.772992 -230.813877)
			(xy 194.723372 -230.834964) (xy 194.671211 -230.8486) (xy 194.61762 -230.854497) (xy 194.563741 -230.852528)
			(xy 194.510723 -230.842735) (xy 194.459696 -230.825327) (xy 194.411748 -230.800675) (xy 194.3679 -230.769305)
			(xy 194.329087 -230.731884) (xy 194.296135 -230.689211) (xy 194.269749 -230.642194) (xy 194.250489 -230.591837)
			(xy 194.238766 -230.539213) (xy 194.234831 -230.485442) (xy 187.428886 -230.485442) (xy 187.428394 -230.512399)
			(xy 187.420544 -230.565739) (xy 187.405012 -230.617368) (xy 187.382127 -230.666185) (xy 187.352379 -230.711149)
			(xy 187.316401 -230.751303) (xy 187.274959 -230.785791) (xy 187.228938 -230.813877) (xy 187.179318 -230.834964)
			(xy 187.127157 -230.8486) (xy 187.073566 -230.854497) (xy 187.019687 -230.852528) (xy 186.966669 -230.842735)
			(xy 186.915642 -230.825327) (xy 186.867694 -230.800675) (xy 186.823846 -230.769305) (xy 186.785033 -230.731884)
			(xy 186.752081 -230.689211) (xy 186.725695 -230.642194) (xy 186.706435 -230.591837) (xy 186.694712 -230.539213)
			(xy 186.690777 -230.485442) (xy 179.884832 -230.485442) (xy 179.88434 -230.512399) (xy 179.87649 -230.565739)
			(xy 179.860958 -230.617368) (xy 179.838073 -230.666185) (xy 179.808325 -230.711149) (xy 179.772347 -230.751303)
			(xy 179.730905 -230.785791) (xy 179.684884 -230.813877) (xy 179.635264 -230.834964) (xy 179.583103 -230.8486)
			(xy 179.529512 -230.854497) (xy 179.475633 -230.852528) (xy 179.422615 -230.842735) (xy 179.371588 -230.825327)
			(xy 179.32364 -230.800675) (xy 179.279792 -230.769305) (xy 179.240979 -230.731884) (xy 179.208027 -230.689211)
			(xy 179.181641 -230.642194) (xy 179.162381 -230.591837) (xy 179.150658 -230.539213) (xy 179.146723 -230.485442)
			(xy 177.881534 -230.485442) (xy 177.881534 -231.335326) (xy 183.246791 -231.335326) (xy 183.250726 -231.281555)
			(xy 183.262449 -231.228931) (xy 183.281709 -231.178574) (xy 183.308095 -231.131557) (xy 183.341047 -231.088884)
			(xy 183.37986 -231.051463) (xy 183.423708 -231.020093) (xy 183.471656 -230.995441) (xy 183.522683 -230.978033)
			(xy 183.575701 -230.96824) (xy 183.62958 -230.966271) (xy 183.683171 -230.972168) (xy 183.735332 -230.985804)
			(xy 183.784952 -231.006891) (xy 183.830973 -231.034977) (xy 183.872415 -231.069465) (xy 183.908393 -231.109619)
			(xy 183.938141 -231.154583) (xy 183.961026 -231.2034) (xy 183.976558 -231.255029) (xy 183.984408 -231.308369)
			(xy 183.9849 -231.335326) (xy 190.790845 -231.335326) (xy 190.79478 -231.281555) (xy 190.806503 -231.228931)
			(xy 190.825763 -231.178574) (xy 190.852149 -231.131557) (xy 190.885101 -231.088884) (xy 190.923914 -231.051463)
			(xy 190.967762 -231.020093) (xy 191.01571 -230.995441) (xy 191.066737 -230.978033) (xy 191.119755 -230.96824)
			(xy 191.173634 -230.966271) (xy 191.227225 -230.972168) (xy 191.279386 -230.985804) (xy 191.329006 -231.006891)
			(xy 191.375027 -231.034977) (xy 191.416469 -231.069465) (xy 191.452447 -231.109619) (xy 191.482195 -231.154583)
			(xy 191.50508 -231.2034) (xy 191.520612 -231.255029) (xy 191.528462 -231.308369) (xy 191.528954 -231.335326)
			(xy 198.334899 -231.335326) (xy 198.338834 -231.281555) (xy 198.350557 -231.228931) (xy 198.369817 -231.178574)
			(xy 198.396203 -231.131557) (xy 198.429155 -231.088884) (xy 198.467968 -231.051463) (xy 198.511816 -231.020093)
			(xy 198.559764 -230.995441) (xy 198.610791 -230.978033) (xy 198.663809 -230.96824) (xy 198.717688 -230.966271)
			(xy 198.771279 -230.972168) (xy 198.82344 -230.985804) (xy 198.87306 -231.006891) (xy 198.919081 -231.034977)
			(xy 198.960523 -231.069465) (xy 198.996501 -231.109619) (xy 199.026249 -231.154583) (xy 199.049134 -231.2034)
			(xy 199.064666 -231.255029) (xy 199.072516 -231.308369) (xy 199.073008 -231.335326) (xy 205.878699 -231.335326)
			(xy 205.882634 -231.281555) (xy 205.894357 -231.228931) (xy 205.913617 -231.178574) (xy 205.940003 -231.131557)
			(xy 205.972955 -231.088884) (xy 206.011768 -231.051463) (xy 206.055616 -231.020093) (xy 206.103564 -230.995441)
			(xy 206.154591 -230.978033) (xy 206.207609 -230.96824) (xy 206.261488 -230.966271) (xy 206.315079 -230.972168)
			(xy 206.36724 -230.985804) (xy 206.41686 -231.006891) (xy 206.462881 -231.034977) (xy 206.504323 -231.069465)
			(xy 206.540301 -231.109619) (xy 206.570049 -231.154583) (xy 206.592934 -231.2034) (xy 206.608466 -231.255029)
			(xy 206.616316 -231.308369) (xy 206.616808 -231.335326) (xy 206.616316 -231.362283) (xy 206.608466 -231.415623)
			(xy 206.592934 -231.467252) (xy 206.570049 -231.516069) (xy 206.540301 -231.561033) (xy 206.504323 -231.601187)
			(xy 206.462881 -231.635675) (xy 206.41686 -231.663761) (xy 206.36724 -231.684848) (xy 206.315079 -231.698484)
			(xy 206.261488 -231.704381) (xy 206.207609 -231.702412) (xy 206.154591 -231.692619) (xy 206.103564 -231.675211)
			(xy 206.055616 -231.650559) (xy 206.011768 -231.619189) (xy 205.972955 -231.581768) (xy 205.940003 -231.539095)
			(xy 205.913617 -231.492078) (xy 205.894357 -231.441721) (xy 205.882634 -231.389097) (xy 205.878699 -231.335326)
			(xy 199.073008 -231.335326) (xy 199.072516 -231.362283) (xy 199.064666 -231.415623) (xy 199.049134 -231.467252)
			(xy 199.026249 -231.516069) (xy 198.996501 -231.561033) (xy 198.960523 -231.601187) (xy 198.919081 -231.635675)
			(xy 198.87306 -231.663761) (xy 198.82344 -231.684848) (xy 198.771279 -231.698484) (xy 198.717688 -231.704381)
			(xy 198.663809 -231.702412) (xy 198.610791 -231.692619) (xy 198.559764 -231.675211) (xy 198.511816 -231.650559)
			(xy 198.467968 -231.619189) (xy 198.429155 -231.581768) (xy 198.396203 -231.539095) (xy 198.369817 -231.492078)
			(xy 198.350557 -231.441721) (xy 198.338834 -231.389097) (xy 198.334899 -231.335326) (xy 191.528954 -231.335326)
			(xy 191.528462 -231.362283) (xy 191.520612 -231.415623) (xy 191.50508 -231.467252) (xy 191.482195 -231.516069)
			(xy 191.452447 -231.561033) (xy 191.416469 -231.601187) (xy 191.375027 -231.635675) (xy 191.329006 -231.663761)
			(xy 191.279386 -231.684848) (xy 191.227225 -231.698484) (xy 191.173634 -231.704381) (xy 191.119755 -231.702412)
			(xy 191.066737 -231.692619) (xy 191.01571 -231.675211) (xy 190.967762 -231.650559) (xy 190.923914 -231.619189)
			(xy 190.885101 -231.581768) (xy 190.852149 -231.539095) (xy 190.825763 -231.492078) (xy 190.806503 -231.441721)
			(xy 190.79478 -231.389097) (xy 190.790845 -231.335326) (xy 183.9849 -231.335326) (xy 183.984408 -231.362283)
			(xy 183.976558 -231.415623) (xy 183.961026 -231.467252) (xy 183.938141 -231.516069) (xy 183.908393 -231.561033)
			(xy 183.872415 -231.601187) (xy 183.830973 -231.635675) (xy 183.784952 -231.663761) (xy 183.735332 -231.684848)
			(xy 183.683171 -231.698484) (xy 183.62958 -231.704381) (xy 183.575701 -231.702412) (xy 183.522683 -231.692619)
			(xy 183.471656 -231.675211) (xy 183.423708 -231.650559) (xy 183.37986 -231.619189) (xy 183.341047 -231.581768)
			(xy 183.308095 -231.539095) (xy 183.281709 -231.492078) (xy 183.262449 -231.441721) (xy 183.250726 -231.389097)
			(xy 183.246791 -231.335326) (xy 177.881534 -231.335326) (xy 177.881534 -232.18521) (xy 179.146723 -232.18521)
			(xy 179.150658 -232.131439) (xy 179.162381 -232.078815) (xy 179.181641 -232.028458) (xy 179.208027 -231.981441)
			(xy 179.240979 -231.938768) (xy 179.279792 -231.901347) (xy 179.32364 -231.869977) (xy 179.371588 -231.845325)
			(xy 179.422615 -231.827917) (xy 179.475633 -231.818124) (xy 179.529512 -231.816155) (xy 179.583103 -231.822052)
			(xy 179.635264 -231.835688) (xy 179.684884 -231.856775) (xy 179.730905 -231.884861) (xy 179.772347 -231.919349)
			(xy 179.808325 -231.959503) (xy 179.838073 -232.004467) (xy 179.860958 -232.053284) (xy 179.87649 -232.104913)
			(xy 179.88434 -232.158253) (xy 179.884832 -232.18521) (xy 186.690777 -232.18521) (xy 186.694712 -232.131439)
			(xy 186.706435 -232.078815) (xy 186.725695 -232.028458) (xy 186.752081 -231.981441) (xy 186.785033 -231.938768)
			(xy 186.823846 -231.901347) (xy 186.867694 -231.869977) (xy 186.915642 -231.845325) (xy 186.966669 -231.827917)
			(xy 187.019687 -231.818124) (xy 187.073566 -231.816155) (xy 187.127157 -231.822052) (xy 187.179318 -231.835688)
			(xy 187.228938 -231.856775) (xy 187.274959 -231.884861) (xy 187.316401 -231.919349) (xy 187.352379 -231.959503)
			(xy 187.382127 -232.004467) (xy 187.405012 -232.053284) (xy 187.420544 -232.104913) (xy 187.428394 -232.158253)
			(xy 187.428886 -232.18521) (xy 194.234831 -232.18521) (xy 194.238766 -232.131439) (xy 194.250489 -232.078815)
			(xy 194.269749 -232.028458) (xy 194.296135 -231.981441) (xy 194.329087 -231.938768) (xy 194.3679 -231.901347)
			(xy 194.411748 -231.869977) (xy 194.459696 -231.845325) (xy 194.510723 -231.827917) (xy 194.563741 -231.818124)
			(xy 194.61762 -231.816155) (xy 194.671211 -231.822052) (xy 194.723372 -231.835688) (xy 194.772992 -231.856775)
			(xy 194.819013 -231.884861) (xy 194.860455 -231.919349) (xy 194.896433 -231.959503) (xy 194.926181 -232.004467)
			(xy 194.949066 -232.053284) (xy 194.964598 -232.104913) (xy 194.972448 -232.158253) (xy 194.97294 -232.18521)
			(xy 201.778631 -232.18521) (xy 201.782566 -232.131439) (xy 201.794289 -232.078815) (xy 201.813549 -232.028458)
			(xy 201.839935 -231.981441) (xy 201.872887 -231.938768) (xy 201.9117 -231.901347) (xy 201.955548 -231.869977)
			(xy 202.003496 -231.845325) (xy 202.054523 -231.827917) (xy 202.107541 -231.818124) (xy 202.16142 -231.816155)
			(xy 202.215011 -231.822052) (xy 202.267172 -231.835688) (xy 202.316792 -231.856775) (xy 202.362813 -231.884861)
			(xy 202.404255 -231.919349) (xy 202.440233 -231.959503) (xy 202.469981 -232.004467) (xy 202.492866 -232.053284)
			(xy 202.508398 -232.104913) (xy 202.516248 -232.158253) (xy 202.51674 -232.18521) (xy 202.516248 -232.212167)
			(xy 202.508398 -232.265507) (xy 202.492866 -232.317136) (xy 202.469981 -232.365953) (xy 202.440233 -232.410917)
			(xy 202.404255 -232.451071) (xy 202.362813 -232.485559) (xy 202.316792 -232.513645) (xy 202.267172 -232.534732)
			(xy 202.215011 -232.548368) (xy 202.16142 -232.554265) (xy 202.107541 -232.552296) (xy 202.054523 -232.542503)
			(xy 202.003496 -232.525095) (xy 201.955548 -232.500443) (xy 201.9117 -232.469073) (xy 201.872887 -232.431652)
			(xy 201.839935 -232.388979) (xy 201.813549 -232.341962) (xy 201.794289 -232.291605) (xy 201.782566 -232.238981)
			(xy 201.778631 -232.18521) (xy 194.97294 -232.18521) (xy 194.972448 -232.212167) (xy 194.964598 -232.265507)
			(xy 194.949066 -232.317136) (xy 194.926181 -232.365953) (xy 194.896433 -232.410917) (xy 194.860455 -232.451071)
			(xy 194.819013 -232.485559) (xy 194.772992 -232.513645) (xy 194.723372 -232.534732) (xy 194.671211 -232.548368)
			(xy 194.61762 -232.554265) (xy 194.563741 -232.552296) (xy 194.510723 -232.542503) (xy 194.459696 -232.525095)
			(xy 194.411748 -232.500443) (xy 194.3679 -232.469073) (xy 194.329087 -232.431652) (xy 194.296135 -232.388979)
			(xy 194.269749 -232.341962) (xy 194.250489 -232.291605) (xy 194.238766 -232.238981) (xy 194.234831 -232.18521)
			(xy 187.428886 -232.18521) (xy 187.428394 -232.212167) (xy 187.420544 -232.265507) (xy 187.405012 -232.317136)
			(xy 187.382127 -232.365953) (xy 187.352379 -232.410917) (xy 187.316401 -232.451071) (xy 187.274959 -232.485559)
			(xy 187.228938 -232.513645) (xy 187.179318 -232.534732) (xy 187.127157 -232.548368) (xy 187.073566 -232.554265)
			(xy 187.019687 -232.552296) (xy 186.966669 -232.542503) (xy 186.915642 -232.525095) (xy 186.867694 -232.500443)
			(xy 186.823846 -232.469073) (xy 186.785033 -232.431652) (xy 186.752081 -232.388979) (xy 186.725695 -232.341962)
			(xy 186.706435 -232.291605) (xy 186.694712 -232.238981) (xy 186.690777 -232.18521) (xy 179.884832 -232.18521)
			(xy 179.88434 -232.212167) (xy 179.87649 -232.265507) (xy 179.860958 -232.317136) (xy 179.838073 -232.365953)
			(xy 179.808325 -232.410917) (xy 179.772347 -232.451071) (xy 179.730905 -232.485559) (xy 179.684884 -232.513645)
			(xy 179.635264 -232.534732) (xy 179.583103 -232.548368) (xy 179.529512 -232.554265) (xy 179.475633 -232.552296)
			(xy 179.422615 -232.542503) (xy 179.371588 -232.525095) (xy 179.32364 -232.500443) (xy 179.279792 -232.469073)
			(xy 179.240979 -232.431652) (xy 179.208027 -232.388979) (xy 179.181641 -232.341962) (xy 179.162381 -232.291605)
			(xy 179.150658 -232.238981) (xy 179.146723 -232.18521) (xy 177.881534 -232.18521) (xy 177.881534 -233.035348)
			(xy 183.246791 -233.035348) (xy 183.250726 -232.981577) (xy 183.262449 -232.928953) (xy 183.281709 -232.878596)
			(xy 183.308095 -232.831579) (xy 183.341047 -232.788906) (xy 183.37986 -232.751485) (xy 183.423708 -232.720115)
			(xy 183.471656 -232.695463) (xy 183.522683 -232.678055) (xy 183.575701 -232.668262) (xy 183.62958 -232.666293)
			(xy 183.683171 -232.67219) (xy 183.735332 -232.685826) (xy 183.784952 -232.706913) (xy 183.830973 -232.734999)
			(xy 183.872415 -232.769487) (xy 183.908393 -232.809641) (xy 183.938141 -232.854605) (xy 183.961026 -232.903422)
			(xy 183.976558 -232.955051) (xy 183.984408 -233.008391) (xy 183.9849 -233.035348) (xy 190.790845 -233.035348)
			(xy 190.79478 -232.981577) (xy 190.806503 -232.928953) (xy 190.825763 -232.878596) (xy 190.852149 -232.831579)
			(xy 190.885101 -232.788906) (xy 190.923914 -232.751485) (xy 190.967762 -232.720115) (xy 191.01571 -232.695463)
			(xy 191.066737 -232.678055) (xy 191.119755 -232.668262) (xy 191.173634 -232.666293) (xy 191.227225 -232.67219)
			(xy 191.279386 -232.685826) (xy 191.329006 -232.706913) (xy 191.375027 -232.734999) (xy 191.416469 -232.769487)
			(xy 191.452447 -232.809641) (xy 191.482195 -232.854605) (xy 191.50508 -232.903422) (xy 191.520612 -232.955051)
			(xy 191.528462 -233.008391) (xy 191.528954 -233.035348) (xy 198.334899 -233.035348) (xy 198.338834 -232.981577)
			(xy 198.350557 -232.928953) (xy 198.369817 -232.878596) (xy 198.396203 -232.831579) (xy 198.429155 -232.788906)
			(xy 198.467968 -232.751485) (xy 198.511816 -232.720115) (xy 198.559764 -232.695463) (xy 198.610791 -232.678055)
			(xy 198.663809 -232.668262) (xy 198.717688 -232.666293) (xy 198.771279 -232.67219) (xy 198.82344 -232.685826)
			(xy 198.87306 -232.706913) (xy 198.919081 -232.734999) (xy 198.960523 -232.769487) (xy 198.996501 -232.809641)
			(xy 199.026249 -232.854605) (xy 199.049134 -232.903422) (xy 199.064666 -232.955051) (xy 199.072516 -233.008391)
			(xy 199.073008 -233.035348) (xy 205.878699 -233.035348) (xy 205.882634 -232.981577) (xy 205.894357 -232.928953)
			(xy 205.913617 -232.878596) (xy 205.940003 -232.831579) (xy 205.972955 -232.788906) (xy 206.011768 -232.751485)
			(xy 206.055616 -232.720115) (xy 206.103564 -232.695463) (xy 206.154591 -232.678055) (xy 206.207609 -232.668262)
			(xy 206.261488 -232.666293) (xy 206.315079 -232.67219) (xy 206.36724 -232.685826) (xy 206.41686 -232.706913)
			(xy 206.462881 -232.734999) (xy 206.504323 -232.769487) (xy 206.540301 -232.809641) (xy 206.570049 -232.854605)
			(xy 206.592934 -232.903422) (xy 206.608466 -232.955051) (xy 206.616316 -233.008391) (xy 206.616808 -233.035348)
			(xy 206.616316 -233.062305) (xy 206.608466 -233.115645) (xy 206.592934 -233.167274) (xy 206.570049 -233.216091)
			(xy 206.540301 -233.261055) (xy 206.504323 -233.301209) (xy 206.462881 -233.335697) (xy 206.41686 -233.363783)
			(xy 206.36724 -233.38487) (xy 206.315079 -233.398506) (xy 206.261488 -233.404403) (xy 206.207609 -233.402434)
			(xy 206.154591 -233.392641) (xy 206.103564 -233.375233) (xy 206.055616 -233.350581) (xy 206.011768 -233.319211)
			(xy 205.972955 -233.28179) (xy 205.940003 -233.239117) (xy 205.913617 -233.1921) (xy 205.894357 -233.141743)
			(xy 205.882634 -233.089119) (xy 205.878699 -233.035348) (xy 199.073008 -233.035348) (xy 199.072516 -233.062305)
			(xy 199.064666 -233.115645) (xy 199.049134 -233.167274) (xy 199.026249 -233.216091) (xy 198.996501 -233.261055)
			(xy 198.960523 -233.301209) (xy 198.919081 -233.335697) (xy 198.87306 -233.363783) (xy 198.82344 -233.38487)
			(xy 198.771279 -233.398506) (xy 198.717688 -233.404403) (xy 198.663809 -233.402434) (xy 198.610791 -233.392641)
			(xy 198.559764 -233.375233) (xy 198.511816 -233.350581) (xy 198.467968 -233.319211) (xy 198.429155 -233.28179)
			(xy 198.396203 -233.239117) (xy 198.369817 -233.1921) (xy 198.350557 -233.141743) (xy 198.338834 -233.089119)
			(xy 198.334899 -233.035348) (xy 191.528954 -233.035348) (xy 191.528462 -233.062305) (xy 191.520612 -233.115645)
			(xy 191.50508 -233.167274) (xy 191.482195 -233.216091) (xy 191.452447 -233.261055) (xy 191.416469 -233.301209)
			(xy 191.375027 -233.335697) (xy 191.329006 -233.363783) (xy 191.279386 -233.38487) (xy 191.227225 -233.398506)
			(xy 191.173634 -233.404403) (xy 191.119755 -233.402434) (xy 191.066737 -233.392641) (xy 191.01571 -233.375233)
			(xy 190.967762 -233.350581) (xy 190.923914 -233.319211) (xy 190.885101 -233.28179) (xy 190.852149 -233.239117)
			(xy 190.825763 -233.1921) (xy 190.806503 -233.141743) (xy 190.79478 -233.089119) (xy 190.790845 -233.035348)
			(xy 183.9849 -233.035348) (xy 183.984408 -233.062305) (xy 183.976558 -233.115645) (xy 183.961026 -233.167274)
			(xy 183.938141 -233.216091) (xy 183.908393 -233.261055) (xy 183.872415 -233.301209) (xy 183.830973 -233.335697)
			(xy 183.784952 -233.363783) (xy 183.735332 -233.38487) (xy 183.683171 -233.398506) (xy 183.62958 -233.404403)
			(xy 183.575701 -233.402434) (xy 183.522683 -233.392641) (xy 183.471656 -233.375233) (xy 183.423708 -233.350581)
			(xy 183.37986 -233.319211) (xy 183.341047 -233.28179) (xy 183.308095 -233.239117) (xy 183.281709 -233.1921)
			(xy 183.262449 -233.141743) (xy 183.250726 -233.089119) (xy 183.246791 -233.035348) (xy 177.881534 -233.035348)
			(xy 177.881534 -233.885232) (xy 179.146723 -233.885232) (xy 179.150658 -233.831461) (xy 179.162381 -233.778837)
			(xy 179.181641 -233.72848) (xy 179.208027 -233.681463) (xy 179.240979 -233.63879) (xy 179.279792 -233.601369)
			(xy 179.32364 -233.569999) (xy 179.371588 -233.545347) (xy 179.422615 -233.527939) (xy 179.475633 -233.518146)
			(xy 179.529512 -233.516177) (xy 179.583103 -233.522074) (xy 179.635264 -233.53571) (xy 179.684884 -233.556797)
			(xy 179.730905 -233.584883) (xy 179.772347 -233.619371) (xy 179.808325 -233.659525) (xy 179.838073 -233.704489)
			(xy 179.860958 -233.753306) (xy 179.87649 -233.804935) (xy 179.88434 -233.858275) (xy 179.884832 -233.885232)
			(xy 186.690777 -233.885232) (xy 186.694712 -233.831461) (xy 186.706435 -233.778837) (xy 186.725695 -233.72848)
			(xy 186.752081 -233.681463) (xy 186.785033 -233.63879) (xy 186.823846 -233.601369) (xy 186.867694 -233.569999)
			(xy 186.915642 -233.545347) (xy 186.966669 -233.527939) (xy 187.019687 -233.518146) (xy 187.073566 -233.516177)
			(xy 187.127157 -233.522074) (xy 187.179318 -233.53571) (xy 187.228938 -233.556797) (xy 187.274959 -233.584883)
			(xy 187.316401 -233.619371) (xy 187.352379 -233.659525) (xy 187.382127 -233.704489) (xy 187.405012 -233.753306)
			(xy 187.420544 -233.804935) (xy 187.428394 -233.858275) (xy 187.428886 -233.885232) (xy 194.234831 -233.885232)
			(xy 194.238766 -233.831461) (xy 194.250489 -233.778837) (xy 194.269749 -233.72848) (xy 194.296135 -233.681463)
			(xy 194.329087 -233.63879) (xy 194.3679 -233.601369) (xy 194.411748 -233.569999) (xy 194.459696 -233.545347)
			(xy 194.510723 -233.527939) (xy 194.563741 -233.518146) (xy 194.61762 -233.516177) (xy 194.671211 -233.522074)
			(xy 194.723372 -233.53571) (xy 194.772992 -233.556797) (xy 194.819013 -233.584883) (xy 194.860455 -233.619371)
			(xy 194.896433 -233.659525) (xy 194.926181 -233.704489) (xy 194.949066 -233.753306) (xy 194.964598 -233.804935)
			(xy 194.972448 -233.858275) (xy 194.97294 -233.885232) (xy 201.778631 -233.885232) (xy 201.782566 -233.831461)
			(xy 201.794289 -233.778837) (xy 201.813549 -233.72848) (xy 201.839935 -233.681463) (xy 201.872887 -233.63879)
			(xy 201.9117 -233.601369) (xy 201.955548 -233.569999) (xy 202.003496 -233.545347) (xy 202.054523 -233.527939)
			(xy 202.107541 -233.518146) (xy 202.16142 -233.516177) (xy 202.215011 -233.522074) (xy 202.267172 -233.53571)
			(xy 202.316792 -233.556797) (xy 202.362813 -233.584883) (xy 202.404255 -233.619371) (xy 202.440233 -233.659525)
			(xy 202.469981 -233.704489) (xy 202.492866 -233.753306) (xy 202.508398 -233.804935) (xy 202.516248 -233.858275)
			(xy 202.51674 -233.885232) (xy 202.516248 -233.912189) (xy 202.508398 -233.965529) (xy 202.492866 -234.017158)
			(xy 202.469981 -234.065975) (xy 202.440233 -234.110939) (xy 202.404255 -234.151093) (xy 202.362813 -234.185581)
			(xy 202.316792 -234.213667) (xy 202.267172 -234.234754) (xy 202.215011 -234.24839) (xy 202.16142 -234.254287)
			(xy 202.107541 -234.252318) (xy 202.054523 -234.242525) (xy 202.003496 -234.225117) (xy 201.955548 -234.200465)
			(xy 201.9117 -234.169095) (xy 201.872887 -234.131674) (xy 201.839935 -234.089001) (xy 201.813549 -234.041984)
			(xy 201.794289 -233.991627) (xy 201.782566 -233.939003) (xy 201.778631 -233.885232) (xy 194.97294 -233.885232)
			(xy 194.972448 -233.912189) (xy 194.964598 -233.965529) (xy 194.949066 -234.017158) (xy 194.926181 -234.065975)
			(xy 194.896433 -234.110939) (xy 194.860455 -234.151093) (xy 194.819013 -234.185581) (xy 194.772992 -234.213667)
			(xy 194.723372 -234.234754) (xy 194.671211 -234.24839) (xy 194.61762 -234.254287) (xy 194.563741 -234.252318)
			(xy 194.510723 -234.242525) (xy 194.459696 -234.225117) (xy 194.411748 -234.200465) (xy 194.3679 -234.169095)
			(xy 194.329087 -234.131674) (xy 194.296135 -234.089001) (xy 194.269749 -234.041984) (xy 194.250489 -233.991627)
			(xy 194.238766 -233.939003) (xy 194.234831 -233.885232) (xy 187.428886 -233.885232) (xy 187.428394 -233.912189)
			(xy 187.420544 -233.965529) (xy 187.405012 -234.017158) (xy 187.382127 -234.065975) (xy 187.352379 -234.110939)
			(xy 187.316401 -234.151093) (xy 187.274959 -234.185581) (xy 187.228938 -234.213667) (xy 187.179318 -234.234754)
			(xy 187.127157 -234.24839) (xy 187.073566 -234.254287) (xy 187.019687 -234.252318) (xy 186.966669 -234.242525)
			(xy 186.915642 -234.225117) (xy 186.867694 -234.200465) (xy 186.823846 -234.169095) (xy 186.785033 -234.131674)
			(xy 186.752081 -234.089001) (xy 186.725695 -234.041984) (xy 186.706435 -233.991627) (xy 186.694712 -233.939003)
			(xy 186.690777 -233.885232) (xy 179.884832 -233.885232) (xy 179.88434 -233.912189) (xy 179.87649 -233.965529)
			(xy 179.860958 -234.017158) (xy 179.838073 -234.065975) (xy 179.808325 -234.110939) (xy 179.772347 -234.151093)
			(xy 179.730905 -234.185581) (xy 179.684884 -234.213667) (xy 179.635264 -234.234754) (xy 179.583103 -234.24839)
			(xy 179.529512 -234.254287) (xy 179.475633 -234.252318) (xy 179.422615 -234.242525) (xy 179.371588 -234.225117)
			(xy 179.32364 -234.200465) (xy 179.279792 -234.169095) (xy 179.240979 -234.131674) (xy 179.208027 -234.089001)
			(xy 179.181641 -234.041984) (xy 179.162381 -233.991627) (xy 179.150658 -233.939003) (xy 179.146723 -233.885232)
			(xy 177.881534 -233.885232) (xy 177.881534 -234.73537) (xy 183.246791 -234.73537) (xy 183.250726 -234.681599)
			(xy 183.262449 -234.628975) (xy 183.281709 -234.578618) (xy 183.308095 -234.531601) (xy 183.341047 -234.488928)
			(xy 183.37986 -234.451507) (xy 183.423708 -234.420137) (xy 183.471656 -234.395485) (xy 183.522683 -234.378077)
			(xy 183.575701 -234.368284) (xy 183.62958 -234.366315) (xy 183.683171 -234.372212) (xy 183.735332 -234.385848)
			(xy 183.784952 -234.406935) (xy 183.830973 -234.435021) (xy 183.872415 -234.469509) (xy 183.908393 -234.509663)
			(xy 183.938141 -234.554627) (xy 183.961026 -234.603444) (xy 183.976558 -234.655073) (xy 183.984408 -234.708413)
			(xy 183.9849 -234.73537) (xy 190.790845 -234.73537) (xy 190.79478 -234.681599) (xy 190.806503 -234.628975)
			(xy 190.825763 -234.578618) (xy 190.852149 -234.531601) (xy 190.885101 -234.488928) (xy 190.923914 -234.451507)
			(xy 190.967762 -234.420137) (xy 191.01571 -234.395485) (xy 191.066737 -234.378077) (xy 191.119755 -234.368284)
			(xy 191.173634 -234.366315) (xy 191.227225 -234.372212) (xy 191.279386 -234.385848) (xy 191.329006 -234.406935)
			(xy 191.375027 -234.435021) (xy 191.416469 -234.469509) (xy 191.452447 -234.509663) (xy 191.482195 -234.554627)
			(xy 191.50508 -234.603444) (xy 191.520612 -234.655073) (xy 191.528462 -234.708413) (xy 191.528954 -234.73537)
			(xy 198.334899 -234.73537) (xy 198.338834 -234.681599) (xy 198.350557 -234.628975) (xy 198.369817 -234.578618)
			(xy 198.396203 -234.531601) (xy 198.429155 -234.488928) (xy 198.467968 -234.451507) (xy 198.511816 -234.420137)
			(xy 198.559764 -234.395485) (xy 198.610791 -234.378077) (xy 198.663809 -234.368284) (xy 198.717688 -234.366315)
			(xy 198.771279 -234.372212) (xy 198.82344 -234.385848) (xy 198.87306 -234.406935) (xy 198.919081 -234.435021)
			(xy 198.960523 -234.469509) (xy 198.996501 -234.509663) (xy 199.026249 -234.554627) (xy 199.049134 -234.603444)
			(xy 199.064666 -234.655073) (xy 199.072516 -234.708413) (xy 199.073008 -234.73537) (xy 205.878699 -234.73537)
			(xy 205.882634 -234.681599) (xy 205.894357 -234.628975) (xy 205.913617 -234.578618) (xy 205.940003 -234.531601)
			(xy 205.972955 -234.488928) (xy 206.011768 -234.451507) (xy 206.055616 -234.420137) (xy 206.103564 -234.395485)
			(xy 206.154591 -234.378077) (xy 206.207609 -234.368284) (xy 206.261488 -234.366315) (xy 206.315079 -234.372212)
			(xy 206.36724 -234.385848) (xy 206.41686 -234.406935) (xy 206.462881 -234.435021) (xy 206.504323 -234.469509)
			(xy 206.540301 -234.509663) (xy 206.570049 -234.554627) (xy 206.592934 -234.603444) (xy 206.608466 -234.655073)
			(xy 206.616316 -234.708413) (xy 206.616808 -234.73537) (xy 206.616316 -234.762327) (xy 206.608466 -234.815667)
			(xy 206.592934 -234.867296) (xy 206.570049 -234.916113) (xy 206.540301 -234.961077) (xy 206.504323 -235.001231)
			(xy 206.462881 -235.035719) (xy 206.41686 -235.063805) (xy 206.36724 -235.084892) (xy 206.315079 -235.098528)
			(xy 206.261488 -235.104425) (xy 206.207609 -235.102456) (xy 206.154591 -235.092663) (xy 206.103564 -235.075255)
			(xy 206.055616 -235.050603) (xy 206.011768 -235.019233) (xy 205.972955 -234.981812) (xy 205.940003 -234.939139)
			(xy 205.913617 -234.892122) (xy 205.894357 -234.841765) (xy 205.882634 -234.789141) (xy 205.878699 -234.73537)
			(xy 199.073008 -234.73537) (xy 199.072516 -234.762327) (xy 199.064666 -234.815667) (xy 199.049134 -234.867296)
			(xy 199.026249 -234.916113) (xy 198.996501 -234.961077) (xy 198.960523 -235.001231) (xy 198.919081 -235.035719)
			(xy 198.87306 -235.063805) (xy 198.82344 -235.084892) (xy 198.771279 -235.098528) (xy 198.717688 -235.104425)
			(xy 198.663809 -235.102456) (xy 198.610791 -235.092663) (xy 198.559764 -235.075255) (xy 198.511816 -235.050603)
			(xy 198.467968 -235.019233) (xy 198.429155 -234.981812) (xy 198.396203 -234.939139) (xy 198.369817 -234.892122)
			(xy 198.350557 -234.841765) (xy 198.338834 -234.789141) (xy 198.334899 -234.73537) (xy 191.528954 -234.73537)
			(xy 191.528462 -234.762327) (xy 191.520612 -234.815667) (xy 191.50508 -234.867296) (xy 191.482195 -234.916113)
			(xy 191.452447 -234.961077) (xy 191.416469 -235.001231) (xy 191.375027 -235.035719) (xy 191.329006 -235.063805)
			(xy 191.279386 -235.084892) (xy 191.227225 -235.098528) (xy 191.173634 -235.104425) (xy 191.119755 -235.102456)
			(xy 191.066737 -235.092663) (xy 191.01571 -235.075255) (xy 190.967762 -235.050603) (xy 190.923914 -235.019233)
			(xy 190.885101 -234.981812) (xy 190.852149 -234.939139) (xy 190.825763 -234.892122) (xy 190.806503 -234.841765)
			(xy 190.79478 -234.789141) (xy 190.790845 -234.73537) (xy 183.9849 -234.73537) (xy 183.984408 -234.762327)
			(xy 183.976558 -234.815667) (xy 183.961026 -234.867296) (xy 183.938141 -234.916113) (xy 183.908393 -234.961077)
			(xy 183.872415 -235.001231) (xy 183.830973 -235.035719) (xy 183.784952 -235.063805) (xy 183.735332 -235.084892)
			(xy 183.683171 -235.098528) (xy 183.62958 -235.104425) (xy 183.575701 -235.102456) (xy 183.522683 -235.092663)
			(xy 183.471656 -235.075255) (xy 183.423708 -235.050603) (xy 183.37986 -235.019233) (xy 183.341047 -234.981812)
			(xy 183.308095 -234.939139) (xy 183.281709 -234.892122) (xy 183.262449 -234.841765) (xy 183.250726 -234.789141)
			(xy 183.246791 -234.73537) (xy 177.881534 -234.73537) (xy 177.881534 -235.585254) (xy 179.146723 -235.585254)
			(xy 179.150658 -235.531483) (xy 179.162381 -235.478859) (xy 179.181641 -235.428502) (xy 179.208027 -235.381485)
			(xy 179.240979 -235.338812) (xy 179.279792 -235.301391) (xy 179.32364 -235.270021) (xy 179.371588 -235.245369)
			(xy 179.422615 -235.227961) (xy 179.475633 -235.218168) (xy 179.529512 -235.216199) (xy 179.583103 -235.222096)
			(xy 179.635264 -235.235732) (xy 179.684884 -235.256819) (xy 179.730905 -235.284905) (xy 179.772347 -235.319393)
			(xy 179.808325 -235.359547) (xy 179.838073 -235.404511) (xy 179.860958 -235.453328) (xy 179.87649 -235.504957)
			(xy 179.88434 -235.558297) (xy 179.884832 -235.585254) (xy 186.690777 -235.585254) (xy 186.694712 -235.531483)
			(xy 186.706435 -235.478859) (xy 186.725695 -235.428502) (xy 186.752081 -235.381485) (xy 186.785033 -235.338812)
			(xy 186.823846 -235.301391) (xy 186.867694 -235.270021) (xy 186.915642 -235.245369) (xy 186.966669 -235.227961)
			(xy 187.019687 -235.218168) (xy 187.073566 -235.216199) (xy 187.127157 -235.222096) (xy 187.179318 -235.235732)
			(xy 187.228938 -235.256819) (xy 187.274959 -235.284905) (xy 187.316401 -235.319393) (xy 187.352379 -235.359547)
			(xy 187.382127 -235.404511) (xy 187.405012 -235.453328) (xy 187.420544 -235.504957) (xy 187.428394 -235.558297)
			(xy 187.428886 -235.585254) (xy 194.234831 -235.585254) (xy 194.238766 -235.531483) (xy 194.250489 -235.478859)
			(xy 194.269749 -235.428502) (xy 194.296135 -235.381485) (xy 194.329087 -235.338812) (xy 194.3679 -235.301391)
			(xy 194.411748 -235.270021) (xy 194.459696 -235.245369) (xy 194.510723 -235.227961) (xy 194.563741 -235.218168)
			(xy 194.61762 -235.216199) (xy 194.671211 -235.222096) (xy 194.723372 -235.235732) (xy 194.772992 -235.256819)
			(xy 194.819013 -235.284905) (xy 194.860455 -235.319393) (xy 194.896433 -235.359547) (xy 194.926181 -235.404511)
			(xy 194.949066 -235.453328) (xy 194.964598 -235.504957) (xy 194.972448 -235.558297) (xy 194.97294 -235.585254)
			(xy 201.778631 -235.585254) (xy 201.782566 -235.531483) (xy 201.794289 -235.478859) (xy 201.813549 -235.428502)
			(xy 201.839935 -235.381485) (xy 201.872887 -235.338812) (xy 201.9117 -235.301391) (xy 201.955548 -235.270021)
			(xy 202.003496 -235.245369) (xy 202.054523 -235.227961) (xy 202.107541 -235.218168) (xy 202.16142 -235.216199)
			(xy 202.215011 -235.222096) (xy 202.267172 -235.235732) (xy 202.316792 -235.256819) (xy 202.362813 -235.284905)
			(xy 202.404255 -235.319393) (xy 202.440233 -235.359547) (xy 202.469981 -235.404511) (xy 202.492866 -235.453328)
			(xy 202.508398 -235.504957) (xy 202.516248 -235.558297) (xy 202.51674 -235.585254) (xy 202.516248 -235.612211)
			(xy 202.508398 -235.665551) (xy 202.492866 -235.71718) (xy 202.469981 -235.765997) (xy 202.440233 -235.810961)
			(xy 202.404255 -235.851115) (xy 202.362813 -235.885603) (xy 202.316792 -235.913689) (xy 202.267172 -235.934776)
			(xy 202.215011 -235.948412) (xy 202.16142 -235.954309) (xy 202.107541 -235.95234) (xy 202.054523 -235.942547)
			(xy 202.003496 -235.925139) (xy 201.955548 -235.900487) (xy 201.9117 -235.869117) (xy 201.872887 -235.831696)
			(xy 201.839935 -235.789023) (xy 201.813549 -235.742006) (xy 201.794289 -235.691649) (xy 201.782566 -235.639025)
			(xy 201.778631 -235.585254) (xy 194.97294 -235.585254) (xy 194.972448 -235.612211) (xy 194.964598 -235.665551)
			(xy 194.949066 -235.71718) (xy 194.926181 -235.765997) (xy 194.896433 -235.810961) (xy 194.860455 -235.851115)
			(xy 194.819013 -235.885603) (xy 194.772992 -235.913689) (xy 194.723372 -235.934776) (xy 194.671211 -235.948412)
			(xy 194.61762 -235.954309) (xy 194.563741 -235.95234) (xy 194.510723 -235.942547) (xy 194.459696 -235.925139)
			(xy 194.411748 -235.900487) (xy 194.3679 -235.869117) (xy 194.329087 -235.831696) (xy 194.296135 -235.789023)
			(xy 194.269749 -235.742006) (xy 194.250489 -235.691649) (xy 194.238766 -235.639025) (xy 194.234831 -235.585254)
			(xy 187.428886 -235.585254) (xy 187.428394 -235.612211) (xy 187.420544 -235.665551) (xy 187.405012 -235.71718)
			(xy 187.382127 -235.765997) (xy 187.352379 -235.810961) (xy 187.316401 -235.851115) (xy 187.274959 -235.885603)
			(xy 187.228938 -235.913689) (xy 187.179318 -235.934776) (xy 187.127157 -235.948412) (xy 187.073566 -235.954309)
			(xy 187.019687 -235.95234) (xy 186.966669 -235.942547) (xy 186.915642 -235.925139) (xy 186.867694 -235.900487)
			(xy 186.823846 -235.869117) (xy 186.785033 -235.831696) (xy 186.752081 -235.789023) (xy 186.725695 -235.742006)
			(xy 186.706435 -235.691649) (xy 186.694712 -235.639025) (xy 186.690777 -235.585254) (xy 179.884832 -235.585254)
			(xy 179.88434 -235.612211) (xy 179.87649 -235.665551) (xy 179.860958 -235.71718) (xy 179.838073 -235.765997)
			(xy 179.808325 -235.810961) (xy 179.772347 -235.851115) (xy 179.730905 -235.885603) (xy 179.684884 -235.913689)
			(xy 179.635264 -235.934776) (xy 179.583103 -235.948412) (xy 179.529512 -235.954309) (xy 179.475633 -235.95234)
			(xy 179.422615 -235.942547) (xy 179.371588 -235.925139) (xy 179.32364 -235.900487) (xy 179.279792 -235.869117)
			(xy 179.240979 -235.831696) (xy 179.208027 -235.789023) (xy 179.181641 -235.742006) (xy 179.162381 -235.691649)
			(xy 179.150658 -235.639025) (xy 179.146723 -235.585254) (xy 177.881534 -235.585254) (xy 177.881534 -236.435392)
			(xy 183.246791 -236.435392) (xy 183.250726 -236.381621) (xy 183.262449 -236.328997) (xy 183.281709 -236.27864)
			(xy 183.308095 -236.231623) (xy 183.341047 -236.18895) (xy 183.37986 -236.151529) (xy 183.423708 -236.120159)
			(xy 183.471656 -236.095507) (xy 183.522683 -236.078099) (xy 183.575701 -236.068306) (xy 183.62958 -236.066337)
			(xy 183.683171 -236.072234) (xy 183.735332 -236.08587) (xy 183.784952 -236.106957) (xy 183.830973 -236.135043)
			(xy 183.872415 -236.169531) (xy 183.908393 -236.209685) (xy 183.938141 -236.254649) (xy 183.961026 -236.303466)
			(xy 183.976558 -236.355095) (xy 183.984408 -236.408435) (xy 183.9849 -236.435392) (xy 190.790845 -236.435392)
			(xy 190.79478 -236.381621) (xy 190.806503 -236.328997) (xy 190.825763 -236.27864) (xy 190.852149 -236.231623)
			(xy 190.885101 -236.18895) (xy 190.923914 -236.151529) (xy 190.967762 -236.120159) (xy 191.01571 -236.095507)
			(xy 191.066737 -236.078099) (xy 191.119755 -236.068306) (xy 191.173634 -236.066337) (xy 191.227225 -236.072234)
			(xy 191.279386 -236.08587) (xy 191.329006 -236.106957) (xy 191.375027 -236.135043) (xy 191.416469 -236.169531)
			(xy 191.452447 -236.209685) (xy 191.482195 -236.254649) (xy 191.50508 -236.303466) (xy 191.520612 -236.355095)
			(xy 191.528462 -236.408435) (xy 191.528954 -236.435392) (xy 198.334899 -236.435392) (xy 198.338834 -236.381621)
			(xy 198.350557 -236.328997) (xy 198.369817 -236.27864) (xy 198.396203 -236.231623) (xy 198.429155 -236.18895)
			(xy 198.467968 -236.151529) (xy 198.511816 -236.120159) (xy 198.559764 -236.095507) (xy 198.610791 -236.078099)
			(xy 198.663809 -236.068306) (xy 198.717688 -236.066337) (xy 198.771279 -236.072234) (xy 198.82344 -236.08587)
			(xy 198.87306 -236.106957) (xy 198.919081 -236.135043) (xy 198.960523 -236.169531) (xy 198.996501 -236.209685)
			(xy 199.026249 -236.254649) (xy 199.049134 -236.303466) (xy 199.064666 -236.355095) (xy 199.072516 -236.408435)
			(xy 199.073008 -236.435392) (xy 205.878699 -236.435392) (xy 205.882634 -236.381621) (xy 205.894357 -236.328997)
			(xy 205.913617 -236.27864) (xy 205.940003 -236.231623) (xy 205.972955 -236.18895) (xy 206.011768 -236.151529)
			(xy 206.055616 -236.120159) (xy 206.103564 -236.095507) (xy 206.154591 -236.078099) (xy 206.207609 -236.068306)
			(xy 206.261488 -236.066337) (xy 206.315079 -236.072234) (xy 206.36724 -236.08587) (xy 206.41686 -236.106957)
			(xy 206.462881 -236.135043) (xy 206.504323 -236.169531) (xy 206.540301 -236.209685) (xy 206.570049 -236.254649)
			(xy 206.592934 -236.303466) (xy 206.608466 -236.355095) (xy 206.616316 -236.408435) (xy 206.616808 -236.435392)
			(xy 206.616316 -236.462349) (xy 206.608466 -236.515689) (xy 206.592934 -236.567318) (xy 206.570049 -236.616135)
			(xy 206.540301 -236.661099) (xy 206.504323 -236.701253) (xy 206.462881 -236.735741) (xy 206.41686 -236.763827)
			(xy 206.36724 -236.784914) (xy 206.315079 -236.79855) (xy 206.261488 -236.804447) (xy 206.207609 -236.802478)
			(xy 206.154591 -236.792685) (xy 206.103564 -236.775277) (xy 206.055616 -236.750625) (xy 206.011768 -236.719255)
			(xy 205.972955 -236.681834) (xy 205.940003 -236.639161) (xy 205.913617 -236.592144) (xy 205.894357 -236.541787)
			(xy 205.882634 -236.489163) (xy 205.878699 -236.435392) (xy 199.073008 -236.435392) (xy 199.072516 -236.462349)
			(xy 199.064666 -236.515689) (xy 199.049134 -236.567318) (xy 199.026249 -236.616135) (xy 198.996501 -236.661099)
			(xy 198.960523 -236.701253) (xy 198.919081 -236.735741) (xy 198.87306 -236.763827) (xy 198.82344 -236.784914)
			(xy 198.771279 -236.79855) (xy 198.717688 -236.804447) (xy 198.663809 -236.802478) (xy 198.610791 -236.792685)
			(xy 198.559764 -236.775277) (xy 198.511816 -236.750625) (xy 198.467968 -236.719255) (xy 198.429155 -236.681834)
			(xy 198.396203 -236.639161) (xy 198.369817 -236.592144) (xy 198.350557 -236.541787) (xy 198.338834 -236.489163)
			(xy 198.334899 -236.435392) (xy 191.528954 -236.435392) (xy 191.528462 -236.462349) (xy 191.520612 -236.515689)
			(xy 191.50508 -236.567318) (xy 191.482195 -236.616135) (xy 191.452447 -236.661099) (xy 191.416469 -236.701253)
			(xy 191.375027 -236.735741) (xy 191.329006 -236.763827) (xy 191.279386 -236.784914) (xy 191.227225 -236.79855)
			(xy 191.173634 -236.804447) (xy 191.119755 -236.802478) (xy 191.066737 -236.792685) (xy 191.01571 -236.775277)
			(xy 190.967762 -236.750625) (xy 190.923914 -236.719255) (xy 190.885101 -236.681834) (xy 190.852149 -236.639161)
			(xy 190.825763 -236.592144) (xy 190.806503 -236.541787) (xy 190.79478 -236.489163) (xy 190.790845 -236.435392)
			(xy 183.9849 -236.435392) (xy 183.984408 -236.462349) (xy 183.976558 -236.515689) (xy 183.961026 -236.567318)
			(xy 183.938141 -236.616135) (xy 183.908393 -236.661099) (xy 183.872415 -236.701253) (xy 183.830973 -236.735741)
			(xy 183.784952 -236.763827) (xy 183.735332 -236.784914) (xy 183.683171 -236.79855) (xy 183.62958 -236.804447)
			(xy 183.575701 -236.802478) (xy 183.522683 -236.792685) (xy 183.471656 -236.775277) (xy 183.423708 -236.750625)
			(xy 183.37986 -236.719255) (xy 183.341047 -236.681834) (xy 183.308095 -236.639161) (xy 183.281709 -236.592144)
			(xy 183.262449 -236.541787) (xy 183.250726 -236.489163) (xy 183.246791 -236.435392) (xy 177.881534 -236.435392)
			(xy 177.881534 -237.285276) (xy 179.146723 -237.285276) (xy 179.150658 -237.231505) (xy 179.162381 -237.178881)
			(xy 179.181641 -237.128524) (xy 179.208027 -237.081507) (xy 179.240979 -237.038834) (xy 179.279792 -237.001413)
			(xy 179.32364 -236.970043) (xy 179.371588 -236.945391) (xy 179.422615 -236.927983) (xy 179.475633 -236.91819)
			(xy 179.529512 -236.916221) (xy 179.583103 -236.922118) (xy 179.635264 -236.935754) (xy 179.684884 -236.956841)
			(xy 179.730905 -236.984927) (xy 179.772347 -237.019415) (xy 179.808325 -237.059569) (xy 179.838073 -237.104533)
			(xy 179.860958 -237.15335) (xy 179.87649 -237.204979) (xy 179.88434 -237.258319) (xy 179.884832 -237.285276)
			(xy 186.690777 -237.285276) (xy 186.694712 -237.231505) (xy 186.706435 -237.178881) (xy 186.725695 -237.128524)
			(xy 186.752081 -237.081507) (xy 186.785033 -237.038834) (xy 186.823846 -237.001413) (xy 186.867694 -236.970043)
			(xy 186.915642 -236.945391) (xy 186.966669 -236.927983) (xy 187.019687 -236.91819) (xy 187.073566 -236.916221)
			(xy 187.127157 -236.922118) (xy 187.179318 -236.935754) (xy 187.228938 -236.956841) (xy 187.274959 -236.984927)
			(xy 187.316401 -237.019415) (xy 187.352379 -237.059569) (xy 187.382127 -237.104533) (xy 187.405012 -237.15335)
			(xy 187.420544 -237.204979) (xy 187.428394 -237.258319) (xy 187.428886 -237.285276) (xy 194.234831 -237.285276)
			(xy 194.238766 -237.231505) (xy 194.250489 -237.178881) (xy 194.269749 -237.128524) (xy 194.296135 -237.081507)
			(xy 194.329087 -237.038834) (xy 194.3679 -237.001413) (xy 194.411748 -236.970043) (xy 194.459696 -236.945391)
			(xy 194.510723 -236.927983) (xy 194.563741 -236.91819) (xy 194.61762 -236.916221) (xy 194.671211 -236.922118)
			(xy 194.723372 -236.935754) (xy 194.772992 -236.956841) (xy 194.819013 -236.984927) (xy 194.860455 -237.019415)
			(xy 194.896433 -237.059569) (xy 194.926181 -237.104533) (xy 194.949066 -237.15335) (xy 194.964598 -237.204979)
			(xy 194.972448 -237.258319) (xy 194.97294 -237.285276) (xy 201.778631 -237.285276) (xy 201.782566 -237.231505)
			(xy 201.794289 -237.178881) (xy 201.813549 -237.128524) (xy 201.839935 -237.081507) (xy 201.872887 -237.038834)
			(xy 201.9117 -237.001413) (xy 201.955548 -236.970043) (xy 202.003496 -236.945391) (xy 202.054523 -236.927983)
			(xy 202.107541 -236.91819) (xy 202.16142 -236.916221) (xy 202.215011 -236.922118) (xy 202.267172 -236.935754)
			(xy 202.316792 -236.956841) (xy 202.362813 -236.984927) (xy 202.404255 -237.019415) (xy 202.440233 -237.059569)
			(xy 202.469981 -237.104533) (xy 202.492866 -237.15335) (xy 202.508398 -237.204979) (xy 202.516248 -237.258319)
			(xy 202.51674 -237.285276) (xy 202.516248 -237.312233) (xy 202.508398 -237.365573) (xy 202.492866 -237.417202)
			(xy 202.469981 -237.466019) (xy 202.440233 -237.510983) (xy 202.404255 -237.551137) (xy 202.362813 -237.585625)
			(xy 202.316792 -237.613711) (xy 202.267172 -237.634798) (xy 202.215011 -237.648434) (xy 202.16142 -237.654331)
			(xy 202.107541 -237.652362) (xy 202.054523 -237.642569) (xy 202.003496 -237.625161) (xy 201.955548 -237.600509)
			(xy 201.9117 -237.569139) (xy 201.872887 -237.531718) (xy 201.839935 -237.489045) (xy 201.813549 -237.442028)
			(xy 201.794289 -237.391671) (xy 201.782566 -237.339047) (xy 201.778631 -237.285276) (xy 194.97294 -237.285276)
			(xy 194.972448 -237.312233) (xy 194.964598 -237.365573) (xy 194.949066 -237.417202) (xy 194.926181 -237.466019)
			(xy 194.896433 -237.510983) (xy 194.860455 -237.551137) (xy 194.819013 -237.585625) (xy 194.772992 -237.613711)
			(xy 194.723372 -237.634798) (xy 194.671211 -237.648434) (xy 194.61762 -237.654331) (xy 194.563741 -237.652362)
			(xy 194.510723 -237.642569) (xy 194.459696 -237.625161) (xy 194.411748 -237.600509) (xy 194.3679 -237.569139)
			(xy 194.329087 -237.531718) (xy 194.296135 -237.489045) (xy 194.269749 -237.442028) (xy 194.250489 -237.391671)
			(xy 194.238766 -237.339047) (xy 194.234831 -237.285276) (xy 187.428886 -237.285276) (xy 187.428394 -237.312233)
			(xy 187.420544 -237.365573) (xy 187.405012 -237.417202) (xy 187.382127 -237.466019) (xy 187.352379 -237.510983)
			(xy 187.316401 -237.551137) (xy 187.274959 -237.585625) (xy 187.228938 -237.613711) (xy 187.179318 -237.634798)
			(xy 187.127157 -237.648434) (xy 187.073566 -237.654331) (xy 187.019687 -237.652362) (xy 186.966669 -237.642569)
			(xy 186.915642 -237.625161) (xy 186.867694 -237.600509) (xy 186.823846 -237.569139) (xy 186.785033 -237.531718)
			(xy 186.752081 -237.489045) (xy 186.725695 -237.442028) (xy 186.706435 -237.391671) (xy 186.694712 -237.339047)
			(xy 186.690777 -237.285276) (xy 179.884832 -237.285276) (xy 179.88434 -237.312233) (xy 179.87649 -237.365573)
			(xy 179.860958 -237.417202) (xy 179.838073 -237.466019) (xy 179.808325 -237.510983) (xy 179.772347 -237.551137)
			(xy 179.730905 -237.585625) (xy 179.684884 -237.613711) (xy 179.635264 -237.634798) (xy 179.583103 -237.648434)
			(xy 179.529512 -237.654331) (xy 179.475633 -237.652362) (xy 179.422615 -237.642569) (xy 179.371588 -237.625161)
			(xy 179.32364 -237.600509) (xy 179.279792 -237.569139) (xy 179.240979 -237.531718) (xy 179.208027 -237.489045)
			(xy 179.181641 -237.442028) (xy 179.162381 -237.391671) (xy 179.150658 -237.339047) (xy 179.146723 -237.285276)
			(xy 177.881534 -237.285276) (xy 177.881534 -238.135414) (xy 183.246791 -238.135414) (xy 183.250726 -238.081643)
			(xy 183.262449 -238.029019) (xy 183.281709 -237.978662) (xy 183.308095 -237.931645) (xy 183.341047 -237.888972)
			(xy 183.37986 -237.851551) (xy 183.423708 -237.820181) (xy 183.471656 -237.795529) (xy 183.522683 -237.778121)
			(xy 183.575701 -237.768328) (xy 183.62958 -237.766359) (xy 183.683171 -237.772256) (xy 183.735332 -237.785892)
			(xy 183.784952 -237.806979) (xy 183.830973 -237.835065) (xy 183.872415 -237.869553) (xy 183.908393 -237.909707)
			(xy 183.938141 -237.954671) (xy 183.961026 -238.003488) (xy 183.976558 -238.055117) (xy 183.984408 -238.108457)
			(xy 183.9849 -238.135414) (xy 190.790845 -238.135414) (xy 190.79478 -238.081643) (xy 190.806503 -238.029019)
			(xy 190.825763 -237.978662) (xy 190.852149 -237.931645) (xy 190.885101 -237.888972) (xy 190.923914 -237.851551)
			(xy 190.967762 -237.820181) (xy 191.01571 -237.795529) (xy 191.066737 -237.778121) (xy 191.119755 -237.768328)
			(xy 191.173634 -237.766359) (xy 191.227225 -237.772256) (xy 191.279386 -237.785892) (xy 191.329006 -237.806979)
			(xy 191.375027 -237.835065) (xy 191.416469 -237.869553) (xy 191.452447 -237.909707) (xy 191.482195 -237.954671)
			(xy 191.50508 -238.003488) (xy 191.520612 -238.055117) (xy 191.528462 -238.108457) (xy 191.528954 -238.135414)
			(xy 198.334899 -238.135414) (xy 198.338834 -238.081643) (xy 198.350557 -238.029019) (xy 198.369817 -237.978662)
			(xy 198.396203 -237.931645) (xy 198.429155 -237.888972) (xy 198.467968 -237.851551) (xy 198.511816 -237.820181)
			(xy 198.559764 -237.795529) (xy 198.610791 -237.778121) (xy 198.663809 -237.768328) (xy 198.717688 -237.766359)
			(xy 198.771279 -237.772256) (xy 198.82344 -237.785892) (xy 198.87306 -237.806979) (xy 198.919081 -237.835065)
			(xy 198.960523 -237.869553) (xy 198.996501 -237.909707) (xy 199.026249 -237.954671) (xy 199.049134 -238.003488)
			(xy 199.064666 -238.055117) (xy 199.072516 -238.108457) (xy 199.073008 -238.135414) (xy 205.878699 -238.135414)
			(xy 205.882634 -238.081643) (xy 205.894357 -238.029019) (xy 205.913617 -237.978662) (xy 205.940003 -237.931645)
			(xy 205.972955 -237.888972) (xy 206.011768 -237.851551) (xy 206.055616 -237.820181) (xy 206.103564 -237.795529)
			(xy 206.154591 -237.778121) (xy 206.207609 -237.768328) (xy 206.261488 -237.766359) (xy 206.315079 -237.772256)
			(xy 206.36724 -237.785892) (xy 206.41686 -237.806979) (xy 206.462881 -237.835065) (xy 206.504323 -237.869553)
			(xy 206.540301 -237.909707) (xy 206.570049 -237.954671) (xy 206.592934 -238.003488) (xy 206.608466 -238.055117)
			(xy 206.616316 -238.108457) (xy 206.616808 -238.135414) (xy 206.616316 -238.162371) (xy 206.608466 -238.215711)
			(xy 206.592934 -238.26734) (xy 206.570049 -238.316157) (xy 206.540301 -238.361121) (xy 206.504323 -238.401275)
			(xy 206.462881 -238.435763) (xy 206.41686 -238.463849) (xy 206.36724 -238.484936) (xy 206.315079 -238.498572)
			(xy 206.261488 -238.504469) (xy 206.207609 -238.5025) (xy 206.154591 -238.492707) (xy 206.103564 -238.475299)
			(xy 206.055616 -238.450647) (xy 206.011768 -238.419277) (xy 205.972955 -238.381856) (xy 205.940003 -238.339183)
			(xy 205.913617 -238.292166) (xy 205.894357 -238.241809) (xy 205.882634 -238.189185) (xy 205.878699 -238.135414)
			(xy 199.073008 -238.135414) (xy 199.072516 -238.162371) (xy 199.064666 -238.215711) (xy 199.049134 -238.26734)
			(xy 199.026249 -238.316157) (xy 198.996501 -238.361121) (xy 198.960523 -238.401275) (xy 198.919081 -238.435763)
			(xy 198.87306 -238.463849) (xy 198.82344 -238.484936) (xy 198.771279 -238.498572) (xy 198.717688 -238.504469)
			(xy 198.663809 -238.5025) (xy 198.610791 -238.492707) (xy 198.559764 -238.475299) (xy 198.511816 -238.450647)
			(xy 198.467968 -238.419277) (xy 198.429155 -238.381856) (xy 198.396203 -238.339183) (xy 198.369817 -238.292166)
			(xy 198.350557 -238.241809) (xy 198.338834 -238.189185) (xy 198.334899 -238.135414) (xy 191.528954 -238.135414)
			(xy 191.528462 -238.162371) (xy 191.520612 -238.215711) (xy 191.50508 -238.26734) (xy 191.482195 -238.316157)
			(xy 191.452447 -238.361121) (xy 191.416469 -238.401275) (xy 191.375027 -238.435763) (xy 191.329006 -238.463849)
			(xy 191.279386 -238.484936) (xy 191.227225 -238.498572) (xy 191.173634 -238.504469) (xy 191.119755 -238.5025)
			(xy 191.066737 -238.492707) (xy 191.01571 -238.475299) (xy 190.967762 -238.450647) (xy 190.923914 -238.419277)
			(xy 190.885101 -238.381856) (xy 190.852149 -238.339183) (xy 190.825763 -238.292166) (xy 190.806503 -238.241809)
			(xy 190.79478 -238.189185) (xy 190.790845 -238.135414) (xy 183.9849 -238.135414) (xy 183.984408 -238.162371)
			(xy 183.976558 -238.215711) (xy 183.961026 -238.26734) (xy 183.938141 -238.316157) (xy 183.908393 -238.361121)
			(xy 183.872415 -238.401275) (xy 183.830973 -238.435763) (xy 183.784952 -238.463849) (xy 183.735332 -238.484936)
			(xy 183.683171 -238.498572) (xy 183.62958 -238.504469) (xy 183.575701 -238.5025) (xy 183.522683 -238.492707)
			(xy 183.471656 -238.475299) (xy 183.423708 -238.450647) (xy 183.37986 -238.419277) (xy 183.341047 -238.381856)
			(xy 183.308095 -238.339183) (xy 183.281709 -238.292166) (xy 183.262449 -238.241809) (xy 183.250726 -238.189185)
			(xy 183.246791 -238.135414) (xy 177.881534 -238.135414) (xy 177.881534 -238.985298) (xy 179.146723 -238.985298)
			(xy 179.150658 -238.931527) (xy 179.162381 -238.878903) (xy 179.181641 -238.828546) (xy 179.208027 -238.781529)
			(xy 179.240979 -238.738856) (xy 179.279792 -238.701435) (xy 179.32364 -238.670065) (xy 179.371588 -238.645413)
			(xy 179.422615 -238.628005) (xy 179.475633 -238.618212) (xy 179.529512 -238.616243) (xy 179.583103 -238.62214)
			(xy 179.635264 -238.635776) (xy 179.684884 -238.656863) (xy 179.730905 -238.684949) (xy 179.772347 -238.719437)
			(xy 179.808325 -238.759591) (xy 179.838073 -238.804555) (xy 179.860958 -238.853372) (xy 179.87649 -238.905001)
			(xy 179.88434 -238.958341) (xy 179.884832 -238.985298) (xy 183.246791 -238.985298) (xy 183.250726 -238.931527)
			(xy 183.262449 -238.878903) (xy 183.281709 -238.828546) (xy 183.308095 -238.781529) (xy 183.341047 -238.738856)
			(xy 183.37986 -238.701435) (xy 183.423708 -238.670065) (xy 183.471656 -238.645413) (xy 183.522683 -238.628005)
			(xy 183.575701 -238.618212) (xy 183.62958 -238.616243) (xy 183.683171 -238.62214) (xy 183.735332 -238.635776)
			(xy 183.784952 -238.656863) (xy 183.830973 -238.684949) (xy 183.872415 -238.719437) (xy 183.908393 -238.759591)
			(xy 183.938141 -238.804555) (xy 183.961026 -238.853372) (xy 183.976558 -238.905001) (xy 183.984408 -238.958341)
			(xy 183.9849 -238.985298) (xy 186.690777 -238.985298) (xy 186.694712 -238.931527) (xy 186.706435 -238.878903)
			(xy 186.725695 -238.828546) (xy 186.752081 -238.781529) (xy 186.785033 -238.738856) (xy 186.823846 -238.701435)
			(xy 186.867694 -238.670065) (xy 186.915642 -238.645413) (xy 186.966669 -238.628005) (xy 187.019687 -238.618212)
			(xy 187.073566 -238.616243) (xy 187.127157 -238.62214) (xy 187.179318 -238.635776) (xy 187.228938 -238.656863)
			(xy 187.274959 -238.684949) (xy 187.316401 -238.719437) (xy 187.352379 -238.759591) (xy 187.382127 -238.804555)
			(xy 187.405012 -238.853372) (xy 187.420544 -238.905001) (xy 187.428394 -238.958341) (xy 187.428886 -238.985298)
			(xy 190.790845 -238.985298) (xy 190.79478 -238.931527) (xy 190.806503 -238.878903) (xy 190.825763 -238.828546)
			(xy 190.852149 -238.781529) (xy 190.885101 -238.738856) (xy 190.923914 -238.701435) (xy 190.967762 -238.670065)
			(xy 191.01571 -238.645413) (xy 191.066737 -238.628005) (xy 191.119755 -238.618212) (xy 191.173634 -238.616243)
			(xy 191.227225 -238.62214) (xy 191.279386 -238.635776) (xy 191.329006 -238.656863) (xy 191.375027 -238.684949)
			(xy 191.416469 -238.719437) (xy 191.452447 -238.759591) (xy 191.482195 -238.804555) (xy 191.50508 -238.853372)
			(xy 191.520612 -238.905001) (xy 191.528462 -238.958341) (xy 191.528954 -238.985298) (xy 194.234831 -238.985298)
			(xy 194.238766 -238.931527) (xy 194.250489 -238.878903) (xy 194.269749 -238.828546) (xy 194.296135 -238.781529)
			(xy 194.329087 -238.738856) (xy 194.3679 -238.701435) (xy 194.411748 -238.670065) (xy 194.459696 -238.645413)
			(xy 194.510723 -238.628005) (xy 194.563741 -238.618212) (xy 194.61762 -238.616243) (xy 194.671211 -238.62214)
			(xy 194.723372 -238.635776) (xy 194.772992 -238.656863) (xy 194.819013 -238.684949) (xy 194.860455 -238.719437)
			(xy 194.896433 -238.759591) (xy 194.926181 -238.804555) (xy 194.949066 -238.853372) (xy 194.964598 -238.905001)
			(xy 194.972448 -238.958341) (xy 194.97294 -238.985298) (xy 198.334899 -238.985298) (xy 198.338834 -238.931527)
			(xy 198.350557 -238.878903) (xy 198.369817 -238.828546) (xy 198.396203 -238.781529) (xy 198.429155 -238.738856)
			(xy 198.467968 -238.701435) (xy 198.511816 -238.670065) (xy 198.559764 -238.645413) (xy 198.610791 -238.628005)
			(xy 198.663809 -238.618212) (xy 198.717688 -238.616243) (xy 198.771279 -238.62214) (xy 198.82344 -238.635776)
			(xy 198.87306 -238.656863) (xy 198.919081 -238.684949) (xy 198.960523 -238.719437) (xy 198.996501 -238.759591)
			(xy 199.026249 -238.804555) (xy 199.049134 -238.853372) (xy 199.064666 -238.905001) (xy 199.072516 -238.958341)
			(xy 199.073008 -238.985298) (xy 201.778631 -238.985298) (xy 201.782566 -238.931527) (xy 201.794289 -238.878903)
			(xy 201.813549 -238.828546) (xy 201.839935 -238.781529) (xy 201.872887 -238.738856) (xy 201.9117 -238.701435)
			(xy 201.955548 -238.670065) (xy 202.003496 -238.645413) (xy 202.054523 -238.628005) (xy 202.107541 -238.618212)
			(xy 202.16142 -238.616243) (xy 202.215011 -238.62214) (xy 202.267172 -238.635776) (xy 202.316792 -238.656863)
			(xy 202.362813 -238.684949) (xy 202.404255 -238.719437) (xy 202.440233 -238.759591) (xy 202.469981 -238.804555)
			(xy 202.492866 -238.853372) (xy 202.508398 -238.905001) (xy 202.516248 -238.958341) (xy 202.51674 -238.985298)
			(xy 205.878699 -238.985298) (xy 205.882634 -238.931527) (xy 205.894357 -238.878903) (xy 205.913617 -238.828546)
			(xy 205.940003 -238.781529) (xy 205.972955 -238.738856) (xy 206.011768 -238.701435) (xy 206.055616 -238.670065)
			(xy 206.103564 -238.645413) (xy 206.154591 -238.628005) (xy 206.207609 -238.618212) (xy 206.261488 -238.616243)
			(xy 206.315079 -238.62214) (xy 206.36724 -238.635776) (xy 206.41686 -238.656863) (xy 206.462881 -238.684949)
			(xy 206.504323 -238.719437) (xy 206.540301 -238.759591) (xy 206.570049 -238.804555) (xy 206.592934 -238.853372)
			(xy 206.608466 -238.905001) (xy 206.616316 -238.958341) (xy 206.616808 -238.985298) (xy 206.616316 -239.012255)
			(xy 206.608466 -239.065595) (xy 206.592934 -239.117224) (xy 206.570049 -239.166041) (xy 206.540301 -239.211005)
			(xy 206.504323 -239.251159) (xy 206.462881 -239.285647) (xy 206.41686 -239.313733) (xy 206.36724 -239.33482)
			(xy 206.315079 -239.348456) (xy 206.261488 -239.354353) (xy 206.207609 -239.352384) (xy 206.154591 -239.342591)
			(xy 206.103564 -239.325183) (xy 206.055616 -239.300531) (xy 206.011768 -239.269161) (xy 205.972955 -239.23174)
			(xy 205.940003 -239.189067) (xy 205.913617 -239.14205) (xy 205.894357 -239.091693) (xy 205.882634 -239.039069)
			(xy 205.878699 -238.985298) (xy 202.51674 -238.985298) (xy 202.516248 -239.012255) (xy 202.508398 -239.065595)
			(xy 202.492866 -239.117224) (xy 202.469981 -239.166041) (xy 202.440233 -239.211005) (xy 202.404255 -239.251159)
			(xy 202.362813 -239.285647) (xy 202.316792 -239.313733) (xy 202.267172 -239.33482) (xy 202.215011 -239.348456)
			(xy 202.16142 -239.354353) (xy 202.107541 -239.352384) (xy 202.054523 -239.342591) (xy 202.003496 -239.325183)
			(xy 201.955548 -239.300531) (xy 201.9117 -239.269161) (xy 201.872887 -239.23174) (xy 201.839935 -239.189067)
			(xy 201.813549 -239.14205) (xy 201.794289 -239.091693) (xy 201.782566 -239.039069) (xy 201.778631 -238.985298)
			(xy 199.073008 -238.985298) (xy 199.072516 -239.012255) (xy 199.064666 -239.065595) (xy 199.049134 -239.117224)
			(xy 199.026249 -239.166041) (xy 198.996501 -239.211005) (xy 198.960523 -239.251159) (xy 198.919081 -239.285647)
			(xy 198.87306 -239.313733) (xy 198.82344 -239.33482) (xy 198.771279 -239.348456) (xy 198.717688 -239.354353)
			(xy 198.663809 -239.352384) (xy 198.610791 -239.342591) (xy 198.559764 -239.325183) (xy 198.511816 -239.300531)
			(xy 198.467968 -239.269161) (xy 198.429155 -239.23174) (xy 198.396203 -239.189067) (xy 198.369817 -239.14205)
			(xy 198.350557 -239.091693) (xy 198.338834 -239.039069) (xy 198.334899 -238.985298) (xy 194.97294 -238.985298)
			(xy 194.972448 -239.012255) (xy 194.964598 -239.065595) (xy 194.949066 -239.117224) (xy 194.926181 -239.166041)
			(xy 194.896433 -239.211005) (xy 194.860455 -239.251159) (xy 194.819013 -239.285647) (xy 194.772992 -239.313733)
			(xy 194.723372 -239.33482) (xy 194.671211 -239.348456) (xy 194.61762 -239.354353) (xy 194.563741 -239.352384)
			(xy 194.510723 -239.342591) (xy 194.459696 -239.325183) (xy 194.411748 -239.300531) (xy 194.3679 -239.269161)
			(xy 194.329087 -239.23174) (xy 194.296135 -239.189067) (xy 194.269749 -239.14205) (xy 194.250489 -239.091693)
			(xy 194.238766 -239.039069) (xy 194.234831 -238.985298) (xy 191.528954 -238.985298) (xy 191.528462 -239.012255)
			(xy 191.520612 -239.065595) (xy 191.50508 -239.117224) (xy 191.482195 -239.166041) (xy 191.452447 -239.211005)
			(xy 191.416469 -239.251159) (xy 191.375027 -239.285647) (xy 191.329006 -239.313733) (xy 191.279386 -239.33482)
			(xy 191.227225 -239.348456) (xy 191.173634 -239.354353) (xy 191.119755 -239.352384) (xy 191.066737 -239.342591)
			(xy 191.01571 -239.325183) (xy 190.967762 -239.300531) (xy 190.923914 -239.269161) (xy 190.885101 -239.23174)
			(xy 190.852149 -239.189067) (xy 190.825763 -239.14205) (xy 190.806503 -239.091693) (xy 190.79478 -239.039069)
			(xy 190.790845 -238.985298) (xy 187.428886 -238.985298) (xy 187.428394 -239.012255) (xy 187.420544 -239.065595)
			(xy 187.405012 -239.117224) (xy 187.382127 -239.166041) (xy 187.352379 -239.211005) (xy 187.316401 -239.251159)
			(xy 187.274959 -239.285647) (xy 187.228938 -239.313733) (xy 187.179318 -239.33482) (xy 187.127157 -239.348456)
			(xy 187.073566 -239.354353) (xy 187.019687 -239.352384) (xy 186.966669 -239.342591) (xy 186.915642 -239.325183)
			(xy 186.867694 -239.300531) (xy 186.823846 -239.269161) (xy 186.785033 -239.23174) (xy 186.752081 -239.189067)
			(xy 186.725695 -239.14205) (xy 186.706435 -239.091693) (xy 186.694712 -239.039069) (xy 186.690777 -238.985298)
			(xy 183.9849 -238.985298) (xy 183.984408 -239.012255) (xy 183.976558 -239.065595) (xy 183.961026 -239.117224)
			(xy 183.938141 -239.166041) (xy 183.908393 -239.211005) (xy 183.872415 -239.251159) (xy 183.830973 -239.285647)
			(xy 183.784952 -239.313733) (xy 183.735332 -239.33482) (xy 183.683171 -239.348456) (xy 183.62958 -239.354353)
			(xy 183.575701 -239.352384) (xy 183.522683 -239.342591) (xy 183.471656 -239.325183) (xy 183.423708 -239.300531)
			(xy 183.37986 -239.269161) (xy 183.341047 -239.23174) (xy 183.308095 -239.189067) (xy 183.281709 -239.14205)
			(xy 183.262449 -239.091693) (xy 183.250726 -239.039069) (xy 183.246791 -238.985298) (xy 179.884832 -238.985298)
			(xy 179.88434 -239.012255) (xy 179.87649 -239.065595) (xy 179.860958 -239.117224) (xy 179.838073 -239.166041)
			(xy 179.808325 -239.211005) (xy 179.772347 -239.251159) (xy 179.730905 -239.285647) (xy 179.684884 -239.313733)
			(xy 179.635264 -239.33482) (xy 179.583103 -239.348456) (xy 179.529512 -239.354353) (xy 179.475633 -239.352384)
			(xy 179.422615 -239.342591) (xy 179.371588 -239.325183) (xy 179.32364 -239.300531) (xy 179.279792 -239.269161)
			(xy 179.240979 -239.23174) (xy 179.208027 -239.189067) (xy 179.181641 -239.14205) (xy 179.162381 -239.091693)
			(xy 179.150658 -239.039069) (xy 179.146723 -238.985298) (xy 177.881534 -238.985298) (xy 177.881534 -239.835436)
			(xy 179.146723 -239.835436) (xy 179.150658 -239.781665) (xy 179.162381 -239.729041) (xy 179.181641 -239.678684)
			(xy 179.208027 -239.631667) (xy 179.240979 -239.588994) (xy 179.279792 -239.551573) (xy 179.32364 -239.520203)
			(xy 179.371588 -239.495551) (xy 179.422615 -239.478143) (xy 179.475633 -239.46835) (xy 179.529512 -239.466381)
			(xy 179.583103 -239.472278) (xy 179.635264 -239.485914) (xy 179.684884 -239.507001) (xy 179.730905 -239.535087)
			(xy 179.772347 -239.569575) (xy 179.808325 -239.609729) (xy 179.838073 -239.654693) (xy 179.860958 -239.70351)
			(xy 179.87649 -239.755139) (xy 179.88434 -239.808479) (xy 179.884832 -239.835436) (xy 186.690777 -239.835436)
			(xy 186.694712 -239.781665) (xy 186.706435 -239.729041) (xy 186.725695 -239.678684) (xy 186.752081 -239.631667)
			(xy 186.785033 -239.588994) (xy 186.823846 -239.551573) (xy 186.867694 -239.520203) (xy 186.915642 -239.495551)
			(xy 186.966669 -239.478143) (xy 187.019687 -239.46835) (xy 187.073566 -239.466381) (xy 187.127157 -239.472278)
			(xy 187.179318 -239.485914) (xy 187.228938 -239.507001) (xy 187.274959 -239.535087) (xy 187.316401 -239.569575)
			(xy 187.352379 -239.609729) (xy 187.382127 -239.654693) (xy 187.405012 -239.70351) (xy 187.420544 -239.755139)
			(xy 187.428394 -239.808479) (xy 187.428886 -239.835436) (xy 194.234831 -239.835436) (xy 194.238766 -239.781665)
			(xy 194.250489 -239.729041) (xy 194.269749 -239.678684) (xy 194.296135 -239.631667) (xy 194.329087 -239.588994)
			(xy 194.3679 -239.551573) (xy 194.411748 -239.520203) (xy 194.459696 -239.495551) (xy 194.510723 -239.478143)
			(xy 194.563741 -239.46835) (xy 194.61762 -239.466381) (xy 194.671211 -239.472278) (xy 194.723372 -239.485914)
			(xy 194.772992 -239.507001) (xy 194.819013 -239.535087) (xy 194.860455 -239.569575) (xy 194.896433 -239.609729)
			(xy 194.926181 -239.654693) (xy 194.949066 -239.70351) (xy 194.964598 -239.755139) (xy 194.972448 -239.808479)
			(xy 194.97294 -239.835436) (xy 201.778631 -239.835436) (xy 201.782566 -239.781665) (xy 201.794289 -239.729041)
			(xy 201.813549 -239.678684) (xy 201.839935 -239.631667) (xy 201.872887 -239.588994) (xy 201.9117 -239.551573)
			(xy 201.955548 -239.520203) (xy 202.003496 -239.495551) (xy 202.054523 -239.478143) (xy 202.107541 -239.46835)
			(xy 202.16142 -239.466381) (xy 202.215011 -239.472278) (xy 202.267172 -239.485914) (xy 202.316792 -239.507001)
			(xy 202.362813 -239.535087) (xy 202.404255 -239.569575) (xy 202.440233 -239.609729) (xy 202.469981 -239.654693)
			(xy 202.492866 -239.70351) (xy 202.508398 -239.755139) (xy 202.516248 -239.808479) (xy 202.51674 -239.835436)
			(xy 202.516248 -239.862393) (xy 202.508398 -239.915733) (xy 202.492866 -239.967362) (xy 202.469981 -240.016179)
			(xy 202.440233 -240.061143) (xy 202.404255 -240.101297) (xy 202.362813 -240.135785) (xy 202.316792 -240.163871)
			(xy 202.267172 -240.184958) (xy 202.215011 -240.198594) (xy 202.16142 -240.204491) (xy 202.107541 -240.202522)
			(xy 202.054523 -240.192729) (xy 202.003496 -240.175321) (xy 201.955548 -240.150669) (xy 201.9117 -240.119299)
			(xy 201.872887 -240.081878) (xy 201.839935 -240.039205) (xy 201.813549 -239.992188) (xy 201.794289 -239.941831)
			(xy 201.782566 -239.889207) (xy 201.778631 -239.835436) (xy 194.97294 -239.835436) (xy 194.972448 -239.862393)
			(xy 194.964598 -239.915733) (xy 194.949066 -239.967362) (xy 194.926181 -240.016179) (xy 194.896433 -240.061143)
			(xy 194.860455 -240.101297) (xy 194.819013 -240.135785) (xy 194.772992 -240.163871) (xy 194.723372 -240.184958)
			(xy 194.671211 -240.198594) (xy 194.61762 -240.204491) (xy 194.563741 -240.202522) (xy 194.510723 -240.192729)
			(xy 194.459696 -240.175321) (xy 194.411748 -240.150669) (xy 194.3679 -240.119299) (xy 194.329087 -240.081878)
			(xy 194.296135 -240.039205) (xy 194.269749 -239.992188) (xy 194.250489 -239.941831) (xy 194.238766 -239.889207)
			(xy 194.234831 -239.835436) (xy 187.428886 -239.835436) (xy 187.428394 -239.862393) (xy 187.420544 -239.915733)
			(xy 187.405012 -239.967362) (xy 187.382127 -240.016179) (xy 187.352379 -240.061143) (xy 187.316401 -240.101297)
			(xy 187.274959 -240.135785) (xy 187.228938 -240.163871) (xy 187.179318 -240.184958) (xy 187.127157 -240.198594)
			(xy 187.073566 -240.204491) (xy 187.019687 -240.202522) (xy 186.966669 -240.192729) (xy 186.915642 -240.175321)
			(xy 186.867694 -240.150669) (xy 186.823846 -240.119299) (xy 186.785033 -240.081878) (xy 186.752081 -240.039205)
			(xy 186.725695 -239.992188) (xy 186.706435 -239.941831) (xy 186.694712 -239.889207) (xy 186.690777 -239.835436)
			(xy 179.884832 -239.835436) (xy 179.88434 -239.862393) (xy 179.87649 -239.915733) (xy 179.860958 -239.967362)
			(xy 179.838073 -240.016179) (xy 179.808325 -240.061143) (xy 179.772347 -240.101297) (xy 179.730905 -240.135785)
			(xy 179.684884 -240.163871) (xy 179.635264 -240.184958) (xy 179.583103 -240.198594) (xy 179.529512 -240.204491)
			(xy 179.475633 -240.202522) (xy 179.422615 -240.192729) (xy 179.371588 -240.175321) (xy 179.32364 -240.150669)
			(xy 179.279792 -240.119299) (xy 179.240979 -240.081878) (xy 179.208027 -240.039205) (xy 179.181641 -239.992188)
			(xy 179.162381 -239.941831) (xy 179.150658 -239.889207) (xy 179.146723 -239.835436) (xy 177.881534 -239.835436)
			(xy 177.881534 -240.68532) (xy 183.246791 -240.68532) (xy 183.250726 -240.631549) (xy 183.262449 -240.578925)
			(xy 183.281709 -240.528568) (xy 183.308095 -240.481551) (xy 183.341047 -240.438878) (xy 183.37986 -240.401457)
			(xy 183.423708 -240.370087) (xy 183.471656 -240.345435) (xy 183.522683 -240.328027) (xy 183.575701 -240.318234)
			(xy 183.62958 -240.316265) (xy 183.683171 -240.322162) (xy 183.735332 -240.335798) (xy 183.784952 -240.356885)
			(xy 183.830973 -240.384971) (xy 183.872415 -240.419459) (xy 183.908393 -240.459613) (xy 183.938141 -240.504577)
			(xy 183.961026 -240.553394) (xy 183.976558 -240.605023) (xy 183.984408 -240.658363) (xy 183.9849 -240.68532)
			(xy 190.790845 -240.68532) (xy 190.79478 -240.631549) (xy 190.806503 -240.578925) (xy 190.825763 -240.528568)
			(xy 190.852149 -240.481551) (xy 190.885101 -240.438878) (xy 190.923914 -240.401457) (xy 190.967762 -240.370087)
			(xy 191.01571 -240.345435) (xy 191.066737 -240.328027) (xy 191.119755 -240.318234) (xy 191.173634 -240.316265)
			(xy 191.227225 -240.322162) (xy 191.279386 -240.335798) (xy 191.329006 -240.356885) (xy 191.375027 -240.384971)
			(xy 191.416469 -240.419459) (xy 191.452447 -240.459613) (xy 191.482195 -240.504577) (xy 191.50508 -240.553394)
			(xy 191.520612 -240.605023) (xy 191.528462 -240.658363) (xy 191.528954 -240.68532) (xy 198.334899 -240.68532)
			(xy 198.338834 -240.631549) (xy 198.350557 -240.578925) (xy 198.369817 -240.528568) (xy 198.396203 -240.481551)
			(xy 198.429155 -240.438878) (xy 198.467968 -240.401457) (xy 198.511816 -240.370087) (xy 198.559764 -240.345435)
			(xy 198.610791 -240.328027) (xy 198.663809 -240.318234) (xy 198.717688 -240.316265) (xy 198.771279 -240.322162)
			(xy 198.82344 -240.335798) (xy 198.87306 -240.356885) (xy 198.919081 -240.384971) (xy 198.960523 -240.419459)
			(xy 198.996501 -240.459613) (xy 199.026249 -240.504577) (xy 199.049134 -240.553394) (xy 199.064666 -240.605023)
			(xy 199.072516 -240.658363) (xy 199.073008 -240.68532) (xy 205.878699 -240.68532) (xy 205.882634 -240.631549)
			(xy 205.894357 -240.578925) (xy 205.913617 -240.528568) (xy 205.940003 -240.481551) (xy 205.972955 -240.438878)
			(xy 206.011768 -240.401457) (xy 206.055616 -240.370087) (xy 206.103564 -240.345435) (xy 206.154591 -240.328027)
			(xy 206.207609 -240.318234) (xy 206.261488 -240.316265) (xy 206.315079 -240.322162) (xy 206.36724 -240.335798)
			(xy 206.41686 -240.356885) (xy 206.462881 -240.384971) (xy 206.504323 -240.419459) (xy 206.540301 -240.459613)
			(xy 206.570049 -240.504577) (xy 206.592934 -240.553394) (xy 206.608466 -240.605023) (xy 206.616316 -240.658363)
			(xy 206.616808 -240.68532) (xy 206.616316 -240.712277) (xy 206.608466 -240.765617) (xy 206.592934 -240.817246)
			(xy 206.570049 -240.866063) (xy 206.540301 -240.911027) (xy 206.504323 -240.951181) (xy 206.462881 -240.985669)
			(xy 206.41686 -241.013755) (xy 206.36724 -241.034842) (xy 206.315079 -241.048478) (xy 206.261488 -241.054375)
			(xy 206.207609 -241.052406) (xy 206.154591 -241.042613) (xy 206.103564 -241.025205) (xy 206.055616 -241.000553)
			(xy 206.011768 -240.969183) (xy 205.972955 -240.931762) (xy 205.940003 -240.889089) (xy 205.913617 -240.842072)
			(xy 205.894357 -240.791715) (xy 205.882634 -240.739091) (xy 205.878699 -240.68532) (xy 199.073008 -240.68532)
			(xy 199.072516 -240.712277) (xy 199.064666 -240.765617) (xy 199.049134 -240.817246) (xy 199.026249 -240.866063)
			(xy 198.996501 -240.911027) (xy 198.960523 -240.951181) (xy 198.919081 -240.985669) (xy 198.87306 -241.013755)
			(xy 198.82344 -241.034842) (xy 198.771279 -241.048478) (xy 198.717688 -241.054375) (xy 198.663809 -241.052406)
			(xy 198.610791 -241.042613) (xy 198.559764 -241.025205) (xy 198.511816 -241.000553) (xy 198.467968 -240.969183)
			(xy 198.429155 -240.931762) (xy 198.396203 -240.889089) (xy 198.369817 -240.842072) (xy 198.350557 -240.791715)
			(xy 198.338834 -240.739091) (xy 198.334899 -240.68532) (xy 191.528954 -240.68532) (xy 191.528462 -240.712277)
			(xy 191.520612 -240.765617) (xy 191.50508 -240.817246) (xy 191.482195 -240.866063) (xy 191.452447 -240.911027)
			(xy 191.416469 -240.951181) (xy 191.375027 -240.985669) (xy 191.329006 -241.013755) (xy 191.279386 -241.034842)
			(xy 191.227225 -241.048478) (xy 191.173634 -241.054375) (xy 191.119755 -241.052406) (xy 191.066737 -241.042613)
			(xy 191.01571 -241.025205) (xy 190.967762 -241.000553) (xy 190.923914 -240.969183) (xy 190.885101 -240.931762)
			(xy 190.852149 -240.889089) (xy 190.825763 -240.842072) (xy 190.806503 -240.791715) (xy 190.79478 -240.739091)
			(xy 190.790845 -240.68532) (xy 183.9849 -240.68532) (xy 183.984408 -240.712277) (xy 183.976558 -240.765617)
			(xy 183.961026 -240.817246) (xy 183.938141 -240.866063) (xy 183.908393 -240.911027) (xy 183.872415 -240.951181)
			(xy 183.830973 -240.985669) (xy 183.784952 -241.013755) (xy 183.735332 -241.034842) (xy 183.683171 -241.048478)
			(xy 183.62958 -241.054375) (xy 183.575701 -241.052406) (xy 183.522683 -241.042613) (xy 183.471656 -241.025205)
			(xy 183.423708 -241.000553) (xy 183.37986 -240.969183) (xy 183.341047 -240.931762) (xy 183.308095 -240.889089)
			(xy 183.281709 -240.842072) (xy 183.262449 -240.791715) (xy 183.250726 -240.739091) (xy 183.246791 -240.68532)
			(xy 177.881534 -240.68532) (xy 177.881534 -241.535204) (xy 179.146723 -241.535204) (xy 179.150658 -241.481433)
			(xy 179.162381 -241.428809) (xy 179.181641 -241.378452) (xy 179.208027 -241.331435) (xy 179.240979 -241.288762)
			(xy 179.279792 -241.251341) (xy 179.32364 -241.219971) (xy 179.371588 -241.195319) (xy 179.422615 -241.177911)
			(xy 179.475633 -241.168118) (xy 179.529512 -241.166149) (xy 179.583103 -241.172046) (xy 179.635264 -241.185682)
			(xy 179.684884 -241.206769) (xy 179.730905 -241.234855) (xy 179.772347 -241.269343) (xy 179.808325 -241.309497)
			(xy 179.838073 -241.354461) (xy 179.860958 -241.403278) (xy 179.87649 -241.454907) (xy 179.88434 -241.508247)
			(xy 179.884832 -241.535204) (xy 186.690777 -241.535204) (xy 186.694712 -241.481433) (xy 186.706435 -241.428809)
			(xy 186.725695 -241.378452) (xy 186.752081 -241.331435) (xy 186.785033 -241.288762) (xy 186.823846 -241.251341)
			(xy 186.867694 -241.219971) (xy 186.915642 -241.195319) (xy 186.966669 -241.177911) (xy 187.019687 -241.168118)
			(xy 187.073566 -241.166149) (xy 187.127157 -241.172046) (xy 187.179318 -241.185682) (xy 187.228938 -241.206769)
			(xy 187.274959 -241.234855) (xy 187.316401 -241.269343) (xy 187.352379 -241.309497) (xy 187.382127 -241.354461)
			(xy 187.405012 -241.403278) (xy 187.420544 -241.454907) (xy 187.428394 -241.508247) (xy 187.428886 -241.535204)
			(xy 194.234831 -241.535204) (xy 194.238766 -241.481433) (xy 194.250489 -241.428809) (xy 194.269749 -241.378452)
			(xy 194.296135 -241.331435) (xy 194.329087 -241.288762) (xy 194.3679 -241.251341) (xy 194.411748 -241.219971)
			(xy 194.459696 -241.195319) (xy 194.510723 -241.177911) (xy 194.563741 -241.168118) (xy 194.61762 -241.166149)
			(xy 194.671211 -241.172046) (xy 194.723372 -241.185682) (xy 194.772992 -241.206769) (xy 194.819013 -241.234855)
			(xy 194.860455 -241.269343) (xy 194.896433 -241.309497) (xy 194.926181 -241.354461) (xy 194.949066 -241.403278)
			(xy 194.964598 -241.454907) (xy 194.972448 -241.508247) (xy 194.97294 -241.535204) (xy 201.778631 -241.535204)
			(xy 201.782566 -241.481433) (xy 201.794289 -241.428809) (xy 201.813549 -241.378452) (xy 201.839935 -241.331435)
			(xy 201.872887 -241.288762) (xy 201.9117 -241.251341) (xy 201.955548 -241.219971) (xy 202.003496 -241.195319)
			(xy 202.054523 -241.177911) (xy 202.107541 -241.168118) (xy 202.16142 -241.166149) (xy 202.215011 -241.172046)
			(xy 202.267172 -241.185682) (xy 202.316792 -241.206769) (xy 202.362813 -241.234855) (xy 202.404255 -241.269343)
			(xy 202.440233 -241.309497) (xy 202.469981 -241.354461) (xy 202.492866 -241.403278) (xy 202.508398 -241.454907)
			(xy 202.516248 -241.508247) (xy 202.51674 -241.535204) (xy 202.516248 -241.562161) (xy 202.508398 -241.615501)
			(xy 202.492866 -241.66713) (xy 202.469981 -241.715947) (xy 202.440233 -241.760911) (xy 202.404255 -241.801065)
			(xy 202.362813 -241.835553) (xy 202.316792 -241.863639) (xy 202.267172 -241.884726) (xy 202.215011 -241.898362)
			(xy 202.16142 -241.904259) (xy 202.107541 -241.90229) (xy 202.054523 -241.892497) (xy 202.003496 -241.875089)
			(xy 201.955548 -241.850437) (xy 201.9117 -241.819067) (xy 201.872887 -241.781646) (xy 201.839935 -241.738973)
			(xy 201.813549 -241.691956) (xy 201.794289 -241.641599) (xy 201.782566 -241.588975) (xy 201.778631 -241.535204)
			(xy 194.97294 -241.535204) (xy 194.972448 -241.562161) (xy 194.964598 -241.615501) (xy 194.949066 -241.66713)
			(xy 194.926181 -241.715947) (xy 194.896433 -241.760911) (xy 194.860455 -241.801065) (xy 194.819013 -241.835553)
			(xy 194.772992 -241.863639) (xy 194.723372 -241.884726) (xy 194.671211 -241.898362) (xy 194.61762 -241.904259)
			(xy 194.563741 -241.90229) (xy 194.510723 -241.892497) (xy 194.459696 -241.875089) (xy 194.411748 -241.850437)
			(xy 194.3679 -241.819067) (xy 194.329087 -241.781646) (xy 194.296135 -241.738973) (xy 194.269749 -241.691956)
			(xy 194.250489 -241.641599) (xy 194.238766 -241.588975) (xy 194.234831 -241.535204) (xy 187.428886 -241.535204)
			(xy 187.428394 -241.562161) (xy 187.420544 -241.615501) (xy 187.405012 -241.66713) (xy 187.382127 -241.715947)
			(xy 187.352379 -241.760911) (xy 187.316401 -241.801065) (xy 187.274959 -241.835553) (xy 187.228938 -241.863639)
			(xy 187.179318 -241.884726) (xy 187.127157 -241.898362) (xy 187.073566 -241.904259) (xy 187.019687 -241.90229)
			(xy 186.966669 -241.892497) (xy 186.915642 -241.875089) (xy 186.867694 -241.850437) (xy 186.823846 -241.819067)
			(xy 186.785033 -241.781646) (xy 186.752081 -241.738973) (xy 186.725695 -241.691956) (xy 186.706435 -241.641599)
			(xy 186.694712 -241.588975) (xy 186.690777 -241.535204) (xy 179.884832 -241.535204) (xy 179.88434 -241.562161)
			(xy 179.87649 -241.615501) (xy 179.860958 -241.66713) (xy 179.838073 -241.715947) (xy 179.808325 -241.760911)
			(xy 179.772347 -241.801065) (xy 179.730905 -241.835553) (xy 179.684884 -241.863639) (xy 179.635264 -241.884726)
			(xy 179.583103 -241.898362) (xy 179.529512 -241.904259) (xy 179.475633 -241.90229) (xy 179.422615 -241.892497)
			(xy 179.371588 -241.875089) (xy 179.32364 -241.850437) (xy 179.279792 -241.819067) (xy 179.240979 -241.781646)
			(xy 179.208027 -241.738973) (xy 179.181641 -241.691956) (xy 179.162381 -241.641599) (xy 179.150658 -241.588975)
			(xy 179.146723 -241.535204) (xy 177.881534 -241.535204) (xy 177.881534 -242.385342) (xy 183.246791 -242.385342)
			(xy 183.250726 -242.331571) (xy 183.262449 -242.278947) (xy 183.281709 -242.22859) (xy 183.308095 -242.181573)
			(xy 183.341047 -242.1389) (xy 183.37986 -242.101479) (xy 183.423708 -242.070109) (xy 183.471656 -242.045457)
			(xy 183.522683 -242.028049) (xy 183.575701 -242.018256) (xy 183.62958 -242.016287) (xy 183.683171 -242.022184)
			(xy 183.735332 -242.03582) (xy 183.784952 -242.056907) (xy 183.830973 -242.084993) (xy 183.872415 -242.119481)
			(xy 183.908393 -242.159635) (xy 183.938141 -242.204599) (xy 183.961026 -242.253416) (xy 183.976558 -242.305045)
			(xy 183.984408 -242.358385) (xy 183.9849 -242.385342) (xy 190.790845 -242.385342) (xy 190.79478 -242.331571)
			(xy 190.806503 -242.278947) (xy 190.825763 -242.22859) (xy 190.852149 -242.181573) (xy 190.885101 -242.1389)
			(xy 190.923914 -242.101479) (xy 190.967762 -242.070109) (xy 191.01571 -242.045457) (xy 191.066737 -242.028049)
			(xy 191.119755 -242.018256) (xy 191.173634 -242.016287) (xy 191.227225 -242.022184) (xy 191.279386 -242.03582)
			(xy 191.329006 -242.056907) (xy 191.375027 -242.084993) (xy 191.416469 -242.119481) (xy 191.452447 -242.159635)
			(xy 191.482195 -242.204599) (xy 191.50508 -242.253416) (xy 191.520612 -242.305045) (xy 191.528462 -242.358385)
			(xy 191.528954 -242.385342) (xy 198.334899 -242.385342) (xy 198.338834 -242.331571) (xy 198.350557 -242.278947)
			(xy 198.369817 -242.22859) (xy 198.396203 -242.181573) (xy 198.429155 -242.1389) (xy 198.467968 -242.101479)
			(xy 198.511816 -242.070109) (xy 198.559764 -242.045457) (xy 198.610791 -242.028049) (xy 198.663809 -242.018256)
			(xy 198.717688 -242.016287) (xy 198.771279 -242.022184) (xy 198.82344 -242.03582) (xy 198.87306 -242.056907)
			(xy 198.919081 -242.084993) (xy 198.960523 -242.119481) (xy 198.996501 -242.159635) (xy 199.026249 -242.204599)
			(xy 199.049134 -242.253416) (xy 199.064666 -242.305045) (xy 199.072516 -242.358385) (xy 199.073008 -242.385342)
			(xy 205.878699 -242.385342) (xy 205.882634 -242.331571) (xy 205.894357 -242.278947) (xy 205.913617 -242.22859)
			(xy 205.940003 -242.181573) (xy 205.972955 -242.1389) (xy 206.011768 -242.101479) (xy 206.055616 -242.070109)
			(xy 206.103564 -242.045457) (xy 206.154591 -242.028049) (xy 206.207609 -242.018256) (xy 206.261488 -242.016287)
			(xy 206.315079 -242.022184) (xy 206.36724 -242.03582) (xy 206.41686 -242.056907) (xy 206.462881 -242.084993)
			(xy 206.504323 -242.119481) (xy 206.540301 -242.159635) (xy 206.570049 -242.204599) (xy 206.592934 -242.253416)
			(xy 206.608466 -242.305045) (xy 206.616316 -242.358385) (xy 206.616808 -242.385342) (xy 206.616316 -242.412299)
			(xy 206.608466 -242.465639) (xy 206.592934 -242.517268) (xy 206.570049 -242.566085) (xy 206.540301 -242.611049)
			(xy 206.504323 -242.651203) (xy 206.462881 -242.685691) (xy 206.41686 -242.713777) (xy 206.36724 -242.734864)
			(xy 206.315079 -242.7485) (xy 206.261488 -242.754397) (xy 206.207609 -242.752428) (xy 206.154591 -242.742635)
			(xy 206.103564 -242.725227) (xy 206.055616 -242.700575) (xy 206.011768 -242.669205) (xy 205.972955 -242.631784)
			(xy 205.940003 -242.589111) (xy 205.913617 -242.542094) (xy 205.894357 -242.491737) (xy 205.882634 -242.439113)
			(xy 205.878699 -242.385342) (xy 199.073008 -242.385342) (xy 199.072516 -242.412299) (xy 199.064666 -242.465639)
			(xy 199.049134 -242.517268) (xy 199.026249 -242.566085) (xy 198.996501 -242.611049) (xy 198.960523 -242.651203)
			(xy 198.919081 -242.685691) (xy 198.87306 -242.713777) (xy 198.82344 -242.734864) (xy 198.771279 -242.7485)
			(xy 198.717688 -242.754397) (xy 198.663809 -242.752428) (xy 198.610791 -242.742635) (xy 198.559764 -242.725227)
			(xy 198.511816 -242.700575) (xy 198.467968 -242.669205) (xy 198.429155 -242.631784) (xy 198.396203 -242.589111)
			(xy 198.369817 -242.542094) (xy 198.350557 -242.491737) (xy 198.338834 -242.439113) (xy 198.334899 -242.385342)
			(xy 191.528954 -242.385342) (xy 191.528462 -242.412299) (xy 191.520612 -242.465639) (xy 191.50508 -242.517268)
			(xy 191.482195 -242.566085) (xy 191.452447 -242.611049) (xy 191.416469 -242.651203) (xy 191.375027 -242.685691)
			(xy 191.329006 -242.713777) (xy 191.279386 -242.734864) (xy 191.227225 -242.7485) (xy 191.173634 -242.754397)
			(xy 191.119755 -242.752428) (xy 191.066737 -242.742635) (xy 191.01571 -242.725227) (xy 190.967762 -242.700575)
			(xy 190.923914 -242.669205) (xy 190.885101 -242.631784) (xy 190.852149 -242.589111) (xy 190.825763 -242.542094)
			(xy 190.806503 -242.491737) (xy 190.79478 -242.439113) (xy 190.790845 -242.385342) (xy 183.9849 -242.385342)
			(xy 183.984408 -242.412299) (xy 183.976558 -242.465639) (xy 183.961026 -242.517268) (xy 183.938141 -242.566085)
			(xy 183.908393 -242.611049) (xy 183.872415 -242.651203) (xy 183.830973 -242.685691) (xy 183.784952 -242.713777)
			(xy 183.735332 -242.734864) (xy 183.683171 -242.7485) (xy 183.62958 -242.754397) (xy 183.575701 -242.752428)
			(xy 183.522683 -242.742635) (xy 183.471656 -242.725227) (xy 183.423708 -242.700575) (xy 183.37986 -242.669205)
			(xy 183.341047 -242.631784) (xy 183.308095 -242.589111) (xy 183.281709 -242.542094) (xy 183.262449 -242.491737)
			(xy 183.250726 -242.439113) (xy 183.246791 -242.385342) (xy 177.881534 -242.385342) (xy 177.881534 -243.235226)
			(xy 179.146723 -243.235226) (xy 179.150658 -243.181455) (xy 179.162381 -243.128831) (xy 179.181641 -243.078474)
			(xy 179.208027 -243.031457) (xy 179.240979 -242.988784) (xy 179.279792 -242.951363) (xy 179.32364 -242.919993)
			(xy 179.371588 -242.895341) (xy 179.422615 -242.877933) (xy 179.475633 -242.86814) (xy 179.529512 -242.866171)
			(xy 179.583103 -242.872068) (xy 179.635264 -242.885704) (xy 179.684884 -242.906791) (xy 179.730905 -242.934877)
			(xy 179.772347 -242.969365) (xy 179.808325 -243.009519) (xy 179.838073 -243.054483) (xy 179.860958 -243.1033)
			(xy 179.87649 -243.154929) (xy 179.88434 -243.208269) (xy 179.884832 -243.235226) (xy 186.690777 -243.235226)
			(xy 186.694712 -243.181455) (xy 186.706435 -243.128831) (xy 186.725695 -243.078474) (xy 186.752081 -243.031457)
			(xy 186.785033 -242.988784) (xy 186.823846 -242.951363) (xy 186.867694 -242.919993) (xy 186.915642 -242.895341)
			(xy 186.966669 -242.877933) (xy 187.019687 -242.86814) (xy 187.073566 -242.866171) (xy 187.127157 -242.872068)
			(xy 187.179318 -242.885704) (xy 187.228938 -242.906791) (xy 187.274959 -242.934877) (xy 187.316401 -242.969365)
			(xy 187.352379 -243.009519) (xy 187.382127 -243.054483) (xy 187.405012 -243.1033) (xy 187.420544 -243.154929)
			(xy 187.428394 -243.208269) (xy 187.428886 -243.235226) (xy 194.234831 -243.235226) (xy 194.238766 -243.181455)
			(xy 194.250489 -243.128831) (xy 194.269749 -243.078474) (xy 194.296135 -243.031457) (xy 194.329087 -242.988784)
			(xy 194.3679 -242.951363) (xy 194.411748 -242.919993) (xy 194.459696 -242.895341) (xy 194.510723 -242.877933)
			(xy 194.563741 -242.86814) (xy 194.61762 -242.866171) (xy 194.671211 -242.872068) (xy 194.723372 -242.885704)
			(xy 194.772992 -242.906791) (xy 194.819013 -242.934877) (xy 194.860455 -242.969365) (xy 194.896433 -243.009519)
			(xy 194.926181 -243.054483) (xy 194.949066 -243.1033) (xy 194.964598 -243.154929) (xy 194.972448 -243.208269)
			(xy 194.97294 -243.235226) (xy 201.778631 -243.235226) (xy 201.782566 -243.181455) (xy 201.794289 -243.128831)
			(xy 201.813549 -243.078474) (xy 201.839935 -243.031457) (xy 201.872887 -242.988784) (xy 201.9117 -242.951363)
			(xy 201.955548 -242.919993) (xy 202.003496 -242.895341) (xy 202.054523 -242.877933) (xy 202.107541 -242.86814)
			(xy 202.16142 -242.866171) (xy 202.215011 -242.872068) (xy 202.267172 -242.885704) (xy 202.316792 -242.906791)
			(xy 202.362813 -242.934877) (xy 202.404255 -242.969365) (xy 202.440233 -243.009519) (xy 202.469981 -243.054483)
			(xy 202.492866 -243.1033) (xy 202.508398 -243.154929) (xy 202.516248 -243.208269) (xy 202.51674 -243.235226)
			(xy 202.516248 -243.262183) (xy 202.508398 -243.315523) (xy 202.492866 -243.367152) (xy 202.469981 -243.415969)
			(xy 202.440233 -243.460933) (xy 202.404255 -243.501087) (xy 202.362813 -243.535575) (xy 202.316792 -243.563661)
			(xy 202.267172 -243.584748) (xy 202.215011 -243.598384) (xy 202.16142 -243.604281) (xy 202.107541 -243.602312)
			(xy 202.054523 -243.592519) (xy 202.003496 -243.575111) (xy 201.955548 -243.550459) (xy 201.9117 -243.519089)
			(xy 201.872887 -243.481668) (xy 201.839935 -243.438995) (xy 201.813549 -243.391978) (xy 201.794289 -243.341621)
			(xy 201.782566 -243.288997) (xy 201.778631 -243.235226) (xy 194.97294 -243.235226) (xy 194.972448 -243.262183)
			(xy 194.964598 -243.315523) (xy 194.949066 -243.367152) (xy 194.926181 -243.415969) (xy 194.896433 -243.460933)
			(xy 194.860455 -243.501087) (xy 194.819013 -243.535575) (xy 194.772992 -243.563661) (xy 194.723372 -243.584748)
			(xy 194.671211 -243.598384) (xy 194.61762 -243.604281) (xy 194.563741 -243.602312) (xy 194.510723 -243.592519)
			(xy 194.459696 -243.575111) (xy 194.411748 -243.550459) (xy 194.3679 -243.519089) (xy 194.329087 -243.481668)
			(xy 194.296135 -243.438995) (xy 194.269749 -243.391978) (xy 194.250489 -243.341621) (xy 194.238766 -243.288997)
			(xy 194.234831 -243.235226) (xy 187.428886 -243.235226) (xy 187.428394 -243.262183) (xy 187.420544 -243.315523)
			(xy 187.405012 -243.367152) (xy 187.382127 -243.415969) (xy 187.352379 -243.460933) (xy 187.316401 -243.501087)
			(xy 187.274959 -243.535575) (xy 187.228938 -243.563661) (xy 187.179318 -243.584748) (xy 187.127157 -243.598384)
			(xy 187.073566 -243.604281) (xy 187.019687 -243.602312) (xy 186.966669 -243.592519) (xy 186.915642 -243.575111)
			(xy 186.867694 -243.550459) (xy 186.823846 -243.519089) (xy 186.785033 -243.481668) (xy 186.752081 -243.438995)
			(xy 186.725695 -243.391978) (xy 186.706435 -243.341621) (xy 186.694712 -243.288997) (xy 186.690777 -243.235226)
			(xy 179.884832 -243.235226) (xy 179.88434 -243.262183) (xy 179.87649 -243.315523) (xy 179.860958 -243.367152)
			(xy 179.838073 -243.415969) (xy 179.808325 -243.460933) (xy 179.772347 -243.501087) (xy 179.730905 -243.535575)
			(xy 179.684884 -243.563661) (xy 179.635264 -243.584748) (xy 179.583103 -243.598384) (xy 179.529512 -243.604281)
			(xy 179.475633 -243.602312) (xy 179.422615 -243.592519) (xy 179.371588 -243.575111) (xy 179.32364 -243.550459)
			(xy 179.279792 -243.519089) (xy 179.240979 -243.481668) (xy 179.208027 -243.438995) (xy 179.181641 -243.391978)
			(xy 179.162381 -243.341621) (xy 179.150658 -243.288997) (xy 179.146723 -243.235226) (xy 177.881534 -243.235226)
			(xy 177.881534 -244.085364) (xy 181.850284 -244.085364) (xy 181.850656 -244.060219) (xy 181.857404 -244.010385)
			(xy 181.863746 -243.98605) (xy 181.865105 -243.980961) (xy 181.865865 -243.970456) (xy 181.86527 -243.965222)
			(xy 181.862812 -243.943885) (xy 181.865049 -243.900998) (xy 181.875329 -243.859302) (xy 181.893286 -243.820291)
			(xy 181.918274 -243.785365) (xy 181.949398 -243.755775) (xy 181.985542 -243.732583) (xy 182.02541 -243.71662)
			(xy 182.067572 -243.708458) (xy 182.089044 -243.70792) (xy 182.356506 -243.70792) (xy 182.356506 -243.725192)
			(xy 182.371746 -243.749576) (xy 182.384954 -243.755926) (xy 182.396384 -243.761768) (xy 182.401972 -243.764816)
			(xy 182.41391 -243.767864) (xy 182.854854 -243.767864) (xy 182.88 -243.751608) (xy 182.886096 -243.737638)
			(xy 182.890396 -243.729039) (xy 182.904178 -243.71566) (xy 182.92196 -243.708398) (xy 182.931562 -243.70792)
			(xy 183.14924 -243.70792) (xy 183.169705 -243.708388) (xy 183.209954 -243.715835) (xy 183.248211 -243.73039)
			(xy 183.283232 -243.751578) (xy 183.298846 -243.764816) (xy 183.305988 -243.770616) (xy 183.323181 -243.777128)
			(xy 183.332374 -243.777516) (xy 183.405526 -243.777516) (xy 183.418734 -243.773706) (xy 183.42483 -243.77015)
			(xy 183.44655 -243.757467) (xy 183.492689 -243.737445) (xy 183.541119 -243.723873) (xy 183.590944 -243.717002)
			(xy 183.616092 -243.716556) (xy 183.643691 -243.717118) (xy 183.698274 -243.725343) (xy 183.75102 -243.741613)
			(xy 183.800753 -243.765562) (xy 183.84636 -243.796655) (xy 183.886824 -243.8342) (xy 183.92124 -243.877355)
			(xy 183.94884 -243.925158) (xy 183.969006 -243.976541) (xy 183.981289 -244.030356) (xy 183.985412 -244.085364)
			(xy 189.394338 -244.085364) (xy 189.394637 -244.062455) (xy 189.400246 -244.016983) (xy 189.405514 -243.994686)
			(xy 189.407038 -243.98859) (xy 189.407038 -243.935504) (xy 189.407394 -243.913191) (xy 189.415844 -243.869377)
			(xy 189.432714 -243.828068) (xy 189.45735 -243.790864) (xy 189.488796 -243.759207) (xy 189.525835 -243.734324)
			(xy 189.567031 -243.71718) (xy 189.610787 -243.708438) (xy 189.633098 -243.70792) (xy 189.900814 -243.70792)
			(xy 189.900814 -243.725192) (xy 189.916054 -243.749576) (xy 189.929262 -243.75618) (xy 189.940438 -243.761768)
			(xy 189.946026 -243.764816) (xy 189.957964 -243.767864) (xy 190.398654 -243.767864) (xy 190.4238 -243.751608)
			(xy 190.429896 -243.737638) (xy 190.434228 -243.729004) (xy 190.448078 -243.715571) (xy 190.465968 -243.708344)
			(xy 190.475616 -243.70792) (xy 190.693294 -243.70792) (xy 190.713758 -243.708415) (xy 190.754005 -243.715853)
			(xy 190.792262 -243.7304) (xy 190.827284 -243.751582) (xy 190.8429 -243.764816) (xy 190.850056 -243.770597)
			(xy 190.867238 -243.77712) (xy 190.876428 -243.777516) (xy 190.94958 -243.777516) (xy 190.962788 -243.773706)
			(xy 190.968884 -243.77015) (xy 190.990592 -243.757445) (xy 191.036735 -243.737428) (xy 191.08517 -243.723862)
			(xy 191.134997 -243.716998) (xy 191.160146 -243.716556) (xy 191.187741 -243.717147) (xy 191.242313 -243.725379)
			(xy 191.295049 -243.741651) (xy 191.344771 -243.765602) (xy 191.390369 -243.796695) (xy 191.430823 -243.834236)
			(xy 191.465231 -243.877387) (xy 191.492824 -243.925183) (xy 191.512985 -243.976559) (xy 191.525265 -244.030365)
			(xy 191.529386 -244.085364) (xy 196.938392 -244.085364) (xy 196.938764 -244.060219) (xy 196.945512 -244.010385)
			(xy 196.951854 -243.98605) (xy 196.953213 -243.980961) (xy 196.953973 -243.970456) (xy 196.953378 -243.965222)
			(xy 196.950912 -243.943886) (xy 196.953149 -243.900998) (xy 196.96343 -243.859301) (xy 196.981387 -243.820289)
			(xy 197.006376 -243.785362) (xy 197.037502 -243.755772) (xy 197.073647 -243.73258) (xy 197.113516 -243.716618)
			(xy 197.15568 -243.708457) (xy 197.177152 -243.70792) (xy 197.444614 -243.70792) (xy 197.444614 -243.725192)
			(xy 197.459854 -243.749576) (xy 197.473062 -243.755926) (xy 197.484492 -243.761768) (xy 197.49008 -243.764816)
			(xy 197.502018 -243.767864) (xy 197.942962 -243.767864) (xy 197.968108 -243.751608) (xy 197.974204 -243.737638)
			(xy 197.978499 -243.729036) (xy 197.992283 -243.715657) (xy 198.010067 -243.708397) (xy 198.01967 -243.70792)
			(xy 198.237348 -243.70792) (xy 198.257813 -243.708384) (xy 198.298062 -243.715832) (xy 198.336319 -243.730388)
			(xy 198.37134 -243.751578) (xy 198.386954 -243.764816) (xy 198.394094 -243.77062) (xy 198.411289 -243.77713)
			(xy 198.420482 -243.777516) (xy 198.493634 -243.777516) (xy 198.506842 -243.773706) (xy 198.512938 -243.77015)
			(xy 198.534656 -243.757464) (xy 198.580796 -243.737442) (xy 198.629227 -243.723871) (xy 198.679052 -243.717002)
			(xy 198.7042 -243.716556) (xy 198.731797 -243.717144) (xy 198.786375 -243.72537) (xy 198.839116 -243.741639)
			(xy 198.888845 -243.765586) (xy 198.934448 -243.796678) (xy 198.974908 -243.83422) (xy 199.009321 -243.877372)
			(xy 199.036918 -243.925172) (xy 199.057083 -243.97655) (xy 199.069364 -244.03036) (xy 199.073486 -244.085364)
			(xy 204.482192 -244.085364) (xy 204.482564 -244.060219) (xy 204.489312 -244.010385) (xy 204.495654 -243.98605)
			(xy 204.497013 -243.980961) (xy 204.497773 -243.970456) (xy 204.497178 -243.965222) (xy 204.494712 -243.943886)
			(xy 204.496949 -243.900998) (xy 204.50723 -243.859301) (xy 204.525187 -243.820289) (xy 204.550176 -243.785362)
			(xy 204.581302 -243.755772) (xy 204.617447 -243.73258) (xy 204.657316 -243.716618) (xy 204.69948 -243.708457)
			(xy 204.720952 -243.70792) (xy 204.988414 -243.70792) (xy 204.988414 -243.725192) (xy 205.003654 -243.749576)
			(xy 205.016862 -243.755926) (xy 205.028292 -243.761768) (xy 205.03388 -243.764816) (xy 205.045818 -243.767864)
			(xy 205.486762 -243.767864) (xy 205.511908 -243.751608) (xy 205.518004 -243.737638) (xy 205.522299 -243.729036)
			(xy 205.536083 -243.715657) (xy 205.553867 -243.708397) (xy 205.56347 -243.70792) (xy 205.781148 -243.70792)
			(xy 205.801613 -243.708384) (xy 205.841862 -243.715832) (xy 205.880119 -243.730388) (xy 205.91514 -243.751578)
			(xy 205.930754 -243.764816) (xy 205.937894 -243.77062) (xy 205.955089 -243.77713) (xy 205.964282 -243.777516)
			(xy 206.037434 -243.777516) (xy 206.050642 -243.773706) (xy 206.056738 -243.77015) (xy 206.078456 -243.757464)
			(xy 206.124596 -243.737442) (xy 206.173027 -243.723871) (xy 206.222852 -243.717002) (xy 206.248 -243.716556)
			(xy 206.275597 -243.717144) (xy 206.330175 -243.72537) (xy 206.382916 -243.741639) (xy 206.432645 -243.765586)
			(xy 206.478248 -243.796678) (xy 206.518708 -243.83422) (xy 206.553121 -243.877372) (xy 206.580718 -243.925172)
			(xy 206.600883 -243.97655) (xy 206.613164 -244.03036) (xy 206.617289 -244.0854) (xy 206.613164 -244.14044)
			(xy 206.600883 -244.19425) (xy 206.580718 -244.245628) (xy 206.553121 -244.293428) (xy 206.518708 -244.33658)
			(xy 206.478248 -244.374122) (xy 206.432645 -244.405214) (xy 206.382916 -244.429161) (xy 206.330175 -244.44543)
			(xy 206.275597 -244.453656) (xy 206.248 -244.454172) (xy 206.222851 -244.453732) (xy 206.173022 -244.446876)
			(xy 206.124589 -244.433306) (xy 206.078452 -244.413274) (xy 206.056738 -244.400578) (xy 206.050642 -244.397022)
			(xy 206.037434 -244.393212) (xy 205.964282 -244.393212) (xy 205.955094 -244.393611) (xy 205.937909 -244.400132)
			(xy 205.930754 -244.405912) (xy 205.915163 -244.419183) (xy 205.880147 -244.440393) (xy 205.84188 -244.454941)
			(xy 205.801617 -244.46235) (xy 205.781148 -244.462808) (xy 205.513686 -244.462808) (xy 205.513686 -244.453664)
			(xy 205.513241 -244.443652) (xy 205.505567 -244.425157) (xy 205.491401 -244.411005) (xy 205.472898 -244.403349)
			(xy 205.462886 -244.402864) (xy 205.045818 -244.402864) (xy 205.03388 -244.405912) (xy 205.028292 -244.40896)
			(xy 205.016354 -244.414802) (xy 205.0161 -244.415056) (xy 205.004416 -244.420898) (xy 205.000712 -244.42288)
			(xy 204.993945 -244.427855) (xy 204.990954 -244.430804) (xy 204.974444 -244.447568) (xy 204.967016 -244.45451)
			(xy 204.94828 -244.462363) (xy 204.938122 -244.462808) (xy 204.720952 -244.462808) (xy 204.700657 -244.462364)
			(xy 204.660714 -244.455142) (xy 204.622703 -244.440902) (xy 204.587847 -244.420103) (xy 204.557266 -244.393413)
			(xy 204.531943 -244.36169) (xy 204.512692 -244.325955) (xy 204.500133 -244.287357) (xy 204.49467 -244.247136)
			(xy 204.495146 -244.226842) (xy 204.495146 -244.183154) (xy 204.493622 -244.176804) (xy 204.488275 -244.154323)
			(xy 204.482539 -244.10847) (xy 204.482192 -244.085364) (xy 199.073486 -244.085364) (xy 199.073489 -244.0854)
			(xy 199.069364 -244.14044) (xy 199.057083 -244.19425) (xy 199.036918 -244.245628) (xy 199.009321 -244.293428)
			(xy 198.974908 -244.33658) (xy 198.934448 -244.374122) (xy 198.888845 -244.405214) (xy 198.839116 -244.429161)
			(xy 198.786375 -244.44543) (xy 198.731797 -244.453656) (xy 198.7042 -244.454172) (xy 198.679051 -244.453732)
			(xy 198.629222 -244.446876) (xy 198.580789 -244.433306) (xy 198.534652 -244.413274) (xy 198.512938 -244.400578)
			(xy 198.506842 -244.397022) (xy 198.493634 -244.393212) (xy 198.420482 -244.393212) (xy 198.411294 -244.393611)
			(xy 198.394109 -244.400132) (xy 198.386954 -244.405912) (xy 198.371363 -244.419183) (xy 198.336347 -244.440393)
			(xy 198.29808 -244.454941) (xy 198.257817 -244.46235) (xy 198.237348 -244.462808) (xy 197.969886 -244.462808)
			(xy 197.969886 -244.453664) (xy 197.969441 -244.443652) (xy 197.961767 -244.425157) (xy 197.947601 -244.411005)
			(xy 197.929098 -244.403349) (xy 197.919086 -244.402864) (xy 197.502018 -244.402864) (xy 197.49008 -244.405912)
			(xy 197.484492 -244.40896) (xy 197.472554 -244.414802) (xy 197.4723 -244.415056) (xy 197.460616 -244.420898)
			(xy 197.456912 -244.42288) (xy 197.450145 -244.427855) (xy 197.447154 -244.430804) (xy 197.430644 -244.447568)
			(xy 197.423216 -244.45451) (xy 197.40448 -244.462363) (xy 197.394322 -244.462808) (xy 197.177152 -244.462808)
			(xy 197.156857 -244.462364) (xy 197.116914 -244.455142) (xy 197.078903 -244.440902) (xy 197.044047 -244.420103)
			(xy 197.013466 -244.393413) (xy 196.988143 -244.36169) (xy 196.968892 -244.325955) (xy 196.956333 -244.287357)
			(xy 196.95087 -244.247136) (xy 196.951346 -244.226842) (xy 196.951346 -244.183154) (xy 196.949822 -244.176804)
			(xy 196.944475 -244.154323) (xy 196.938739 -244.10847) (xy 196.938392 -244.085364) (xy 191.529386 -244.085364)
			(xy 191.529389 -244.0854) (xy 191.525265 -244.140435) (xy 191.512985 -244.194241) (xy 191.492824 -244.245617)
			(xy 191.465231 -244.293413) (xy 191.430823 -244.336564) (xy 191.390369 -244.374105) (xy 191.344771 -244.405198)
			(xy 191.295049 -244.429149) (xy 191.242313 -244.445421) (xy 191.187741 -244.453653) (xy 191.160146 -244.454172)
			(xy 191.134996 -244.453756) (xy 191.085166 -244.446893) (xy 191.036733 -244.433316) (xy 190.990597 -244.413277)
			(xy 190.968884 -244.400578) (xy 190.962788 -244.397022) (xy 190.94958 -244.393212) (xy 190.876428 -244.393212)
			(xy 190.867242 -244.393633) (xy 190.850057 -244.400139) (xy 190.8429 -244.405912) (xy 190.827292 -244.419161)
			(xy 190.792282 -244.440376) (xy 190.75402 -244.454929) (xy 190.713762 -244.462346) (xy 190.693294 -244.462808)
			(xy 190.425578 -244.462808) (xy 190.425578 -244.452648) (xy 190.425247 -244.442811) (xy 190.417741 -244.424628)
			(xy 190.403823 -244.410727) (xy 190.385631 -244.403242) (xy 190.375794 -244.402864) (xy 189.957964 -244.402864)
			(xy 189.946026 -244.405912) (xy 189.940438 -244.40896) (xy 189.9285 -244.414802) (xy 189.928246 -244.415056)
			(xy 189.916816 -244.420898) (xy 189.91327 -244.422793) (xy 189.906763 -244.427512) (xy 189.903862 -244.430296)
			(xy 189.886336 -244.447822) (xy 189.87892 -244.454642) (xy 189.860333 -244.462373) (xy 189.850268 -244.462808)
			(xy 189.633098 -244.462808) (xy 189.610784 -244.462349) (xy 189.567022 -244.453604) (xy 189.525821 -244.436454)
			(xy 189.48878 -244.411563) (xy 189.457334 -244.379897) (xy 189.432702 -244.342682) (xy 189.41584 -244.301363)
			(xy 189.407401 -244.257541) (xy 189.407038 -244.235224) (xy 189.407038 -244.182138) (xy 189.405514 -244.176042)
			(xy 189.40026 -244.153743) (xy 189.394655 -244.108272) (xy 189.394338 -244.085364) (xy 183.985412 -244.085364)
			(xy 183.985415 -244.0854) (xy 183.981289 -244.140444) (xy 183.969006 -244.194259) (xy 183.94884 -244.245642)
			(xy 183.92124 -244.293445) (xy 183.886824 -244.3366) (xy 183.84636 -244.374145) (xy 183.800753 -244.405238)
			(xy 183.75102 -244.429187) (xy 183.698274 -244.445457) (xy 183.643691 -244.453682) (xy 183.616092 -244.454172)
			(xy 183.590943 -244.453736) (xy 183.541114 -244.446879) (xy 183.492681 -244.433308) (xy 183.446544 -244.413274)
			(xy 183.42483 -244.400578) (xy 183.418734 -244.397022) (xy 183.405526 -244.393212) (xy 183.332374 -244.393212)
			(xy 183.323185 -244.393607) (xy 183.306001 -244.400131) (xy 183.298846 -244.405912) (xy 183.283258 -244.419186)
			(xy 183.248241 -244.440396) (xy 183.209973 -244.454943) (xy 183.169709 -244.46235) (xy 183.14924 -244.462808)
			(xy 182.881778 -244.462808) (xy 182.881778 -244.453664) (xy 182.881341 -244.443651) (xy 182.873665 -244.425155)
			(xy 182.859497 -244.411002) (xy 182.840991 -244.403348) (xy 182.830978 -244.402864) (xy 182.41391 -244.402864)
			(xy 182.401972 -244.405912) (xy 182.396384 -244.40896) (xy 182.384446 -244.414802) (xy 182.384192 -244.415056)
			(xy 182.372508 -244.420898) (xy 182.368803 -244.422878) (xy 182.362037 -244.427855) (xy 182.359046 -244.430804)
			(xy 182.342536 -244.447568) (xy 182.335111 -244.454514) (xy 182.316372 -244.462365) (xy 182.306214 -244.462808)
			(xy 182.089044 -244.462808) (xy 182.068748 -244.462371) (xy 182.028805 -244.455148) (xy 181.990795 -244.440907)
			(xy 181.955938 -244.420107) (xy 181.925357 -244.393416) (xy 181.900034 -244.361692) (xy 181.880784 -244.325957)
			(xy 181.868225 -244.287358) (xy 181.862762 -244.247136) (xy 181.863238 -244.226842) (xy 181.863238 -244.183154)
			(xy 181.861714 -244.176804) (xy 181.856367 -244.154323) (xy 181.850631 -244.10847) (xy 181.850284 -244.085364)
			(xy 177.881534 -244.085364) (xy 177.881534 -244.935248) (xy 179.146723 -244.935248) (xy 179.150658 -244.881477)
			(xy 179.162381 -244.828853) (xy 179.181641 -244.778496) (xy 179.208027 -244.731479) (xy 179.240979 -244.688806)
			(xy 179.279792 -244.651385) (xy 179.32364 -244.620015) (xy 179.371588 -244.595363) (xy 179.422615 -244.577955)
			(xy 179.475633 -244.568162) (xy 179.529512 -244.566193) (xy 179.583103 -244.57209) (xy 179.635264 -244.585726)
			(xy 179.684884 -244.606813) (xy 179.730905 -244.634899) (xy 179.772347 -244.669387) (xy 179.808325 -244.709541)
			(xy 179.838073 -244.754505) (xy 179.860958 -244.803322) (xy 179.87649 -244.854951) (xy 179.88434 -244.908291)
			(xy 179.884832 -244.935248) (xy 186.690777 -244.935248) (xy 186.694712 -244.881477) (xy 186.706435 -244.828853)
			(xy 186.725695 -244.778496) (xy 186.752081 -244.731479) (xy 186.785033 -244.688806) (xy 186.823846 -244.651385)
			(xy 186.867694 -244.620015) (xy 186.915642 -244.595363) (xy 186.966669 -244.577955) (xy 187.019687 -244.568162)
			(xy 187.073566 -244.566193) (xy 187.127157 -244.57209) (xy 187.179318 -244.585726) (xy 187.228938 -244.606813)
			(xy 187.274959 -244.634899) (xy 187.316401 -244.669387) (xy 187.352379 -244.709541) (xy 187.382127 -244.754505)
			(xy 187.405012 -244.803322) (xy 187.420544 -244.854951) (xy 187.428394 -244.908291) (xy 187.428886 -244.935248)
			(xy 194.234831 -244.935248) (xy 194.238766 -244.881477) (xy 194.250489 -244.828853) (xy 194.269749 -244.778496)
			(xy 194.296135 -244.731479) (xy 194.329087 -244.688806) (xy 194.3679 -244.651385) (xy 194.411748 -244.620015)
			(xy 194.459696 -244.595363) (xy 194.510723 -244.577955) (xy 194.563741 -244.568162) (xy 194.61762 -244.566193)
			(xy 194.671211 -244.57209) (xy 194.723372 -244.585726) (xy 194.772992 -244.606813) (xy 194.819013 -244.634899)
			(xy 194.860455 -244.669387) (xy 194.896433 -244.709541) (xy 194.926181 -244.754505) (xy 194.949066 -244.803322)
			(xy 194.964598 -244.854951) (xy 194.972448 -244.908291) (xy 194.97294 -244.935248) (xy 201.778631 -244.935248)
			(xy 201.782566 -244.881477) (xy 201.794289 -244.828853) (xy 201.813549 -244.778496) (xy 201.839935 -244.731479)
			(xy 201.872887 -244.688806) (xy 201.9117 -244.651385) (xy 201.955548 -244.620015) (xy 202.003496 -244.595363)
			(xy 202.054523 -244.577955) (xy 202.107541 -244.568162) (xy 202.16142 -244.566193) (xy 202.215011 -244.57209)
			(xy 202.267172 -244.585726) (xy 202.316792 -244.606813) (xy 202.362813 -244.634899) (xy 202.404255 -244.669387)
			(xy 202.440233 -244.709541) (xy 202.469981 -244.754505) (xy 202.492866 -244.803322) (xy 202.508398 -244.854951)
			(xy 202.516248 -244.908291) (xy 202.51674 -244.935248) (xy 202.516248 -244.962205) (xy 202.508398 -245.015545)
			(xy 202.492866 -245.067174) (xy 202.469981 -245.115991) (xy 202.440233 -245.160955) (xy 202.404255 -245.201109)
			(xy 202.362813 -245.235597) (xy 202.316792 -245.263683) (xy 202.267172 -245.28477) (xy 202.215011 -245.298406)
			(xy 202.16142 -245.304303) (xy 202.107541 -245.302334) (xy 202.054523 -245.292541) (xy 202.003496 -245.275133)
			(xy 201.955548 -245.250481) (xy 201.9117 -245.219111) (xy 201.872887 -245.18169) (xy 201.839935 -245.139017)
			(xy 201.813549 -245.092) (xy 201.794289 -245.041643) (xy 201.782566 -244.989019) (xy 201.778631 -244.935248)
			(xy 194.97294 -244.935248) (xy 194.972448 -244.962205) (xy 194.964598 -245.015545) (xy 194.949066 -245.067174)
			(xy 194.926181 -245.115991) (xy 194.896433 -245.160955) (xy 194.860455 -245.201109) (xy 194.819013 -245.235597)
			(xy 194.772992 -245.263683) (xy 194.723372 -245.28477) (xy 194.671211 -245.298406) (xy 194.61762 -245.304303)
			(xy 194.563741 -245.302334) (xy 194.510723 -245.292541) (xy 194.459696 -245.275133) (xy 194.411748 -245.250481)
			(xy 194.3679 -245.219111) (xy 194.329087 -245.18169) (xy 194.296135 -245.139017) (xy 194.269749 -245.092)
			(xy 194.250489 -245.041643) (xy 194.238766 -244.989019) (xy 194.234831 -244.935248) (xy 187.428886 -244.935248)
			(xy 187.428394 -244.962205) (xy 187.420544 -245.015545) (xy 187.405012 -245.067174) (xy 187.382127 -245.115991)
			(xy 187.352379 -245.160955) (xy 187.316401 -245.201109) (xy 187.274959 -245.235597) (xy 187.228938 -245.263683)
			(xy 187.179318 -245.28477) (xy 187.127157 -245.298406) (xy 187.073566 -245.304303) (xy 187.019687 -245.302334)
			(xy 186.966669 -245.292541) (xy 186.915642 -245.275133) (xy 186.867694 -245.250481) (xy 186.823846 -245.219111)
			(xy 186.785033 -245.18169) (xy 186.752081 -245.139017) (xy 186.725695 -245.092) (xy 186.706435 -245.041643)
			(xy 186.694712 -244.989019) (xy 186.690777 -244.935248) (xy 179.884832 -244.935248) (xy 179.88434 -244.962205)
			(xy 179.87649 -245.015545) (xy 179.860958 -245.067174) (xy 179.838073 -245.115991) (xy 179.808325 -245.160955)
			(xy 179.772347 -245.201109) (xy 179.730905 -245.235597) (xy 179.684884 -245.263683) (xy 179.635264 -245.28477)
			(xy 179.583103 -245.298406) (xy 179.529512 -245.304303) (xy 179.475633 -245.302334) (xy 179.422615 -245.292541)
			(xy 179.371588 -245.275133) (xy 179.32364 -245.250481) (xy 179.279792 -245.219111) (xy 179.240979 -245.18169)
			(xy 179.208027 -245.139017) (xy 179.181641 -245.092) (xy 179.162381 -245.041643) (xy 179.150658 -244.989019)
			(xy 179.146723 -244.935248) (xy 177.881534 -244.935248) (xy 177.881534 -245.785386) (xy 183.246791 -245.785386)
			(xy 183.250726 -245.731615) (xy 183.262449 -245.678991) (xy 183.281709 -245.628634) (xy 183.308095 -245.581617)
			(xy 183.341047 -245.538944) (xy 183.37986 -245.501523) (xy 183.423708 -245.470153) (xy 183.471656 -245.445501)
			(xy 183.522683 -245.428093) (xy 183.575701 -245.4183) (xy 183.62958 -245.416331) (xy 183.683171 -245.422228)
			(xy 183.735332 -245.435864) (xy 183.784952 -245.456951) (xy 183.830973 -245.485037) (xy 183.872415 -245.519525)
			(xy 183.908393 -245.559679) (xy 183.938141 -245.604643) (xy 183.961026 -245.65346) (xy 183.976558 -245.705089)
			(xy 183.984408 -245.758429) (xy 183.9849 -245.785386) (xy 190.790845 -245.785386) (xy 190.79478 -245.731615)
			(xy 190.806503 -245.678991) (xy 190.825763 -245.628634) (xy 190.852149 -245.581617) (xy 190.885101 -245.538944)
			(xy 190.923914 -245.501523) (xy 190.967762 -245.470153) (xy 191.01571 -245.445501) (xy 191.066737 -245.428093)
			(xy 191.119755 -245.4183) (xy 191.173634 -245.416331) (xy 191.227225 -245.422228) (xy 191.279386 -245.435864)
			(xy 191.329006 -245.456951) (xy 191.375027 -245.485037) (xy 191.416469 -245.519525) (xy 191.452447 -245.559679)
			(xy 191.482195 -245.604643) (xy 191.50508 -245.65346) (xy 191.520612 -245.705089) (xy 191.528462 -245.758429)
			(xy 191.528954 -245.785386) (xy 198.334899 -245.785386) (xy 198.338834 -245.731615) (xy 198.350557 -245.678991)
			(xy 198.369817 -245.628634) (xy 198.396203 -245.581617) (xy 198.429155 -245.538944) (xy 198.467968 -245.501523)
			(xy 198.511816 -245.470153) (xy 198.559764 -245.445501) (xy 198.610791 -245.428093) (xy 198.663809 -245.4183)
			(xy 198.717688 -245.416331) (xy 198.771279 -245.422228) (xy 198.82344 -245.435864) (xy 198.87306 -245.456951)
			(xy 198.919081 -245.485037) (xy 198.960523 -245.519525) (xy 198.996501 -245.559679) (xy 199.026249 -245.604643)
			(xy 199.049134 -245.65346) (xy 199.064666 -245.705089) (xy 199.072516 -245.758429) (xy 199.073008 -245.785386)
			(xy 205.878699 -245.785386) (xy 205.882634 -245.731615) (xy 205.894357 -245.678991) (xy 205.913617 -245.628634)
			(xy 205.940003 -245.581617) (xy 205.972955 -245.538944) (xy 206.011768 -245.501523) (xy 206.055616 -245.470153)
			(xy 206.103564 -245.445501) (xy 206.154591 -245.428093) (xy 206.207609 -245.4183) (xy 206.261488 -245.416331)
			(xy 206.315079 -245.422228) (xy 206.36724 -245.435864) (xy 206.41686 -245.456951) (xy 206.462881 -245.485037)
			(xy 206.504323 -245.519525) (xy 206.540301 -245.559679) (xy 206.570049 -245.604643) (xy 206.592934 -245.65346)
			(xy 206.608466 -245.705089) (xy 206.616316 -245.758429) (xy 206.616808 -245.785386) (xy 206.616316 -245.812343)
			(xy 206.608466 -245.865683) (xy 206.592934 -245.917312) (xy 206.570049 -245.966129) (xy 206.540301 -246.011093)
			(xy 206.504323 -246.051247) (xy 206.462881 -246.085735) (xy 206.41686 -246.113821) (xy 206.36724 -246.134908)
			(xy 206.315079 -246.148544) (xy 206.261488 -246.154441) (xy 206.207609 -246.152472) (xy 206.154591 -246.142679)
			(xy 206.103564 -246.125271) (xy 206.055616 -246.100619) (xy 206.011768 -246.069249) (xy 205.972955 -246.031828)
			(xy 205.940003 -245.989155) (xy 205.913617 -245.942138) (xy 205.894357 -245.891781) (xy 205.882634 -245.839157)
			(xy 205.878699 -245.785386) (xy 199.073008 -245.785386) (xy 199.072516 -245.812343) (xy 199.064666 -245.865683)
			(xy 199.049134 -245.917312) (xy 199.026249 -245.966129) (xy 198.996501 -246.011093) (xy 198.960523 -246.051247)
			(xy 198.919081 -246.085735) (xy 198.87306 -246.113821) (xy 198.82344 -246.134908) (xy 198.771279 -246.148544)
			(xy 198.717688 -246.154441) (xy 198.663809 -246.152472) (xy 198.610791 -246.142679) (xy 198.559764 -246.125271)
			(xy 198.511816 -246.100619) (xy 198.467968 -246.069249) (xy 198.429155 -246.031828) (xy 198.396203 -245.989155)
			(xy 198.369817 -245.942138) (xy 198.350557 -245.891781) (xy 198.338834 -245.839157) (xy 198.334899 -245.785386)
			(xy 191.528954 -245.785386) (xy 191.528462 -245.812343) (xy 191.520612 -245.865683) (xy 191.50508 -245.917312)
			(xy 191.482195 -245.966129) (xy 191.452447 -246.011093) (xy 191.416469 -246.051247) (xy 191.375027 -246.085735)
			(xy 191.329006 -246.113821) (xy 191.279386 -246.134908) (xy 191.227225 -246.148544) (xy 191.173634 -246.154441)
			(xy 191.119755 -246.152472) (xy 191.066737 -246.142679) (xy 191.01571 -246.125271) (xy 190.967762 -246.100619)
			(xy 190.923914 -246.069249) (xy 190.885101 -246.031828) (xy 190.852149 -245.989155) (xy 190.825763 -245.942138)
			(xy 190.806503 -245.891781) (xy 190.79478 -245.839157) (xy 190.790845 -245.785386) (xy 183.9849 -245.785386)
			(xy 183.984408 -245.812343) (xy 183.976558 -245.865683) (xy 183.961026 -245.917312) (xy 183.938141 -245.966129)
			(xy 183.908393 -246.011093) (xy 183.872415 -246.051247) (xy 183.830973 -246.085735) (xy 183.784952 -246.113821)
			(xy 183.735332 -246.134908) (xy 183.683171 -246.148544) (xy 183.62958 -246.154441) (xy 183.575701 -246.152472)
			(xy 183.522683 -246.142679) (xy 183.471656 -246.125271) (xy 183.423708 -246.100619) (xy 183.37986 -246.069249)
			(xy 183.341047 -246.031828) (xy 183.308095 -245.989155) (xy 183.281709 -245.942138) (xy 183.262449 -245.891781)
			(xy 183.250726 -245.839157) (xy 183.246791 -245.785386) (xy 177.881534 -245.785386) (xy 177.881534 -246.63527)
			(xy 179.146723 -246.63527) (xy 179.150658 -246.581499) (xy 179.162381 -246.528875) (xy 179.181641 -246.478518)
			(xy 179.208027 -246.431501) (xy 179.240979 -246.388828) (xy 179.279792 -246.351407) (xy 179.32364 -246.320037)
			(xy 179.371588 -246.295385) (xy 179.422615 -246.277977) (xy 179.475633 -246.268184) (xy 179.529512 -246.266215)
			(xy 179.583103 -246.272112) (xy 179.635264 -246.285748) (xy 179.684884 -246.306835) (xy 179.730905 -246.334921)
			(xy 179.772347 -246.369409) (xy 179.808325 -246.409563) (xy 179.838073 -246.454527) (xy 179.860958 -246.503344)
			(xy 179.87649 -246.554973) (xy 179.88434 -246.608313) (xy 179.884832 -246.63527) (xy 186.690777 -246.63527)
			(xy 186.694712 -246.581499) (xy 186.706435 -246.528875) (xy 186.725695 -246.478518) (xy 186.752081 -246.431501)
			(xy 186.785033 -246.388828) (xy 186.823846 -246.351407) (xy 186.867694 -246.320037) (xy 186.915642 -246.295385)
			(xy 186.966669 -246.277977) (xy 187.019687 -246.268184) (xy 187.073566 -246.266215) (xy 187.127157 -246.272112)
			(xy 187.179318 -246.285748) (xy 187.228938 -246.306835) (xy 187.274959 -246.334921) (xy 187.316401 -246.369409)
			(xy 187.352379 -246.409563) (xy 187.382127 -246.454527) (xy 187.405012 -246.503344) (xy 187.420544 -246.554973)
			(xy 187.428394 -246.608313) (xy 187.428886 -246.63527) (xy 194.234831 -246.63527) (xy 194.238766 -246.581499)
			(xy 194.250489 -246.528875) (xy 194.269749 -246.478518) (xy 194.296135 -246.431501) (xy 194.329087 -246.388828)
			(xy 194.3679 -246.351407) (xy 194.411748 -246.320037) (xy 194.459696 -246.295385) (xy 194.510723 -246.277977)
			(xy 194.563741 -246.268184) (xy 194.61762 -246.266215) (xy 194.671211 -246.272112) (xy 194.723372 -246.285748)
			(xy 194.772992 -246.306835) (xy 194.819013 -246.334921) (xy 194.860455 -246.369409) (xy 194.896433 -246.409563)
			(xy 194.926181 -246.454527) (xy 194.949066 -246.503344) (xy 194.964598 -246.554973) (xy 194.972448 -246.608313)
			(xy 194.97294 -246.63527) (xy 201.778631 -246.63527) (xy 201.782566 -246.581499) (xy 201.794289 -246.528875)
			(xy 201.813549 -246.478518) (xy 201.839935 -246.431501) (xy 201.872887 -246.388828) (xy 201.9117 -246.351407)
			(xy 201.955548 -246.320037) (xy 202.003496 -246.295385) (xy 202.054523 -246.277977) (xy 202.107541 -246.268184)
			(xy 202.16142 -246.266215) (xy 202.215011 -246.272112) (xy 202.267172 -246.285748) (xy 202.316792 -246.306835)
			(xy 202.362813 -246.334921) (xy 202.404255 -246.369409) (xy 202.440233 -246.409563) (xy 202.469981 -246.454527)
			(xy 202.492866 -246.503344) (xy 202.508398 -246.554973) (xy 202.516248 -246.608313) (xy 202.51674 -246.63527)
			(xy 202.516248 -246.662227) (xy 202.508398 -246.715567) (xy 202.492866 -246.767196) (xy 202.469981 -246.816013)
			(xy 202.440233 -246.860977) (xy 202.404255 -246.901131) (xy 202.362813 -246.935619) (xy 202.316792 -246.963705)
			(xy 202.267172 -246.984792) (xy 202.215011 -246.998428) (xy 202.16142 -247.004325) (xy 202.107541 -247.002356)
			(xy 202.054523 -246.992563) (xy 202.003496 -246.975155) (xy 201.955548 -246.950503) (xy 201.9117 -246.919133)
			(xy 201.872887 -246.881712) (xy 201.839935 -246.839039) (xy 201.813549 -246.792022) (xy 201.794289 -246.741665)
			(xy 201.782566 -246.689041) (xy 201.778631 -246.63527) (xy 194.97294 -246.63527) (xy 194.972448 -246.662227)
			(xy 194.964598 -246.715567) (xy 194.949066 -246.767196) (xy 194.926181 -246.816013) (xy 194.896433 -246.860977)
			(xy 194.860455 -246.901131) (xy 194.819013 -246.935619) (xy 194.772992 -246.963705) (xy 194.723372 -246.984792)
			(xy 194.671211 -246.998428) (xy 194.61762 -247.004325) (xy 194.563741 -247.002356) (xy 194.510723 -246.992563)
			(xy 194.459696 -246.975155) (xy 194.411748 -246.950503) (xy 194.3679 -246.919133) (xy 194.329087 -246.881712)
			(xy 194.296135 -246.839039) (xy 194.269749 -246.792022) (xy 194.250489 -246.741665) (xy 194.238766 -246.689041)
			(xy 194.234831 -246.63527) (xy 187.428886 -246.63527) (xy 187.428394 -246.662227) (xy 187.420544 -246.715567)
			(xy 187.405012 -246.767196) (xy 187.382127 -246.816013) (xy 187.352379 -246.860977) (xy 187.316401 -246.901131)
			(xy 187.274959 -246.935619) (xy 187.228938 -246.963705) (xy 187.179318 -246.984792) (xy 187.127157 -246.998428)
			(xy 187.073566 -247.004325) (xy 187.019687 -247.002356) (xy 186.966669 -246.992563) (xy 186.915642 -246.975155)
			(xy 186.867694 -246.950503) (xy 186.823846 -246.919133) (xy 186.785033 -246.881712) (xy 186.752081 -246.839039)
			(xy 186.725695 -246.792022) (xy 186.706435 -246.741665) (xy 186.694712 -246.689041) (xy 186.690777 -246.63527)
			(xy 179.884832 -246.63527) (xy 179.88434 -246.662227) (xy 179.87649 -246.715567) (xy 179.860958 -246.767196)
			(xy 179.838073 -246.816013) (xy 179.808325 -246.860977) (xy 179.772347 -246.901131) (xy 179.730905 -246.935619)
			(xy 179.684884 -246.963705) (xy 179.635264 -246.984792) (xy 179.583103 -246.998428) (xy 179.529512 -247.004325)
			(xy 179.475633 -247.002356) (xy 179.422615 -246.992563) (xy 179.371588 -246.975155) (xy 179.32364 -246.950503)
			(xy 179.279792 -246.919133) (xy 179.240979 -246.881712) (xy 179.208027 -246.839039) (xy 179.181641 -246.792022)
			(xy 179.162381 -246.741665) (xy 179.150658 -246.689041) (xy 179.146723 -246.63527) (xy 177.881534 -246.63527)
			(xy 177.881534 -247.485408) (xy 183.246791 -247.485408) (xy 183.250726 -247.431637) (xy 183.262449 -247.379013)
			(xy 183.281709 -247.328656) (xy 183.308095 -247.281639) (xy 183.341047 -247.238966) (xy 183.37986 -247.201545)
			(xy 183.423708 -247.170175) (xy 183.471656 -247.145523) (xy 183.522683 -247.128115) (xy 183.575701 -247.118322)
			(xy 183.62958 -247.116353) (xy 183.683171 -247.12225) (xy 183.735332 -247.135886) (xy 183.784952 -247.156973)
			(xy 183.830973 -247.185059) (xy 183.872415 -247.219547) (xy 183.908393 -247.259701) (xy 183.938141 -247.304665)
			(xy 183.961026 -247.353482) (xy 183.976558 -247.405111) (xy 183.984408 -247.458451) (xy 183.9849 -247.485408)
			(xy 190.790845 -247.485408) (xy 190.79478 -247.431637) (xy 190.806503 -247.379013) (xy 190.825763 -247.328656)
			(xy 190.852149 -247.281639) (xy 190.885101 -247.238966) (xy 190.923914 -247.201545) (xy 190.967762 -247.170175)
			(xy 191.01571 -247.145523) (xy 191.066737 -247.128115) (xy 191.119755 -247.118322) (xy 191.173634 -247.116353)
			(xy 191.227225 -247.12225) (xy 191.279386 -247.135886) (xy 191.329006 -247.156973) (xy 191.375027 -247.185059)
			(xy 191.416469 -247.219547) (xy 191.452447 -247.259701) (xy 191.482195 -247.304665) (xy 191.50508 -247.353482)
			(xy 191.520612 -247.405111) (xy 191.528462 -247.458451) (xy 191.528954 -247.485408) (xy 198.334899 -247.485408)
			(xy 198.338834 -247.431637) (xy 198.350557 -247.379013) (xy 198.369817 -247.328656) (xy 198.396203 -247.281639)
			(xy 198.429155 -247.238966) (xy 198.467968 -247.201545) (xy 198.511816 -247.170175) (xy 198.559764 -247.145523)
			(xy 198.610791 -247.128115) (xy 198.663809 -247.118322) (xy 198.717688 -247.116353) (xy 198.771279 -247.12225)
			(xy 198.82344 -247.135886) (xy 198.87306 -247.156973) (xy 198.919081 -247.185059) (xy 198.960523 -247.219547)
			(xy 198.996501 -247.259701) (xy 199.026249 -247.304665) (xy 199.049134 -247.353482) (xy 199.064666 -247.405111)
			(xy 199.072516 -247.458451) (xy 199.073008 -247.485408) (xy 205.878699 -247.485408) (xy 205.882634 -247.431637)
			(xy 205.894357 -247.379013) (xy 205.913617 -247.328656) (xy 205.940003 -247.281639) (xy 205.972955 -247.238966)
			(xy 206.011768 -247.201545) (xy 206.055616 -247.170175) (xy 206.103564 -247.145523) (xy 206.154591 -247.128115)
			(xy 206.207609 -247.118322) (xy 206.261488 -247.116353) (xy 206.315079 -247.12225) (xy 206.36724 -247.135886)
			(xy 206.41686 -247.156973) (xy 206.462881 -247.185059) (xy 206.504323 -247.219547) (xy 206.540301 -247.259701)
			(xy 206.570049 -247.304665) (xy 206.592934 -247.353482) (xy 206.608466 -247.405111) (xy 206.616316 -247.458451)
			(xy 206.616808 -247.485408) (xy 206.616316 -247.512365) (xy 206.608466 -247.565705) (xy 206.592934 -247.617334)
			(xy 206.570049 -247.666151) (xy 206.540301 -247.711115) (xy 206.504323 -247.751269) (xy 206.462881 -247.785757)
			(xy 206.41686 -247.813843) (xy 206.36724 -247.83493) (xy 206.315079 -247.848566) (xy 206.261488 -247.854463)
			(xy 206.207609 -247.852494) (xy 206.154591 -247.842701) (xy 206.103564 -247.825293) (xy 206.055616 -247.800641)
			(xy 206.011768 -247.769271) (xy 205.972955 -247.73185) (xy 205.940003 -247.689177) (xy 205.913617 -247.64216)
			(xy 205.894357 -247.591803) (xy 205.882634 -247.539179) (xy 205.878699 -247.485408) (xy 199.073008 -247.485408)
			(xy 199.072516 -247.512365) (xy 199.064666 -247.565705) (xy 199.049134 -247.617334) (xy 199.026249 -247.666151)
			(xy 198.996501 -247.711115) (xy 198.960523 -247.751269) (xy 198.919081 -247.785757) (xy 198.87306 -247.813843)
			(xy 198.82344 -247.83493) (xy 198.771279 -247.848566) (xy 198.717688 -247.854463) (xy 198.663809 -247.852494)
			(xy 198.610791 -247.842701) (xy 198.559764 -247.825293) (xy 198.511816 -247.800641) (xy 198.467968 -247.769271)
			(xy 198.429155 -247.73185) (xy 198.396203 -247.689177) (xy 198.369817 -247.64216) (xy 198.350557 -247.591803)
			(xy 198.338834 -247.539179) (xy 198.334899 -247.485408) (xy 191.528954 -247.485408) (xy 191.528462 -247.512365)
			(xy 191.520612 -247.565705) (xy 191.50508 -247.617334) (xy 191.482195 -247.666151) (xy 191.452447 -247.711115)
			(xy 191.416469 -247.751269) (xy 191.375027 -247.785757) (xy 191.329006 -247.813843) (xy 191.279386 -247.83493)
			(xy 191.227225 -247.848566) (xy 191.173634 -247.854463) (xy 191.119755 -247.852494) (xy 191.066737 -247.842701)
			(xy 191.01571 -247.825293) (xy 190.967762 -247.800641) (xy 190.923914 -247.769271) (xy 190.885101 -247.73185)
			(xy 190.852149 -247.689177) (xy 190.825763 -247.64216) (xy 190.806503 -247.591803) (xy 190.79478 -247.539179)
			(xy 190.790845 -247.485408) (xy 183.9849 -247.485408) (xy 183.984408 -247.512365) (xy 183.976558 -247.565705)
			(xy 183.961026 -247.617334) (xy 183.938141 -247.666151) (xy 183.908393 -247.711115) (xy 183.872415 -247.751269)
			(xy 183.830973 -247.785757) (xy 183.784952 -247.813843) (xy 183.735332 -247.83493) (xy 183.683171 -247.848566)
			(xy 183.62958 -247.854463) (xy 183.575701 -247.852494) (xy 183.522683 -247.842701) (xy 183.471656 -247.825293)
			(xy 183.423708 -247.800641) (xy 183.37986 -247.769271) (xy 183.341047 -247.73185) (xy 183.308095 -247.689177)
			(xy 183.281709 -247.64216) (xy 183.262449 -247.591803) (xy 183.250726 -247.539179) (xy 183.246791 -247.485408)
			(xy 177.881534 -247.485408) (xy 177.881534 -248.335292) (xy 179.146723 -248.335292) (xy 179.150658 -248.281521)
			(xy 179.162381 -248.228897) (xy 179.181641 -248.17854) (xy 179.208027 -248.131523) (xy 179.240979 -248.08885)
			(xy 179.279792 -248.051429) (xy 179.32364 -248.020059) (xy 179.371588 -247.995407) (xy 179.422615 -247.977999)
			(xy 179.475633 -247.968206) (xy 179.529512 -247.966237) (xy 179.583103 -247.972134) (xy 179.635264 -247.98577)
			(xy 179.684884 -248.006857) (xy 179.730905 -248.034943) (xy 179.772347 -248.069431) (xy 179.808325 -248.109585)
			(xy 179.838073 -248.154549) (xy 179.860958 -248.203366) (xy 179.87649 -248.254995) (xy 179.88434 -248.308335)
			(xy 179.884832 -248.335292) (xy 186.690777 -248.335292) (xy 186.694712 -248.281521) (xy 186.706435 -248.228897)
			(xy 186.725695 -248.17854) (xy 186.752081 -248.131523) (xy 186.785033 -248.08885) (xy 186.823846 -248.051429)
			(xy 186.867694 -248.020059) (xy 186.915642 -247.995407) (xy 186.966669 -247.977999) (xy 187.019687 -247.968206)
			(xy 187.073566 -247.966237) (xy 187.127157 -247.972134) (xy 187.179318 -247.98577) (xy 187.228938 -248.006857)
			(xy 187.274959 -248.034943) (xy 187.316401 -248.069431) (xy 187.352379 -248.109585) (xy 187.382127 -248.154549)
			(xy 187.405012 -248.203366) (xy 187.420544 -248.254995) (xy 187.428394 -248.308335) (xy 187.428886 -248.335292)
			(xy 194.234831 -248.335292) (xy 194.238766 -248.281521) (xy 194.250489 -248.228897) (xy 194.269749 -248.17854)
			(xy 194.296135 -248.131523) (xy 194.329087 -248.08885) (xy 194.3679 -248.051429) (xy 194.411748 -248.020059)
			(xy 194.459696 -247.995407) (xy 194.510723 -247.977999) (xy 194.563741 -247.968206) (xy 194.61762 -247.966237)
			(xy 194.671211 -247.972134) (xy 194.723372 -247.98577) (xy 194.772992 -248.006857) (xy 194.819013 -248.034943)
			(xy 194.860455 -248.069431) (xy 194.896433 -248.109585) (xy 194.926181 -248.154549) (xy 194.949066 -248.203366)
			(xy 194.964598 -248.254995) (xy 194.972448 -248.308335) (xy 194.97294 -248.335292) (xy 201.778631 -248.335292)
			(xy 201.782566 -248.281521) (xy 201.794289 -248.228897) (xy 201.813549 -248.17854) (xy 201.839935 -248.131523)
			(xy 201.872887 -248.08885) (xy 201.9117 -248.051429) (xy 201.955548 -248.020059) (xy 202.003496 -247.995407)
			(xy 202.054523 -247.977999) (xy 202.107541 -247.968206) (xy 202.16142 -247.966237) (xy 202.215011 -247.972134)
			(xy 202.267172 -247.98577) (xy 202.316792 -248.006857) (xy 202.362813 -248.034943) (xy 202.404255 -248.069431)
			(xy 202.440233 -248.109585) (xy 202.469981 -248.154549) (xy 202.492866 -248.203366) (xy 202.508398 -248.254995)
			(xy 202.516248 -248.308335) (xy 202.51674 -248.335292) (xy 202.516248 -248.362249) (xy 202.508398 -248.415589)
			(xy 202.492866 -248.467218) (xy 202.469981 -248.516035) (xy 202.440233 -248.560999) (xy 202.404255 -248.601153)
			(xy 202.362813 -248.635641) (xy 202.316792 -248.663727) (xy 202.267172 -248.684814) (xy 202.215011 -248.69845)
			(xy 202.16142 -248.704347) (xy 202.107541 -248.702378) (xy 202.054523 -248.692585) (xy 202.003496 -248.675177)
			(xy 201.955548 -248.650525) (xy 201.9117 -248.619155) (xy 201.872887 -248.581734) (xy 201.839935 -248.539061)
			(xy 201.813549 -248.492044) (xy 201.794289 -248.441687) (xy 201.782566 -248.389063) (xy 201.778631 -248.335292)
			(xy 194.97294 -248.335292) (xy 194.972448 -248.362249) (xy 194.964598 -248.415589) (xy 194.949066 -248.467218)
			(xy 194.926181 -248.516035) (xy 194.896433 -248.560999) (xy 194.860455 -248.601153) (xy 194.819013 -248.635641)
			(xy 194.772992 -248.663727) (xy 194.723372 -248.684814) (xy 194.671211 -248.69845) (xy 194.61762 -248.704347)
			(xy 194.563741 -248.702378) (xy 194.510723 -248.692585) (xy 194.459696 -248.675177) (xy 194.411748 -248.650525)
			(xy 194.3679 -248.619155) (xy 194.329087 -248.581734) (xy 194.296135 -248.539061) (xy 194.269749 -248.492044)
			(xy 194.250489 -248.441687) (xy 194.238766 -248.389063) (xy 194.234831 -248.335292) (xy 187.428886 -248.335292)
			(xy 187.428394 -248.362249) (xy 187.420544 -248.415589) (xy 187.405012 -248.467218) (xy 187.382127 -248.516035)
			(xy 187.352379 -248.560999) (xy 187.316401 -248.601153) (xy 187.274959 -248.635641) (xy 187.228938 -248.663727)
			(xy 187.179318 -248.684814) (xy 187.127157 -248.69845) (xy 187.073566 -248.704347) (xy 187.019687 -248.702378)
			(xy 186.966669 -248.692585) (xy 186.915642 -248.675177) (xy 186.867694 -248.650525) (xy 186.823846 -248.619155)
			(xy 186.785033 -248.581734) (xy 186.752081 -248.539061) (xy 186.725695 -248.492044) (xy 186.706435 -248.441687)
			(xy 186.694712 -248.389063) (xy 186.690777 -248.335292) (xy 179.884832 -248.335292) (xy 179.88434 -248.362249)
			(xy 179.87649 -248.415589) (xy 179.860958 -248.467218) (xy 179.838073 -248.516035) (xy 179.808325 -248.560999)
			(xy 179.772347 -248.601153) (xy 179.730905 -248.635641) (xy 179.684884 -248.663727) (xy 179.635264 -248.684814)
			(xy 179.583103 -248.69845) (xy 179.529512 -248.704347) (xy 179.475633 -248.702378) (xy 179.422615 -248.692585)
			(xy 179.371588 -248.675177) (xy 179.32364 -248.650525) (xy 179.279792 -248.619155) (xy 179.240979 -248.581734)
			(xy 179.208027 -248.539061) (xy 179.181641 -248.492044) (xy 179.162381 -248.441687) (xy 179.150658 -248.389063)
			(xy 179.146723 -248.335292) (xy 177.881534 -248.335292) (xy 177.881534 -249.18543) (xy 183.246791 -249.18543)
			(xy 183.250726 -249.131659) (xy 183.262449 -249.079035) (xy 183.281709 -249.028678) (xy 183.308095 -248.981661)
			(xy 183.341047 -248.938988) (xy 183.37986 -248.901567) (xy 183.423708 -248.870197) (xy 183.471656 -248.845545)
			(xy 183.522683 -248.828137) (xy 183.575701 -248.818344) (xy 183.62958 -248.816375) (xy 183.683171 -248.822272)
			(xy 183.735332 -248.835908) (xy 183.784952 -248.856995) (xy 183.830973 -248.885081) (xy 183.872415 -248.919569)
			(xy 183.908393 -248.959723) (xy 183.938141 -249.004687) (xy 183.961026 -249.053504) (xy 183.976558 -249.105133)
			(xy 183.984408 -249.158473) (xy 183.9849 -249.18543) (xy 190.790845 -249.18543) (xy 190.79478 -249.131659)
			(xy 190.806503 -249.079035) (xy 190.825763 -249.028678) (xy 190.852149 -248.981661) (xy 190.885101 -248.938988)
			(xy 190.923914 -248.901567) (xy 190.967762 -248.870197) (xy 191.01571 -248.845545) (xy 191.066737 -248.828137)
			(xy 191.119755 -248.818344) (xy 191.173634 -248.816375) (xy 191.227225 -248.822272) (xy 191.279386 -248.835908)
			(xy 191.329006 -248.856995) (xy 191.375027 -248.885081) (xy 191.416469 -248.919569) (xy 191.452447 -248.959723)
			(xy 191.482195 -249.004687) (xy 191.50508 -249.053504) (xy 191.520612 -249.105133) (xy 191.528462 -249.158473)
			(xy 191.528954 -249.18543) (xy 198.334899 -249.18543) (xy 198.338834 -249.131659) (xy 198.350557 -249.079035)
			(xy 198.369817 -249.028678) (xy 198.396203 -248.981661) (xy 198.429155 -248.938988) (xy 198.467968 -248.901567)
			(xy 198.511816 -248.870197) (xy 198.559764 -248.845545) (xy 198.610791 -248.828137) (xy 198.663809 -248.818344)
			(xy 198.717688 -248.816375) (xy 198.771279 -248.822272) (xy 198.82344 -248.835908) (xy 198.87306 -248.856995)
			(xy 198.919081 -248.885081) (xy 198.960523 -248.919569) (xy 198.996501 -248.959723) (xy 199.026249 -249.004687)
			(xy 199.049134 -249.053504) (xy 199.064666 -249.105133) (xy 199.072516 -249.158473) (xy 199.073008 -249.18543)
			(xy 205.878699 -249.18543) (xy 205.882634 -249.131659) (xy 205.894357 -249.079035) (xy 205.913617 -249.028678)
			(xy 205.940003 -248.981661) (xy 205.972955 -248.938988) (xy 206.011768 -248.901567) (xy 206.055616 -248.870197)
			(xy 206.103564 -248.845545) (xy 206.154591 -248.828137) (xy 206.207609 -248.818344) (xy 206.261488 -248.816375)
			(xy 206.315079 -248.822272) (xy 206.36724 -248.835908) (xy 206.41686 -248.856995) (xy 206.462881 -248.885081)
			(xy 206.504323 -248.919569) (xy 206.540301 -248.959723) (xy 206.570049 -249.004687) (xy 206.592934 -249.053504)
			(xy 206.608466 -249.105133) (xy 206.616316 -249.158473) (xy 206.616808 -249.18543) (xy 206.616316 -249.212387)
			(xy 206.608466 -249.265727) (xy 206.592934 -249.317356) (xy 206.570049 -249.366173) (xy 206.540301 -249.411137)
			(xy 206.504323 -249.451291) (xy 206.462881 -249.485779) (xy 206.41686 -249.513865) (xy 206.36724 -249.534952)
			(xy 206.315079 -249.548588) (xy 206.261488 -249.554485) (xy 206.207609 -249.552516) (xy 206.154591 -249.542723)
			(xy 206.103564 -249.525315) (xy 206.055616 -249.500663) (xy 206.011768 -249.469293) (xy 205.972955 -249.431872)
			(xy 205.940003 -249.389199) (xy 205.913617 -249.342182) (xy 205.894357 -249.291825) (xy 205.882634 -249.239201)
			(xy 205.878699 -249.18543) (xy 199.073008 -249.18543) (xy 199.072516 -249.212387) (xy 199.064666 -249.265727)
			(xy 199.049134 -249.317356) (xy 199.026249 -249.366173) (xy 198.996501 -249.411137) (xy 198.960523 -249.451291)
			(xy 198.919081 -249.485779) (xy 198.87306 -249.513865) (xy 198.82344 -249.534952) (xy 198.771279 -249.548588)
			(xy 198.717688 -249.554485) (xy 198.663809 -249.552516) (xy 198.610791 -249.542723) (xy 198.559764 -249.525315)
			(xy 198.511816 -249.500663) (xy 198.467968 -249.469293) (xy 198.429155 -249.431872) (xy 198.396203 -249.389199)
			(xy 198.369817 -249.342182) (xy 198.350557 -249.291825) (xy 198.338834 -249.239201) (xy 198.334899 -249.18543)
			(xy 191.528954 -249.18543) (xy 191.528462 -249.212387) (xy 191.520612 -249.265727) (xy 191.50508 -249.317356)
			(xy 191.482195 -249.366173) (xy 191.452447 -249.411137) (xy 191.416469 -249.451291) (xy 191.375027 -249.485779)
			(xy 191.329006 -249.513865) (xy 191.279386 -249.534952) (xy 191.227225 -249.548588) (xy 191.173634 -249.554485)
			(xy 191.119755 -249.552516) (xy 191.066737 -249.542723) (xy 191.01571 -249.525315) (xy 190.967762 -249.500663)
			(xy 190.923914 -249.469293) (xy 190.885101 -249.431872) (xy 190.852149 -249.389199) (xy 190.825763 -249.342182)
			(xy 190.806503 -249.291825) (xy 190.79478 -249.239201) (xy 190.790845 -249.18543) (xy 183.9849 -249.18543)
			(xy 183.984408 -249.212387) (xy 183.976558 -249.265727) (xy 183.961026 -249.317356) (xy 183.938141 -249.366173)
			(xy 183.908393 -249.411137) (xy 183.872415 -249.451291) (xy 183.830973 -249.485779) (xy 183.784952 -249.513865)
			(xy 183.735332 -249.534952) (xy 183.683171 -249.548588) (xy 183.62958 -249.554485) (xy 183.575701 -249.552516)
			(xy 183.522683 -249.542723) (xy 183.471656 -249.525315) (xy 183.423708 -249.500663) (xy 183.37986 -249.469293)
			(xy 183.341047 -249.431872) (xy 183.308095 -249.389199) (xy 183.281709 -249.342182) (xy 183.262449 -249.291825)
			(xy 183.250726 -249.239201) (xy 183.246791 -249.18543) (xy 177.881534 -249.18543) (xy 177.881534 -250.035314)
			(xy 179.146723 -250.035314) (xy 179.150658 -249.981543) (xy 179.162381 -249.928919) (xy 179.181641 -249.878562)
			(xy 179.208027 -249.831545) (xy 179.240979 -249.788872) (xy 179.279792 -249.751451) (xy 179.32364 -249.720081)
			(xy 179.371588 -249.695429) (xy 179.422615 -249.678021) (xy 179.475633 -249.668228) (xy 179.529512 -249.666259)
			(xy 179.583103 -249.672156) (xy 179.635264 -249.685792) (xy 179.684884 -249.706879) (xy 179.730905 -249.734965)
			(xy 179.772347 -249.769453) (xy 179.808325 -249.809607) (xy 179.838073 -249.854571) (xy 179.860958 -249.903388)
			(xy 179.87649 -249.955017) (xy 179.88434 -250.008357) (xy 179.884832 -250.035314) (xy 186.690777 -250.035314)
			(xy 186.694712 -249.981543) (xy 186.706435 -249.928919) (xy 186.725695 -249.878562) (xy 186.752081 -249.831545)
			(xy 186.785033 -249.788872) (xy 186.823846 -249.751451) (xy 186.867694 -249.720081) (xy 186.915642 -249.695429)
			(xy 186.966669 -249.678021) (xy 187.019687 -249.668228) (xy 187.073566 -249.666259) (xy 187.127157 -249.672156)
			(xy 187.179318 -249.685792) (xy 187.228938 -249.706879) (xy 187.274959 -249.734965) (xy 187.316401 -249.769453)
			(xy 187.352379 -249.809607) (xy 187.382127 -249.854571) (xy 187.405012 -249.903388) (xy 187.420544 -249.955017)
			(xy 187.428394 -250.008357) (xy 187.428886 -250.035314) (xy 194.234831 -250.035314) (xy 194.238766 -249.981543)
			(xy 194.250489 -249.928919) (xy 194.269749 -249.878562) (xy 194.296135 -249.831545) (xy 194.329087 -249.788872)
			(xy 194.3679 -249.751451) (xy 194.411748 -249.720081) (xy 194.459696 -249.695429) (xy 194.510723 -249.678021)
			(xy 194.563741 -249.668228) (xy 194.61762 -249.666259) (xy 194.671211 -249.672156) (xy 194.723372 -249.685792)
			(xy 194.772992 -249.706879) (xy 194.819013 -249.734965) (xy 194.860455 -249.769453) (xy 194.896433 -249.809607)
			(xy 194.926181 -249.854571) (xy 194.949066 -249.903388) (xy 194.964598 -249.955017) (xy 194.972448 -250.008357)
			(xy 194.97294 -250.035314) (xy 201.778631 -250.035314) (xy 201.782566 -249.981543) (xy 201.794289 -249.928919)
			(xy 201.813549 -249.878562) (xy 201.839935 -249.831545) (xy 201.872887 -249.788872) (xy 201.9117 -249.751451)
			(xy 201.955548 -249.720081) (xy 202.003496 -249.695429) (xy 202.054523 -249.678021) (xy 202.107541 -249.668228)
			(xy 202.16142 -249.666259) (xy 202.215011 -249.672156) (xy 202.267172 -249.685792) (xy 202.316792 -249.706879)
			(xy 202.362813 -249.734965) (xy 202.404255 -249.769453) (xy 202.440233 -249.809607) (xy 202.469981 -249.854571)
			(xy 202.492866 -249.903388) (xy 202.508398 -249.955017) (xy 202.516248 -250.008357) (xy 202.51674 -250.035314)
			(xy 202.516248 -250.062271) (xy 202.508398 -250.115611) (xy 202.492866 -250.16724) (xy 202.469981 -250.216057)
			(xy 202.440233 -250.261021) (xy 202.404255 -250.301175) (xy 202.362813 -250.335663) (xy 202.316792 -250.363749)
			(xy 202.267172 -250.384836) (xy 202.215011 -250.398472) (xy 202.16142 -250.404369) (xy 202.107541 -250.4024)
			(xy 202.054523 -250.392607) (xy 202.003496 -250.375199) (xy 201.955548 -250.350547) (xy 201.9117 -250.319177)
			(xy 201.872887 -250.281756) (xy 201.839935 -250.239083) (xy 201.813549 -250.192066) (xy 201.794289 -250.141709)
			(xy 201.782566 -250.089085) (xy 201.778631 -250.035314) (xy 194.97294 -250.035314) (xy 194.972448 -250.062271)
			(xy 194.964598 -250.115611) (xy 194.949066 -250.16724) (xy 194.926181 -250.216057) (xy 194.896433 -250.261021)
			(xy 194.860455 -250.301175) (xy 194.819013 -250.335663) (xy 194.772992 -250.363749) (xy 194.723372 -250.384836)
			(xy 194.671211 -250.398472) (xy 194.61762 -250.404369) (xy 194.563741 -250.4024) (xy 194.510723 -250.392607)
			(xy 194.459696 -250.375199) (xy 194.411748 -250.350547) (xy 194.3679 -250.319177) (xy 194.329087 -250.281756)
			(xy 194.296135 -250.239083) (xy 194.269749 -250.192066) (xy 194.250489 -250.141709) (xy 194.238766 -250.089085)
			(xy 194.234831 -250.035314) (xy 187.428886 -250.035314) (xy 187.428394 -250.062271) (xy 187.420544 -250.115611)
			(xy 187.405012 -250.16724) (xy 187.382127 -250.216057) (xy 187.352379 -250.261021) (xy 187.316401 -250.301175)
			(xy 187.274959 -250.335663) (xy 187.228938 -250.363749) (xy 187.179318 -250.384836) (xy 187.127157 -250.398472)
			(xy 187.073566 -250.404369) (xy 187.019687 -250.4024) (xy 186.966669 -250.392607) (xy 186.915642 -250.375199)
			(xy 186.867694 -250.350547) (xy 186.823846 -250.319177) (xy 186.785033 -250.281756) (xy 186.752081 -250.239083)
			(xy 186.725695 -250.192066) (xy 186.706435 -250.141709) (xy 186.694712 -250.089085) (xy 186.690777 -250.035314)
			(xy 179.884832 -250.035314) (xy 179.88434 -250.062271) (xy 179.87649 -250.115611) (xy 179.860958 -250.16724)
			(xy 179.838073 -250.216057) (xy 179.808325 -250.261021) (xy 179.772347 -250.301175) (xy 179.730905 -250.335663)
			(xy 179.684884 -250.363749) (xy 179.635264 -250.384836) (xy 179.583103 -250.398472) (xy 179.529512 -250.404369)
			(xy 179.475633 -250.4024) (xy 179.422615 -250.392607) (xy 179.371588 -250.375199) (xy 179.32364 -250.350547)
			(xy 179.279792 -250.319177) (xy 179.240979 -250.281756) (xy 179.208027 -250.239083) (xy 179.181641 -250.192066)
			(xy 179.162381 -250.141709) (xy 179.150658 -250.089085) (xy 179.146723 -250.035314) (xy 177.881534 -250.035314)
			(xy 177.881534 -250.885198) (xy 183.246791 -250.885198) (xy 183.250726 -250.831427) (xy 183.262449 -250.778803)
			(xy 183.281709 -250.728446) (xy 183.308095 -250.681429) (xy 183.341047 -250.638756) (xy 183.37986 -250.601335)
			(xy 183.423708 -250.569965) (xy 183.471656 -250.545313) (xy 183.522683 -250.527905) (xy 183.575701 -250.518112)
			(xy 183.62958 -250.516143) (xy 183.683171 -250.52204) (xy 183.735332 -250.535676) (xy 183.784952 -250.556763)
			(xy 183.830973 -250.584849) (xy 183.872415 -250.619337) (xy 183.908393 -250.659491) (xy 183.938141 -250.704455)
			(xy 183.961026 -250.753272) (xy 183.976558 -250.804901) (xy 183.984408 -250.858241) (xy 183.9849 -250.885198)
			(xy 190.790845 -250.885198) (xy 190.79478 -250.831427) (xy 190.806503 -250.778803) (xy 190.825763 -250.728446)
			(xy 190.852149 -250.681429) (xy 190.885101 -250.638756) (xy 190.923914 -250.601335) (xy 190.967762 -250.569965)
			(xy 191.01571 -250.545313) (xy 191.066737 -250.527905) (xy 191.119755 -250.518112) (xy 191.173634 -250.516143)
			(xy 191.227225 -250.52204) (xy 191.279386 -250.535676) (xy 191.329006 -250.556763) (xy 191.375027 -250.584849)
			(xy 191.416469 -250.619337) (xy 191.452447 -250.659491) (xy 191.482195 -250.704455) (xy 191.50508 -250.753272)
			(xy 191.520612 -250.804901) (xy 191.528462 -250.858241) (xy 191.528954 -250.885198) (xy 198.334899 -250.885198)
			(xy 198.338834 -250.831427) (xy 198.350557 -250.778803) (xy 198.369817 -250.728446) (xy 198.396203 -250.681429)
			(xy 198.429155 -250.638756) (xy 198.467968 -250.601335) (xy 198.511816 -250.569965) (xy 198.559764 -250.545313)
			(xy 198.610791 -250.527905) (xy 198.663809 -250.518112) (xy 198.717688 -250.516143) (xy 198.771279 -250.52204)
			(xy 198.82344 -250.535676) (xy 198.87306 -250.556763) (xy 198.919081 -250.584849) (xy 198.960523 -250.619337)
			(xy 198.996501 -250.659491) (xy 199.026249 -250.704455) (xy 199.049134 -250.753272) (xy 199.064666 -250.804901)
			(xy 199.072516 -250.858241) (xy 199.073008 -250.885198) (xy 205.878699 -250.885198) (xy 205.882634 -250.831427)
			(xy 205.894357 -250.778803) (xy 205.913617 -250.728446) (xy 205.940003 -250.681429) (xy 205.972955 -250.638756)
			(xy 206.011768 -250.601335) (xy 206.055616 -250.569965) (xy 206.103564 -250.545313) (xy 206.154591 -250.527905)
			(xy 206.207609 -250.518112) (xy 206.261488 -250.516143) (xy 206.315079 -250.52204) (xy 206.36724 -250.535676)
			(xy 206.41686 -250.556763) (xy 206.462881 -250.584849) (xy 206.504323 -250.619337) (xy 206.540301 -250.659491)
			(xy 206.570049 -250.704455) (xy 206.592934 -250.753272) (xy 206.608466 -250.804901) (xy 206.616316 -250.858241)
			(xy 206.616808 -250.885198) (xy 206.616316 -250.912155) (xy 206.608466 -250.965495) (xy 206.592934 -251.017124)
			(xy 206.570049 -251.065941) (xy 206.540301 -251.110905) (xy 206.504323 -251.151059) (xy 206.462881 -251.185547)
			(xy 206.41686 -251.213633) (xy 206.36724 -251.23472) (xy 206.315079 -251.248356) (xy 206.261488 -251.254253)
			(xy 206.207609 -251.252284) (xy 206.154591 -251.242491) (xy 206.103564 -251.225083) (xy 206.055616 -251.200431)
			(xy 206.011768 -251.169061) (xy 205.972955 -251.13164) (xy 205.940003 -251.088967) (xy 205.913617 -251.04195)
			(xy 205.894357 -250.991593) (xy 205.882634 -250.938969) (xy 205.878699 -250.885198) (xy 199.073008 -250.885198)
			(xy 199.072516 -250.912155) (xy 199.064666 -250.965495) (xy 199.049134 -251.017124) (xy 199.026249 -251.065941)
			(xy 198.996501 -251.110905) (xy 198.960523 -251.151059) (xy 198.919081 -251.185547) (xy 198.87306 -251.213633)
			(xy 198.82344 -251.23472) (xy 198.771279 -251.248356) (xy 198.717688 -251.254253) (xy 198.663809 -251.252284)
			(xy 198.610791 -251.242491) (xy 198.559764 -251.225083) (xy 198.511816 -251.200431) (xy 198.467968 -251.169061)
			(xy 198.429155 -251.13164) (xy 198.396203 -251.088967) (xy 198.369817 -251.04195) (xy 198.350557 -250.991593)
			(xy 198.338834 -250.938969) (xy 198.334899 -250.885198) (xy 191.528954 -250.885198) (xy 191.528462 -250.912155)
			(xy 191.520612 -250.965495) (xy 191.50508 -251.017124) (xy 191.482195 -251.065941) (xy 191.452447 -251.110905)
			(xy 191.416469 -251.151059) (xy 191.375027 -251.185547) (xy 191.329006 -251.213633) (xy 191.279386 -251.23472)
			(xy 191.227225 -251.248356) (xy 191.173634 -251.254253) (xy 191.119755 -251.252284) (xy 191.066737 -251.242491)
			(xy 191.01571 -251.225083) (xy 190.967762 -251.200431) (xy 190.923914 -251.169061) (xy 190.885101 -251.13164)
			(xy 190.852149 -251.088967) (xy 190.825763 -251.04195) (xy 190.806503 -250.991593) (xy 190.79478 -250.938969)
			(xy 190.790845 -250.885198) (xy 183.9849 -250.885198) (xy 183.984408 -250.912155) (xy 183.976558 -250.965495)
			(xy 183.961026 -251.017124) (xy 183.938141 -251.065941) (xy 183.908393 -251.110905) (xy 183.872415 -251.151059)
			(xy 183.830973 -251.185547) (xy 183.784952 -251.213633) (xy 183.735332 -251.23472) (xy 183.683171 -251.248356)
			(xy 183.62958 -251.254253) (xy 183.575701 -251.252284) (xy 183.522683 -251.242491) (xy 183.471656 -251.225083)
			(xy 183.423708 -251.200431) (xy 183.37986 -251.169061) (xy 183.341047 -251.13164) (xy 183.308095 -251.088967)
			(xy 183.281709 -251.04195) (xy 183.262449 -250.991593) (xy 183.250726 -250.938969) (xy 183.246791 -250.885198)
			(xy 177.881534 -250.885198) (xy 177.881534 -251.735336) (xy 179.146723 -251.735336) (xy 179.150658 -251.681565)
			(xy 179.162381 -251.628941) (xy 179.181641 -251.578584) (xy 179.208027 -251.531567) (xy 179.240979 -251.488894)
			(xy 179.279792 -251.451473) (xy 179.32364 -251.420103) (xy 179.371588 -251.395451) (xy 179.422615 -251.378043)
			(xy 179.475633 -251.36825) (xy 179.529512 -251.366281) (xy 179.583103 -251.372178) (xy 179.635264 -251.385814)
			(xy 179.684884 -251.406901) (xy 179.730905 -251.434987) (xy 179.772347 -251.469475) (xy 179.808325 -251.509629)
			(xy 179.838073 -251.554593) (xy 179.860958 -251.60341) (xy 179.87649 -251.655039) (xy 179.88434 -251.708379)
			(xy 179.884832 -251.735336) (xy 186.690777 -251.735336) (xy 186.694712 -251.681565) (xy 186.706435 -251.628941)
			(xy 186.725695 -251.578584) (xy 186.752081 -251.531567) (xy 186.785033 -251.488894) (xy 186.823846 -251.451473)
			(xy 186.867694 -251.420103) (xy 186.915642 -251.395451) (xy 186.966669 -251.378043) (xy 187.019687 -251.36825)
			(xy 187.073566 -251.366281) (xy 187.127157 -251.372178) (xy 187.179318 -251.385814) (xy 187.228938 -251.406901)
			(xy 187.274959 -251.434987) (xy 187.316401 -251.469475) (xy 187.352379 -251.509629) (xy 187.382127 -251.554593)
			(xy 187.405012 -251.60341) (xy 187.420544 -251.655039) (xy 187.428394 -251.708379) (xy 187.428886 -251.735336)
			(xy 194.234831 -251.735336) (xy 194.238766 -251.681565) (xy 194.250489 -251.628941) (xy 194.269749 -251.578584)
			(xy 194.296135 -251.531567) (xy 194.329087 -251.488894) (xy 194.3679 -251.451473) (xy 194.411748 -251.420103)
			(xy 194.459696 -251.395451) (xy 194.510723 -251.378043) (xy 194.563741 -251.36825) (xy 194.61762 -251.366281)
			(xy 194.671211 -251.372178) (xy 194.723372 -251.385814) (xy 194.772992 -251.406901) (xy 194.819013 -251.434987)
			(xy 194.860455 -251.469475) (xy 194.896433 -251.509629) (xy 194.926181 -251.554593) (xy 194.949066 -251.60341)
			(xy 194.964598 -251.655039) (xy 194.972448 -251.708379) (xy 194.97294 -251.735336) (xy 201.778631 -251.735336)
			(xy 201.782566 -251.681565) (xy 201.794289 -251.628941) (xy 201.813549 -251.578584) (xy 201.839935 -251.531567)
			(xy 201.872887 -251.488894) (xy 201.9117 -251.451473) (xy 201.955548 -251.420103) (xy 202.003496 -251.395451)
			(xy 202.054523 -251.378043) (xy 202.107541 -251.36825) (xy 202.16142 -251.366281) (xy 202.215011 -251.372178)
			(xy 202.267172 -251.385814) (xy 202.316792 -251.406901) (xy 202.362813 -251.434987) (xy 202.404255 -251.469475)
			(xy 202.440233 -251.509629) (xy 202.469981 -251.554593) (xy 202.492866 -251.60341) (xy 202.508398 -251.655039)
			(xy 202.516248 -251.708379) (xy 202.51674 -251.735336) (xy 202.516248 -251.762293) (xy 202.508398 -251.815633)
			(xy 202.492866 -251.867262) (xy 202.469981 -251.916079) (xy 202.440233 -251.961043) (xy 202.404255 -252.001197)
			(xy 202.362813 -252.035685) (xy 202.316792 -252.063771) (xy 202.267172 -252.084858) (xy 202.215011 -252.098494)
			(xy 202.16142 -252.104391) (xy 202.107541 -252.102422) (xy 202.054523 -252.092629) (xy 202.003496 -252.075221)
			(xy 201.955548 -252.050569) (xy 201.9117 -252.019199) (xy 201.872887 -251.981778) (xy 201.839935 -251.939105)
			(xy 201.813549 -251.892088) (xy 201.794289 -251.841731) (xy 201.782566 -251.789107) (xy 201.778631 -251.735336)
			(xy 194.97294 -251.735336) (xy 194.972448 -251.762293) (xy 194.964598 -251.815633) (xy 194.949066 -251.867262)
			(xy 194.926181 -251.916079) (xy 194.896433 -251.961043) (xy 194.860455 -252.001197) (xy 194.819013 -252.035685)
			(xy 194.772992 -252.063771) (xy 194.723372 -252.084858) (xy 194.671211 -252.098494) (xy 194.61762 -252.104391)
			(xy 194.563741 -252.102422) (xy 194.510723 -252.092629) (xy 194.459696 -252.075221) (xy 194.411748 -252.050569)
			(xy 194.3679 -252.019199) (xy 194.329087 -251.981778) (xy 194.296135 -251.939105) (xy 194.269749 -251.892088)
			(xy 194.250489 -251.841731) (xy 194.238766 -251.789107) (xy 194.234831 -251.735336) (xy 187.428886 -251.735336)
			(xy 187.428394 -251.762293) (xy 187.420544 -251.815633) (xy 187.405012 -251.867262) (xy 187.382127 -251.916079)
			(xy 187.352379 -251.961043) (xy 187.316401 -252.001197) (xy 187.274959 -252.035685) (xy 187.228938 -252.063771)
			(xy 187.179318 -252.084858) (xy 187.127157 -252.098494) (xy 187.073566 -252.104391) (xy 187.019687 -252.102422)
			(xy 186.966669 -252.092629) (xy 186.915642 -252.075221) (xy 186.867694 -252.050569) (xy 186.823846 -252.019199)
			(xy 186.785033 -251.981778) (xy 186.752081 -251.939105) (xy 186.725695 -251.892088) (xy 186.706435 -251.841731)
			(xy 186.694712 -251.789107) (xy 186.690777 -251.735336) (xy 179.884832 -251.735336) (xy 179.88434 -251.762293)
			(xy 179.87649 -251.815633) (xy 179.860958 -251.867262) (xy 179.838073 -251.916079) (xy 179.808325 -251.961043)
			(xy 179.772347 -252.001197) (xy 179.730905 -252.035685) (xy 179.684884 -252.063771) (xy 179.635264 -252.084858)
			(xy 179.583103 -252.098494) (xy 179.529512 -252.104391) (xy 179.475633 -252.102422) (xy 179.422615 -252.092629)
			(xy 179.371588 -252.075221) (xy 179.32364 -252.050569) (xy 179.279792 -252.019199) (xy 179.240979 -251.981778)
			(xy 179.208027 -251.939105) (xy 179.181641 -251.892088) (xy 179.162381 -251.841731) (xy 179.150658 -251.789107)
			(xy 179.146723 -251.735336) (xy 177.881534 -251.735336) (xy 177.881534 -252.58522) (xy 183.246791 -252.58522)
			(xy 183.250726 -252.531449) (xy 183.262449 -252.478825) (xy 183.281709 -252.428468) (xy 183.308095 -252.381451)
			(xy 183.341047 -252.338778) (xy 183.37986 -252.301357) (xy 183.423708 -252.269987) (xy 183.471656 -252.245335)
			(xy 183.522683 -252.227927) (xy 183.575701 -252.218134) (xy 183.62958 -252.216165) (xy 183.683171 -252.222062)
			(xy 183.735332 -252.235698) (xy 183.784952 -252.256785) (xy 183.830973 -252.284871) (xy 183.872415 -252.319359)
			(xy 183.908393 -252.359513) (xy 183.938141 -252.404477) (xy 183.961026 -252.453294) (xy 183.976558 -252.504923)
			(xy 183.984408 -252.558263) (xy 183.9849 -252.58522) (xy 190.790845 -252.58522) (xy 190.79478 -252.531449)
			(xy 190.806503 -252.478825) (xy 190.825763 -252.428468) (xy 190.852149 -252.381451) (xy 190.885101 -252.338778)
			(xy 190.923914 -252.301357) (xy 190.967762 -252.269987) (xy 191.01571 -252.245335) (xy 191.066737 -252.227927)
			(xy 191.119755 -252.218134) (xy 191.173634 -252.216165) (xy 191.227225 -252.222062) (xy 191.279386 -252.235698)
			(xy 191.329006 -252.256785) (xy 191.375027 -252.284871) (xy 191.416469 -252.319359) (xy 191.452447 -252.359513)
			(xy 191.482195 -252.404477) (xy 191.50508 -252.453294) (xy 191.520612 -252.504923) (xy 191.528462 -252.558263)
			(xy 191.528954 -252.58522) (xy 198.334899 -252.58522) (xy 198.338834 -252.531449) (xy 198.350557 -252.478825)
			(xy 198.369817 -252.428468) (xy 198.396203 -252.381451) (xy 198.429155 -252.338778) (xy 198.467968 -252.301357)
			(xy 198.511816 -252.269987) (xy 198.559764 -252.245335) (xy 198.610791 -252.227927) (xy 198.663809 -252.218134)
			(xy 198.717688 -252.216165) (xy 198.771279 -252.222062) (xy 198.82344 -252.235698) (xy 198.87306 -252.256785)
			(xy 198.919081 -252.284871) (xy 198.960523 -252.319359) (xy 198.996501 -252.359513) (xy 199.026249 -252.404477)
			(xy 199.049134 -252.453294) (xy 199.064666 -252.504923) (xy 199.072516 -252.558263) (xy 199.073008 -252.58522)
			(xy 205.878699 -252.58522) (xy 205.882634 -252.531449) (xy 205.894357 -252.478825) (xy 205.913617 -252.428468)
			(xy 205.940003 -252.381451) (xy 205.972955 -252.338778) (xy 206.011768 -252.301357) (xy 206.055616 -252.269987)
			(xy 206.103564 -252.245335) (xy 206.154591 -252.227927) (xy 206.207609 -252.218134) (xy 206.261488 -252.216165)
			(xy 206.315079 -252.222062) (xy 206.36724 -252.235698) (xy 206.41686 -252.256785) (xy 206.462881 -252.284871)
			(xy 206.504323 -252.319359) (xy 206.540301 -252.359513) (xy 206.570049 -252.404477) (xy 206.592934 -252.453294)
			(xy 206.608466 -252.504923) (xy 206.616316 -252.558263) (xy 206.616808 -252.58522) (xy 206.616316 -252.612177)
			(xy 206.608466 -252.665517) (xy 206.592934 -252.717146) (xy 206.570049 -252.765963) (xy 206.540301 -252.810927)
			(xy 206.504323 -252.851081) (xy 206.462881 -252.885569) (xy 206.41686 -252.913655) (xy 206.36724 -252.934742)
			(xy 206.315079 -252.948378) (xy 206.261488 -252.954275) (xy 206.207609 -252.952306) (xy 206.154591 -252.942513)
			(xy 206.103564 -252.925105) (xy 206.055616 -252.900453) (xy 206.011768 -252.869083) (xy 205.972955 -252.831662)
			(xy 205.940003 -252.788989) (xy 205.913617 -252.741972) (xy 205.894357 -252.691615) (xy 205.882634 -252.638991)
			(xy 205.878699 -252.58522) (xy 199.073008 -252.58522) (xy 199.072516 -252.612177) (xy 199.064666 -252.665517)
			(xy 199.049134 -252.717146) (xy 199.026249 -252.765963) (xy 198.996501 -252.810927) (xy 198.960523 -252.851081)
			(xy 198.919081 -252.885569) (xy 198.87306 -252.913655) (xy 198.82344 -252.934742) (xy 198.771279 -252.948378)
			(xy 198.717688 -252.954275) (xy 198.663809 -252.952306) (xy 198.610791 -252.942513) (xy 198.559764 -252.925105)
			(xy 198.511816 -252.900453) (xy 198.467968 -252.869083) (xy 198.429155 -252.831662) (xy 198.396203 -252.788989)
			(xy 198.369817 -252.741972) (xy 198.350557 -252.691615) (xy 198.338834 -252.638991) (xy 198.334899 -252.58522)
			(xy 191.528954 -252.58522) (xy 191.528462 -252.612177) (xy 191.520612 -252.665517) (xy 191.50508 -252.717146)
			(xy 191.482195 -252.765963) (xy 191.452447 -252.810927) (xy 191.416469 -252.851081) (xy 191.375027 -252.885569)
			(xy 191.329006 -252.913655) (xy 191.279386 -252.934742) (xy 191.227225 -252.948378) (xy 191.173634 -252.954275)
			(xy 191.119755 -252.952306) (xy 191.066737 -252.942513) (xy 191.01571 -252.925105) (xy 190.967762 -252.900453)
			(xy 190.923914 -252.869083) (xy 190.885101 -252.831662) (xy 190.852149 -252.788989) (xy 190.825763 -252.741972)
			(xy 190.806503 -252.691615) (xy 190.79478 -252.638991) (xy 190.790845 -252.58522) (xy 183.9849 -252.58522)
			(xy 183.984408 -252.612177) (xy 183.976558 -252.665517) (xy 183.961026 -252.717146) (xy 183.938141 -252.765963)
			(xy 183.908393 -252.810927) (xy 183.872415 -252.851081) (xy 183.830973 -252.885569) (xy 183.784952 -252.913655)
			(xy 183.735332 -252.934742) (xy 183.683171 -252.948378) (xy 183.62958 -252.954275) (xy 183.575701 -252.952306)
			(xy 183.522683 -252.942513) (xy 183.471656 -252.925105) (xy 183.423708 -252.900453) (xy 183.37986 -252.869083)
			(xy 183.341047 -252.831662) (xy 183.308095 -252.788989) (xy 183.281709 -252.741972) (xy 183.262449 -252.691615)
			(xy 183.250726 -252.638991) (xy 183.246791 -252.58522) (xy 177.881534 -252.58522) (xy 177.881534 -253.435358)
			(xy 179.146723 -253.435358) (xy 179.150658 -253.381587) (xy 179.162381 -253.328963) (xy 179.181641 -253.278606)
			(xy 179.208027 -253.231589) (xy 179.240979 -253.188916) (xy 179.279792 -253.151495) (xy 179.32364 -253.120125)
			(xy 179.371588 -253.095473) (xy 179.422615 -253.078065) (xy 179.475633 -253.068272) (xy 179.529512 -253.066303)
			(xy 179.583103 -253.0722) (xy 179.635264 -253.085836) (xy 179.684884 -253.106923) (xy 179.730905 -253.135009)
			(xy 179.772347 -253.169497) (xy 179.808325 -253.209651) (xy 179.838073 -253.254615) (xy 179.860958 -253.303432)
			(xy 179.87649 -253.355061) (xy 179.88434 -253.408401) (xy 179.884832 -253.435358) (xy 186.690777 -253.435358)
			(xy 186.694712 -253.381587) (xy 186.706435 -253.328963) (xy 186.725695 -253.278606) (xy 186.752081 -253.231589)
			(xy 186.785033 -253.188916) (xy 186.823846 -253.151495) (xy 186.867694 -253.120125) (xy 186.915642 -253.095473)
			(xy 186.966669 -253.078065) (xy 187.019687 -253.068272) (xy 187.073566 -253.066303) (xy 187.127157 -253.0722)
			(xy 187.179318 -253.085836) (xy 187.228938 -253.106923) (xy 187.274959 -253.135009) (xy 187.316401 -253.169497)
			(xy 187.352379 -253.209651) (xy 187.382127 -253.254615) (xy 187.405012 -253.303432) (xy 187.420544 -253.355061)
			(xy 187.428394 -253.408401) (xy 187.428886 -253.435358) (xy 194.234831 -253.435358) (xy 194.238766 -253.381587)
			(xy 194.250489 -253.328963) (xy 194.269749 -253.278606) (xy 194.296135 -253.231589) (xy 194.329087 -253.188916)
			(xy 194.3679 -253.151495) (xy 194.411748 -253.120125) (xy 194.459696 -253.095473) (xy 194.510723 -253.078065)
			(xy 194.563741 -253.068272) (xy 194.61762 -253.066303) (xy 194.671211 -253.0722) (xy 194.723372 -253.085836)
			(xy 194.772992 -253.106923) (xy 194.819013 -253.135009) (xy 194.860455 -253.169497) (xy 194.896433 -253.209651)
			(xy 194.926181 -253.254615) (xy 194.949066 -253.303432) (xy 194.964598 -253.355061) (xy 194.972448 -253.408401)
			(xy 194.97294 -253.435358) (xy 201.778631 -253.435358) (xy 201.782566 -253.381587) (xy 201.794289 -253.328963)
			(xy 201.813549 -253.278606) (xy 201.839935 -253.231589) (xy 201.872887 -253.188916) (xy 201.9117 -253.151495)
			(xy 201.955548 -253.120125) (xy 202.003496 -253.095473) (xy 202.054523 -253.078065) (xy 202.107541 -253.068272)
			(xy 202.16142 -253.066303) (xy 202.215011 -253.0722) (xy 202.267172 -253.085836) (xy 202.316792 -253.106923)
			(xy 202.362813 -253.135009) (xy 202.404255 -253.169497) (xy 202.440233 -253.209651) (xy 202.469981 -253.254615)
			(xy 202.492866 -253.303432) (xy 202.508398 -253.355061) (xy 202.516248 -253.408401) (xy 202.51674 -253.435358)
			(xy 202.516248 -253.462315) (xy 202.508398 -253.515655) (xy 202.492866 -253.567284) (xy 202.469981 -253.616101)
			(xy 202.440233 -253.661065) (xy 202.404255 -253.701219) (xy 202.362813 -253.735707) (xy 202.316792 -253.763793)
			(xy 202.267172 -253.78488) (xy 202.215011 -253.798516) (xy 202.16142 -253.804413) (xy 202.107541 -253.802444)
			(xy 202.054523 -253.792651) (xy 202.003496 -253.775243) (xy 201.955548 -253.750591) (xy 201.9117 -253.719221)
			(xy 201.872887 -253.6818) (xy 201.839935 -253.639127) (xy 201.813549 -253.59211) (xy 201.794289 -253.541753)
			(xy 201.782566 -253.489129) (xy 201.778631 -253.435358) (xy 194.97294 -253.435358) (xy 194.972448 -253.462315)
			(xy 194.964598 -253.515655) (xy 194.949066 -253.567284) (xy 194.926181 -253.616101) (xy 194.896433 -253.661065)
			(xy 194.860455 -253.701219) (xy 194.819013 -253.735707) (xy 194.772992 -253.763793) (xy 194.723372 -253.78488)
			(xy 194.671211 -253.798516) (xy 194.61762 -253.804413) (xy 194.563741 -253.802444) (xy 194.510723 -253.792651)
			(xy 194.459696 -253.775243) (xy 194.411748 -253.750591) (xy 194.3679 -253.719221) (xy 194.329087 -253.6818)
			(xy 194.296135 -253.639127) (xy 194.269749 -253.59211) (xy 194.250489 -253.541753) (xy 194.238766 -253.489129)
			(xy 194.234831 -253.435358) (xy 187.428886 -253.435358) (xy 187.428394 -253.462315) (xy 187.420544 -253.515655)
			(xy 187.405012 -253.567284) (xy 187.382127 -253.616101) (xy 187.352379 -253.661065) (xy 187.316401 -253.701219)
			(xy 187.274959 -253.735707) (xy 187.228938 -253.763793) (xy 187.179318 -253.78488) (xy 187.127157 -253.798516)
			(xy 187.073566 -253.804413) (xy 187.019687 -253.802444) (xy 186.966669 -253.792651) (xy 186.915642 -253.775243)
			(xy 186.867694 -253.750591) (xy 186.823846 -253.719221) (xy 186.785033 -253.6818) (xy 186.752081 -253.639127)
			(xy 186.725695 -253.59211) (xy 186.706435 -253.541753) (xy 186.694712 -253.489129) (xy 186.690777 -253.435358)
			(xy 179.884832 -253.435358) (xy 179.88434 -253.462315) (xy 179.87649 -253.515655) (xy 179.860958 -253.567284)
			(xy 179.838073 -253.616101) (xy 179.808325 -253.661065) (xy 179.772347 -253.701219) (xy 179.730905 -253.735707)
			(xy 179.684884 -253.763793) (xy 179.635264 -253.78488) (xy 179.583103 -253.798516) (xy 179.529512 -253.804413)
			(xy 179.475633 -253.802444) (xy 179.422615 -253.792651) (xy 179.371588 -253.775243) (xy 179.32364 -253.750591)
			(xy 179.279792 -253.719221) (xy 179.240979 -253.6818) (xy 179.208027 -253.639127) (xy 179.181641 -253.59211)
			(xy 179.162381 -253.541753) (xy 179.150658 -253.489129) (xy 179.146723 -253.435358) (xy 177.881534 -253.435358)
			(xy 177.881534 -254.285242) (xy 179.146723 -254.285242) (xy 179.150658 -254.231471) (xy 179.162381 -254.178847)
			(xy 179.181641 -254.12849) (xy 179.208027 -254.081473) (xy 179.240979 -254.0388) (xy 179.279792 -254.001379)
			(xy 179.32364 -253.970009) (xy 179.371588 -253.945357) (xy 179.422615 -253.927949) (xy 179.475633 -253.918156)
			(xy 179.529512 -253.916187) (xy 179.583103 -253.922084) (xy 179.635264 -253.93572) (xy 179.684884 -253.956807)
			(xy 179.730905 -253.984893) (xy 179.772347 -254.019381) (xy 179.808325 -254.059535) (xy 179.838073 -254.104499)
			(xy 179.860958 -254.153316) (xy 179.87649 -254.204945) (xy 179.88434 -254.258285) (xy 179.884832 -254.285242)
			(xy 183.246791 -254.285242) (xy 183.250726 -254.231471) (xy 183.262449 -254.178847) (xy 183.281709 -254.12849)
			(xy 183.308095 -254.081473) (xy 183.341047 -254.0388) (xy 183.37986 -254.001379) (xy 183.423708 -253.970009)
			(xy 183.471656 -253.945357) (xy 183.522683 -253.927949) (xy 183.575701 -253.918156) (xy 183.62958 -253.916187)
			(xy 183.683171 -253.922084) (xy 183.735332 -253.93572) (xy 183.784952 -253.956807) (xy 183.830973 -253.984893)
			(xy 183.872415 -254.019381) (xy 183.908393 -254.059535) (xy 183.938141 -254.104499) (xy 183.961026 -254.153316)
			(xy 183.976558 -254.204945) (xy 183.984408 -254.258285) (xy 183.9849 -254.285242) (xy 186.690777 -254.285242)
			(xy 186.694712 -254.231471) (xy 186.706435 -254.178847) (xy 186.725695 -254.12849) (xy 186.752081 -254.081473)
			(xy 186.785033 -254.0388) (xy 186.823846 -254.001379) (xy 186.867694 -253.970009) (xy 186.915642 -253.945357)
			(xy 186.966669 -253.927949) (xy 187.019687 -253.918156) (xy 187.073566 -253.916187) (xy 187.127157 -253.922084)
			(xy 187.179318 -253.93572) (xy 187.228938 -253.956807) (xy 187.274959 -253.984893) (xy 187.316401 -254.019381)
			(xy 187.352379 -254.059535) (xy 187.382127 -254.104499) (xy 187.405012 -254.153316) (xy 187.420544 -254.204945)
			(xy 187.428394 -254.258285) (xy 187.428886 -254.285242) (xy 190.790845 -254.285242) (xy 190.79478 -254.231471)
			(xy 190.806503 -254.178847) (xy 190.825763 -254.12849) (xy 190.852149 -254.081473) (xy 190.885101 -254.0388)
			(xy 190.923914 -254.001379) (xy 190.967762 -253.970009) (xy 191.01571 -253.945357) (xy 191.066737 -253.927949)
			(xy 191.119755 -253.918156) (xy 191.173634 -253.916187) (xy 191.227225 -253.922084) (xy 191.279386 -253.93572)
			(xy 191.329006 -253.956807) (xy 191.375027 -253.984893) (xy 191.416469 -254.019381) (xy 191.452447 -254.059535)
			(xy 191.482195 -254.104499) (xy 191.50508 -254.153316) (xy 191.520612 -254.204945) (xy 191.528462 -254.258285)
			(xy 191.528954 -254.285242) (xy 194.234831 -254.285242) (xy 194.238766 -254.231471) (xy 194.250489 -254.178847)
			(xy 194.269749 -254.12849) (xy 194.296135 -254.081473) (xy 194.329087 -254.0388) (xy 194.3679 -254.001379)
			(xy 194.411748 -253.970009) (xy 194.459696 -253.945357) (xy 194.510723 -253.927949) (xy 194.563741 -253.918156)
			(xy 194.61762 -253.916187) (xy 194.671211 -253.922084) (xy 194.723372 -253.93572) (xy 194.772992 -253.956807)
			(xy 194.819013 -253.984893) (xy 194.860455 -254.019381) (xy 194.896433 -254.059535) (xy 194.926181 -254.104499)
			(xy 194.949066 -254.153316) (xy 194.964598 -254.204945) (xy 194.972448 -254.258285) (xy 194.97294 -254.285242)
			(xy 198.334899 -254.285242) (xy 198.338834 -254.231471) (xy 198.350557 -254.178847) (xy 198.369817 -254.12849)
			(xy 198.396203 -254.081473) (xy 198.429155 -254.0388) (xy 198.467968 -254.001379) (xy 198.511816 -253.970009)
			(xy 198.559764 -253.945357) (xy 198.610791 -253.927949) (xy 198.663809 -253.918156) (xy 198.717688 -253.916187)
			(xy 198.771279 -253.922084) (xy 198.82344 -253.93572) (xy 198.87306 -253.956807) (xy 198.919081 -253.984893)
			(xy 198.960523 -254.019381) (xy 198.996501 -254.059535) (xy 199.026249 -254.104499) (xy 199.049134 -254.153316)
			(xy 199.064666 -254.204945) (xy 199.072516 -254.258285) (xy 199.073008 -254.285242) (xy 201.778631 -254.285242)
			(xy 201.782566 -254.231471) (xy 201.794289 -254.178847) (xy 201.813549 -254.12849) (xy 201.839935 -254.081473)
			(xy 201.872887 -254.0388) (xy 201.9117 -254.001379) (xy 201.955548 -253.970009) (xy 202.003496 -253.945357)
			(xy 202.054523 -253.927949) (xy 202.107541 -253.918156) (xy 202.16142 -253.916187) (xy 202.215011 -253.922084)
			(xy 202.267172 -253.93572) (xy 202.316792 -253.956807) (xy 202.362813 -253.984893) (xy 202.404255 -254.019381)
			(xy 202.440233 -254.059535) (xy 202.469981 -254.104499) (xy 202.492866 -254.153316) (xy 202.508398 -254.204945)
			(xy 202.516248 -254.258285) (xy 202.51674 -254.285242) (xy 205.878699 -254.285242) (xy 205.882634 -254.231471)
			(xy 205.894357 -254.178847) (xy 205.913617 -254.12849) (xy 205.940003 -254.081473) (xy 205.972955 -254.0388)
			(xy 206.011768 -254.001379) (xy 206.055616 -253.970009) (xy 206.103564 -253.945357) (xy 206.154591 -253.927949)
			(xy 206.207609 -253.918156) (xy 206.261488 -253.916187) (xy 206.315079 -253.922084) (xy 206.36724 -253.93572)
			(xy 206.41686 -253.956807) (xy 206.462881 -253.984893) (xy 206.504323 -254.019381) (xy 206.540301 -254.059535)
			(xy 206.570049 -254.104499) (xy 206.592934 -254.153316) (xy 206.608466 -254.204945) (xy 206.616316 -254.258285)
			(xy 206.616808 -254.285242) (xy 206.616316 -254.312199) (xy 206.608466 -254.365539) (xy 206.592934 -254.417168)
			(xy 206.570049 -254.465985) (xy 206.540301 -254.510949) (xy 206.504323 -254.551103) (xy 206.462881 -254.585591)
			(xy 206.41686 -254.613677) (xy 206.36724 -254.634764) (xy 206.315079 -254.6484) (xy 206.261488 -254.654297)
			(xy 206.207609 -254.652328) (xy 206.154591 -254.642535) (xy 206.103564 -254.625127) (xy 206.055616 -254.600475)
			(xy 206.011768 -254.569105) (xy 205.972955 -254.531684) (xy 205.940003 -254.489011) (xy 205.913617 -254.441994)
			(xy 205.894357 -254.391637) (xy 205.882634 -254.339013) (xy 205.878699 -254.285242) (xy 202.51674 -254.285242)
			(xy 202.516248 -254.312199) (xy 202.508398 -254.365539) (xy 202.492866 -254.417168) (xy 202.469981 -254.465985)
			(xy 202.440233 -254.510949) (xy 202.404255 -254.551103) (xy 202.362813 -254.585591) (xy 202.316792 -254.613677)
			(xy 202.267172 -254.634764) (xy 202.215011 -254.6484) (xy 202.16142 -254.654297) (xy 202.107541 -254.652328)
			(xy 202.054523 -254.642535) (xy 202.003496 -254.625127) (xy 201.955548 -254.600475) (xy 201.9117 -254.569105)
			(xy 201.872887 -254.531684) (xy 201.839935 -254.489011) (xy 201.813549 -254.441994) (xy 201.794289 -254.391637)
			(xy 201.782566 -254.339013) (xy 201.778631 -254.285242) (xy 199.073008 -254.285242) (xy 199.072516 -254.312199)
			(xy 199.064666 -254.365539) (xy 199.049134 -254.417168) (xy 199.026249 -254.465985) (xy 198.996501 -254.510949)
			(xy 198.960523 -254.551103) (xy 198.919081 -254.585591) (xy 198.87306 -254.613677) (xy 198.82344 -254.634764)
			(xy 198.771279 -254.6484) (xy 198.717688 -254.654297) (xy 198.663809 -254.652328) (xy 198.610791 -254.642535)
			(xy 198.559764 -254.625127) (xy 198.511816 -254.600475) (xy 198.467968 -254.569105) (xy 198.429155 -254.531684)
			(xy 198.396203 -254.489011) (xy 198.369817 -254.441994) (xy 198.350557 -254.391637) (xy 198.338834 -254.339013)
			(xy 198.334899 -254.285242) (xy 194.97294 -254.285242) (xy 194.972448 -254.312199) (xy 194.964598 -254.365539)
			(xy 194.949066 -254.417168) (xy 194.926181 -254.465985) (xy 194.896433 -254.510949) (xy 194.860455 -254.551103)
			(xy 194.819013 -254.585591) (xy 194.772992 -254.613677) (xy 194.723372 -254.634764) (xy 194.671211 -254.6484)
			(xy 194.61762 -254.654297) (xy 194.563741 -254.652328) (xy 194.510723 -254.642535) (xy 194.459696 -254.625127)
			(xy 194.411748 -254.600475) (xy 194.3679 -254.569105) (xy 194.329087 -254.531684) (xy 194.296135 -254.489011)
			(xy 194.269749 -254.441994) (xy 194.250489 -254.391637) (xy 194.238766 -254.339013) (xy 194.234831 -254.285242)
			(xy 191.528954 -254.285242) (xy 191.528462 -254.312199) (xy 191.520612 -254.365539) (xy 191.50508 -254.417168)
			(xy 191.482195 -254.465985) (xy 191.452447 -254.510949) (xy 191.416469 -254.551103) (xy 191.375027 -254.585591)
			(xy 191.329006 -254.613677) (xy 191.279386 -254.634764) (xy 191.227225 -254.6484) (xy 191.173634 -254.654297)
			(xy 191.119755 -254.652328) (xy 191.066737 -254.642535) (xy 191.01571 -254.625127) (xy 190.967762 -254.600475)
			(xy 190.923914 -254.569105) (xy 190.885101 -254.531684) (xy 190.852149 -254.489011) (xy 190.825763 -254.441994)
			(xy 190.806503 -254.391637) (xy 190.79478 -254.339013) (xy 190.790845 -254.285242) (xy 187.428886 -254.285242)
			(xy 187.428394 -254.312199) (xy 187.420544 -254.365539) (xy 187.405012 -254.417168) (xy 187.382127 -254.465985)
			(xy 187.352379 -254.510949) (xy 187.316401 -254.551103) (xy 187.274959 -254.585591) (xy 187.228938 -254.613677)
			(xy 187.179318 -254.634764) (xy 187.127157 -254.6484) (xy 187.073566 -254.654297) (xy 187.019687 -254.652328)
			(xy 186.966669 -254.642535) (xy 186.915642 -254.625127) (xy 186.867694 -254.600475) (xy 186.823846 -254.569105)
			(xy 186.785033 -254.531684) (xy 186.752081 -254.489011) (xy 186.725695 -254.441994) (xy 186.706435 -254.391637)
			(xy 186.694712 -254.339013) (xy 186.690777 -254.285242) (xy 183.9849 -254.285242) (xy 183.984408 -254.312199)
			(xy 183.976558 -254.365539) (xy 183.961026 -254.417168) (xy 183.938141 -254.465985) (xy 183.908393 -254.510949)
			(xy 183.872415 -254.551103) (xy 183.830973 -254.585591) (xy 183.784952 -254.613677) (xy 183.735332 -254.634764)
			(xy 183.683171 -254.6484) (xy 183.62958 -254.654297) (xy 183.575701 -254.652328) (xy 183.522683 -254.642535)
			(xy 183.471656 -254.625127) (xy 183.423708 -254.600475) (xy 183.37986 -254.569105) (xy 183.341047 -254.531684)
			(xy 183.308095 -254.489011) (xy 183.281709 -254.441994) (xy 183.262449 -254.391637) (xy 183.250726 -254.339013)
			(xy 183.246791 -254.285242) (xy 179.884832 -254.285242) (xy 179.88434 -254.312199) (xy 179.87649 -254.365539)
			(xy 179.860958 -254.417168) (xy 179.838073 -254.465985) (xy 179.808325 -254.510949) (xy 179.772347 -254.551103)
			(xy 179.730905 -254.585591) (xy 179.684884 -254.613677) (xy 179.635264 -254.634764) (xy 179.583103 -254.6484)
			(xy 179.529512 -254.654297) (xy 179.475633 -254.652328) (xy 179.422615 -254.642535) (xy 179.371588 -254.625127)
			(xy 179.32364 -254.600475) (xy 179.279792 -254.569105) (xy 179.240979 -254.531684) (xy 179.208027 -254.489011)
			(xy 179.181641 -254.441994) (xy 179.162381 -254.391637) (xy 179.150658 -254.339013) (xy 179.146723 -254.285242)
			(xy 177.881534 -254.285242) (xy 177.881534 -261.08533) (xy 183.246791 -261.08533) (xy 183.250726 -261.031559)
			(xy 183.262449 -260.978935) (xy 183.281709 -260.928578) (xy 183.308095 -260.881561) (xy 183.341047 -260.838888)
			(xy 183.37986 -260.801467) (xy 183.423708 -260.770097) (xy 183.471656 -260.745445) (xy 183.522683 -260.728037)
			(xy 183.575701 -260.718244) (xy 183.62958 -260.716275) (xy 183.683171 -260.722172) (xy 183.735332 -260.735808)
			(xy 183.784952 -260.756895) (xy 183.830973 -260.784981) (xy 183.872415 -260.819469) (xy 183.908393 -260.859623)
			(xy 183.938141 -260.904587) (xy 183.961026 -260.953404) (xy 183.976558 -261.005033) (xy 183.984408 -261.058373)
			(xy 183.9849 -261.08533) (xy 190.790845 -261.08533) (xy 190.79478 -261.031559) (xy 190.806503 -260.978935)
			(xy 190.825763 -260.928578) (xy 190.852149 -260.881561) (xy 190.885101 -260.838888) (xy 190.923914 -260.801467)
			(xy 190.967762 -260.770097) (xy 191.01571 -260.745445) (xy 191.066737 -260.728037) (xy 191.119755 -260.718244)
			(xy 191.173634 -260.716275) (xy 191.227225 -260.722172) (xy 191.279386 -260.735808) (xy 191.329006 -260.756895)
			(xy 191.375027 -260.784981) (xy 191.416469 -260.819469) (xy 191.452447 -260.859623) (xy 191.482195 -260.904587)
			(xy 191.50508 -260.953404) (xy 191.520612 -261.005033) (xy 191.528462 -261.058373) (xy 191.528954 -261.08533)
			(xy 198.334899 -261.08533) (xy 198.338834 -261.031559) (xy 198.350557 -260.978935) (xy 198.369817 -260.928578)
			(xy 198.396203 -260.881561) (xy 198.429155 -260.838888) (xy 198.467968 -260.801467) (xy 198.511816 -260.770097)
			(xy 198.559764 -260.745445) (xy 198.610791 -260.728037) (xy 198.663809 -260.718244) (xy 198.717688 -260.716275)
			(xy 198.771279 -260.722172) (xy 198.82344 -260.735808) (xy 198.87306 -260.756895) (xy 198.919081 -260.784981)
			(xy 198.960523 -260.819469) (xy 198.996501 -260.859623) (xy 199.026249 -260.904587) (xy 199.049134 -260.953404)
			(xy 199.064666 -261.005033) (xy 199.072516 -261.058373) (xy 199.073008 -261.08533) (xy 205.878699 -261.08533)
			(xy 205.882634 -261.031559) (xy 205.894357 -260.978935) (xy 205.913617 -260.928578) (xy 205.940003 -260.881561)
			(xy 205.972955 -260.838888) (xy 206.011768 -260.801467) (xy 206.055616 -260.770097) (xy 206.103564 -260.745445)
			(xy 206.154591 -260.728037) (xy 206.207609 -260.718244) (xy 206.261488 -260.716275) (xy 206.315079 -260.722172)
			(xy 206.36724 -260.735808) (xy 206.41686 -260.756895) (xy 206.462881 -260.784981) (xy 206.504323 -260.819469)
			(xy 206.540301 -260.859623) (xy 206.570049 -260.904587) (xy 206.592934 -260.953404) (xy 206.608466 -261.005033)
			(xy 206.616316 -261.058373) (xy 206.616808 -261.08533) (xy 206.616316 -261.112287) (xy 206.608466 -261.165627)
			(xy 206.592934 -261.217256) (xy 206.570049 -261.266073) (xy 206.540301 -261.311037) (xy 206.504323 -261.351191)
			(xy 206.462881 -261.385679) (xy 206.41686 -261.413765) (xy 206.36724 -261.434852) (xy 206.315079 -261.448488)
			(xy 206.261488 -261.454385) (xy 206.207609 -261.452416) (xy 206.154591 -261.442623) (xy 206.103564 -261.425215)
			(xy 206.055616 -261.400563) (xy 206.011768 -261.369193) (xy 205.972955 -261.331772) (xy 205.940003 -261.289099)
			(xy 205.913617 -261.242082) (xy 205.894357 -261.191725) (xy 205.882634 -261.139101) (xy 205.878699 -261.08533)
			(xy 199.073008 -261.08533) (xy 199.072516 -261.112287) (xy 199.064666 -261.165627) (xy 199.049134 -261.217256)
			(xy 199.026249 -261.266073) (xy 198.996501 -261.311037) (xy 198.960523 -261.351191) (xy 198.919081 -261.385679)
			(xy 198.87306 -261.413765) (xy 198.82344 -261.434852) (xy 198.771279 -261.448488) (xy 198.717688 -261.454385)
			(xy 198.663809 -261.452416) (xy 198.610791 -261.442623) (xy 198.559764 -261.425215) (xy 198.511816 -261.400563)
			(xy 198.467968 -261.369193) (xy 198.429155 -261.331772) (xy 198.396203 -261.289099) (xy 198.369817 -261.242082)
			(xy 198.350557 -261.191725) (xy 198.338834 -261.139101) (xy 198.334899 -261.08533) (xy 191.528954 -261.08533)
			(xy 191.528462 -261.112287) (xy 191.520612 -261.165627) (xy 191.50508 -261.217256) (xy 191.482195 -261.266073)
			(xy 191.452447 -261.311037) (xy 191.416469 -261.351191) (xy 191.375027 -261.385679) (xy 191.329006 -261.413765)
			(xy 191.279386 -261.434852) (xy 191.227225 -261.448488) (xy 191.173634 -261.454385) (xy 191.119755 -261.452416)
			(xy 191.066737 -261.442623) (xy 191.01571 -261.425215) (xy 190.967762 -261.400563) (xy 190.923914 -261.369193)
			(xy 190.885101 -261.331772) (xy 190.852149 -261.289099) (xy 190.825763 -261.242082) (xy 190.806503 -261.191725)
			(xy 190.79478 -261.139101) (xy 190.790845 -261.08533) (xy 183.9849 -261.08533) (xy 183.984408 -261.112287)
			(xy 183.976558 -261.165627) (xy 183.961026 -261.217256) (xy 183.938141 -261.266073) (xy 183.908393 -261.311037)
			(xy 183.872415 -261.351191) (xy 183.830973 -261.385679) (xy 183.784952 -261.413765) (xy 183.735332 -261.434852)
			(xy 183.683171 -261.448488) (xy 183.62958 -261.454385) (xy 183.575701 -261.452416) (xy 183.522683 -261.442623)
			(xy 183.471656 -261.425215) (xy 183.423708 -261.400563) (xy 183.37986 -261.369193) (xy 183.341047 -261.331772)
			(xy 183.308095 -261.289099) (xy 183.281709 -261.242082) (xy 183.262449 -261.191725) (xy 183.250726 -261.139101)
			(xy 183.246791 -261.08533) (xy 177.881534 -261.08533) (xy 177.881534 -261.935214) (xy 179.146723 -261.935214)
			(xy 179.150658 -261.881443) (xy 179.162381 -261.828819) (xy 179.181641 -261.778462) (xy 179.208027 -261.731445)
			(xy 179.240979 -261.688772) (xy 179.279792 -261.651351) (xy 179.32364 -261.619981) (xy 179.371588 -261.595329)
			(xy 179.422615 -261.577921) (xy 179.475633 -261.568128) (xy 179.529512 -261.566159) (xy 179.583103 -261.572056)
			(xy 179.635264 -261.585692) (xy 179.684884 -261.606779) (xy 179.730905 -261.634865) (xy 179.772347 -261.669353)
			(xy 179.808325 -261.709507) (xy 179.838073 -261.754471) (xy 179.860958 -261.803288) (xy 179.87649 -261.854917)
			(xy 179.88434 -261.908257) (xy 179.884832 -261.935214) (xy 186.690777 -261.935214) (xy 186.694712 -261.881443)
			(xy 186.706435 -261.828819) (xy 186.725695 -261.778462) (xy 186.752081 -261.731445) (xy 186.785033 -261.688772)
			(xy 186.823846 -261.651351) (xy 186.867694 -261.619981) (xy 186.915642 -261.595329) (xy 186.966669 -261.577921)
			(xy 187.019687 -261.568128) (xy 187.073566 -261.566159) (xy 187.127157 -261.572056) (xy 187.179318 -261.585692)
			(xy 187.228938 -261.606779) (xy 187.274959 -261.634865) (xy 187.316401 -261.669353) (xy 187.352379 -261.709507)
			(xy 187.382127 -261.754471) (xy 187.405012 -261.803288) (xy 187.420544 -261.854917) (xy 187.428394 -261.908257)
			(xy 187.428886 -261.935214) (xy 194.234831 -261.935214) (xy 194.238766 -261.881443) (xy 194.250489 -261.828819)
			(xy 194.269749 -261.778462) (xy 194.296135 -261.731445) (xy 194.329087 -261.688772) (xy 194.3679 -261.651351)
			(xy 194.411748 -261.619981) (xy 194.459696 -261.595329) (xy 194.510723 -261.577921) (xy 194.563741 -261.568128)
			(xy 194.61762 -261.566159) (xy 194.671211 -261.572056) (xy 194.723372 -261.585692) (xy 194.772992 -261.606779)
			(xy 194.819013 -261.634865) (xy 194.860455 -261.669353) (xy 194.896433 -261.709507) (xy 194.926181 -261.754471)
			(xy 194.949066 -261.803288) (xy 194.964598 -261.854917) (xy 194.972448 -261.908257) (xy 194.97294 -261.935214)
			(xy 201.778631 -261.935214) (xy 201.782566 -261.881443) (xy 201.794289 -261.828819) (xy 201.813549 -261.778462)
			(xy 201.839935 -261.731445) (xy 201.872887 -261.688772) (xy 201.9117 -261.651351) (xy 201.955548 -261.619981)
			(xy 202.003496 -261.595329) (xy 202.054523 -261.577921) (xy 202.107541 -261.568128) (xy 202.16142 -261.566159)
			(xy 202.215011 -261.572056) (xy 202.267172 -261.585692) (xy 202.316792 -261.606779) (xy 202.362813 -261.634865)
			(xy 202.404255 -261.669353) (xy 202.440233 -261.709507) (xy 202.469981 -261.754471) (xy 202.492866 -261.803288)
			(xy 202.508398 -261.854917) (xy 202.516248 -261.908257) (xy 202.51674 -261.935214) (xy 202.516248 -261.962171)
			(xy 202.508398 -262.015511) (xy 202.492866 -262.06714) (xy 202.469981 -262.115957) (xy 202.440233 -262.160921)
			(xy 202.404255 -262.201075) (xy 202.362813 -262.235563) (xy 202.316792 -262.263649) (xy 202.267172 -262.284736)
			(xy 202.215011 -262.298372) (xy 202.16142 -262.304269) (xy 202.107541 -262.3023) (xy 202.054523 -262.292507)
			(xy 202.003496 -262.275099) (xy 201.955548 -262.250447) (xy 201.9117 -262.219077) (xy 201.872887 -262.181656)
			(xy 201.839935 -262.138983) (xy 201.813549 -262.091966) (xy 201.794289 -262.041609) (xy 201.782566 -261.988985)
			(xy 201.778631 -261.935214) (xy 194.97294 -261.935214) (xy 194.972448 -261.962171) (xy 194.964598 -262.015511)
			(xy 194.949066 -262.06714) (xy 194.926181 -262.115957) (xy 194.896433 -262.160921) (xy 194.860455 -262.201075)
			(xy 194.819013 -262.235563) (xy 194.772992 -262.263649) (xy 194.723372 -262.284736) (xy 194.671211 -262.298372)
			(xy 194.61762 -262.304269) (xy 194.563741 -262.3023) (xy 194.510723 -262.292507) (xy 194.459696 -262.275099)
			(xy 194.411748 -262.250447) (xy 194.3679 -262.219077) (xy 194.329087 -262.181656) (xy 194.296135 -262.138983)
			(xy 194.269749 -262.091966) (xy 194.250489 -262.041609) (xy 194.238766 -261.988985) (xy 194.234831 -261.935214)
			(xy 187.428886 -261.935214) (xy 187.428394 -261.962171) (xy 187.420544 -262.015511) (xy 187.405012 -262.06714)
			(xy 187.382127 -262.115957) (xy 187.352379 -262.160921) (xy 187.316401 -262.201075) (xy 187.274959 -262.235563)
			(xy 187.228938 -262.263649) (xy 187.179318 -262.284736) (xy 187.127157 -262.298372) (xy 187.073566 -262.304269)
			(xy 187.019687 -262.3023) (xy 186.966669 -262.292507) (xy 186.915642 -262.275099) (xy 186.867694 -262.250447)
			(xy 186.823846 -262.219077) (xy 186.785033 -262.181656) (xy 186.752081 -262.138983) (xy 186.725695 -262.091966)
			(xy 186.706435 -262.041609) (xy 186.694712 -261.988985) (xy 186.690777 -261.935214) (xy 179.884832 -261.935214)
			(xy 179.88434 -261.962171) (xy 179.87649 -262.015511) (xy 179.860958 -262.06714) (xy 179.838073 -262.115957)
			(xy 179.808325 -262.160921) (xy 179.772347 -262.201075) (xy 179.730905 -262.235563) (xy 179.684884 -262.263649)
			(xy 179.635264 -262.284736) (xy 179.583103 -262.298372) (xy 179.529512 -262.304269) (xy 179.475633 -262.3023)
			(xy 179.422615 -262.292507) (xy 179.371588 -262.275099) (xy 179.32364 -262.250447) (xy 179.279792 -262.219077)
			(xy 179.240979 -262.181656) (xy 179.208027 -262.138983) (xy 179.181641 -262.091966) (xy 179.162381 -262.041609)
			(xy 179.150658 -261.988985) (xy 179.146723 -261.935214) (xy 177.881534 -261.935214) (xy 177.881534 -262.785352)
			(xy 183.246791 -262.785352) (xy 183.250726 -262.731581) (xy 183.262449 -262.678957) (xy 183.281709 -262.6286)
			(xy 183.308095 -262.581583) (xy 183.341047 -262.53891) (xy 183.37986 -262.501489) (xy 183.423708 -262.470119)
			(xy 183.471656 -262.445467) (xy 183.522683 -262.428059) (xy 183.575701 -262.418266) (xy 183.62958 -262.416297)
			(xy 183.683171 -262.422194) (xy 183.735332 -262.43583) (xy 183.784952 -262.456917) (xy 183.830973 -262.485003)
			(xy 183.872415 -262.519491) (xy 183.908393 -262.559645) (xy 183.938141 -262.604609) (xy 183.961026 -262.653426)
			(xy 183.976558 -262.705055) (xy 183.984408 -262.758395) (xy 183.9849 -262.785352) (xy 190.790845 -262.785352)
			(xy 190.79478 -262.731581) (xy 190.806503 -262.678957) (xy 190.825763 -262.6286) (xy 190.852149 -262.581583)
			(xy 190.885101 -262.53891) (xy 190.923914 -262.501489) (xy 190.967762 -262.470119) (xy 191.01571 -262.445467)
			(xy 191.066737 -262.428059) (xy 191.119755 -262.418266) (xy 191.173634 -262.416297) (xy 191.227225 -262.422194)
			(xy 191.279386 -262.43583) (xy 191.329006 -262.456917) (xy 191.375027 -262.485003) (xy 191.416469 -262.519491)
			(xy 191.452447 -262.559645) (xy 191.482195 -262.604609) (xy 191.50508 -262.653426) (xy 191.520612 -262.705055)
			(xy 191.528462 -262.758395) (xy 191.528954 -262.785352) (xy 198.334899 -262.785352) (xy 198.338834 -262.731581)
			(xy 198.350557 -262.678957) (xy 198.369817 -262.6286) (xy 198.396203 -262.581583) (xy 198.429155 -262.53891)
			(xy 198.467968 -262.501489) (xy 198.511816 -262.470119) (xy 198.559764 -262.445467) (xy 198.610791 -262.428059)
			(xy 198.663809 -262.418266) (xy 198.717688 -262.416297) (xy 198.771279 -262.422194) (xy 198.82344 -262.43583)
			(xy 198.87306 -262.456917) (xy 198.919081 -262.485003) (xy 198.960523 -262.519491) (xy 198.996501 -262.559645)
			(xy 199.026249 -262.604609) (xy 199.049134 -262.653426) (xy 199.064666 -262.705055) (xy 199.072516 -262.758395)
			(xy 199.073008 -262.785352) (xy 205.878699 -262.785352) (xy 205.882634 -262.731581) (xy 205.894357 -262.678957)
			(xy 205.913617 -262.6286) (xy 205.940003 -262.581583) (xy 205.972955 -262.53891) (xy 206.011768 -262.501489)
			(xy 206.055616 -262.470119) (xy 206.103564 -262.445467) (xy 206.154591 -262.428059) (xy 206.207609 -262.418266)
			(xy 206.261488 -262.416297) (xy 206.315079 -262.422194) (xy 206.36724 -262.43583) (xy 206.41686 -262.456917)
			(xy 206.462881 -262.485003) (xy 206.504323 -262.519491) (xy 206.540301 -262.559645) (xy 206.570049 -262.604609)
			(xy 206.592934 -262.653426) (xy 206.608466 -262.705055) (xy 206.616316 -262.758395) (xy 206.616808 -262.785352)
			(xy 206.616316 -262.812309) (xy 206.608466 -262.865649) (xy 206.592934 -262.917278) (xy 206.570049 -262.966095)
			(xy 206.540301 -263.011059) (xy 206.504323 -263.051213) (xy 206.462881 -263.085701) (xy 206.41686 -263.113787)
			(xy 206.36724 -263.134874) (xy 206.315079 -263.14851) (xy 206.261488 -263.154407) (xy 206.207609 -263.152438)
			(xy 206.154591 -263.142645) (xy 206.103564 -263.125237) (xy 206.055616 -263.100585) (xy 206.011768 -263.069215)
			(xy 205.972955 -263.031794) (xy 205.940003 -262.989121) (xy 205.913617 -262.942104) (xy 205.894357 -262.891747)
			(xy 205.882634 -262.839123) (xy 205.878699 -262.785352) (xy 199.073008 -262.785352) (xy 199.072516 -262.812309)
			(xy 199.064666 -262.865649) (xy 199.049134 -262.917278) (xy 199.026249 -262.966095) (xy 198.996501 -263.011059)
			(xy 198.960523 -263.051213) (xy 198.919081 -263.085701) (xy 198.87306 -263.113787) (xy 198.82344 -263.134874)
			(xy 198.771279 -263.14851) (xy 198.717688 -263.154407) (xy 198.663809 -263.152438) (xy 198.610791 -263.142645)
			(xy 198.559764 -263.125237) (xy 198.511816 -263.100585) (xy 198.467968 -263.069215) (xy 198.429155 -263.031794)
			(xy 198.396203 -262.989121) (xy 198.369817 -262.942104) (xy 198.350557 -262.891747) (xy 198.338834 -262.839123)
			(xy 198.334899 -262.785352) (xy 191.528954 -262.785352) (xy 191.528462 -262.812309) (xy 191.520612 -262.865649)
			(xy 191.50508 -262.917278) (xy 191.482195 -262.966095) (xy 191.452447 -263.011059) (xy 191.416469 -263.051213)
			(xy 191.375027 -263.085701) (xy 191.329006 -263.113787) (xy 191.279386 -263.134874) (xy 191.227225 -263.14851)
			(xy 191.173634 -263.154407) (xy 191.119755 -263.152438) (xy 191.066737 -263.142645) (xy 191.01571 -263.125237)
			(xy 190.967762 -263.100585) (xy 190.923914 -263.069215) (xy 190.885101 -263.031794) (xy 190.852149 -262.989121)
			(xy 190.825763 -262.942104) (xy 190.806503 -262.891747) (xy 190.79478 -262.839123) (xy 190.790845 -262.785352)
			(xy 183.9849 -262.785352) (xy 183.984408 -262.812309) (xy 183.976558 -262.865649) (xy 183.961026 -262.917278)
			(xy 183.938141 -262.966095) (xy 183.908393 -263.011059) (xy 183.872415 -263.051213) (xy 183.830973 -263.085701)
			(xy 183.784952 -263.113787) (xy 183.735332 -263.134874) (xy 183.683171 -263.14851) (xy 183.62958 -263.154407)
			(xy 183.575701 -263.152438) (xy 183.522683 -263.142645) (xy 183.471656 -263.125237) (xy 183.423708 -263.100585)
			(xy 183.37986 -263.069215) (xy 183.341047 -263.031794) (xy 183.308095 -262.989121) (xy 183.281709 -262.942104)
			(xy 183.262449 -262.891747) (xy 183.250726 -262.839123) (xy 183.246791 -262.785352) (xy 177.881534 -262.785352)
			(xy 177.881534 -263.635236) (xy 179.146723 -263.635236) (xy 179.150658 -263.581465) (xy 179.162381 -263.528841)
			(xy 179.181641 -263.478484) (xy 179.208027 -263.431467) (xy 179.240979 -263.388794) (xy 179.279792 -263.351373)
			(xy 179.32364 -263.320003) (xy 179.371588 -263.295351) (xy 179.422615 -263.277943) (xy 179.475633 -263.26815)
			(xy 179.529512 -263.266181) (xy 179.583103 -263.272078) (xy 179.635264 -263.285714) (xy 179.684884 -263.306801)
			(xy 179.730905 -263.334887) (xy 179.772347 -263.369375) (xy 179.808325 -263.409529) (xy 179.838073 -263.454493)
			(xy 179.860958 -263.50331) (xy 179.87649 -263.554939) (xy 179.88434 -263.608279) (xy 179.884832 -263.635236)
			(xy 186.690777 -263.635236) (xy 186.694712 -263.581465) (xy 186.706435 -263.528841) (xy 186.725695 -263.478484)
			(xy 186.752081 -263.431467) (xy 186.785033 -263.388794) (xy 186.823846 -263.351373) (xy 186.867694 -263.320003)
			(xy 186.915642 -263.295351) (xy 186.966669 -263.277943) (xy 187.019687 -263.26815) (xy 187.073566 -263.266181)
			(xy 187.127157 -263.272078) (xy 187.179318 -263.285714) (xy 187.228938 -263.306801) (xy 187.274959 -263.334887)
			(xy 187.316401 -263.369375) (xy 187.352379 -263.409529) (xy 187.382127 -263.454493) (xy 187.405012 -263.50331)
			(xy 187.420544 -263.554939) (xy 187.428394 -263.608279) (xy 187.428886 -263.635236) (xy 194.234831 -263.635236)
			(xy 194.238766 -263.581465) (xy 194.250489 -263.528841) (xy 194.269749 -263.478484) (xy 194.296135 -263.431467)
			(xy 194.329087 -263.388794) (xy 194.3679 -263.351373) (xy 194.411748 -263.320003) (xy 194.459696 -263.295351)
			(xy 194.510723 -263.277943) (xy 194.563741 -263.26815) (xy 194.61762 -263.266181) (xy 194.671211 -263.272078)
			(xy 194.723372 -263.285714) (xy 194.772992 -263.306801) (xy 194.819013 -263.334887) (xy 194.860455 -263.369375)
			(xy 194.896433 -263.409529) (xy 194.926181 -263.454493) (xy 194.949066 -263.50331) (xy 194.964598 -263.554939)
			(xy 194.972448 -263.608279) (xy 194.97294 -263.635236) (xy 201.778631 -263.635236) (xy 201.782566 -263.581465)
			(xy 201.794289 -263.528841) (xy 201.813549 -263.478484) (xy 201.839935 -263.431467) (xy 201.872887 -263.388794)
			(xy 201.9117 -263.351373) (xy 201.955548 -263.320003) (xy 202.003496 -263.295351) (xy 202.054523 -263.277943)
			(xy 202.107541 -263.26815) (xy 202.16142 -263.266181) (xy 202.215011 -263.272078) (xy 202.267172 -263.285714)
			(xy 202.316792 -263.306801) (xy 202.362813 -263.334887) (xy 202.404255 -263.369375) (xy 202.440233 -263.409529)
			(xy 202.469981 -263.454493) (xy 202.492866 -263.50331) (xy 202.508398 -263.554939) (xy 202.516248 -263.608279)
			(xy 202.51674 -263.635236) (xy 202.516248 -263.662193) (xy 202.508398 -263.715533) (xy 202.492866 -263.767162)
			(xy 202.469981 -263.815979) (xy 202.440233 -263.860943) (xy 202.404255 -263.901097) (xy 202.362813 -263.935585)
			(xy 202.316792 -263.963671) (xy 202.267172 -263.984758) (xy 202.215011 -263.998394) (xy 202.16142 -264.004291)
			(xy 202.107541 -264.002322) (xy 202.054523 -263.992529) (xy 202.003496 -263.975121) (xy 201.955548 -263.950469)
			(xy 201.9117 -263.919099) (xy 201.872887 -263.881678) (xy 201.839935 -263.839005) (xy 201.813549 -263.791988)
			(xy 201.794289 -263.741631) (xy 201.782566 -263.689007) (xy 201.778631 -263.635236) (xy 194.97294 -263.635236)
			(xy 194.972448 -263.662193) (xy 194.964598 -263.715533) (xy 194.949066 -263.767162) (xy 194.926181 -263.815979)
			(xy 194.896433 -263.860943) (xy 194.860455 -263.901097) (xy 194.819013 -263.935585) (xy 194.772992 -263.963671)
			(xy 194.723372 -263.984758) (xy 194.671211 -263.998394) (xy 194.61762 -264.004291) (xy 194.563741 -264.002322)
			(xy 194.510723 -263.992529) (xy 194.459696 -263.975121) (xy 194.411748 -263.950469) (xy 194.3679 -263.919099)
			(xy 194.329087 -263.881678) (xy 194.296135 -263.839005) (xy 194.269749 -263.791988) (xy 194.250489 -263.741631)
			(xy 194.238766 -263.689007) (xy 194.234831 -263.635236) (xy 187.428886 -263.635236) (xy 187.428394 -263.662193)
			(xy 187.420544 -263.715533) (xy 187.405012 -263.767162) (xy 187.382127 -263.815979) (xy 187.352379 -263.860943)
			(xy 187.316401 -263.901097) (xy 187.274959 -263.935585) (xy 187.228938 -263.963671) (xy 187.179318 -263.984758)
			(xy 187.127157 -263.998394) (xy 187.073566 -264.004291) (xy 187.019687 -264.002322) (xy 186.966669 -263.992529)
			(xy 186.915642 -263.975121) (xy 186.867694 -263.950469) (xy 186.823846 -263.919099) (xy 186.785033 -263.881678)
			(xy 186.752081 -263.839005) (xy 186.725695 -263.791988) (xy 186.706435 -263.741631) (xy 186.694712 -263.689007)
			(xy 186.690777 -263.635236) (xy 179.884832 -263.635236) (xy 179.88434 -263.662193) (xy 179.87649 -263.715533)
			(xy 179.860958 -263.767162) (xy 179.838073 -263.815979) (xy 179.808325 -263.860943) (xy 179.772347 -263.901097)
			(xy 179.730905 -263.935585) (xy 179.684884 -263.963671) (xy 179.635264 -263.984758) (xy 179.583103 -263.998394)
			(xy 179.529512 -264.004291) (xy 179.475633 -264.002322) (xy 179.422615 -263.992529) (xy 179.371588 -263.975121)
			(xy 179.32364 -263.950469) (xy 179.279792 -263.919099) (xy 179.240979 -263.881678) (xy 179.208027 -263.839005)
			(xy 179.181641 -263.791988) (xy 179.162381 -263.741631) (xy 179.150658 -263.689007) (xy 179.146723 -263.635236)
			(xy 177.881534 -263.635236) (xy 177.881534 -264.485374) (xy 183.246791 -264.485374) (xy 183.250726 -264.431603)
			(xy 183.262449 -264.378979) (xy 183.281709 -264.328622) (xy 183.308095 -264.281605) (xy 183.341047 -264.238932)
			(xy 183.37986 -264.201511) (xy 183.423708 -264.170141) (xy 183.471656 -264.145489) (xy 183.522683 -264.128081)
			(xy 183.575701 -264.118288) (xy 183.62958 -264.116319) (xy 183.683171 -264.122216) (xy 183.735332 -264.135852)
			(xy 183.784952 -264.156939) (xy 183.830973 -264.185025) (xy 183.872415 -264.219513) (xy 183.908393 -264.259667)
			(xy 183.938141 -264.304631) (xy 183.961026 -264.353448) (xy 183.976558 -264.405077) (xy 183.984408 -264.458417)
			(xy 183.9849 -264.485374) (xy 190.790845 -264.485374) (xy 190.79478 -264.431603) (xy 190.806503 -264.378979)
			(xy 190.825763 -264.328622) (xy 190.852149 -264.281605) (xy 190.885101 -264.238932) (xy 190.923914 -264.201511)
			(xy 190.967762 -264.170141) (xy 191.01571 -264.145489) (xy 191.066737 -264.128081) (xy 191.119755 -264.118288)
			(xy 191.173634 -264.116319) (xy 191.227225 -264.122216) (xy 191.279386 -264.135852) (xy 191.329006 -264.156939)
			(xy 191.375027 -264.185025) (xy 191.416469 -264.219513) (xy 191.452447 -264.259667) (xy 191.482195 -264.304631)
			(xy 191.50508 -264.353448) (xy 191.520612 -264.405077) (xy 191.528462 -264.458417) (xy 191.528954 -264.485374)
			(xy 198.334899 -264.485374) (xy 198.338834 -264.431603) (xy 198.350557 -264.378979) (xy 198.369817 -264.328622)
			(xy 198.396203 -264.281605) (xy 198.429155 -264.238932) (xy 198.467968 -264.201511) (xy 198.511816 -264.170141)
			(xy 198.559764 -264.145489) (xy 198.610791 -264.128081) (xy 198.663809 -264.118288) (xy 198.717688 -264.116319)
			(xy 198.771279 -264.122216) (xy 198.82344 -264.135852) (xy 198.87306 -264.156939) (xy 198.919081 -264.185025)
			(xy 198.960523 -264.219513) (xy 198.996501 -264.259667) (xy 199.026249 -264.304631) (xy 199.049134 -264.353448)
			(xy 199.064666 -264.405077) (xy 199.072516 -264.458417) (xy 199.073008 -264.485374) (xy 205.878699 -264.485374)
			(xy 205.882634 -264.431603) (xy 205.894357 -264.378979) (xy 205.913617 -264.328622) (xy 205.940003 -264.281605)
			(xy 205.972955 -264.238932) (xy 206.011768 -264.201511) (xy 206.055616 -264.170141) (xy 206.103564 -264.145489)
			(xy 206.154591 -264.128081) (xy 206.207609 -264.118288) (xy 206.261488 -264.116319) (xy 206.315079 -264.122216)
			(xy 206.36724 -264.135852) (xy 206.41686 -264.156939) (xy 206.462881 -264.185025) (xy 206.504323 -264.219513)
			(xy 206.540301 -264.259667) (xy 206.570049 -264.304631) (xy 206.592934 -264.353448) (xy 206.608466 -264.405077)
			(xy 206.616316 -264.458417) (xy 206.616808 -264.485374) (xy 206.616316 -264.512331) (xy 206.608466 -264.565671)
			(xy 206.592934 -264.6173) (xy 206.570049 -264.666117) (xy 206.540301 -264.711081) (xy 206.504323 -264.751235)
			(xy 206.462881 -264.785723) (xy 206.41686 -264.813809) (xy 206.36724 -264.834896) (xy 206.315079 -264.848532)
			(xy 206.261488 -264.854429) (xy 206.207609 -264.85246) (xy 206.154591 -264.842667) (xy 206.103564 -264.825259)
			(xy 206.055616 -264.800607) (xy 206.011768 -264.769237) (xy 205.972955 -264.731816) (xy 205.940003 -264.689143)
			(xy 205.913617 -264.642126) (xy 205.894357 -264.591769) (xy 205.882634 -264.539145) (xy 205.878699 -264.485374)
			(xy 199.073008 -264.485374) (xy 199.072516 -264.512331) (xy 199.064666 -264.565671) (xy 199.049134 -264.6173)
			(xy 199.026249 -264.666117) (xy 198.996501 -264.711081) (xy 198.960523 -264.751235) (xy 198.919081 -264.785723)
			(xy 198.87306 -264.813809) (xy 198.82344 -264.834896) (xy 198.771279 -264.848532) (xy 198.717688 -264.854429)
			(xy 198.663809 -264.85246) (xy 198.610791 -264.842667) (xy 198.559764 -264.825259) (xy 198.511816 -264.800607)
			(xy 198.467968 -264.769237) (xy 198.429155 -264.731816) (xy 198.396203 -264.689143) (xy 198.369817 -264.642126)
			(xy 198.350557 -264.591769) (xy 198.338834 -264.539145) (xy 198.334899 -264.485374) (xy 191.528954 -264.485374)
			(xy 191.528462 -264.512331) (xy 191.520612 -264.565671) (xy 191.50508 -264.6173) (xy 191.482195 -264.666117)
			(xy 191.452447 -264.711081) (xy 191.416469 -264.751235) (xy 191.375027 -264.785723) (xy 191.329006 -264.813809)
			(xy 191.279386 -264.834896) (xy 191.227225 -264.848532) (xy 191.173634 -264.854429) (xy 191.119755 -264.85246)
			(xy 191.066737 -264.842667) (xy 191.01571 -264.825259) (xy 190.967762 -264.800607) (xy 190.923914 -264.769237)
			(xy 190.885101 -264.731816) (xy 190.852149 -264.689143) (xy 190.825763 -264.642126) (xy 190.806503 -264.591769)
			(xy 190.79478 -264.539145) (xy 190.790845 -264.485374) (xy 183.9849 -264.485374) (xy 183.984408 -264.512331)
			(xy 183.976558 -264.565671) (xy 183.961026 -264.6173) (xy 183.938141 -264.666117) (xy 183.908393 -264.711081)
			(xy 183.872415 -264.751235) (xy 183.830973 -264.785723) (xy 183.784952 -264.813809) (xy 183.735332 -264.834896)
			(xy 183.683171 -264.848532) (xy 183.62958 -264.854429) (xy 183.575701 -264.85246) (xy 183.522683 -264.842667)
			(xy 183.471656 -264.825259) (xy 183.423708 -264.800607) (xy 183.37986 -264.769237) (xy 183.341047 -264.731816)
			(xy 183.308095 -264.689143) (xy 183.281709 -264.642126) (xy 183.262449 -264.591769) (xy 183.250726 -264.539145)
			(xy 183.246791 -264.485374) (xy 177.881534 -264.485374) (xy 177.881534 -265.335258) (xy 179.146723 -265.335258)
			(xy 179.150658 -265.281487) (xy 179.162381 -265.228863) (xy 179.181641 -265.178506) (xy 179.208027 -265.131489)
			(xy 179.240979 -265.088816) (xy 179.279792 -265.051395) (xy 179.32364 -265.020025) (xy 179.371588 -264.995373)
			(xy 179.422615 -264.977965) (xy 179.475633 -264.968172) (xy 179.529512 -264.966203) (xy 179.583103 -264.9721)
			(xy 179.635264 -264.985736) (xy 179.684884 -265.006823) (xy 179.730905 -265.034909) (xy 179.772347 -265.069397)
			(xy 179.808325 -265.109551) (xy 179.838073 -265.154515) (xy 179.860958 -265.203332) (xy 179.87649 -265.254961)
			(xy 179.88434 -265.308301) (xy 179.884832 -265.335258) (xy 186.690777 -265.335258) (xy 186.694712 -265.281487)
			(xy 186.706435 -265.228863) (xy 186.725695 -265.178506) (xy 186.752081 -265.131489) (xy 186.785033 -265.088816)
			(xy 186.823846 -265.051395) (xy 186.867694 -265.020025) (xy 186.915642 -264.995373) (xy 186.966669 -264.977965)
			(xy 187.019687 -264.968172) (xy 187.073566 -264.966203) (xy 187.127157 -264.9721) (xy 187.179318 -264.985736)
			(xy 187.228938 -265.006823) (xy 187.274959 -265.034909) (xy 187.316401 -265.069397) (xy 187.352379 -265.109551)
			(xy 187.382127 -265.154515) (xy 187.405012 -265.203332) (xy 187.420544 -265.254961) (xy 187.428394 -265.308301)
			(xy 187.428886 -265.335258) (xy 194.234831 -265.335258) (xy 194.238766 -265.281487) (xy 194.250489 -265.228863)
			(xy 194.269749 -265.178506) (xy 194.296135 -265.131489) (xy 194.329087 -265.088816) (xy 194.3679 -265.051395)
			(xy 194.411748 -265.020025) (xy 194.459696 -264.995373) (xy 194.510723 -264.977965) (xy 194.563741 -264.968172)
			(xy 194.61762 -264.966203) (xy 194.671211 -264.9721) (xy 194.723372 -264.985736) (xy 194.772992 -265.006823)
			(xy 194.819013 -265.034909) (xy 194.860455 -265.069397) (xy 194.896433 -265.109551) (xy 194.926181 -265.154515)
			(xy 194.949066 -265.203332) (xy 194.964598 -265.254961) (xy 194.972448 -265.308301) (xy 194.97294 -265.335258)
			(xy 201.778631 -265.335258) (xy 201.782566 -265.281487) (xy 201.794289 -265.228863) (xy 201.813549 -265.178506)
			(xy 201.839935 -265.131489) (xy 201.872887 -265.088816) (xy 201.9117 -265.051395) (xy 201.955548 -265.020025)
			(xy 202.003496 -264.995373) (xy 202.054523 -264.977965) (xy 202.107541 -264.968172) (xy 202.16142 -264.966203)
			(xy 202.215011 -264.9721) (xy 202.267172 -264.985736) (xy 202.316792 -265.006823) (xy 202.362813 -265.034909)
			(xy 202.404255 -265.069397) (xy 202.440233 -265.109551) (xy 202.469981 -265.154515) (xy 202.492866 -265.203332)
			(xy 202.508398 -265.254961) (xy 202.516248 -265.308301) (xy 202.51674 -265.335258) (xy 202.516248 -265.362215)
			(xy 202.508398 -265.415555) (xy 202.492866 -265.467184) (xy 202.469981 -265.516001) (xy 202.440233 -265.560965)
			(xy 202.404255 -265.601119) (xy 202.362813 -265.635607) (xy 202.316792 -265.663693) (xy 202.267172 -265.68478)
			(xy 202.215011 -265.698416) (xy 202.16142 -265.704313) (xy 202.107541 -265.702344) (xy 202.054523 -265.692551)
			(xy 202.003496 -265.675143) (xy 201.955548 -265.650491) (xy 201.9117 -265.619121) (xy 201.872887 -265.5817)
			(xy 201.839935 -265.539027) (xy 201.813549 -265.49201) (xy 201.794289 -265.441653) (xy 201.782566 -265.389029)
			(xy 201.778631 -265.335258) (xy 194.97294 -265.335258) (xy 194.972448 -265.362215) (xy 194.964598 -265.415555)
			(xy 194.949066 -265.467184) (xy 194.926181 -265.516001) (xy 194.896433 -265.560965) (xy 194.860455 -265.601119)
			(xy 194.819013 -265.635607) (xy 194.772992 -265.663693) (xy 194.723372 -265.68478) (xy 194.671211 -265.698416)
			(xy 194.61762 -265.704313) (xy 194.563741 -265.702344) (xy 194.510723 -265.692551) (xy 194.459696 -265.675143)
			(xy 194.411748 -265.650491) (xy 194.3679 -265.619121) (xy 194.329087 -265.5817) (xy 194.296135 -265.539027)
			(xy 194.269749 -265.49201) (xy 194.250489 -265.441653) (xy 194.238766 -265.389029) (xy 194.234831 -265.335258)
			(xy 187.428886 -265.335258) (xy 187.428394 -265.362215) (xy 187.420544 -265.415555) (xy 187.405012 -265.467184)
			(xy 187.382127 -265.516001) (xy 187.352379 -265.560965) (xy 187.316401 -265.601119) (xy 187.274959 -265.635607)
			(xy 187.228938 -265.663693) (xy 187.179318 -265.68478) (xy 187.127157 -265.698416) (xy 187.073566 -265.704313)
			(xy 187.019687 -265.702344) (xy 186.966669 -265.692551) (xy 186.915642 -265.675143) (xy 186.867694 -265.650491)
			(xy 186.823846 -265.619121) (xy 186.785033 -265.5817) (xy 186.752081 -265.539027) (xy 186.725695 -265.49201)
			(xy 186.706435 -265.441653) (xy 186.694712 -265.389029) (xy 186.690777 -265.335258) (xy 179.884832 -265.335258)
			(xy 179.88434 -265.362215) (xy 179.87649 -265.415555) (xy 179.860958 -265.467184) (xy 179.838073 -265.516001)
			(xy 179.808325 -265.560965) (xy 179.772347 -265.601119) (xy 179.730905 -265.635607) (xy 179.684884 -265.663693)
			(xy 179.635264 -265.68478) (xy 179.583103 -265.698416) (xy 179.529512 -265.704313) (xy 179.475633 -265.702344)
			(xy 179.422615 -265.692551) (xy 179.371588 -265.675143) (xy 179.32364 -265.650491) (xy 179.279792 -265.619121)
			(xy 179.240979 -265.5817) (xy 179.208027 -265.539027) (xy 179.181641 -265.49201) (xy 179.162381 -265.441653)
			(xy 179.150658 -265.389029) (xy 179.146723 -265.335258) (xy 177.881534 -265.335258) (xy 177.881534 -266.185396)
			(xy 183.246791 -266.185396) (xy 183.250726 -266.131625) (xy 183.262449 -266.079001) (xy 183.281709 -266.028644)
			(xy 183.308095 -265.981627) (xy 183.341047 -265.938954) (xy 183.37986 -265.901533) (xy 183.423708 -265.870163)
			(xy 183.471656 -265.845511) (xy 183.522683 -265.828103) (xy 183.575701 -265.81831) (xy 183.62958 -265.816341)
			(xy 183.683171 -265.822238) (xy 183.735332 -265.835874) (xy 183.784952 -265.856961) (xy 183.830973 -265.885047)
			(xy 183.872415 -265.919535) (xy 183.908393 -265.959689) (xy 183.938141 -266.004653) (xy 183.961026 -266.05347)
			(xy 183.976558 -266.105099) (xy 183.984408 -266.158439) (xy 183.9849 -266.185396) (xy 190.790845 -266.185396)
			(xy 190.79478 -266.131625) (xy 190.806503 -266.079001) (xy 190.825763 -266.028644) (xy 190.852149 -265.981627)
			(xy 190.885101 -265.938954) (xy 190.923914 -265.901533) (xy 190.967762 -265.870163) (xy 191.01571 -265.845511)
			(xy 191.066737 -265.828103) (xy 191.119755 -265.81831) (xy 191.173634 -265.816341) (xy 191.227225 -265.822238)
			(xy 191.279386 -265.835874) (xy 191.329006 -265.856961) (xy 191.375027 -265.885047) (xy 191.416469 -265.919535)
			(xy 191.452447 -265.959689) (xy 191.482195 -266.004653) (xy 191.50508 -266.05347) (xy 191.520612 -266.105099)
			(xy 191.528462 -266.158439) (xy 191.528954 -266.185396) (xy 198.334899 -266.185396) (xy 198.338834 -266.131625)
			(xy 198.350557 -266.079001) (xy 198.369817 -266.028644) (xy 198.396203 -265.981627) (xy 198.429155 -265.938954)
			(xy 198.467968 -265.901533) (xy 198.511816 -265.870163) (xy 198.559764 -265.845511) (xy 198.610791 -265.828103)
			(xy 198.663809 -265.81831) (xy 198.717688 -265.816341) (xy 198.771279 -265.822238) (xy 198.82344 -265.835874)
			(xy 198.87306 -265.856961) (xy 198.919081 -265.885047) (xy 198.960523 -265.919535) (xy 198.996501 -265.959689)
			(xy 199.026249 -266.004653) (xy 199.049134 -266.05347) (xy 199.064666 -266.105099) (xy 199.072516 -266.158439)
			(xy 199.073008 -266.185396) (xy 205.878699 -266.185396) (xy 205.882634 -266.131625) (xy 205.894357 -266.079001)
			(xy 205.913617 -266.028644) (xy 205.940003 -265.981627) (xy 205.972955 -265.938954) (xy 206.011768 -265.901533)
			(xy 206.055616 -265.870163) (xy 206.103564 -265.845511) (xy 206.154591 -265.828103) (xy 206.207609 -265.81831)
			(xy 206.261488 -265.816341) (xy 206.315079 -265.822238) (xy 206.36724 -265.835874) (xy 206.41686 -265.856961)
			(xy 206.462881 -265.885047) (xy 206.504323 -265.919535) (xy 206.540301 -265.959689) (xy 206.570049 -266.004653)
			(xy 206.592934 -266.05347) (xy 206.608466 -266.105099) (xy 206.616316 -266.158439) (xy 206.616808 -266.185396)
			(xy 206.616316 -266.212353) (xy 206.608466 -266.265693) (xy 206.592934 -266.317322) (xy 206.570049 -266.366139)
			(xy 206.540301 -266.411103) (xy 206.504323 -266.451257) (xy 206.462881 -266.485745) (xy 206.41686 -266.513831)
			(xy 206.36724 -266.534918) (xy 206.315079 -266.548554) (xy 206.261488 -266.554451) (xy 206.207609 -266.552482)
			(xy 206.154591 -266.542689) (xy 206.103564 -266.525281) (xy 206.055616 -266.500629) (xy 206.011768 -266.469259)
			(xy 205.972955 -266.431838) (xy 205.940003 -266.389165) (xy 205.913617 -266.342148) (xy 205.894357 -266.291791)
			(xy 205.882634 -266.239167) (xy 205.878699 -266.185396) (xy 199.073008 -266.185396) (xy 199.072516 -266.212353)
			(xy 199.064666 -266.265693) (xy 199.049134 -266.317322) (xy 199.026249 -266.366139) (xy 198.996501 -266.411103)
			(xy 198.960523 -266.451257) (xy 198.919081 -266.485745) (xy 198.87306 -266.513831) (xy 198.82344 -266.534918)
			(xy 198.771279 -266.548554) (xy 198.717688 -266.554451) (xy 198.663809 -266.552482) (xy 198.610791 -266.542689)
			(xy 198.559764 -266.525281) (xy 198.511816 -266.500629) (xy 198.467968 -266.469259) (xy 198.429155 -266.431838)
			(xy 198.396203 -266.389165) (xy 198.369817 -266.342148) (xy 198.350557 -266.291791) (xy 198.338834 -266.239167)
			(xy 198.334899 -266.185396) (xy 191.528954 -266.185396) (xy 191.528462 -266.212353) (xy 191.520612 -266.265693)
			(xy 191.50508 -266.317322) (xy 191.482195 -266.366139) (xy 191.452447 -266.411103) (xy 191.416469 -266.451257)
			(xy 191.375027 -266.485745) (xy 191.329006 -266.513831) (xy 191.279386 -266.534918) (xy 191.227225 -266.548554)
			(xy 191.173634 -266.554451) (xy 191.119755 -266.552482) (xy 191.066737 -266.542689) (xy 191.01571 -266.525281)
			(xy 190.967762 -266.500629) (xy 190.923914 -266.469259) (xy 190.885101 -266.431838) (xy 190.852149 -266.389165)
			(xy 190.825763 -266.342148) (xy 190.806503 -266.291791) (xy 190.79478 -266.239167) (xy 190.790845 -266.185396)
			(xy 183.9849 -266.185396) (xy 183.984408 -266.212353) (xy 183.976558 -266.265693) (xy 183.961026 -266.317322)
			(xy 183.938141 -266.366139) (xy 183.908393 -266.411103) (xy 183.872415 -266.451257) (xy 183.830973 -266.485745)
			(xy 183.784952 -266.513831) (xy 183.735332 -266.534918) (xy 183.683171 -266.548554) (xy 183.62958 -266.554451)
			(xy 183.575701 -266.552482) (xy 183.522683 -266.542689) (xy 183.471656 -266.525281) (xy 183.423708 -266.500629)
			(xy 183.37986 -266.469259) (xy 183.341047 -266.431838) (xy 183.308095 -266.389165) (xy 183.281709 -266.342148)
			(xy 183.262449 -266.291791) (xy 183.250726 -266.239167) (xy 183.246791 -266.185396) (xy 177.881534 -266.185396)
			(xy 177.881534 -267.03528) (xy 179.146723 -267.03528) (xy 179.150658 -266.981509) (xy 179.162381 -266.928885)
			(xy 179.181641 -266.878528) (xy 179.208027 -266.831511) (xy 179.240979 -266.788838) (xy 179.279792 -266.751417)
			(xy 179.32364 -266.720047) (xy 179.371588 -266.695395) (xy 179.422615 -266.677987) (xy 179.475633 -266.668194)
			(xy 179.529512 -266.666225) (xy 179.583103 -266.672122) (xy 179.635264 -266.685758) (xy 179.684884 -266.706845)
			(xy 179.730905 -266.734931) (xy 179.772347 -266.769419) (xy 179.808325 -266.809573) (xy 179.838073 -266.854537)
			(xy 179.860958 -266.903354) (xy 179.87649 -266.954983) (xy 179.88434 -267.008323) (xy 179.884832 -267.03528)
			(xy 186.690777 -267.03528) (xy 186.694712 -266.981509) (xy 186.706435 -266.928885) (xy 186.725695 -266.878528)
			(xy 186.752081 -266.831511) (xy 186.785033 -266.788838) (xy 186.823846 -266.751417) (xy 186.867694 -266.720047)
			(xy 186.915642 -266.695395) (xy 186.966669 -266.677987) (xy 187.019687 -266.668194) (xy 187.073566 -266.666225)
			(xy 187.127157 -266.672122) (xy 187.179318 -266.685758) (xy 187.228938 -266.706845) (xy 187.274959 -266.734931)
			(xy 187.316401 -266.769419) (xy 187.352379 -266.809573) (xy 187.382127 -266.854537) (xy 187.405012 -266.903354)
			(xy 187.420544 -266.954983) (xy 187.428394 -267.008323) (xy 187.428886 -267.03528) (xy 194.234831 -267.03528)
			(xy 194.238766 -266.981509) (xy 194.250489 -266.928885) (xy 194.269749 -266.878528) (xy 194.296135 -266.831511)
			(xy 194.329087 -266.788838) (xy 194.3679 -266.751417) (xy 194.411748 -266.720047) (xy 194.459696 -266.695395)
			(xy 194.510723 -266.677987) (xy 194.563741 -266.668194) (xy 194.61762 -266.666225) (xy 194.671211 -266.672122)
			(xy 194.723372 -266.685758) (xy 194.772992 -266.706845) (xy 194.819013 -266.734931) (xy 194.860455 -266.769419)
			(xy 194.896433 -266.809573) (xy 194.926181 -266.854537) (xy 194.949066 -266.903354) (xy 194.964598 -266.954983)
			(xy 194.972448 -267.008323) (xy 194.97294 -267.03528) (xy 201.778631 -267.03528) (xy 201.782566 -266.981509)
			(xy 201.794289 -266.928885) (xy 201.813549 -266.878528) (xy 201.839935 -266.831511) (xy 201.872887 -266.788838)
			(xy 201.9117 -266.751417) (xy 201.955548 -266.720047) (xy 202.003496 -266.695395) (xy 202.054523 -266.677987)
			(xy 202.107541 -266.668194) (xy 202.16142 -266.666225) (xy 202.215011 -266.672122) (xy 202.267172 -266.685758)
			(xy 202.316792 -266.706845) (xy 202.362813 -266.734931) (xy 202.404255 -266.769419) (xy 202.440233 -266.809573)
			(xy 202.469981 -266.854537) (xy 202.492866 -266.903354) (xy 202.508398 -266.954983) (xy 202.516248 -267.008323)
			(xy 202.51674 -267.03528) (xy 202.516248 -267.062237) (xy 202.508398 -267.115577) (xy 202.492866 -267.167206)
			(xy 202.469981 -267.216023) (xy 202.440233 -267.260987) (xy 202.404255 -267.301141) (xy 202.362813 -267.335629)
			(xy 202.316792 -267.363715) (xy 202.267172 -267.384802) (xy 202.215011 -267.398438) (xy 202.16142 -267.404335)
			(xy 202.107541 -267.402366) (xy 202.054523 -267.392573) (xy 202.003496 -267.375165) (xy 201.955548 -267.350513)
			(xy 201.9117 -267.319143) (xy 201.872887 -267.281722) (xy 201.839935 -267.239049) (xy 201.813549 -267.192032)
			(xy 201.794289 -267.141675) (xy 201.782566 -267.089051) (xy 201.778631 -267.03528) (xy 194.97294 -267.03528)
			(xy 194.972448 -267.062237) (xy 194.964598 -267.115577) (xy 194.949066 -267.167206) (xy 194.926181 -267.216023)
			(xy 194.896433 -267.260987) (xy 194.860455 -267.301141) (xy 194.819013 -267.335629) (xy 194.772992 -267.363715)
			(xy 194.723372 -267.384802) (xy 194.671211 -267.398438) (xy 194.61762 -267.404335) (xy 194.563741 -267.402366)
			(xy 194.510723 -267.392573) (xy 194.459696 -267.375165) (xy 194.411748 -267.350513) (xy 194.3679 -267.319143)
			(xy 194.329087 -267.281722) (xy 194.296135 -267.239049) (xy 194.269749 -267.192032) (xy 194.250489 -267.141675)
			(xy 194.238766 -267.089051) (xy 194.234831 -267.03528) (xy 187.428886 -267.03528) (xy 187.428394 -267.062237)
			(xy 187.420544 -267.115577) (xy 187.405012 -267.167206) (xy 187.382127 -267.216023) (xy 187.352379 -267.260987)
			(xy 187.316401 -267.301141) (xy 187.274959 -267.335629) (xy 187.228938 -267.363715) (xy 187.179318 -267.384802)
			(xy 187.127157 -267.398438) (xy 187.073566 -267.404335) (xy 187.019687 -267.402366) (xy 186.966669 -267.392573)
			(xy 186.915642 -267.375165) (xy 186.867694 -267.350513) (xy 186.823846 -267.319143) (xy 186.785033 -267.281722)
			(xy 186.752081 -267.239049) (xy 186.725695 -267.192032) (xy 186.706435 -267.141675) (xy 186.694712 -267.089051)
			(xy 186.690777 -267.03528) (xy 179.884832 -267.03528) (xy 179.88434 -267.062237) (xy 179.87649 -267.115577)
			(xy 179.860958 -267.167206) (xy 179.838073 -267.216023) (xy 179.808325 -267.260987) (xy 179.772347 -267.301141)
			(xy 179.730905 -267.335629) (xy 179.684884 -267.363715) (xy 179.635264 -267.384802) (xy 179.583103 -267.398438)
			(xy 179.529512 -267.404335) (xy 179.475633 -267.402366) (xy 179.422615 -267.392573) (xy 179.371588 -267.375165)
			(xy 179.32364 -267.350513) (xy 179.279792 -267.319143) (xy 179.240979 -267.281722) (xy 179.208027 -267.239049)
			(xy 179.181641 -267.192032) (xy 179.162381 -267.141675) (xy 179.150658 -267.089051) (xy 179.146723 -267.03528)
			(xy 177.881534 -267.03528) (xy 177.881534 -267.885418) (xy 183.246791 -267.885418) (xy 183.250726 -267.831647)
			(xy 183.262449 -267.779023) (xy 183.281709 -267.728666) (xy 183.308095 -267.681649) (xy 183.341047 -267.638976)
			(xy 183.37986 -267.601555) (xy 183.423708 -267.570185) (xy 183.471656 -267.545533) (xy 183.522683 -267.528125)
			(xy 183.575701 -267.518332) (xy 183.62958 -267.516363) (xy 183.683171 -267.52226) (xy 183.735332 -267.535896)
			(xy 183.784952 -267.556983) (xy 183.830973 -267.585069) (xy 183.872415 -267.619557) (xy 183.908393 -267.659711)
			(xy 183.938141 -267.704675) (xy 183.961026 -267.753492) (xy 183.976558 -267.805121) (xy 183.984408 -267.858461)
			(xy 183.9849 -267.885418) (xy 190.790845 -267.885418) (xy 190.79478 -267.831647) (xy 190.806503 -267.779023)
			(xy 190.825763 -267.728666) (xy 190.852149 -267.681649) (xy 190.885101 -267.638976) (xy 190.923914 -267.601555)
			(xy 190.967762 -267.570185) (xy 191.01571 -267.545533) (xy 191.066737 -267.528125) (xy 191.119755 -267.518332)
			(xy 191.173634 -267.516363) (xy 191.227225 -267.52226) (xy 191.279386 -267.535896) (xy 191.329006 -267.556983)
			(xy 191.375027 -267.585069) (xy 191.416469 -267.619557) (xy 191.452447 -267.659711) (xy 191.482195 -267.704675)
			(xy 191.50508 -267.753492) (xy 191.520612 -267.805121) (xy 191.528462 -267.858461) (xy 191.528954 -267.885418)
			(xy 198.334899 -267.885418) (xy 198.338834 -267.831647) (xy 198.350557 -267.779023) (xy 198.369817 -267.728666)
			(xy 198.396203 -267.681649) (xy 198.429155 -267.638976) (xy 198.467968 -267.601555) (xy 198.511816 -267.570185)
			(xy 198.559764 -267.545533) (xy 198.610791 -267.528125) (xy 198.663809 -267.518332) (xy 198.717688 -267.516363)
			(xy 198.771279 -267.52226) (xy 198.82344 -267.535896) (xy 198.87306 -267.556983) (xy 198.919081 -267.585069)
			(xy 198.960523 -267.619557) (xy 198.996501 -267.659711) (xy 199.026249 -267.704675) (xy 199.049134 -267.753492)
			(xy 199.064666 -267.805121) (xy 199.072516 -267.858461) (xy 199.073008 -267.885418) (xy 205.878699 -267.885418)
			(xy 205.882634 -267.831647) (xy 205.894357 -267.779023) (xy 205.913617 -267.728666) (xy 205.940003 -267.681649)
			(xy 205.972955 -267.638976) (xy 206.011768 -267.601555) (xy 206.055616 -267.570185) (xy 206.103564 -267.545533)
			(xy 206.154591 -267.528125) (xy 206.207609 -267.518332) (xy 206.261488 -267.516363) (xy 206.315079 -267.52226)
			(xy 206.36724 -267.535896) (xy 206.41686 -267.556983) (xy 206.462881 -267.585069) (xy 206.504323 -267.619557)
			(xy 206.540301 -267.659711) (xy 206.570049 -267.704675) (xy 206.592934 -267.753492) (xy 206.608466 -267.805121)
			(xy 206.616316 -267.858461) (xy 206.616808 -267.885418) (xy 206.616316 -267.912375) (xy 206.608466 -267.965715)
			(xy 206.592934 -268.017344) (xy 206.570049 -268.066161) (xy 206.540301 -268.111125) (xy 206.504323 -268.151279)
			(xy 206.462881 -268.185767) (xy 206.41686 -268.213853) (xy 206.36724 -268.23494) (xy 206.315079 -268.248576)
			(xy 206.261488 -268.254473) (xy 206.207609 -268.252504) (xy 206.154591 -268.242711) (xy 206.103564 -268.225303)
			(xy 206.055616 -268.200651) (xy 206.011768 -268.169281) (xy 205.972955 -268.13186) (xy 205.940003 -268.089187)
			(xy 205.913617 -268.04217) (xy 205.894357 -267.991813) (xy 205.882634 -267.939189) (xy 205.878699 -267.885418)
			(xy 199.073008 -267.885418) (xy 199.072516 -267.912375) (xy 199.064666 -267.965715) (xy 199.049134 -268.017344)
			(xy 199.026249 -268.066161) (xy 198.996501 -268.111125) (xy 198.960523 -268.151279) (xy 198.919081 -268.185767)
			(xy 198.87306 -268.213853) (xy 198.82344 -268.23494) (xy 198.771279 -268.248576) (xy 198.717688 -268.254473)
			(xy 198.663809 -268.252504) (xy 198.610791 -268.242711) (xy 198.559764 -268.225303) (xy 198.511816 -268.200651)
			(xy 198.467968 -268.169281) (xy 198.429155 -268.13186) (xy 198.396203 -268.089187) (xy 198.369817 -268.04217)
			(xy 198.350557 -267.991813) (xy 198.338834 -267.939189) (xy 198.334899 -267.885418) (xy 191.528954 -267.885418)
			(xy 191.528462 -267.912375) (xy 191.520612 -267.965715) (xy 191.50508 -268.017344) (xy 191.482195 -268.066161)
			(xy 191.452447 -268.111125) (xy 191.416469 -268.151279) (xy 191.375027 -268.185767) (xy 191.329006 -268.213853)
			(xy 191.279386 -268.23494) (xy 191.227225 -268.248576) (xy 191.173634 -268.254473) (xy 191.119755 -268.252504)
			(xy 191.066737 -268.242711) (xy 191.01571 -268.225303) (xy 190.967762 -268.200651) (xy 190.923914 -268.169281)
			(xy 190.885101 -268.13186) (xy 190.852149 -268.089187) (xy 190.825763 -268.04217) (xy 190.806503 -267.991813)
			(xy 190.79478 -267.939189) (xy 190.790845 -267.885418) (xy 183.9849 -267.885418) (xy 183.984408 -267.912375)
			(xy 183.976558 -267.965715) (xy 183.961026 -268.017344) (xy 183.938141 -268.066161) (xy 183.908393 -268.111125)
			(xy 183.872415 -268.151279) (xy 183.830973 -268.185767) (xy 183.784952 -268.213853) (xy 183.735332 -268.23494)
			(xy 183.683171 -268.248576) (xy 183.62958 -268.254473) (xy 183.575701 -268.252504) (xy 183.522683 -268.242711)
			(xy 183.471656 -268.225303) (xy 183.423708 -268.200651) (xy 183.37986 -268.169281) (xy 183.341047 -268.13186)
			(xy 183.308095 -268.089187) (xy 183.281709 -268.04217) (xy 183.262449 -267.991813) (xy 183.250726 -267.939189)
			(xy 183.246791 -267.885418) (xy 177.881534 -267.885418) (xy 177.881534 -268.735302) (xy 179.146723 -268.735302)
			(xy 179.150658 -268.681531) (xy 179.162381 -268.628907) (xy 179.181641 -268.57855) (xy 179.208027 -268.531533)
			(xy 179.240979 -268.48886) (xy 179.279792 -268.451439) (xy 179.32364 -268.420069) (xy 179.371588 -268.395417)
			(xy 179.422615 -268.378009) (xy 179.475633 -268.368216) (xy 179.529512 -268.366247) (xy 179.583103 -268.372144)
			(xy 179.635264 -268.38578) (xy 179.684884 -268.406867) (xy 179.730905 -268.434953) (xy 179.772347 -268.469441)
			(xy 179.808325 -268.509595) (xy 179.838073 -268.554559) (xy 179.860958 -268.603376) (xy 179.87649 -268.655005)
			(xy 179.88434 -268.708345) (xy 179.884832 -268.735302) (xy 186.690777 -268.735302) (xy 186.694712 -268.681531)
			(xy 186.706435 -268.628907) (xy 186.725695 -268.57855) (xy 186.752081 -268.531533) (xy 186.785033 -268.48886)
			(xy 186.823846 -268.451439) (xy 186.867694 -268.420069) (xy 186.915642 -268.395417) (xy 186.966669 -268.378009)
			(xy 187.019687 -268.368216) (xy 187.073566 -268.366247) (xy 187.127157 -268.372144) (xy 187.179318 -268.38578)
			(xy 187.228938 -268.406867) (xy 187.274959 -268.434953) (xy 187.316401 -268.469441) (xy 187.352379 -268.509595)
			(xy 187.382127 -268.554559) (xy 187.405012 -268.603376) (xy 187.420544 -268.655005) (xy 187.428394 -268.708345)
			(xy 187.428886 -268.735302) (xy 194.234831 -268.735302) (xy 194.238766 -268.681531) (xy 194.250489 -268.628907)
			(xy 194.269749 -268.57855) (xy 194.296135 -268.531533) (xy 194.329087 -268.48886) (xy 194.3679 -268.451439)
			(xy 194.411748 -268.420069) (xy 194.459696 -268.395417) (xy 194.510723 -268.378009) (xy 194.563741 -268.368216)
			(xy 194.61762 -268.366247) (xy 194.671211 -268.372144) (xy 194.723372 -268.38578) (xy 194.772992 -268.406867)
			(xy 194.819013 -268.434953) (xy 194.860455 -268.469441) (xy 194.896433 -268.509595) (xy 194.926181 -268.554559)
			(xy 194.949066 -268.603376) (xy 194.964598 -268.655005) (xy 194.972448 -268.708345) (xy 194.97294 -268.735302)
			(xy 201.778631 -268.735302) (xy 201.782566 -268.681531) (xy 201.794289 -268.628907) (xy 201.813549 -268.57855)
			(xy 201.839935 -268.531533) (xy 201.872887 -268.48886) (xy 201.9117 -268.451439) (xy 201.955548 -268.420069)
			(xy 202.003496 -268.395417) (xy 202.054523 -268.378009) (xy 202.107541 -268.368216) (xy 202.16142 -268.366247)
			(xy 202.215011 -268.372144) (xy 202.267172 -268.38578) (xy 202.316792 -268.406867) (xy 202.362813 -268.434953)
			(xy 202.404255 -268.469441) (xy 202.440233 -268.509595) (xy 202.469981 -268.554559) (xy 202.492866 -268.603376)
			(xy 202.508398 -268.655005) (xy 202.516248 -268.708345) (xy 202.51674 -268.735302) (xy 202.516248 -268.762259)
			(xy 202.508398 -268.815599) (xy 202.492866 -268.867228) (xy 202.469981 -268.916045) (xy 202.440233 -268.961009)
			(xy 202.404255 -269.001163) (xy 202.362813 -269.035651) (xy 202.316792 -269.063737) (xy 202.267172 -269.084824)
			(xy 202.215011 -269.09846) (xy 202.16142 -269.104357) (xy 202.107541 -269.102388) (xy 202.054523 -269.092595)
			(xy 202.003496 -269.075187) (xy 201.955548 -269.050535) (xy 201.9117 -269.019165) (xy 201.872887 -268.981744)
			(xy 201.839935 -268.939071) (xy 201.813549 -268.892054) (xy 201.794289 -268.841697) (xy 201.782566 -268.789073)
			(xy 201.778631 -268.735302) (xy 194.97294 -268.735302) (xy 194.972448 -268.762259) (xy 194.964598 -268.815599)
			(xy 194.949066 -268.867228) (xy 194.926181 -268.916045) (xy 194.896433 -268.961009) (xy 194.860455 -269.001163)
			(xy 194.819013 -269.035651) (xy 194.772992 -269.063737) (xy 194.723372 -269.084824) (xy 194.671211 -269.09846)
			(xy 194.61762 -269.104357) (xy 194.563741 -269.102388) (xy 194.510723 -269.092595) (xy 194.459696 -269.075187)
			(xy 194.411748 -269.050535) (xy 194.3679 -269.019165) (xy 194.329087 -268.981744) (xy 194.296135 -268.939071)
			(xy 194.269749 -268.892054) (xy 194.250489 -268.841697) (xy 194.238766 -268.789073) (xy 194.234831 -268.735302)
			(xy 187.428886 -268.735302) (xy 187.428394 -268.762259) (xy 187.420544 -268.815599) (xy 187.405012 -268.867228)
			(xy 187.382127 -268.916045) (xy 187.352379 -268.961009) (xy 187.316401 -269.001163) (xy 187.274959 -269.035651)
			(xy 187.228938 -269.063737) (xy 187.179318 -269.084824) (xy 187.127157 -269.09846) (xy 187.073566 -269.104357)
			(xy 187.019687 -269.102388) (xy 186.966669 -269.092595) (xy 186.915642 -269.075187) (xy 186.867694 -269.050535)
			(xy 186.823846 -269.019165) (xy 186.785033 -268.981744) (xy 186.752081 -268.939071) (xy 186.725695 -268.892054)
			(xy 186.706435 -268.841697) (xy 186.694712 -268.789073) (xy 186.690777 -268.735302) (xy 179.884832 -268.735302)
			(xy 179.88434 -268.762259) (xy 179.87649 -268.815599) (xy 179.860958 -268.867228) (xy 179.838073 -268.916045)
			(xy 179.808325 -268.961009) (xy 179.772347 -269.001163) (xy 179.730905 -269.035651) (xy 179.684884 -269.063737)
			(xy 179.635264 -269.084824) (xy 179.583103 -269.09846) (xy 179.529512 -269.104357) (xy 179.475633 -269.102388)
			(xy 179.422615 -269.092595) (xy 179.371588 -269.075187) (xy 179.32364 -269.050535) (xy 179.279792 -269.019165)
			(xy 179.240979 -268.981744) (xy 179.208027 -268.939071) (xy 179.181641 -268.892054) (xy 179.162381 -268.841697)
			(xy 179.150658 -268.789073) (xy 179.146723 -268.735302) (xy 177.881534 -268.735302) (xy 177.881534 -269.58544)
			(xy 183.246791 -269.58544) (xy 183.250726 -269.531669) (xy 183.262449 -269.479045) (xy 183.281709 -269.428688)
			(xy 183.308095 -269.381671) (xy 183.341047 -269.338998) (xy 183.37986 -269.301577) (xy 183.423708 -269.270207)
			(xy 183.471656 -269.245555) (xy 183.522683 -269.228147) (xy 183.575701 -269.218354) (xy 183.62958 -269.216385)
			(xy 183.683171 -269.222282) (xy 183.735332 -269.235918) (xy 183.784952 -269.257005) (xy 183.830973 -269.285091)
			(xy 183.872415 -269.319579) (xy 183.908393 -269.359733) (xy 183.938141 -269.404697) (xy 183.961026 -269.453514)
			(xy 183.976558 -269.505143) (xy 183.984408 -269.558483) (xy 183.9849 -269.58544) (xy 190.790845 -269.58544)
			(xy 190.79478 -269.531669) (xy 190.806503 -269.479045) (xy 190.825763 -269.428688) (xy 190.852149 -269.381671)
			(xy 190.885101 -269.338998) (xy 190.923914 -269.301577) (xy 190.967762 -269.270207) (xy 191.01571 -269.245555)
			(xy 191.066737 -269.228147) (xy 191.119755 -269.218354) (xy 191.173634 -269.216385) (xy 191.227225 -269.222282)
			(xy 191.279386 -269.235918) (xy 191.329006 -269.257005) (xy 191.375027 -269.285091) (xy 191.416469 -269.319579)
			(xy 191.452447 -269.359733) (xy 191.482195 -269.404697) (xy 191.50508 -269.453514) (xy 191.520612 -269.505143)
			(xy 191.528462 -269.558483) (xy 191.528954 -269.58544) (xy 198.334899 -269.58544) (xy 198.338834 -269.531669)
			(xy 198.350557 -269.479045) (xy 198.369817 -269.428688) (xy 198.396203 -269.381671) (xy 198.429155 -269.338998)
			(xy 198.467968 -269.301577) (xy 198.511816 -269.270207) (xy 198.559764 -269.245555) (xy 198.610791 -269.228147)
			(xy 198.663809 -269.218354) (xy 198.717688 -269.216385) (xy 198.771279 -269.222282) (xy 198.82344 -269.235918)
			(xy 198.87306 -269.257005) (xy 198.919081 -269.285091) (xy 198.960523 -269.319579) (xy 198.996501 -269.359733)
			(xy 199.026249 -269.404697) (xy 199.049134 -269.453514) (xy 199.064666 -269.505143) (xy 199.072516 -269.558483)
			(xy 199.073008 -269.58544) (xy 205.878699 -269.58544) (xy 205.882634 -269.531669) (xy 205.894357 -269.479045)
			(xy 205.913617 -269.428688) (xy 205.940003 -269.381671) (xy 205.972955 -269.338998) (xy 206.011768 -269.301577)
			(xy 206.055616 -269.270207) (xy 206.103564 -269.245555) (xy 206.154591 -269.228147) (xy 206.207609 -269.218354)
			(xy 206.261488 -269.216385) (xy 206.315079 -269.222282) (xy 206.36724 -269.235918) (xy 206.41686 -269.257005)
			(xy 206.462881 -269.285091) (xy 206.504323 -269.319579) (xy 206.540301 -269.359733) (xy 206.570049 -269.404697)
			(xy 206.592934 -269.453514) (xy 206.608466 -269.505143) (xy 206.616316 -269.558483) (xy 206.616808 -269.58544)
			(xy 206.616316 -269.612397) (xy 206.608466 -269.665737) (xy 206.592934 -269.717366) (xy 206.570049 -269.766183)
			(xy 206.540301 -269.811147) (xy 206.504323 -269.851301) (xy 206.462881 -269.885789) (xy 206.41686 -269.913875)
			(xy 206.36724 -269.934962) (xy 206.315079 -269.948598) (xy 206.261488 -269.954495) (xy 206.207609 -269.952526)
			(xy 206.154591 -269.942733) (xy 206.103564 -269.925325) (xy 206.055616 -269.900673) (xy 206.011768 -269.869303)
			(xy 205.972955 -269.831882) (xy 205.940003 -269.789209) (xy 205.913617 -269.742192) (xy 205.894357 -269.691835)
			(xy 205.882634 -269.639211) (xy 205.878699 -269.58544) (xy 199.073008 -269.58544) (xy 199.072516 -269.612397)
			(xy 199.064666 -269.665737) (xy 199.049134 -269.717366) (xy 199.026249 -269.766183) (xy 198.996501 -269.811147)
			(xy 198.960523 -269.851301) (xy 198.919081 -269.885789) (xy 198.87306 -269.913875) (xy 198.82344 -269.934962)
			(xy 198.771279 -269.948598) (xy 198.717688 -269.954495) (xy 198.663809 -269.952526) (xy 198.610791 -269.942733)
			(xy 198.559764 -269.925325) (xy 198.511816 -269.900673) (xy 198.467968 -269.869303) (xy 198.429155 -269.831882)
			(xy 198.396203 -269.789209) (xy 198.369817 -269.742192) (xy 198.350557 -269.691835) (xy 198.338834 -269.639211)
			(xy 198.334899 -269.58544) (xy 191.528954 -269.58544) (xy 191.528462 -269.612397) (xy 191.520612 -269.665737)
			(xy 191.50508 -269.717366) (xy 191.482195 -269.766183) (xy 191.452447 -269.811147) (xy 191.416469 -269.851301)
			(xy 191.375027 -269.885789) (xy 191.329006 -269.913875) (xy 191.279386 -269.934962) (xy 191.227225 -269.948598)
			(xy 191.173634 -269.954495) (xy 191.119755 -269.952526) (xy 191.066737 -269.942733) (xy 191.01571 -269.925325)
			(xy 190.967762 -269.900673) (xy 190.923914 -269.869303) (xy 190.885101 -269.831882) (xy 190.852149 -269.789209)
			(xy 190.825763 -269.742192) (xy 190.806503 -269.691835) (xy 190.79478 -269.639211) (xy 190.790845 -269.58544)
			(xy 183.9849 -269.58544) (xy 183.984408 -269.612397) (xy 183.976558 -269.665737) (xy 183.961026 -269.717366)
			(xy 183.938141 -269.766183) (xy 183.908393 -269.811147) (xy 183.872415 -269.851301) (xy 183.830973 -269.885789)
			(xy 183.784952 -269.913875) (xy 183.735332 -269.934962) (xy 183.683171 -269.948598) (xy 183.62958 -269.954495)
			(xy 183.575701 -269.952526) (xy 183.522683 -269.942733) (xy 183.471656 -269.925325) (xy 183.423708 -269.900673)
			(xy 183.37986 -269.869303) (xy 183.341047 -269.831882) (xy 183.308095 -269.789209) (xy 183.281709 -269.742192)
			(xy 183.262449 -269.691835) (xy 183.250726 -269.639211) (xy 183.246791 -269.58544) (xy 177.881534 -269.58544)
			(xy 177.881534 -270.435324) (xy 179.146723 -270.435324) (xy 179.150658 -270.381553) (xy 179.162381 -270.328929)
			(xy 179.181641 -270.278572) (xy 179.208027 -270.231555) (xy 179.240979 -270.188882) (xy 179.279792 -270.151461)
			(xy 179.32364 -270.120091) (xy 179.371588 -270.095439) (xy 179.422615 -270.078031) (xy 179.475633 -270.068238)
			(xy 179.529512 -270.066269) (xy 179.583103 -270.072166) (xy 179.635264 -270.085802) (xy 179.684884 -270.106889)
			(xy 179.730905 -270.134975) (xy 179.772347 -270.169463) (xy 179.808325 -270.209617) (xy 179.838073 -270.254581)
			(xy 179.860958 -270.303398) (xy 179.87649 -270.355027) (xy 179.88434 -270.408367) (xy 179.884832 -270.435324)
			(xy 183.246791 -270.435324) (xy 183.250726 -270.381553) (xy 183.262449 -270.328929) (xy 183.281709 -270.278572)
			(xy 183.308095 -270.231555) (xy 183.341047 -270.188882) (xy 183.37986 -270.151461) (xy 183.423708 -270.120091)
			(xy 183.471656 -270.095439) (xy 183.522683 -270.078031) (xy 183.575701 -270.068238) (xy 183.62958 -270.066269)
			(xy 183.683171 -270.072166) (xy 183.735332 -270.085802) (xy 183.784952 -270.106889) (xy 183.830973 -270.134975)
			(xy 183.872415 -270.169463) (xy 183.908393 -270.209617) (xy 183.938141 -270.254581) (xy 183.961026 -270.303398)
			(xy 183.976558 -270.355027) (xy 183.984408 -270.408367) (xy 183.9849 -270.435324) (xy 186.690777 -270.435324)
			(xy 186.694712 -270.381553) (xy 186.706435 -270.328929) (xy 186.725695 -270.278572) (xy 186.752081 -270.231555)
			(xy 186.785033 -270.188882) (xy 186.823846 -270.151461) (xy 186.867694 -270.120091) (xy 186.915642 -270.095439)
			(xy 186.966669 -270.078031) (xy 187.019687 -270.068238) (xy 187.073566 -270.066269) (xy 187.127157 -270.072166)
			(xy 187.179318 -270.085802) (xy 187.228938 -270.106889) (xy 187.274959 -270.134975) (xy 187.316401 -270.169463)
			(xy 187.352379 -270.209617) (xy 187.382127 -270.254581) (xy 187.405012 -270.303398) (xy 187.420544 -270.355027)
			(xy 187.428394 -270.408367) (xy 187.428886 -270.435324) (xy 190.790845 -270.435324) (xy 190.79478 -270.381553)
			(xy 190.806503 -270.328929) (xy 190.825763 -270.278572) (xy 190.852149 -270.231555) (xy 190.885101 -270.188882)
			(xy 190.923914 -270.151461) (xy 190.967762 -270.120091) (xy 191.01571 -270.095439) (xy 191.066737 -270.078031)
			(xy 191.119755 -270.068238) (xy 191.173634 -270.066269) (xy 191.227225 -270.072166) (xy 191.279386 -270.085802)
			(xy 191.329006 -270.106889) (xy 191.375027 -270.134975) (xy 191.416469 -270.169463) (xy 191.452447 -270.209617)
			(xy 191.482195 -270.254581) (xy 191.50508 -270.303398) (xy 191.520612 -270.355027) (xy 191.528462 -270.408367)
			(xy 191.528954 -270.435324) (xy 194.234831 -270.435324) (xy 194.238766 -270.381553) (xy 194.250489 -270.328929)
			(xy 194.269749 -270.278572) (xy 194.296135 -270.231555) (xy 194.329087 -270.188882) (xy 194.3679 -270.151461)
			(xy 194.411748 -270.120091) (xy 194.459696 -270.095439) (xy 194.510723 -270.078031) (xy 194.563741 -270.068238)
			(xy 194.61762 -270.066269) (xy 194.671211 -270.072166) (xy 194.723372 -270.085802) (xy 194.772992 -270.106889)
			(xy 194.819013 -270.134975) (xy 194.860455 -270.169463) (xy 194.896433 -270.209617) (xy 194.926181 -270.254581)
			(xy 194.949066 -270.303398) (xy 194.964598 -270.355027) (xy 194.972448 -270.408367) (xy 194.97294 -270.435324)
			(xy 198.334899 -270.435324) (xy 198.338834 -270.381553) (xy 198.350557 -270.328929) (xy 198.369817 -270.278572)
			(xy 198.396203 -270.231555) (xy 198.429155 -270.188882) (xy 198.467968 -270.151461) (xy 198.511816 -270.120091)
			(xy 198.559764 -270.095439) (xy 198.610791 -270.078031) (xy 198.663809 -270.068238) (xy 198.717688 -270.066269)
			(xy 198.771279 -270.072166) (xy 198.82344 -270.085802) (xy 198.87306 -270.106889) (xy 198.919081 -270.134975)
			(xy 198.960523 -270.169463) (xy 198.996501 -270.209617) (xy 199.026249 -270.254581) (xy 199.049134 -270.303398)
			(xy 199.064666 -270.355027) (xy 199.072516 -270.408367) (xy 199.073008 -270.435324) (xy 201.778631 -270.435324)
			(xy 201.782566 -270.381553) (xy 201.794289 -270.328929) (xy 201.813549 -270.278572) (xy 201.839935 -270.231555)
			(xy 201.872887 -270.188882) (xy 201.9117 -270.151461) (xy 201.955548 -270.120091) (xy 202.003496 -270.095439)
			(xy 202.054523 -270.078031) (xy 202.107541 -270.068238) (xy 202.16142 -270.066269) (xy 202.215011 -270.072166)
			(xy 202.267172 -270.085802) (xy 202.316792 -270.106889) (xy 202.362813 -270.134975) (xy 202.404255 -270.169463)
			(xy 202.440233 -270.209617) (xy 202.469981 -270.254581) (xy 202.492866 -270.303398) (xy 202.508398 -270.355027)
			(xy 202.516248 -270.408367) (xy 202.51674 -270.435324) (xy 205.878699 -270.435324) (xy 205.882634 -270.381553)
			(xy 205.894357 -270.328929) (xy 205.913617 -270.278572) (xy 205.940003 -270.231555) (xy 205.972955 -270.188882)
			(xy 206.011768 -270.151461) (xy 206.055616 -270.120091) (xy 206.103564 -270.095439) (xy 206.154591 -270.078031)
			(xy 206.207609 -270.068238) (xy 206.261488 -270.066269) (xy 206.315079 -270.072166) (xy 206.36724 -270.085802)
			(xy 206.41686 -270.106889) (xy 206.462881 -270.134975) (xy 206.504323 -270.169463) (xy 206.540301 -270.209617)
			(xy 206.570049 -270.254581) (xy 206.592934 -270.303398) (xy 206.608466 -270.355027) (xy 206.616316 -270.408367)
			(xy 206.616808 -270.435324) (xy 206.616316 -270.462281) (xy 206.608466 -270.515621) (xy 206.592934 -270.56725)
			(xy 206.570049 -270.616067) (xy 206.540301 -270.661031) (xy 206.504323 -270.701185) (xy 206.462881 -270.735673)
			(xy 206.41686 -270.763759) (xy 206.36724 -270.784846) (xy 206.315079 -270.798482) (xy 206.261488 -270.804379)
			(xy 206.207609 -270.80241) (xy 206.154591 -270.792617) (xy 206.103564 -270.775209) (xy 206.055616 -270.750557)
			(xy 206.011768 -270.719187) (xy 205.972955 -270.681766) (xy 205.940003 -270.639093) (xy 205.913617 -270.592076)
			(xy 205.894357 -270.541719) (xy 205.882634 -270.489095) (xy 205.878699 -270.435324) (xy 202.51674 -270.435324)
			(xy 202.516248 -270.462281) (xy 202.508398 -270.515621) (xy 202.492866 -270.56725) (xy 202.469981 -270.616067)
			(xy 202.440233 -270.661031) (xy 202.404255 -270.701185) (xy 202.362813 -270.735673) (xy 202.316792 -270.763759)
			(xy 202.267172 -270.784846) (xy 202.215011 -270.798482) (xy 202.16142 -270.804379) (xy 202.107541 -270.80241)
			(xy 202.054523 -270.792617) (xy 202.003496 -270.775209) (xy 201.955548 -270.750557) (xy 201.9117 -270.719187)
			(xy 201.872887 -270.681766) (xy 201.839935 -270.639093) (xy 201.813549 -270.592076) (xy 201.794289 -270.541719)
			(xy 201.782566 -270.489095) (xy 201.778631 -270.435324) (xy 199.073008 -270.435324) (xy 199.072516 -270.462281)
			(xy 199.064666 -270.515621) (xy 199.049134 -270.56725) (xy 199.026249 -270.616067) (xy 198.996501 -270.661031)
			(xy 198.960523 -270.701185) (xy 198.919081 -270.735673) (xy 198.87306 -270.763759) (xy 198.82344 -270.784846)
			(xy 198.771279 -270.798482) (xy 198.717688 -270.804379) (xy 198.663809 -270.80241) (xy 198.610791 -270.792617)
			(xy 198.559764 -270.775209) (xy 198.511816 -270.750557) (xy 198.467968 -270.719187) (xy 198.429155 -270.681766)
			(xy 198.396203 -270.639093) (xy 198.369817 -270.592076) (xy 198.350557 -270.541719) (xy 198.338834 -270.489095)
			(xy 198.334899 -270.435324) (xy 194.97294 -270.435324) (xy 194.972448 -270.462281) (xy 194.964598 -270.515621)
			(xy 194.949066 -270.56725) (xy 194.926181 -270.616067) (xy 194.896433 -270.661031) (xy 194.860455 -270.701185)
			(xy 194.819013 -270.735673) (xy 194.772992 -270.763759) (xy 194.723372 -270.784846) (xy 194.671211 -270.798482)
			(xy 194.61762 -270.804379) (xy 194.563741 -270.80241) (xy 194.510723 -270.792617) (xy 194.459696 -270.775209)
			(xy 194.411748 -270.750557) (xy 194.3679 -270.719187) (xy 194.329087 -270.681766) (xy 194.296135 -270.639093)
			(xy 194.269749 -270.592076) (xy 194.250489 -270.541719) (xy 194.238766 -270.489095) (xy 194.234831 -270.435324)
			(xy 191.528954 -270.435324) (xy 191.528462 -270.462281) (xy 191.520612 -270.515621) (xy 191.50508 -270.56725)
			(xy 191.482195 -270.616067) (xy 191.452447 -270.661031) (xy 191.416469 -270.701185) (xy 191.375027 -270.735673)
			(xy 191.329006 -270.763759) (xy 191.279386 -270.784846) (xy 191.227225 -270.798482) (xy 191.173634 -270.804379)
			(xy 191.119755 -270.80241) (xy 191.066737 -270.792617) (xy 191.01571 -270.775209) (xy 190.967762 -270.750557)
			(xy 190.923914 -270.719187) (xy 190.885101 -270.681766) (xy 190.852149 -270.639093) (xy 190.825763 -270.592076)
			(xy 190.806503 -270.541719) (xy 190.79478 -270.489095) (xy 190.790845 -270.435324) (xy 187.428886 -270.435324)
			(xy 187.428394 -270.462281) (xy 187.420544 -270.515621) (xy 187.405012 -270.56725) (xy 187.382127 -270.616067)
			(xy 187.352379 -270.661031) (xy 187.316401 -270.701185) (xy 187.274959 -270.735673) (xy 187.228938 -270.763759)
			(xy 187.179318 -270.784846) (xy 187.127157 -270.798482) (xy 187.073566 -270.804379) (xy 187.019687 -270.80241)
			(xy 186.966669 -270.792617) (xy 186.915642 -270.775209) (xy 186.867694 -270.750557) (xy 186.823846 -270.719187)
			(xy 186.785033 -270.681766) (xy 186.752081 -270.639093) (xy 186.725695 -270.592076) (xy 186.706435 -270.541719)
			(xy 186.694712 -270.489095) (xy 186.690777 -270.435324) (xy 183.9849 -270.435324) (xy 183.984408 -270.462281)
			(xy 183.976558 -270.515621) (xy 183.961026 -270.56725) (xy 183.938141 -270.616067) (xy 183.908393 -270.661031)
			(xy 183.872415 -270.701185) (xy 183.830973 -270.735673) (xy 183.784952 -270.763759) (xy 183.735332 -270.784846)
			(xy 183.683171 -270.798482) (xy 183.62958 -270.804379) (xy 183.575701 -270.80241) (xy 183.522683 -270.792617)
			(xy 183.471656 -270.775209) (xy 183.423708 -270.750557) (xy 183.37986 -270.719187) (xy 183.341047 -270.681766)
			(xy 183.308095 -270.639093) (xy 183.281709 -270.592076) (xy 183.262449 -270.541719) (xy 183.250726 -270.489095)
			(xy 183.246791 -270.435324) (xy 179.884832 -270.435324) (xy 179.88434 -270.462281) (xy 179.87649 -270.515621)
			(xy 179.860958 -270.56725) (xy 179.838073 -270.616067) (xy 179.808325 -270.661031) (xy 179.772347 -270.701185)
			(xy 179.730905 -270.735673) (xy 179.684884 -270.763759) (xy 179.635264 -270.784846) (xy 179.583103 -270.798482)
			(xy 179.529512 -270.804379) (xy 179.475633 -270.80241) (xy 179.422615 -270.792617) (xy 179.371588 -270.775209)
			(xy 179.32364 -270.750557) (xy 179.279792 -270.719187) (xy 179.240979 -270.681766) (xy 179.208027 -270.639093)
			(xy 179.181641 -270.592076) (xy 179.162381 -270.541719) (xy 179.150658 -270.489095) (xy 179.146723 -270.435324)
			(xy 177.881534 -270.435324) (xy 177.881534 -271.285208) (xy 179.146723 -271.285208) (xy 179.150658 -271.231437)
			(xy 179.162381 -271.178813) (xy 179.181641 -271.128456) (xy 179.208027 -271.081439) (xy 179.240979 -271.038766)
			(xy 179.279792 -271.001345) (xy 179.32364 -270.969975) (xy 179.371588 -270.945323) (xy 179.422615 -270.927915)
			(xy 179.475633 -270.918122) (xy 179.529512 -270.916153) (xy 179.583103 -270.92205) (xy 179.635264 -270.935686)
			(xy 179.684884 -270.956773) (xy 179.730905 -270.984859) (xy 179.772347 -271.019347) (xy 179.808325 -271.059501)
			(xy 179.838073 -271.104465) (xy 179.860958 -271.153282) (xy 179.87649 -271.204911) (xy 179.88434 -271.258251)
			(xy 179.884832 -271.285208) (xy 186.690777 -271.285208) (xy 186.694712 -271.231437) (xy 186.706435 -271.178813)
			(xy 186.725695 -271.128456) (xy 186.752081 -271.081439) (xy 186.785033 -271.038766) (xy 186.823846 -271.001345)
			(xy 186.867694 -270.969975) (xy 186.915642 -270.945323) (xy 186.966669 -270.927915) (xy 187.019687 -270.918122)
			(xy 187.073566 -270.916153) (xy 187.127157 -270.92205) (xy 187.179318 -270.935686) (xy 187.228938 -270.956773)
			(xy 187.274959 -270.984859) (xy 187.316401 -271.019347) (xy 187.352379 -271.059501) (xy 187.382127 -271.104465)
			(xy 187.405012 -271.153282) (xy 187.420544 -271.204911) (xy 187.428394 -271.258251) (xy 187.428886 -271.285208)
			(xy 194.234831 -271.285208) (xy 194.238766 -271.231437) (xy 194.250489 -271.178813) (xy 194.269749 -271.128456)
			(xy 194.296135 -271.081439) (xy 194.329087 -271.038766) (xy 194.3679 -271.001345) (xy 194.411748 -270.969975)
			(xy 194.459696 -270.945323) (xy 194.510723 -270.927915) (xy 194.563741 -270.918122) (xy 194.61762 -270.916153)
			(xy 194.671211 -270.92205) (xy 194.723372 -270.935686) (xy 194.772992 -270.956773) (xy 194.819013 -270.984859)
			(xy 194.860455 -271.019347) (xy 194.896433 -271.059501) (xy 194.926181 -271.104465) (xy 194.949066 -271.153282)
			(xy 194.964598 -271.204911) (xy 194.972448 -271.258251) (xy 194.97294 -271.285208) (xy 201.778631 -271.285208)
			(xy 201.782566 -271.231437) (xy 201.794289 -271.178813) (xy 201.813549 -271.128456) (xy 201.839935 -271.081439)
			(xy 201.872887 -271.038766) (xy 201.9117 -271.001345) (xy 201.955548 -270.969975) (xy 202.003496 -270.945323)
			(xy 202.054523 -270.927915) (xy 202.107541 -270.918122) (xy 202.16142 -270.916153) (xy 202.215011 -270.92205)
			(xy 202.267172 -270.935686) (xy 202.316792 -270.956773) (xy 202.362813 -270.984859) (xy 202.404255 -271.019347)
			(xy 202.440233 -271.059501) (xy 202.469981 -271.104465) (xy 202.492866 -271.153282) (xy 202.508398 -271.204911)
			(xy 202.516248 -271.258251) (xy 202.51674 -271.285208) (xy 202.516248 -271.312165) (xy 202.508398 -271.365505)
			(xy 202.492866 -271.417134) (xy 202.469981 -271.465951) (xy 202.440233 -271.510915) (xy 202.404255 -271.551069)
			(xy 202.362813 -271.585557) (xy 202.316792 -271.613643) (xy 202.267172 -271.63473) (xy 202.215011 -271.648366)
			(xy 202.16142 -271.654263) (xy 202.107541 -271.652294) (xy 202.054523 -271.642501) (xy 202.003496 -271.625093)
			(xy 201.955548 -271.600441) (xy 201.9117 -271.569071) (xy 201.872887 -271.53165) (xy 201.839935 -271.488977)
			(xy 201.813549 -271.44196) (xy 201.794289 -271.391603) (xy 201.782566 -271.338979) (xy 201.778631 -271.285208)
			(xy 194.97294 -271.285208) (xy 194.972448 -271.312165) (xy 194.964598 -271.365505) (xy 194.949066 -271.417134)
			(xy 194.926181 -271.465951) (xy 194.896433 -271.510915) (xy 194.860455 -271.551069) (xy 194.819013 -271.585557)
			(xy 194.772992 -271.613643) (xy 194.723372 -271.63473) (xy 194.671211 -271.648366) (xy 194.61762 -271.654263)
			(xy 194.563741 -271.652294) (xy 194.510723 -271.642501) (xy 194.459696 -271.625093) (xy 194.411748 -271.600441)
			(xy 194.3679 -271.569071) (xy 194.329087 -271.53165) (xy 194.296135 -271.488977) (xy 194.269749 -271.44196)
			(xy 194.250489 -271.391603) (xy 194.238766 -271.338979) (xy 194.234831 -271.285208) (xy 187.428886 -271.285208)
			(xy 187.428394 -271.312165) (xy 187.420544 -271.365505) (xy 187.405012 -271.417134) (xy 187.382127 -271.465951)
			(xy 187.352379 -271.510915) (xy 187.316401 -271.551069) (xy 187.274959 -271.585557) (xy 187.228938 -271.613643)
			(xy 187.179318 -271.63473) (xy 187.127157 -271.648366) (xy 187.073566 -271.654263) (xy 187.019687 -271.652294)
			(xy 186.966669 -271.642501) (xy 186.915642 -271.625093) (xy 186.867694 -271.600441) (xy 186.823846 -271.569071)
			(xy 186.785033 -271.53165) (xy 186.752081 -271.488977) (xy 186.725695 -271.44196) (xy 186.706435 -271.391603)
			(xy 186.694712 -271.338979) (xy 186.690777 -271.285208) (xy 179.884832 -271.285208) (xy 179.88434 -271.312165)
			(xy 179.87649 -271.365505) (xy 179.860958 -271.417134) (xy 179.838073 -271.465951) (xy 179.808325 -271.510915)
			(xy 179.772347 -271.551069) (xy 179.730905 -271.585557) (xy 179.684884 -271.613643) (xy 179.635264 -271.63473)
			(xy 179.583103 -271.648366) (xy 179.529512 -271.654263) (xy 179.475633 -271.652294) (xy 179.422615 -271.642501)
			(xy 179.371588 -271.625093) (xy 179.32364 -271.600441) (xy 179.279792 -271.569071) (xy 179.240979 -271.53165)
			(xy 179.208027 -271.488977) (xy 179.181641 -271.44196) (xy 179.162381 -271.391603) (xy 179.150658 -271.338979)
			(xy 179.146723 -271.285208) (xy 177.881534 -271.285208) (xy 177.881534 -272.135346) (xy 183.246791 -272.135346)
			(xy 183.250726 -272.081575) (xy 183.262449 -272.028951) (xy 183.281709 -271.978594) (xy 183.308095 -271.931577)
			(xy 183.341047 -271.888904) (xy 183.37986 -271.851483) (xy 183.423708 -271.820113) (xy 183.471656 -271.795461)
			(xy 183.522683 -271.778053) (xy 183.575701 -271.76826) (xy 183.62958 -271.766291) (xy 183.683171 -271.772188)
			(xy 183.735332 -271.785824) (xy 183.784952 -271.806911) (xy 183.830973 -271.834997) (xy 183.872415 -271.869485)
			(xy 183.908393 -271.909639) (xy 183.938141 -271.954603) (xy 183.961026 -272.00342) (xy 183.976558 -272.055049)
			(xy 183.984408 -272.108389) (xy 183.9849 -272.135346) (xy 190.790845 -272.135346) (xy 190.79478 -272.081575)
			(xy 190.806503 -272.028951) (xy 190.825763 -271.978594) (xy 190.852149 -271.931577) (xy 190.885101 -271.888904)
			(xy 190.923914 -271.851483) (xy 190.967762 -271.820113) (xy 191.01571 -271.795461) (xy 191.066737 -271.778053)
			(xy 191.119755 -271.76826) (xy 191.173634 -271.766291) (xy 191.227225 -271.772188) (xy 191.279386 -271.785824)
			(xy 191.329006 -271.806911) (xy 191.375027 -271.834997) (xy 191.416469 -271.869485) (xy 191.452447 -271.909639)
			(xy 191.482195 -271.954603) (xy 191.50508 -272.00342) (xy 191.520612 -272.055049) (xy 191.528462 -272.108389)
			(xy 191.528954 -272.135346) (xy 198.334899 -272.135346) (xy 198.338834 -272.081575) (xy 198.350557 -272.028951)
			(xy 198.369817 -271.978594) (xy 198.396203 -271.931577) (xy 198.429155 -271.888904) (xy 198.467968 -271.851483)
			(xy 198.511816 -271.820113) (xy 198.559764 -271.795461) (xy 198.610791 -271.778053) (xy 198.663809 -271.76826)
			(xy 198.717688 -271.766291) (xy 198.771279 -271.772188) (xy 198.82344 -271.785824) (xy 198.87306 -271.806911)
			(xy 198.919081 -271.834997) (xy 198.960523 -271.869485) (xy 198.996501 -271.909639) (xy 199.026249 -271.954603)
			(xy 199.049134 -272.00342) (xy 199.064666 -272.055049) (xy 199.072516 -272.108389) (xy 199.073008 -272.135346)
			(xy 205.878699 -272.135346) (xy 205.882634 -272.081575) (xy 205.894357 -272.028951) (xy 205.913617 -271.978594)
			(xy 205.940003 -271.931577) (xy 205.972955 -271.888904) (xy 206.011768 -271.851483) (xy 206.055616 -271.820113)
			(xy 206.103564 -271.795461) (xy 206.154591 -271.778053) (xy 206.207609 -271.76826) (xy 206.261488 -271.766291)
			(xy 206.315079 -271.772188) (xy 206.36724 -271.785824) (xy 206.41686 -271.806911) (xy 206.462881 -271.834997)
			(xy 206.504323 -271.869485) (xy 206.540301 -271.909639) (xy 206.570049 -271.954603) (xy 206.592934 -272.00342)
			(xy 206.608466 -272.055049) (xy 206.616316 -272.108389) (xy 206.616808 -272.135346) (xy 206.616316 -272.162303)
			(xy 206.608466 -272.215643) (xy 206.592934 -272.267272) (xy 206.570049 -272.316089) (xy 206.540301 -272.361053)
			(xy 206.504323 -272.401207) (xy 206.462881 -272.435695) (xy 206.41686 -272.463781) (xy 206.36724 -272.484868)
			(xy 206.315079 -272.498504) (xy 206.261488 -272.504401) (xy 206.207609 -272.502432) (xy 206.154591 -272.492639)
			(xy 206.103564 -272.475231) (xy 206.055616 -272.450579) (xy 206.011768 -272.419209) (xy 205.972955 -272.381788)
			(xy 205.940003 -272.339115) (xy 205.913617 -272.292098) (xy 205.894357 -272.241741) (xy 205.882634 -272.189117)
			(xy 205.878699 -272.135346) (xy 199.073008 -272.135346) (xy 199.072516 -272.162303) (xy 199.064666 -272.215643)
			(xy 199.049134 -272.267272) (xy 199.026249 -272.316089) (xy 198.996501 -272.361053) (xy 198.960523 -272.401207)
			(xy 198.919081 -272.435695) (xy 198.87306 -272.463781) (xy 198.82344 -272.484868) (xy 198.771279 -272.498504)
			(xy 198.717688 -272.504401) (xy 198.663809 -272.502432) (xy 198.610791 -272.492639) (xy 198.559764 -272.475231)
			(xy 198.511816 -272.450579) (xy 198.467968 -272.419209) (xy 198.429155 -272.381788) (xy 198.396203 -272.339115)
			(xy 198.369817 -272.292098) (xy 198.350557 -272.241741) (xy 198.338834 -272.189117) (xy 198.334899 -272.135346)
			(xy 191.528954 -272.135346) (xy 191.528462 -272.162303) (xy 191.520612 -272.215643) (xy 191.50508 -272.267272)
			(xy 191.482195 -272.316089) (xy 191.452447 -272.361053) (xy 191.416469 -272.401207) (xy 191.375027 -272.435695)
			(xy 191.329006 -272.463781) (xy 191.279386 -272.484868) (xy 191.227225 -272.498504) (xy 191.173634 -272.504401)
			(xy 191.119755 -272.502432) (xy 191.066737 -272.492639) (xy 191.01571 -272.475231) (xy 190.967762 -272.450579)
			(xy 190.923914 -272.419209) (xy 190.885101 -272.381788) (xy 190.852149 -272.339115) (xy 190.825763 -272.292098)
			(xy 190.806503 -272.241741) (xy 190.79478 -272.189117) (xy 190.790845 -272.135346) (xy 183.9849 -272.135346)
			(xy 183.984408 -272.162303) (xy 183.976558 -272.215643) (xy 183.961026 -272.267272) (xy 183.938141 -272.316089)
			(xy 183.908393 -272.361053) (xy 183.872415 -272.401207) (xy 183.830973 -272.435695) (xy 183.784952 -272.463781)
			(xy 183.735332 -272.484868) (xy 183.683171 -272.498504) (xy 183.62958 -272.504401) (xy 183.575701 -272.502432)
			(xy 183.522683 -272.492639) (xy 183.471656 -272.475231) (xy 183.423708 -272.450579) (xy 183.37986 -272.419209)
			(xy 183.341047 -272.381788) (xy 183.308095 -272.339115) (xy 183.281709 -272.292098) (xy 183.262449 -272.241741)
			(xy 183.250726 -272.189117) (xy 183.246791 -272.135346) (xy 177.881534 -272.135346) (xy 177.881534 -272.98523)
			(xy 179.146723 -272.98523) (xy 179.150658 -272.931459) (xy 179.162381 -272.878835) (xy 179.181641 -272.828478)
			(xy 179.208027 -272.781461) (xy 179.240979 -272.738788) (xy 179.279792 -272.701367) (xy 179.32364 -272.669997)
			(xy 179.371588 -272.645345) (xy 179.422615 -272.627937) (xy 179.475633 -272.618144) (xy 179.529512 -272.616175)
			(xy 179.583103 -272.622072) (xy 179.635264 -272.635708) (xy 179.684884 -272.656795) (xy 179.730905 -272.684881)
			(xy 179.772347 -272.719369) (xy 179.808325 -272.759523) (xy 179.838073 -272.804487) (xy 179.860958 -272.853304)
			(xy 179.87649 -272.904933) (xy 179.88434 -272.958273) (xy 179.884832 -272.98523) (xy 186.690777 -272.98523)
			(xy 186.694712 -272.931459) (xy 186.706435 -272.878835) (xy 186.725695 -272.828478) (xy 186.752081 -272.781461)
			(xy 186.785033 -272.738788) (xy 186.823846 -272.701367) (xy 186.867694 -272.669997) (xy 186.915642 -272.645345)
			(xy 186.966669 -272.627937) (xy 187.019687 -272.618144) (xy 187.073566 -272.616175) (xy 187.127157 -272.622072)
			(xy 187.179318 -272.635708) (xy 187.228938 -272.656795) (xy 187.274959 -272.684881) (xy 187.316401 -272.719369)
			(xy 187.352379 -272.759523) (xy 187.382127 -272.804487) (xy 187.405012 -272.853304) (xy 187.420544 -272.904933)
			(xy 187.428394 -272.958273) (xy 187.428886 -272.98523) (xy 194.234831 -272.98523) (xy 194.238766 -272.931459)
			(xy 194.250489 -272.878835) (xy 194.269749 -272.828478) (xy 194.296135 -272.781461) (xy 194.329087 -272.738788)
			(xy 194.3679 -272.701367) (xy 194.411748 -272.669997) (xy 194.459696 -272.645345) (xy 194.510723 -272.627937)
			(xy 194.563741 -272.618144) (xy 194.61762 -272.616175) (xy 194.671211 -272.622072) (xy 194.723372 -272.635708)
			(xy 194.772992 -272.656795) (xy 194.819013 -272.684881) (xy 194.860455 -272.719369) (xy 194.896433 -272.759523)
			(xy 194.926181 -272.804487) (xy 194.949066 -272.853304) (xy 194.964598 -272.904933) (xy 194.972448 -272.958273)
			(xy 194.97294 -272.98523) (xy 201.778631 -272.98523) (xy 201.782566 -272.931459) (xy 201.794289 -272.878835)
			(xy 201.813549 -272.828478) (xy 201.839935 -272.781461) (xy 201.872887 -272.738788) (xy 201.9117 -272.701367)
			(xy 201.955548 -272.669997) (xy 202.003496 -272.645345) (xy 202.054523 -272.627937) (xy 202.107541 -272.618144)
			(xy 202.16142 -272.616175) (xy 202.215011 -272.622072) (xy 202.267172 -272.635708) (xy 202.316792 -272.656795)
			(xy 202.362813 -272.684881) (xy 202.404255 -272.719369) (xy 202.440233 -272.759523) (xy 202.469981 -272.804487)
			(xy 202.492866 -272.853304) (xy 202.508398 -272.904933) (xy 202.516248 -272.958273) (xy 202.51674 -272.98523)
			(xy 202.516248 -273.012187) (xy 202.508398 -273.065527) (xy 202.492866 -273.117156) (xy 202.469981 -273.165973)
			(xy 202.440233 -273.210937) (xy 202.404255 -273.251091) (xy 202.362813 -273.285579) (xy 202.316792 -273.313665)
			(xy 202.267172 -273.334752) (xy 202.215011 -273.348388) (xy 202.16142 -273.354285) (xy 202.107541 -273.352316)
			(xy 202.054523 -273.342523) (xy 202.003496 -273.325115) (xy 201.955548 -273.300463) (xy 201.9117 -273.269093)
			(xy 201.872887 -273.231672) (xy 201.839935 -273.188999) (xy 201.813549 -273.141982) (xy 201.794289 -273.091625)
			(xy 201.782566 -273.039001) (xy 201.778631 -272.98523) (xy 194.97294 -272.98523) (xy 194.972448 -273.012187)
			(xy 194.964598 -273.065527) (xy 194.949066 -273.117156) (xy 194.926181 -273.165973) (xy 194.896433 -273.210937)
			(xy 194.860455 -273.251091) (xy 194.819013 -273.285579) (xy 194.772992 -273.313665) (xy 194.723372 -273.334752)
			(xy 194.671211 -273.348388) (xy 194.61762 -273.354285) (xy 194.563741 -273.352316) (xy 194.510723 -273.342523)
			(xy 194.459696 -273.325115) (xy 194.411748 -273.300463) (xy 194.3679 -273.269093) (xy 194.329087 -273.231672)
			(xy 194.296135 -273.188999) (xy 194.269749 -273.141982) (xy 194.250489 -273.091625) (xy 194.238766 -273.039001)
			(xy 194.234831 -272.98523) (xy 187.428886 -272.98523) (xy 187.428394 -273.012187) (xy 187.420544 -273.065527)
			(xy 187.405012 -273.117156) (xy 187.382127 -273.165973) (xy 187.352379 -273.210937) (xy 187.316401 -273.251091)
			(xy 187.274959 -273.285579) (xy 187.228938 -273.313665) (xy 187.179318 -273.334752) (xy 187.127157 -273.348388)
			(xy 187.073566 -273.354285) (xy 187.019687 -273.352316) (xy 186.966669 -273.342523) (xy 186.915642 -273.325115)
			(xy 186.867694 -273.300463) (xy 186.823846 -273.269093) (xy 186.785033 -273.231672) (xy 186.752081 -273.188999)
			(xy 186.725695 -273.141982) (xy 186.706435 -273.091625) (xy 186.694712 -273.039001) (xy 186.690777 -272.98523)
			(xy 179.884832 -272.98523) (xy 179.88434 -273.012187) (xy 179.87649 -273.065527) (xy 179.860958 -273.117156)
			(xy 179.838073 -273.165973) (xy 179.808325 -273.210937) (xy 179.772347 -273.251091) (xy 179.730905 -273.285579)
			(xy 179.684884 -273.313665) (xy 179.635264 -273.334752) (xy 179.583103 -273.348388) (xy 179.529512 -273.354285)
			(xy 179.475633 -273.352316) (xy 179.422615 -273.342523) (xy 179.371588 -273.325115) (xy 179.32364 -273.300463)
			(xy 179.279792 -273.269093) (xy 179.240979 -273.231672) (xy 179.208027 -273.188999) (xy 179.181641 -273.141982)
			(xy 179.162381 -273.091625) (xy 179.150658 -273.039001) (xy 179.146723 -272.98523) (xy 177.881534 -272.98523)
			(xy 177.881534 -273.835368) (xy 183.246791 -273.835368) (xy 183.250726 -273.781597) (xy 183.262449 -273.728973)
			(xy 183.281709 -273.678616) (xy 183.308095 -273.631599) (xy 183.341047 -273.588926) (xy 183.37986 -273.551505)
			(xy 183.423708 -273.520135) (xy 183.471656 -273.495483) (xy 183.522683 -273.478075) (xy 183.575701 -273.468282)
			(xy 183.62958 -273.466313) (xy 183.683171 -273.47221) (xy 183.735332 -273.485846) (xy 183.784952 -273.506933)
			(xy 183.830973 -273.535019) (xy 183.872415 -273.569507) (xy 183.908393 -273.609661) (xy 183.938141 -273.654625)
			(xy 183.961026 -273.703442) (xy 183.976558 -273.755071) (xy 183.984408 -273.808411) (xy 183.9849 -273.835368)
			(xy 190.790845 -273.835368) (xy 190.79478 -273.781597) (xy 190.806503 -273.728973) (xy 190.825763 -273.678616)
			(xy 190.852149 -273.631599) (xy 190.885101 -273.588926) (xy 190.923914 -273.551505) (xy 190.967762 -273.520135)
			(xy 191.01571 -273.495483) (xy 191.066737 -273.478075) (xy 191.119755 -273.468282) (xy 191.173634 -273.466313)
			(xy 191.227225 -273.47221) (xy 191.279386 -273.485846) (xy 191.329006 -273.506933) (xy 191.375027 -273.535019)
			(xy 191.416469 -273.569507) (xy 191.452447 -273.609661) (xy 191.482195 -273.654625) (xy 191.50508 -273.703442)
			(xy 191.520612 -273.755071) (xy 191.528462 -273.808411) (xy 191.528954 -273.835368) (xy 198.334899 -273.835368)
			(xy 198.338834 -273.781597) (xy 198.350557 -273.728973) (xy 198.369817 -273.678616) (xy 198.396203 -273.631599)
			(xy 198.429155 -273.588926) (xy 198.467968 -273.551505) (xy 198.511816 -273.520135) (xy 198.559764 -273.495483)
			(xy 198.610791 -273.478075) (xy 198.663809 -273.468282) (xy 198.717688 -273.466313) (xy 198.771279 -273.47221)
			(xy 198.82344 -273.485846) (xy 198.87306 -273.506933) (xy 198.919081 -273.535019) (xy 198.960523 -273.569507)
			(xy 198.996501 -273.609661) (xy 199.026249 -273.654625) (xy 199.049134 -273.703442) (xy 199.064666 -273.755071)
			(xy 199.072516 -273.808411) (xy 199.073008 -273.835368) (xy 205.878699 -273.835368) (xy 205.882634 -273.781597)
			(xy 205.894357 -273.728973) (xy 205.913617 -273.678616) (xy 205.940003 -273.631599) (xy 205.972955 -273.588926)
			(xy 206.011768 -273.551505) (xy 206.055616 -273.520135) (xy 206.103564 -273.495483) (xy 206.154591 -273.478075)
			(xy 206.207609 -273.468282) (xy 206.261488 -273.466313) (xy 206.315079 -273.47221) (xy 206.36724 -273.485846)
			(xy 206.41686 -273.506933) (xy 206.462881 -273.535019) (xy 206.504323 -273.569507) (xy 206.540301 -273.609661)
			(xy 206.570049 -273.654625) (xy 206.592934 -273.703442) (xy 206.608466 -273.755071) (xy 206.616316 -273.808411)
			(xy 206.616808 -273.835368) (xy 206.616316 -273.862325) (xy 206.608466 -273.915665) (xy 206.592934 -273.967294)
			(xy 206.570049 -274.016111) (xy 206.540301 -274.061075) (xy 206.504323 -274.101229) (xy 206.462881 -274.135717)
			(xy 206.41686 -274.163803) (xy 206.36724 -274.18489) (xy 206.315079 -274.198526) (xy 206.261488 -274.204423)
			(xy 206.207609 -274.202454) (xy 206.154591 -274.192661) (xy 206.103564 -274.175253) (xy 206.055616 -274.150601)
			(xy 206.011768 -274.119231) (xy 205.972955 -274.08181) (xy 205.940003 -274.039137) (xy 205.913617 -273.99212)
			(xy 205.894357 -273.941763) (xy 205.882634 -273.889139) (xy 205.878699 -273.835368) (xy 199.073008 -273.835368)
			(xy 199.072516 -273.862325) (xy 199.064666 -273.915665) (xy 199.049134 -273.967294) (xy 199.026249 -274.016111)
			(xy 198.996501 -274.061075) (xy 198.960523 -274.101229) (xy 198.919081 -274.135717) (xy 198.87306 -274.163803)
			(xy 198.82344 -274.18489) (xy 198.771279 -274.198526) (xy 198.717688 -274.204423) (xy 198.663809 -274.202454)
			(xy 198.610791 -274.192661) (xy 198.559764 -274.175253) (xy 198.511816 -274.150601) (xy 198.467968 -274.119231)
			(xy 198.429155 -274.08181) (xy 198.396203 -274.039137) (xy 198.369817 -273.99212) (xy 198.350557 -273.941763)
			(xy 198.338834 -273.889139) (xy 198.334899 -273.835368) (xy 191.528954 -273.835368) (xy 191.528462 -273.862325)
			(xy 191.520612 -273.915665) (xy 191.50508 -273.967294) (xy 191.482195 -274.016111) (xy 191.452447 -274.061075)
			(xy 191.416469 -274.101229) (xy 191.375027 -274.135717) (xy 191.329006 -274.163803) (xy 191.279386 -274.18489)
			(xy 191.227225 -274.198526) (xy 191.173634 -274.204423) (xy 191.119755 -274.202454) (xy 191.066737 -274.192661)
			(xy 191.01571 -274.175253) (xy 190.967762 -274.150601) (xy 190.923914 -274.119231) (xy 190.885101 -274.08181)
			(xy 190.852149 -274.039137) (xy 190.825763 -273.99212) (xy 190.806503 -273.941763) (xy 190.79478 -273.889139)
			(xy 190.790845 -273.835368) (xy 183.9849 -273.835368) (xy 183.984408 -273.862325) (xy 183.976558 -273.915665)
			(xy 183.961026 -273.967294) (xy 183.938141 -274.016111) (xy 183.908393 -274.061075) (xy 183.872415 -274.101229)
			(xy 183.830973 -274.135717) (xy 183.784952 -274.163803) (xy 183.735332 -274.18489) (xy 183.683171 -274.198526)
			(xy 183.62958 -274.204423) (xy 183.575701 -274.202454) (xy 183.522683 -274.192661) (xy 183.471656 -274.175253)
			(xy 183.423708 -274.150601) (xy 183.37986 -274.119231) (xy 183.341047 -274.08181) (xy 183.308095 -274.039137)
			(xy 183.281709 -273.99212) (xy 183.262449 -273.941763) (xy 183.250726 -273.889139) (xy 183.246791 -273.835368)
			(xy 177.881534 -273.835368) (xy 177.881534 -274.685252) (xy 179.146723 -274.685252) (xy 179.150658 -274.631481)
			(xy 179.162381 -274.578857) (xy 179.181641 -274.5285) (xy 179.208027 -274.481483) (xy 179.240979 -274.43881)
			(xy 179.279792 -274.401389) (xy 179.32364 -274.370019) (xy 179.371588 -274.345367) (xy 179.422615 -274.327959)
			(xy 179.475633 -274.318166) (xy 179.529512 -274.316197) (xy 179.583103 -274.322094) (xy 179.635264 -274.33573)
			(xy 179.684884 -274.356817) (xy 179.730905 -274.384903) (xy 179.772347 -274.419391) (xy 179.808325 -274.459545)
			(xy 179.838073 -274.504509) (xy 179.860958 -274.553326) (xy 179.87649 -274.604955) (xy 179.88434 -274.658295)
			(xy 179.884832 -274.685252) (xy 186.690777 -274.685252) (xy 186.694712 -274.631481) (xy 186.706435 -274.578857)
			(xy 186.725695 -274.5285) (xy 186.752081 -274.481483) (xy 186.785033 -274.43881) (xy 186.823846 -274.401389)
			(xy 186.867694 -274.370019) (xy 186.915642 -274.345367) (xy 186.966669 -274.327959) (xy 187.019687 -274.318166)
			(xy 187.073566 -274.316197) (xy 187.127157 -274.322094) (xy 187.179318 -274.33573) (xy 187.228938 -274.356817)
			(xy 187.274959 -274.384903) (xy 187.316401 -274.419391) (xy 187.352379 -274.459545) (xy 187.382127 -274.504509)
			(xy 187.405012 -274.553326) (xy 187.420544 -274.604955) (xy 187.428394 -274.658295) (xy 187.428886 -274.685252)
			(xy 194.234831 -274.685252) (xy 194.238766 -274.631481) (xy 194.250489 -274.578857) (xy 194.269749 -274.5285)
			(xy 194.296135 -274.481483) (xy 194.329087 -274.43881) (xy 194.3679 -274.401389) (xy 194.411748 -274.370019)
			(xy 194.459696 -274.345367) (xy 194.510723 -274.327959) (xy 194.563741 -274.318166) (xy 194.61762 -274.316197)
			(xy 194.671211 -274.322094) (xy 194.723372 -274.33573) (xy 194.772992 -274.356817) (xy 194.819013 -274.384903)
			(xy 194.860455 -274.419391) (xy 194.896433 -274.459545) (xy 194.926181 -274.504509) (xy 194.949066 -274.553326)
			(xy 194.964598 -274.604955) (xy 194.972448 -274.658295) (xy 194.97294 -274.685252) (xy 201.778631 -274.685252)
			(xy 201.782566 -274.631481) (xy 201.794289 -274.578857) (xy 201.813549 -274.5285) (xy 201.839935 -274.481483)
			(xy 201.872887 -274.43881) (xy 201.9117 -274.401389) (xy 201.955548 -274.370019) (xy 202.003496 -274.345367)
			(xy 202.054523 -274.327959) (xy 202.107541 -274.318166) (xy 202.16142 -274.316197) (xy 202.215011 -274.322094)
			(xy 202.267172 -274.33573) (xy 202.316792 -274.356817) (xy 202.362813 -274.384903) (xy 202.404255 -274.419391)
			(xy 202.440233 -274.459545) (xy 202.469981 -274.504509) (xy 202.492866 -274.553326) (xy 202.508398 -274.604955)
			(xy 202.516248 -274.658295) (xy 202.51674 -274.685252) (xy 202.516248 -274.712209) (xy 202.508398 -274.765549)
			(xy 202.492866 -274.817178) (xy 202.469981 -274.865995) (xy 202.440233 -274.910959) (xy 202.404255 -274.951113)
			(xy 202.362813 -274.985601) (xy 202.316792 -275.013687) (xy 202.267172 -275.034774) (xy 202.215011 -275.04841)
			(xy 202.16142 -275.054307) (xy 202.107541 -275.052338) (xy 202.054523 -275.042545) (xy 202.003496 -275.025137)
			(xy 201.955548 -275.000485) (xy 201.9117 -274.969115) (xy 201.872887 -274.931694) (xy 201.839935 -274.889021)
			(xy 201.813549 -274.842004) (xy 201.794289 -274.791647) (xy 201.782566 -274.739023) (xy 201.778631 -274.685252)
			(xy 194.97294 -274.685252) (xy 194.972448 -274.712209) (xy 194.964598 -274.765549) (xy 194.949066 -274.817178)
			(xy 194.926181 -274.865995) (xy 194.896433 -274.910959) (xy 194.860455 -274.951113) (xy 194.819013 -274.985601)
			(xy 194.772992 -275.013687) (xy 194.723372 -275.034774) (xy 194.671211 -275.04841) (xy 194.61762 -275.054307)
			(xy 194.563741 -275.052338) (xy 194.510723 -275.042545) (xy 194.459696 -275.025137) (xy 194.411748 -275.000485)
			(xy 194.3679 -274.969115) (xy 194.329087 -274.931694) (xy 194.296135 -274.889021) (xy 194.269749 -274.842004)
			(xy 194.250489 -274.791647) (xy 194.238766 -274.739023) (xy 194.234831 -274.685252) (xy 187.428886 -274.685252)
			(xy 187.428394 -274.712209) (xy 187.420544 -274.765549) (xy 187.405012 -274.817178) (xy 187.382127 -274.865995)
			(xy 187.352379 -274.910959) (xy 187.316401 -274.951113) (xy 187.274959 -274.985601) (xy 187.228938 -275.013687)
			(xy 187.179318 -275.034774) (xy 187.127157 -275.04841) (xy 187.073566 -275.054307) (xy 187.019687 -275.052338)
			(xy 186.966669 -275.042545) (xy 186.915642 -275.025137) (xy 186.867694 -275.000485) (xy 186.823846 -274.969115)
			(xy 186.785033 -274.931694) (xy 186.752081 -274.889021) (xy 186.725695 -274.842004) (xy 186.706435 -274.791647)
			(xy 186.694712 -274.739023) (xy 186.690777 -274.685252) (xy 179.884832 -274.685252) (xy 179.88434 -274.712209)
			(xy 179.87649 -274.765549) (xy 179.860958 -274.817178) (xy 179.838073 -274.865995) (xy 179.808325 -274.910959)
			(xy 179.772347 -274.951113) (xy 179.730905 -274.985601) (xy 179.684884 -275.013687) (xy 179.635264 -275.034774)
			(xy 179.583103 -275.04841) (xy 179.529512 -275.054307) (xy 179.475633 -275.052338) (xy 179.422615 -275.042545)
			(xy 179.371588 -275.025137) (xy 179.32364 -275.000485) (xy 179.279792 -274.969115) (xy 179.240979 -274.931694)
			(xy 179.208027 -274.889021) (xy 179.181641 -274.842004) (xy 179.162381 -274.791647) (xy 179.150658 -274.739023)
			(xy 179.146723 -274.685252) (xy 177.881534 -274.685252) (xy 177.881534 -275.53539) (xy 183.246791 -275.53539)
			(xy 183.250726 -275.481619) (xy 183.262449 -275.428995) (xy 183.281709 -275.378638) (xy 183.308095 -275.331621)
			(xy 183.341047 -275.288948) (xy 183.37986 -275.251527) (xy 183.423708 -275.220157) (xy 183.471656 -275.195505)
			(xy 183.522683 -275.178097) (xy 183.575701 -275.168304) (xy 183.62958 -275.166335) (xy 183.683171 -275.172232)
			(xy 183.735332 -275.185868) (xy 183.784952 -275.206955) (xy 183.830973 -275.235041) (xy 183.872415 -275.269529)
			(xy 183.908393 -275.309683) (xy 183.938141 -275.354647) (xy 183.961026 -275.403464) (xy 183.976558 -275.455093)
			(xy 183.984408 -275.508433) (xy 183.9849 -275.53539) (xy 190.790845 -275.53539) (xy 190.79478 -275.481619)
			(xy 190.806503 -275.428995) (xy 190.825763 -275.378638) (xy 190.852149 -275.331621) (xy 190.885101 -275.288948)
			(xy 190.923914 -275.251527) (xy 190.967762 -275.220157) (xy 191.01571 -275.195505) (xy 191.066737 -275.178097)
			(xy 191.119755 -275.168304) (xy 191.173634 -275.166335) (xy 191.227225 -275.172232) (xy 191.279386 -275.185868)
			(xy 191.329006 -275.206955) (xy 191.375027 -275.235041) (xy 191.416469 -275.269529) (xy 191.452447 -275.309683)
			(xy 191.482195 -275.354647) (xy 191.50508 -275.403464) (xy 191.520612 -275.455093) (xy 191.528462 -275.508433)
			(xy 191.528954 -275.53539) (xy 198.334899 -275.53539) (xy 198.338834 -275.481619) (xy 198.350557 -275.428995)
			(xy 198.369817 -275.378638) (xy 198.396203 -275.331621) (xy 198.429155 -275.288948) (xy 198.467968 -275.251527)
			(xy 198.511816 -275.220157) (xy 198.559764 -275.195505) (xy 198.610791 -275.178097) (xy 198.663809 -275.168304)
			(xy 198.717688 -275.166335) (xy 198.771279 -275.172232) (xy 198.82344 -275.185868) (xy 198.87306 -275.206955)
			(xy 198.919081 -275.235041) (xy 198.960523 -275.269529) (xy 198.996501 -275.309683) (xy 199.026249 -275.354647)
			(xy 199.049134 -275.403464) (xy 199.064666 -275.455093) (xy 199.072516 -275.508433) (xy 199.073008 -275.53539)
			(xy 205.878699 -275.53539) (xy 205.882634 -275.481619) (xy 205.894357 -275.428995) (xy 205.913617 -275.378638)
			(xy 205.940003 -275.331621) (xy 205.972955 -275.288948) (xy 206.011768 -275.251527) (xy 206.055616 -275.220157)
			(xy 206.103564 -275.195505) (xy 206.154591 -275.178097) (xy 206.207609 -275.168304) (xy 206.261488 -275.166335)
			(xy 206.315079 -275.172232) (xy 206.36724 -275.185868) (xy 206.41686 -275.206955) (xy 206.462881 -275.235041)
			(xy 206.504323 -275.269529) (xy 206.540301 -275.309683) (xy 206.570049 -275.354647) (xy 206.592934 -275.403464)
			(xy 206.608466 -275.455093) (xy 206.616316 -275.508433) (xy 206.616808 -275.53539) (xy 206.616316 -275.562347)
			(xy 206.608466 -275.615687) (xy 206.592934 -275.667316) (xy 206.570049 -275.716133) (xy 206.540301 -275.761097)
			(xy 206.504323 -275.801251) (xy 206.462881 -275.835739) (xy 206.41686 -275.863825) (xy 206.36724 -275.884912)
			(xy 206.315079 -275.898548) (xy 206.261488 -275.904445) (xy 206.207609 -275.902476) (xy 206.154591 -275.892683)
			(xy 206.103564 -275.875275) (xy 206.055616 -275.850623) (xy 206.011768 -275.819253) (xy 205.972955 -275.781832)
			(xy 205.940003 -275.739159) (xy 205.913617 -275.692142) (xy 205.894357 -275.641785) (xy 205.882634 -275.589161)
			(xy 205.878699 -275.53539) (xy 199.073008 -275.53539) (xy 199.072516 -275.562347) (xy 199.064666 -275.615687)
			(xy 199.049134 -275.667316) (xy 199.026249 -275.716133) (xy 198.996501 -275.761097) (xy 198.960523 -275.801251)
			(xy 198.919081 -275.835739) (xy 198.87306 -275.863825) (xy 198.82344 -275.884912) (xy 198.771279 -275.898548)
			(xy 198.717688 -275.904445) (xy 198.663809 -275.902476) (xy 198.610791 -275.892683) (xy 198.559764 -275.875275)
			(xy 198.511816 -275.850623) (xy 198.467968 -275.819253) (xy 198.429155 -275.781832) (xy 198.396203 -275.739159)
			(xy 198.369817 -275.692142) (xy 198.350557 -275.641785) (xy 198.338834 -275.589161) (xy 198.334899 -275.53539)
			(xy 191.528954 -275.53539) (xy 191.528462 -275.562347) (xy 191.520612 -275.615687) (xy 191.50508 -275.667316)
			(xy 191.482195 -275.716133) (xy 191.452447 -275.761097) (xy 191.416469 -275.801251) (xy 191.375027 -275.835739)
			(xy 191.329006 -275.863825) (xy 191.279386 -275.884912) (xy 191.227225 -275.898548) (xy 191.173634 -275.904445)
			(xy 191.119755 -275.902476) (xy 191.066737 -275.892683) (xy 191.01571 -275.875275) (xy 190.967762 -275.850623)
			(xy 190.923914 -275.819253) (xy 190.885101 -275.781832) (xy 190.852149 -275.739159) (xy 190.825763 -275.692142)
			(xy 190.806503 -275.641785) (xy 190.79478 -275.589161) (xy 190.790845 -275.53539) (xy 183.9849 -275.53539)
			(xy 183.984408 -275.562347) (xy 183.976558 -275.615687) (xy 183.961026 -275.667316) (xy 183.938141 -275.716133)
			(xy 183.908393 -275.761097) (xy 183.872415 -275.801251) (xy 183.830973 -275.835739) (xy 183.784952 -275.863825)
			(xy 183.735332 -275.884912) (xy 183.683171 -275.898548) (xy 183.62958 -275.904445) (xy 183.575701 -275.902476)
			(xy 183.522683 -275.892683) (xy 183.471656 -275.875275) (xy 183.423708 -275.850623) (xy 183.37986 -275.819253)
			(xy 183.341047 -275.781832) (xy 183.308095 -275.739159) (xy 183.281709 -275.692142) (xy 183.262449 -275.641785)
			(xy 183.250726 -275.589161) (xy 183.246791 -275.53539) (xy 177.881534 -275.53539) (xy 177.881534 -276.385274)
			(xy 179.146723 -276.385274) (xy 179.150658 -276.331503) (xy 179.162381 -276.278879) (xy 179.181641 -276.228522)
			(xy 179.208027 -276.181505) (xy 179.240979 -276.138832) (xy 179.279792 -276.101411) (xy 179.32364 -276.070041)
			(xy 179.371588 -276.045389) (xy 179.422615 -276.027981) (xy 179.475633 -276.018188) (xy 179.529512 -276.016219)
			(xy 179.583103 -276.022116) (xy 179.635264 -276.035752) (xy 179.684884 -276.056839) (xy 179.730905 -276.084925)
			(xy 179.772347 -276.119413) (xy 179.808325 -276.159567) (xy 179.838073 -276.204531) (xy 179.860958 -276.253348)
			(xy 179.87649 -276.304977) (xy 179.88434 -276.358317) (xy 179.884832 -276.385274) (xy 183.246791 -276.385274)
			(xy 183.250726 -276.331503) (xy 183.262449 -276.278879) (xy 183.281709 -276.228522) (xy 183.308095 -276.181505)
			(xy 183.341047 -276.138832) (xy 183.37986 -276.101411) (xy 183.423708 -276.070041) (xy 183.471656 -276.045389)
			(xy 183.522683 -276.027981) (xy 183.575701 -276.018188) (xy 183.62958 -276.016219) (xy 183.683171 -276.022116)
			(xy 183.735332 -276.035752) (xy 183.784952 -276.056839) (xy 183.830973 -276.084925) (xy 183.872415 -276.119413)
			(xy 183.908393 -276.159567) (xy 183.938141 -276.204531) (xy 183.961026 -276.253348) (xy 183.976558 -276.304977)
			(xy 183.984408 -276.358317) (xy 183.9849 -276.385274) (xy 186.690777 -276.385274) (xy 186.694712 -276.331503)
			(xy 186.706435 -276.278879) (xy 186.725695 -276.228522) (xy 186.752081 -276.181505) (xy 186.785033 -276.138832)
			(xy 186.823846 -276.101411) (xy 186.867694 -276.070041) (xy 186.915642 -276.045389) (xy 186.966669 -276.027981)
			(xy 187.019687 -276.018188) (xy 187.073566 -276.016219) (xy 187.127157 -276.022116) (xy 187.179318 -276.035752)
			(xy 187.228938 -276.056839) (xy 187.274959 -276.084925) (xy 187.316401 -276.119413) (xy 187.352379 -276.159567)
			(xy 187.382127 -276.204531) (xy 187.405012 -276.253348) (xy 187.420544 -276.304977) (xy 187.428394 -276.358317)
			(xy 187.428886 -276.385274) (xy 190.790845 -276.385274) (xy 190.79478 -276.331503) (xy 190.806503 -276.278879)
			(xy 190.825763 -276.228522) (xy 190.852149 -276.181505) (xy 190.885101 -276.138832) (xy 190.923914 -276.101411)
			(xy 190.967762 -276.070041) (xy 191.01571 -276.045389) (xy 191.066737 -276.027981) (xy 191.119755 -276.018188)
			(xy 191.173634 -276.016219) (xy 191.227225 -276.022116) (xy 191.279386 -276.035752) (xy 191.329006 -276.056839)
			(xy 191.375027 -276.084925) (xy 191.416469 -276.119413) (xy 191.452447 -276.159567) (xy 191.482195 -276.204531)
			(xy 191.50508 -276.253348) (xy 191.520612 -276.304977) (xy 191.528462 -276.358317) (xy 191.528954 -276.385274)
			(xy 194.234831 -276.385274) (xy 194.238766 -276.331503) (xy 194.250489 -276.278879) (xy 194.269749 -276.228522)
			(xy 194.296135 -276.181505) (xy 194.329087 -276.138832) (xy 194.3679 -276.101411) (xy 194.411748 -276.070041)
			(xy 194.459696 -276.045389) (xy 194.510723 -276.027981) (xy 194.563741 -276.018188) (xy 194.61762 -276.016219)
			(xy 194.671211 -276.022116) (xy 194.723372 -276.035752) (xy 194.772992 -276.056839) (xy 194.819013 -276.084925)
			(xy 194.860455 -276.119413) (xy 194.896433 -276.159567) (xy 194.926181 -276.204531) (xy 194.949066 -276.253348)
			(xy 194.964598 -276.304977) (xy 194.972448 -276.358317) (xy 194.97294 -276.385274) (xy 198.334899 -276.385274)
			(xy 198.338834 -276.331503) (xy 198.350557 -276.278879) (xy 198.369817 -276.228522) (xy 198.396203 -276.181505)
			(xy 198.429155 -276.138832) (xy 198.467968 -276.101411) (xy 198.511816 -276.070041) (xy 198.559764 -276.045389)
			(xy 198.610791 -276.027981) (xy 198.663809 -276.018188) (xy 198.717688 -276.016219) (xy 198.771279 -276.022116)
			(xy 198.82344 -276.035752) (xy 198.87306 -276.056839) (xy 198.919081 -276.084925) (xy 198.960523 -276.119413)
			(xy 198.996501 -276.159567) (xy 199.026249 -276.204531) (xy 199.049134 -276.253348) (xy 199.064666 -276.304977)
			(xy 199.072516 -276.358317) (xy 199.073008 -276.385274) (xy 201.778631 -276.385274) (xy 201.782566 -276.331503)
			(xy 201.794289 -276.278879) (xy 201.813549 -276.228522) (xy 201.839935 -276.181505) (xy 201.872887 -276.138832)
			(xy 201.9117 -276.101411) (xy 201.955548 -276.070041) (xy 202.003496 -276.045389) (xy 202.054523 -276.027981)
			(xy 202.107541 -276.018188) (xy 202.16142 -276.016219) (xy 202.215011 -276.022116) (xy 202.267172 -276.035752)
			(xy 202.316792 -276.056839) (xy 202.362813 -276.084925) (xy 202.404255 -276.119413) (xy 202.440233 -276.159567)
			(xy 202.469981 -276.204531) (xy 202.492866 -276.253348) (xy 202.508398 -276.304977) (xy 202.516248 -276.358317)
			(xy 202.51674 -276.385274) (xy 205.878699 -276.385274) (xy 205.882634 -276.331503) (xy 205.894357 -276.278879)
			(xy 205.913617 -276.228522) (xy 205.940003 -276.181505) (xy 205.972955 -276.138832) (xy 206.011768 -276.101411)
			(xy 206.055616 -276.070041) (xy 206.103564 -276.045389) (xy 206.154591 -276.027981) (xy 206.207609 -276.018188)
			(xy 206.261488 -276.016219) (xy 206.315079 -276.022116) (xy 206.36724 -276.035752) (xy 206.41686 -276.056839)
			(xy 206.462881 -276.084925) (xy 206.504323 -276.119413) (xy 206.540301 -276.159567) (xy 206.570049 -276.204531)
			(xy 206.592934 -276.253348) (xy 206.608466 -276.304977) (xy 206.616316 -276.358317) (xy 206.616808 -276.385274)
			(xy 206.616316 -276.412231) (xy 206.608466 -276.465571) (xy 206.592934 -276.5172) (xy 206.570049 -276.566017)
			(xy 206.540301 -276.610981) (xy 206.504323 -276.651135) (xy 206.462881 -276.685623) (xy 206.41686 -276.713709)
			(xy 206.36724 -276.734796) (xy 206.315079 -276.748432) (xy 206.261488 -276.754329) (xy 206.207609 -276.75236)
			(xy 206.154591 -276.742567) (xy 206.103564 -276.725159) (xy 206.055616 -276.700507) (xy 206.011768 -276.669137)
			(xy 205.972955 -276.631716) (xy 205.940003 -276.589043) (xy 205.913617 -276.542026) (xy 205.894357 -276.491669)
			(xy 205.882634 -276.439045) (xy 205.878699 -276.385274) (xy 202.51674 -276.385274) (xy 202.516248 -276.412231)
			(xy 202.508398 -276.465571) (xy 202.492866 -276.5172) (xy 202.469981 -276.566017) (xy 202.440233 -276.610981)
			(xy 202.404255 -276.651135) (xy 202.362813 -276.685623) (xy 202.316792 -276.713709) (xy 202.267172 -276.734796)
			(xy 202.215011 -276.748432) (xy 202.16142 -276.754329) (xy 202.107541 -276.75236) (xy 202.054523 -276.742567)
			(xy 202.003496 -276.725159) (xy 201.955548 -276.700507) (xy 201.9117 -276.669137) (xy 201.872887 -276.631716)
			(xy 201.839935 -276.589043) (xy 201.813549 -276.542026) (xy 201.794289 -276.491669) (xy 201.782566 -276.439045)
			(xy 201.778631 -276.385274) (xy 199.073008 -276.385274) (xy 199.072516 -276.412231) (xy 199.064666 -276.465571)
			(xy 199.049134 -276.5172) (xy 199.026249 -276.566017) (xy 198.996501 -276.610981) (xy 198.960523 -276.651135)
			(xy 198.919081 -276.685623) (xy 198.87306 -276.713709) (xy 198.82344 -276.734796) (xy 198.771279 -276.748432)
			(xy 198.717688 -276.754329) (xy 198.663809 -276.75236) (xy 198.610791 -276.742567) (xy 198.559764 -276.725159)
			(xy 198.511816 -276.700507) (xy 198.467968 -276.669137) (xy 198.429155 -276.631716) (xy 198.396203 -276.589043)
			(xy 198.369817 -276.542026) (xy 198.350557 -276.491669) (xy 198.338834 -276.439045) (xy 198.334899 -276.385274)
			(xy 194.97294 -276.385274) (xy 194.972448 -276.412231) (xy 194.964598 -276.465571) (xy 194.949066 -276.5172)
			(xy 194.926181 -276.566017) (xy 194.896433 -276.610981) (xy 194.860455 -276.651135) (xy 194.819013 -276.685623)
			(xy 194.772992 -276.713709) (xy 194.723372 -276.734796) (xy 194.671211 -276.748432) (xy 194.61762 -276.754329)
			(xy 194.563741 -276.75236) (xy 194.510723 -276.742567) (xy 194.459696 -276.725159) (xy 194.411748 -276.700507)
			(xy 194.3679 -276.669137) (xy 194.329087 -276.631716) (xy 194.296135 -276.589043) (xy 194.269749 -276.542026)
			(xy 194.250489 -276.491669) (xy 194.238766 -276.439045) (xy 194.234831 -276.385274) (xy 191.528954 -276.385274)
			(xy 191.528462 -276.412231) (xy 191.520612 -276.465571) (xy 191.50508 -276.5172) (xy 191.482195 -276.566017)
			(xy 191.452447 -276.610981) (xy 191.416469 -276.651135) (xy 191.375027 -276.685623) (xy 191.329006 -276.713709)
			(xy 191.279386 -276.734796) (xy 191.227225 -276.748432) (xy 191.173634 -276.754329) (xy 191.119755 -276.75236)
			(xy 191.066737 -276.742567) (xy 191.01571 -276.725159) (xy 190.967762 -276.700507) (xy 190.923914 -276.669137)
			(xy 190.885101 -276.631716) (xy 190.852149 -276.589043) (xy 190.825763 -276.542026) (xy 190.806503 -276.491669)
			(xy 190.79478 -276.439045) (xy 190.790845 -276.385274) (xy 187.428886 -276.385274) (xy 187.428394 -276.412231)
			(xy 187.420544 -276.465571) (xy 187.405012 -276.5172) (xy 187.382127 -276.566017) (xy 187.352379 -276.610981)
			(xy 187.316401 -276.651135) (xy 187.274959 -276.685623) (xy 187.228938 -276.713709) (xy 187.179318 -276.734796)
			(xy 187.127157 -276.748432) (xy 187.073566 -276.754329) (xy 187.019687 -276.75236) (xy 186.966669 -276.742567)
			(xy 186.915642 -276.725159) (xy 186.867694 -276.700507) (xy 186.823846 -276.669137) (xy 186.785033 -276.631716)
			(xy 186.752081 -276.589043) (xy 186.725695 -276.542026) (xy 186.706435 -276.491669) (xy 186.694712 -276.439045)
			(xy 186.690777 -276.385274) (xy 183.9849 -276.385274) (xy 183.984408 -276.412231) (xy 183.976558 -276.465571)
			(xy 183.961026 -276.5172) (xy 183.938141 -276.566017) (xy 183.908393 -276.610981) (xy 183.872415 -276.651135)
			(xy 183.830973 -276.685623) (xy 183.784952 -276.713709) (xy 183.735332 -276.734796) (xy 183.683171 -276.748432)
			(xy 183.62958 -276.754329) (xy 183.575701 -276.75236) (xy 183.522683 -276.742567) (xy 183.471656 -276.725159)
			(xy 183.423708 -276.700507) (xy 183.37986 -276.669137) (xy 183.341047 -276.631716) (xy 183.308095 -276.589043)
			(xy 183.281709 -276.542026) (xy 183.262449 -276.491669) (xy 183.250726 -276.439045) (xy 183.246791 -276.385274)
			(xy 179.884832 -276.385274) (xy 179.88434 -276.412231) (xy 179.87649 -276.465571) (xy 179.860958 -276.5172)
			(xy 179.838073 -276.566017) (xy 179.808325 -276.610981) (xy 179.772347 -276.651135) (xy 179.730905 -276.685623)
			(xy 179.684884 -276.713709) (xy 179.635264 -276.734796) (xy 179.583103 -276.748432) (xy 179.529512 -276.754329)
			(xy 179.475633 -276.75236) (xy 179.422615 -276.742567) (xy 179.371588 -276.725159) (xy 179.32364 -276.700507)
			(xy 179.279792 -276.669137) (xy 179.240979 -276.631716) (xy 179.208027 -276.589043) (xy 179.181641 -276.542026)
			(xy 179.162381 -276.491669) (xy 179.150658 -276.439045) (xy 179.146723 -276.385274) (xy 177.881534 -276.385274)
			(xy 177.881534 -277.235412) (xy 179.146723 -277.235412) (xy 179.150658 -277.181641) (xy 179.162381 -277.129017)
			(xy 179.181641 -277.07866) (xy 179.208027 -277.031643) (xy 179.240979 -276.98897) (xy 179.279792 -276.951549)
			(xy 179.32364 -276.920179) (xy 179.371588 -276.895527) (xy 179.422615 -276.878119) (xy 179.475633 -276.868326)
			(xy 179.529512 -276.866357) (xy 179.583103 -276.872254) (xy 179.635264 -276.88589) (xy 179.684884 -276.906977)
			(xy 179.730905 -276.935063) (xy 179.772347 -276.969551) (xy 179.808325 -277.009705) (xy 179.838073 -277.054669)
			(xy 179.860958 -277.103486) (xy 179.87649 -277.155115) (xy 179.88434 -277.208455) (xy 179.884832 -277.235412)
			(xy 186.690777 -277.235412) (xy 186.694712 -277.181641) (xy 186.706435 -277.129017) (xy 186.725695 -277.07866)
			(xy 186.752081 -277.031643) (xy 186.785033 -276.98897) (xy 186.823846 -276.951549) (xy 186.867694 -276.920179)
			(xy 186.915642 -276.895527) (xy 186.966669 -276.878119) (xy 187.019687 -276.868326) (xy 187.073566 -276.866357)
			(xy 187.127157 -276.872254) (xy 187.179318 -276.88589) (xy 187.228938 -276.906977) (xy 187.274959 -276.935063)
			(xy 187.316401 -276.969551) (xy 187.352379 -277.009705) (xy 187.382127 -277.054669) (xy 187.405012 -277.103486)
			(xy 187.420544 -277.155115) (xy 187.428394 -277.208455) (xy 187.428886 -277.235412) (xy 194.234831 -277.235412)
			(xy 194.238766 -277.181641) (xy 194.250489 -277.129017) (xy 194.269749 -277.07866) (xy 194.296135 -277.031643)
			(xy 194.329087 -276.98897) (xy 194.3679 -276.951549) (xy 194.411748 -276.920179) (xy 194.459696 -276.895527)
			(xy 194.510723 -276.878119) (xy 194.563741 -276.868326) (xy 194.61762 -276.866357) (xy 194.671211 -276.872254)
			(xy 194.723372 -276.88589) (xy 194.772992 -276.906977) (xy 194.819013 -276.935063) (xy 194.860455 -276.969551)
			(xy 194.896433 -277.009705) (xy 194.926181 -277.054669) (xy 194.949066 -277.103486) (xy 194.964598 -277.155115)
			(xy 194.972448 -277.208455) (xy 194.97294 -277.235412) (xy 201.778631 -277.235412) (xy 201.782566 -277.181641)
			(xy 201.794289 -277.129017) (xy 201.813549 -277.07866) (xy 201.839935 -277.031643) (xy 201.872887 -276.98897)
			(xy 201.9117 -276.951549) (xy 201.955548 -276.920179) (xy 202.003496 -276.895527) (xy 202.054523 -276.878119)
			(xy 202.107541 -276.868326) (xy 202.16142 -276.866357) (xy 202.215011 -276.872254) (xy 202.267172 -276.88589)
			(xy 202.316792 -276.906977) (xy 202.362813 -276.935063) (xy 202.404255 -276.969551) (xy 202.440233 -277.009705)
			(xy 202.469981 -277.054669) (xy 202.492866 -277.103486) (xy 202.508398 -277.155115) (xy 202.516248 -277.208455)
			(xy 202.51674 -277.235412) (xy 202.516248 -277.262369) (xy 202.508398 -277.315709) (xy 202.492866 -277.367338)
			(xy 202.469981 -277.416155) (xy 202.440233 -277.461119) (xy 202.404255 -277.501273) (xy 202.362813 -277.535761)
			(xy 202.316792 -277.563847) (xy 202.267172 -277.584934) (xy 202.215011 -277.59857) (xy 202.16142 -277.604467)
			(xy 202.107541 -277.602498) (xy 202.054523 -277.592705) (xy 202.003496 -277.575297) (xy 201.955548 -277.550645)
			(xy 201.9117 -277.519275) (xy 201.872887 -277.481854) (xy 201.839935 -277.439181) (xy 201.813549 -277.392164)
			(xy 201.794289 -277.341807) (xy 201.782566 -277.289183) (xy 201.778631 -277.235412) (xy 194.97294 -277.235412)
			(xy 194.972448 -277.262369) (xy 194.964598 -277.315709) (xy 194.949066 -277.367338) (xy 194.926181 -277.416155)
			(xy 194.896433 -277.461119) (xy 194.860455 -277.501273) (xy 194.819013 -277.535761) (xy 194.772992 -277.563847)
			(xy 194.723372 -277.584934) (xy 194.671211 -277.59857) (xy 194.61762 -277.604467) (xy 194.563741 -277.602498)
			(xy 194.510723 -277.592705) (xy 194.459696 -277.575297) (xy 194.411748 -277.550645) (xy 194.3679 -277.519275)
			(xy 194.329087 -277.481854) (xy 194.296135 -277.439181) (xy 194.269749 -277.392164) (xy 194.250489 -277.341807)
			(xy 194.238766 -277.289183) (xy 194.234831 -277.235412) (xy 187.428886 -277.235412) (xy 187.428394 -277.262369)
			(xy 187.420544 -277.315709) (xy 187.405012 -277.367338) (xy 187.382127 -277.416155) (xy 187.352379 -277.461119)
			(xy 187.316401 -277.501273) (xy 187.274959 -277.535761) (xy 187.228938 -277.563847) (xy 187.179318 -277.584934)
			(xy 187.127157 -277.59857) (xy 187.073566 -277.604467) (xy 187.019687 -277.602498) (xy 186.966669 -277.592705)
			(xy 186.915642 -277.575297) (xy 186.867694 -277.550645) (xy 186.823846 -277.519275) (xy 186.785033 -277.481854)
			(xy 186.752081 -277.439181) (xy 186.725695 -277.392164) (xy 186.706435 -277.341807) (xy 186.694712 -277.289183)
			(xy 186.690777 -277.235412) (xy 179.884832 -277.235412) (xy 179.88434 -277.262369) (xy 179.87649 -277.315709)
			(xy 179.860958 -277.367338) (xy 179.838073 -277.416155) (xy 179.808325 -277.461119) (xy 179.772347 -277.501273)
			(xy 179.730905 -277.535761) (xy 179.684884 -277.563847) (xy 179.635264 -277.584934) (xy 179.583103 -277.59857)
			(xy 179.529512 -277.604467) (xy 179.475633 -277.602498) (xy 179.422615 -277.592705) (xy 179.371588 -277.575297)
			(xy 179.32364 -277.550645) (xy 179.279792 -277.519275) (xy 179.240979 -277.481854) (xy 179.208027 -277.439181)
			(xy 179.181641 -277.392164) (xy 179.162381 -277.341807) (xy 179.150658 -277.289183) (xy 179.146723 -277.235412)
			(xy 177.881534 -277.235412) (xy 177.881534 -278.085296) (xy 183.246791 -278.085296) (xy 183.250726 -278.031525)
			(xy 183.262449 -277.978901) (xy 183.281709 -277.928544) (xy 183.308095 -277.881527) (xy 183.341047 -277.838854)
			(xy 183.37986 -277.801433) (xy 183.423708 -277.770063) (xy 183.471656 -277.745411) (xy 183.522683 -277.728003)
			(xy 183.575701 -277.71821) (xy 183.62958 -277.716241) (xy 183.683171 -277.722138) (xy 183.735332 -277.735774)
			(xy 183.784952 -277.756861) (xy 183.830973 -277.784947) (xy 183.872415 -277.819435) (xy 183.908393 -277.859589)
			(xy 183.938141 -277.904553) (xy 183.961026 -277.95337) (xy 183.976558 -278.004999) (xy 183.984408 -278.058339)
			(xy 183.9849 -278.085296) (xy 190.790845 -278.085296) (xy 190.79478 -278.031525) (xy 190.806503 -277.978901)
			(xy 190.825763 -277.928544) (xy 190.852149 -277.881527) (xy 190.885101 -277.838854) (xy 190.923914 -277.801433)
			(xy 190.967762 -277.770063) (xy 191.01571 -277.745411) (xy 191.066737 -277.728003) (xy 191.119755 -277.71821)
			(xy 191.173634 -277.716241) (xy 191.227225 -277.722138) (xy 191.279386 -277.735774) (xy 191.329006 -277.756861)
			(xy 191.375027 -277.784947) (xy 191.416469 -277.819435) (xy 191.452447 -277.859589) (xy 191.482195 -277.904553)
			(xy 191.50508 -277.95337) (xy 191.520612 -278.004999) (xy 191.528462 -278.058339) (xy 191.528954 -278.085296)
			(xy 198.334899 -278.085296) (xy 198.338834 -278.031525) (xy 198.350557 -277.978901) (xy 198.369817 -277.928544)
			(xy 198.396203 -277.881527) (xy 198.429155 -277.838854) (xy 198.467968 -277.801433) (xy 198.511816 -277.770063)
			(xy 198.559764 -277.745411) (xy 198.610791 -277.728003) (xy 198.663809 -277.71821) (xy 198.717688 -277.716241)
			(xy 198.771279 -277.722138) (xy 198.82344 -277.735774) (xy 198.87306 -277.756861) (xy 198.919081 -277.784947)
			(xy 198.960523 -277.819435) (xy 198.996501 -277.859589) (xy 199.026249 -277.904553) (xy 199.049134 -277.95337)
			(xy 199.064666 -278.004999) (xy 199.072516 -278.058339) (xy 199.073008 -278.085296) (xy 205.878699 -278.085296)
			(xy 205.882634 -278.031525) (xy 205.894357 -277.978901) (xy 205.913617 -277.928544) (xy 205.940003 -277.881527)
			(xy 205.972955 -277.838854) (xy 206.011768 -277.801433) (xy 206.055616 -277.770063) (xy 206.103564 -277.745411)
			(xy 206.154591 -277.728003) (xy 206.207609 -277.71821) (xy 206.261488 -277.716241) (xy 206.315079 -277.722138)
			(xy 206.36724 -277.735774) (xy 206.41686 -277.756861) (xy 206.462881 -277.784947) (xy 206.504323 -277.819435)
			(xy 206.540301 -277.859589) (xy 206.570049 -277.904553) (xy 206.592934 -277.95337) (xy 206.608466 -278.004999)
			(xy 206.616316 -278.058339) (xy 206.616808 -278.085296) (xy 206.616316 -278.112253) (xy 206.608466 -278.165593)
			(xy 206.592934 -278.217222) (xy 206.570049 -278.266039) (xy 206.540301 -278.311003) (xy 206.504323 -278.351157)
			(xy 206.462881 -278.385645) (xy 206.41686 -278.413731) (xy 206.36724 -278.434818) (xy 206.315079 -278.448454)
			(xy 206.261488 -278.454351) (xy 206.207609 -278.452382) (xy 206.154591 -278.442589) (xy 206.103564 -278.425181)
			(xy 206.055616 -278.400529) (xy 206.011768 -278.369159) (xy 205.972955 -278.331738) (xy 205.940003 -278.289065)
			(xy 205.913617 -278.242048) (xy 205.894357 -278.191691) (xy 205.882634 -278.139067) (xy 205.878699 -278.085296)
			(xy 199.073008 -278.085296) (xy 199.072516 -278.112253) (xy 199.064666 -278.165593) (xy 199.049134 -278.217222)
			(xy 199.026249 -278.266039) (xy 198.996501 -278.311003) (xy 198.960523 -278.351157) (xy 198.919081 -278.385645)
			(xy 198.87306 -278.413731) (xy 198.82344 -278.434818) (xy 198.771279 -278.448454) (xy 198.717688 -278.454351)
			(xy 198.663809 -278.452382) (xy 198.610791 -278.442589) (xy 198.559764 -278.425181) (xy 198.511816 -278.400529)
			(xy 198.467968 -278.369159) (xy 198.429155 -278.331738) (xy 198.396203 -278.289065) (xy 198.369817 -278.242048)
			(xy 198.350557 -278.191691) (xy 198.338834 -278.139067) (xy 198.334899 -278.085296) (xy 191.528954 -278.085296)
			(xy 191.528462 -278.112253) (xy 191.520612 -278.165593) (xy 191.50508 -278.217222) (xy 191.482195 -278.266039)
			(xy 191.452447 -278.311003) (xy 191.416469 -278.351157) (xy 191.375027 -278.385645) (xy 191.329006 -278.413731)
			(xy 191.279386 -278.434818) (xy 191.227225 -278.448454) (xy 191.173634 -278.454351) (xy 191.119755 -278.452382)
			(xy 191.066737 -278.442589) (xy 191.01571 -278.425181) (xy 190.967762 -278.400529) (xy 190.923914 -278.369159)
			(xy 190.885101 -278.331738) (xy 190.852149 -278.289065) (xy 190.825763 -278.242048) (xy 190.806503 -278.191691)
			(xy 190.79478 -278.139067) (xy 190.790845 -278.085296) (xy 183.9849 -278.085296) (xy 183.984408 -278.112253)
			(xy 183.976558 -278.165593) (xy 183.961026 -278.217222) (xy 183.938141 -278.266039) (xy 183.908393 -278.311003)
			(xy 183.872415 -278.351157) (xy 183.830973 -278.385645) (xy 183.784952 -278.413731) (xy 183.735332 -278.434818)
			(xy 183.683171 -278.448454) (xy 183.62958 -278.454351) (xy 183.575701 -278.452382) (xy 183.522683 -278.442589)
			(xy 183.471656 -278.425181) (xy 183.423708 -278.400529) (xy 183.37986 -278.369159) (xy 183.341047 -278.331738)
			(xy 183.308095 -278.289065) (xy 183.281709 -278.242048) (xy 183.262449 -278.191691) (xy 183.250726 -278.139067)
			(xy 183.246791 -278.085296) (xy 177.881534 -278.085296) (xy 177.881534 -278.935434) (xy 179.146723 -278.935434)
			(xy 179.150658 -278.881663) (xy 179.162381 -278.829039) (xy 179.181641 -278.778682) (xy 179.208027 -278.731665)
			(xy 179.240979 -278.688992) (xy 179.279792 -278.651571) (xy 179.32364 -278.620201) (xy 179.371588 -278.595549)
			(xy 179.422615 -278.578141) (xy 179.475633 -278.568348) (xy 179.529512 -278.566379) (xy 179.583103 -278.572276)
			(xy 179.635264 -278.585912) (xy 179.684884 -278.606999) (xy 179.730905 -278.635085) (xy 179.772347 -278.669573)
			(xy 179.808325 -278.709727) (xy 179.838073 -278.754691) (xy 179.860958 -278.803508) (xy 179.87649 -278.855137)
			(xy 179.88434 -278.908477) (xy 179.884832 -278.935434) (xy 186.690777 -278.935434) (xy 186.694712 -278.881663)
			(xy 186.706435 -278.829039) (xy 186.725695 -278.778682) (xy 186.752081 -278.731665) (xy 186.785033 -278.688992)
			(xy 186.823846 -278.651571) (xy 186.867694 -278.620201) (xy 186.915642 -278.595549) (xy 186.966669 -278.578141)
			(xy 187.019687 -278.568348) (xy 187.073566 -278.566379) (xy 187.127157 -278.572276) (xy 187.179318 -278.585912)
			(xy 187.228938 -278.606999) (xy 187.274959 -278.635085) (xy 187.316401 -278.669573) (xy 187.352379 -278.709727)
			(xy 187.382127 -278.754691) (xy 187.405012 -278.803508) (xy 187.420544 -278.855137) (xy 187.428394 -278.908477)
			(xy 187.428886 -278.935434) (xy 194.234831 -278.935434) (xy 194.238766 -278.881663) (xy 194.250489 -278.829039)
			(xy 194.269749 -278.778682) (xy 194.296135 -278.731665) (xy 194.329087 -278.688992) (xy 194.3679 -278.651571)
			(xy 194.411748 -278.620201) (xy 194.459696 -278.595549) (xy 194.510723 -278.578141) (xy 194.563741 -278.568348)
			(xy 194.61762 -278.566379) (xy 194.671211 -278.572276) (xy 194.723372 -278.585912) (xy 194.772992 -278.606999)
			(xy 194.819013 -278.635085) (xy 194.860455 -278.669573) (xy 194.896433 -278.709727) (xy 194.926181 -278.754691)
			(xy 194.949066 -278.803508) (xy 194.964598 -278.855137) (xy 194.972448 -278.908477) (xy 194.97294 -278.935434)
			(xy 201.778631 -278.935434) (xy 201.782566 -278.881663) (xy 201.794289 -278.829039) (xy 201.813549 -278.778682)
			(xy 201.839935 -278.731665) (xy 201.872887 -278.688992) (xy 201.9117 -278.651571) (xy 201.955548 -278.620201)
			(xy 202.003496 -278.595549) (xy 202.054523 -278.578141) (xy 202.107541 -278.568348) (xy 202.16142 -278.566379)
			(xy 202.215011 -278.572276) (xy 202.267172 -278.585912) (xy 202.316792 -278.606999) (xy 202.362813 -278.635085)
			(xy 202.404255 -278.669573) (xy 202.440233 -278.709727) (xy 202.469981 -278.754691) (xy 202.492866 -278.803508)
			(xy 202.508398 -278.855137) (xy 202.516248 -278.908477) (xy 202.51674 -278.935434) (xy 202.516248 -278.962391)
			(xy 202.508398 -279.015731) (xy 202.492866 -279.06736) (xy 202.469981 -279.116177) (xy 202.440233 -279.161141)
			(xy 202.404255 -279.201295) (xy 202.362813 -279.235783) (xy 202.316792 -279.263869) (xy 202.267172 -279.284956)
			(xy 202.215011 -279.298592) (xy 202.16142 -279.304489) (xy 202.107541 -279.30252) (xy 202.054523 -279.292727)
			(xy 202.003496 -279.275319) (xy 201.955548 -279.250667) (xy 201.9117 -279.219297) (xy 201.872887 -279.181876)
			(xy 201.839935 -279.139203) (xy 201.813549 -279.092186) (xy 201.794289 -279.041829) (xy 201.782566 -278.989205)
			(xy 201.778631 -278.935434) (xy 194.97294 -278.935434) (xy 194.972448 -278.962391) (xy 194.964598 -279.015731)
			(xy 194.949066 -279.06736) (xy 194.926181 -279.116177) (xy 194.896433 -279.161141) (xy 194.860455 -279.201295)
			(xy 194.819013 -279.235783) (xy 194.772992 -279.263869) (xy 194.723372 -279.284956) (xy 194.671211 -279.298592)
			(xy 194.61762 -279.304489) (xy 194.563741 -279.30252) (xy 194.510723 -279.292727) (xy 194.459696 -279.275319)
			(xy 194.411748 -279.250667) (xy 194.3679 -279.219297) (xy 194.329087 -279.181876) (xy 194.296135 -279.139203)
			(xy 194.269749 -279.092186) (xy 194.250489 -279.041829) (xy 194.238766 -278.989205) (xy 194.234831 -278.935434)
			(xy 187.428886 -278.935434) (xy 187.428394 -278.962391) (xy 187.420544 -279.015731) (xy 187.405012 -279.06736)
			(xy 187.382127 -279.116177) (xy 187.352379 -279.161141) (xy 187.316401 -279.201295) (xy 187.274959 -279.235783)
			(xy 187.228938 -279.263869) (xy 187.179318 -279.284956) (xy 187.127157 -279.298592) (xy 187.073566 -279.304489)
			(xy 187.019687 -279.30252) (xy 186.966669 -279.292727) (xy 186.915642 -279.275319) (xy 186.867694 -279.250667)
			(xy 186.823846 -279.219297) (xy 186.785033 -279.181876) (xy 186.752081 -279.139203) (xy 186.725695 -279.092186)
			(xy 186.706435 -279.041829) (xy 186.694712 -278.989205) (xy 186.690777 -278.935434) (xy 179.884832 -278.935434)
			(xy 179.88434 -278.962391) (xy 179.87649 -279.015731) (xy 179.860958 -279.06736) (xy 179.838073 -279.116177)
			(xy 179.808325 -279.161141) (xy 179.772347 -279.201295) (xy 179.730905 -279.235783) (xy 179.684884 -279.263869)
			(xy 179.635264 -279.284956) (xy 179.583103 -279.298592) (xy 179.529512 -279.304489) (xy 179.475633 -279.30252)
			(xy 179.422615 -279.292727) (xy 179.371588 -279.275319) (xy 179.32364 -279.250667) (xy 179.279792 -279.219297)
			(xy 179.240979 -279.181876) (xy 179.208027 -279.139203) (xy 179.181641 -279.092186) (xy 179.162381 -279.041829)
			(xy 179.150658 -278.989205) (xy 179.146723 -278.935434) (xy 177.881534 -278.935434) (xy 177.881534 -279.785318)
			(xy 183.246791 -279.785318) (xy 183.250726 -279.731547) (xy 183.262449 -279.678923) (xy 183.281709 -279.628566)
			(xy 183.308095 -279.581549) (xy 183.341047 -279.538876) (xy 183.37986 -279.501455) (xy 183.423708 -279.470085)
			(xy 183.471656 -279.445433) (xy 183.522683 -279.428025) (xy 183.575701 -279.418232) (xy 183.62958 -279.416263)
			(xy 183.683171 -279.42216) (xy 183.735332 -279.435796) (xy 183.784952 -279.456883) (xy 183.830973 -279.484969)
			(xy 183.872415 -279.519457) (xy 183.908393 -279.559611) (xy 183.938141 -279.604575) (xy 183.961026 -279.653392)
			(xy 183.976558 -279.705021) (xy 183.984408 -279.758361) (xy 183.9849 -279.785318) (xy 190.790845 -279.785318)
			(xy 190.79478 -279.731547) (xy 190.806503 -279.678923) (xy 190.825763 -279.628566) (xy 190.852149 -279.581549)
			(xy 190.885101 -279.538876) (xy 190.923914 -279.501455) (xy 190.967762 -279.470085) (xy 191.01571 -279.445433)
			(xy 191.066737 -279.428025) (xy 191.119755 -279.418232) (xy 191.173634 -279.416263) (xy 191.227225 -279.42216)
			(xy 191.279386 -279.435796) (xy 191.329006 -279.456883) (xy 191.375027 -279.484969) (xy 191.416469 -279.519457)
			(xy 191.452447 -279.559611) (xy 191.482195 -279.604575) (xy 191.50508 -279.653392) (xy 191.520612 -279.705021)
			(xy 191.528462 -279.758361) (xy 191.528954 -279.785318) (xy 198.334899 -279.785318) (xy 198.338834 -279.731547)
			(xy 198.350557 -279.678923) (xy 198.369817 -279.628566) (xy 198.396203 -279.581549) (xy 198.429155 -279.538876)
			(xy 198.467968 -279.501455) (xy 198.511816 -279.470085) (xy 198.559764 -279.445433) (xy 198.610791 -279.428025)
			(xy 198.663809 -279.418232) (xy 198.717688 -279.416263) (xy 198.771279 -279.42216) (xy 198.82344 -279.435796)
			(xy 198.87306 -279.456883) (xy 198.919081 -279.484969) (xy 198.960523 -279.519457) (xy 198.996501 -279.559611)
			(xy 199.026249 -279.604575) (xy 199.049134 -279.653392) (xy 199.064666 -279.705021) (xy 199.072516 -279.758361)
			(xy 199.073008 -279.785318) (xy 205.878699 -279.785318) (xy 205.882634 -279.731547) (xy 205.894357 -279.678923)
			(xy 205.913617 -279.628566) (xy 205.940003 -279.581549) (xy 205.972955 -279.538876) (xy 206.011768 -279.501455)
			(xy 206.055616 -279.470085) (xy 206.103564 -279.445433) (xy 206.154591 -279.428025) (xy 206.207609 -279.418232)
			(xy 206.261488 -279.416263) (xy 206.315079 -279.42216) (xy 206.36724 -279.435796) (xy 206.41686 -279.456883)
			(xy 206.462881 -279.484969) (xy 206.504323 -279.519457) (xy 206.540301 -279.559611) (xy 206.570049 -279.604575)
			(xy 206.592934 -279.653392) (xy 206.608466 -279.705021) (xy 206.616316 -279.758361) (xy 206.616808 -279.785318)
			(xy 206.616316 -279.812275) (xy 206.608466 -279.865615) (xy 206.592934 -279.917244) (xy 206.570049 -279.966061)
			(xy 206.540301 -280.011025) (xy 206.504323 -280.051179) (xy 206.462881 -280.085667) (xy 206.41686 -280.113753)
			(xy 206.36724 -280.13484) (xy 206.315079 -280.148476) (xy 206.261488 -280.154373) (xy 206.207609 -280.152404)
			(xy 206.154591 -280.142611) (xy 206.103564 -280.125203) (xy 206.055616 -280.100551) (xy 206.011768 -280.069181)
			(xy 205.972955 -280.03176) (xy 205.940003 -279.989087) (xy 205.913617 -279.94207) (xy 205.894357 -279.891713)
			(xy 205.882634 -279.839089) (xy 205.878699 -279.785318) (xy 199.073008 -279.785318) (xy 199.072516 -279.812275)
			(xy 199.064666 -279.865615) (xy 199.049134 -279.917244) (xy 199.026249 -279.966061) (xy 198.996501 -280.011025)
			(xy 198.960523 -280.051179) (xy 198.919081 -280.085667) (xy 198.87306 -280.113753) (xy 198.82344 -280.13484)
			(xy 198.771279 -280.148476) (xy 198.717688 -280.154373) (xy 198.663809 -280.152404) (xy 198.610791 -280.142611)
			(xy 198.559764 -280.125203) (xy 198.511816 -280.100551) (xy 198.467968 -280.069181) (xy 198.429155 -280.03176)
			(xy 198.396203 -279.989087) (xy 198.369817 -279.94207) (xy 198.350557 -279.891713) (xy 198.338834 -279.839089)
			(xy 198.334899 -279.785318) (xy 191.528954 -279.785318) (xy 191.528462 -279.812275) (xy 191.520612 -279.865615)
			(xy 191.50508 -279.917244) (xy 191.482195 -279.966061) (xy 191.452447 -280.011025) (xy 191.416469 -280.051179)
			(xy 191.375027 -280.085667) (xy 191.329006 -280.113753) (xy 191.279386 -280.13484) (xy 191.227225 -280.148476)
			(xy 191.173634 -280.154373) (xy 191.119755 -280.152404) (xy 191.066737 -280.142611) (xy 191.01571 -280.125203)
			(xy 190.967762 -280.100551) (xy 190.923914 -280.069181) (xy 190.885101 -280.03176) (xy 190.852149 -279.989087)
			(xy 190.825763 -279.94207) (xy 190.806503 -279.891713) (xy 190.79478 -279.839089) (xy 190.790845 -279.785318)
			(xy 183.9849 -279.785318) (xy 183.984408 -279.812275) (xy 183.976558 -279.865615) (xy 183.961026 -279.917244)
			(xy 183.938141 -279.966061) (xy 183.908393 -280.011025) (xy 183.872415 -280.051179) (xy 183.830973 -280.085667)
			(xy 183.784952 -280.113753) (xy 183.735332 -280.13484) (xy 183.683171 -280.148476) (xy 183.62958 -280.154373)
			(xy 183.575701 -280.152404) (xy 183.522683 -280.142611) (xy 183.471656 -280.125203) (xy 183.423708 -280.100551)
			(xy 183.37986 -280.069181) (xy 183.341047 -280.03176) (xy 183.308095 -279.989087) (xy 183.281709 -279.94207)
			(xy 183.262449 -279.891713) (xy 183.250726 -279.839089) (xy 183.246791 -279.785318) (xy 177.881534 -279.785318)
			(xy 177.881534 -280.635202) (xy 179.146723 -280.635202) (xy 179.150658 -280.581431) (xy 179.162381 -280.528807)
			(xy 179.181641 -280.47845) (xy 179.208027 -280.431433) (xy 179.240979 -280.38876) (xy 179.279792 -280.351339)
			(xy 179.32364 -280.319969) (xy 179.371588 -280.295317) (xy 179.422615 -280.277909) (xy 179.475633 -280.268116)
			(xy 179.529512 -280.266147) (xy 179.583103 -280.272044) (xy 179.635264 -280.28568) (xy 179.684884 -280.306767)
			(xy 179.730905 -280.334853) (xy 179.772347 -280.369341) (xy 179.808325 -280.409495) (xy 179.838073 -280.454459)
			(xy 179.860958 -280.503276) (xy 179.87649 -280.554905) (xy 179.88434 -280.608245) (xy 179.884832 -280.635202)
			(xy 186.690777 -280.635202) (xy 186.694712 -280.581431) (xy 186.706435 -280.528807) (xy 186.725695 -280.47845)
			(xy 186.752081 -280.431433) (xy 186.785033 -280.38876) (xy 186.823846 -280.351339) (xy 186.867694 -280.319969)
			(xy 186.915642 -280.295317) (xy 186.966669 -280.277909) (xy 187.019687 -280.268116) (xy 187.073566 -280.266147)
			(xy 187.127157 -280.272044) (xy 187.179318 -280.28568) (xy 187.228938 -280.306767) (xy 187.274959 -280.334853)
			(xy 187.316401 -280.369341) (xy 187.352379 -280.409495) (xy 187.382127 -280.454459) (xy 187.405012 -280.503276)
			(xy 187.420544 -280.554905) (xy 187.428394 -280.608245) (xy 187.428886 -280.635202) (xy 194.234831 -280.635202)
			(xy 194.238766 -280.581431) (xy 194.250489 -280.528807) (xy 194.269749 -280.47845) (xy 194.296135 -280.431433)
			(xy 194.329087 -280.38876) (xy 194.3679 -280.351339) (xy 194.411748 -280.319969) (xy 194.459696 -280.295317)
			(xy 194.510723 -280.277909) (xy 194.563741 -280.268116) (xy 194.61762 -280.266147) (xy 194.671211 -280.272044)
			(xy 194.723372 -280.28568) (xy 194.772992 -280.306767) (xy 194.819013 -280.334853) (xy 194.860455 -280.369341)
			(xy 194.896433 -280.409495) (xy 194.926181 -280.454459) (xy 194.949066 -280.503276) (xy 194.964598 -280.554905)
			(xy 194.972448 -280.608245) (xy 194.97294 -280.635202) (xy 201.778631 -280.635202) (xy 201.782566 -280.581431)
			(xy 201.794289 -280.528807) (xy 201.813549 -280.47845) (xy 201.839935 -280.431433) (xy 201.872887 -280.38876)
			(xy 201.9117 -280.351339) (xy 201.955548 -280.319969) (xy 202.003496 -280.295317) (xy 202.054523 -280.277909)
			(xy 202.107541 -280.268116) (xy 202.16142 -280.266147) (xy 202.215011 -280.272044) (xy 202.267172 -280.28568)
			(xy 202.316792 -280.306767) (xy 202.362813 -280.334853) (xy 202.404255 -280.369341) (xy 202.440233 -280.409495)
			(xy 202.469981 -280.454459) (xy 202.492866 -280.503276) (xy 202.508398 -280.554905) (xy 202.516248 -280.608245)
			(xy 202.51674 -280.635202) (xy 202.516248 -280.662159) (xy 202.508398 -280.715499) (xy 202.492866 -280.767128)
			(xy 202.469981 -280.815945) (xy 202.440233 -280.860909) (xy 202.404255 -280.901063) (xy 202.362813 -280.935551)
			(xy 202.316792 -280.963637) (xy 202.267172 -280.984724) (xy 202.215011 -280.99836) (xy 202.16142 -281.004257)
			(xy 202.107541 -281.002288) (xy 202.054523 -280.992495) (xy 202.003496 -280.975087) (xy 201.955548 -280.950435)
			(xy 201.9117 -280.919065) (xy 201.872887 -280.881644) (xy 201.839935 -280.838971) (xy 201.813549 -280.791954)
			(xy 201.794289 -280.741597) (xy 201.782566 -280.688973) (xy 201.778631 -280.635202) (xy 194.97294 -280.635202)
			(xy 194.972448 -280.662159) (xy 194.964598 -280.715499) (xy 194.949066 -280.767128) (xy 194.926181 -280.815945)
			(xy 194.896433 -280.860909) (xy 194.860455 -280.901063) (xy 194.819013 -280.935551) (xy 194.772992 -280.963637)
			(xy 194.723372 -280.984724) (xy 194.671211 -280.99836) (xy 194.61762 -281.004257) (xy 194.563741 -281.002288)
			(xy 194.510723 -280.992495) (xy 194.459696 -280.975087) (xy 194.411748 -280.950435) (xy 194.3679 -280.919065)
			(xy 194.329087 -280.881644) (xy 194.296135 -280.838971) (xy 194.269749 -280.791954) (xy 194.250489 -280.741597)
			(xy 194.238766 -280.688973) (xy 194.234831 -280.635202) (xy 187.428886 -280.635202) (xy 187.428394 -280.662159)
			(xy 187.420544 -280.715499) (xy 187.405012 -280.767128) (xy 187.382127 -280.815945) (xy 187.352379 -280.860909)
			(xy 187.316401 -280.901063) (xy 187.274959 -280.935551) (xy 187.228938 -280.963637) (xy 187.179318 -280.984724)
			(xy 187.127157 -280.99836) (xy 187.073566 -281.004257) (xy 187.019687 -281.002288) (xy 186.966669 -280.992495)
			(xy 186.915642 -280.975087) (xy 186.867694 -280.950435) (xy 186.823846 -280.919065) (xy 186.785033 -280.881644)
			(xy 186.752081 -280.838971) (xy 186.725695 -280.791954) (xy 186.706435 -280.741597) (xy 186.694712 -280.688973)
			(xy 186.690777 -280.635202) (xy 179.884832 -280.635202) (xy 179.88434 -280.662159) (xy 179.87649 -280.715499)
			(xy 179.860958 -280.767128) (xy 179.838073 -280.815945) (xy 179.808325 -280.860909) (xy 179.772347 -280.901063)
			(xy 179.730905 -280.935551) (xy 179.684884 -280.963637) (xy 179.635264 -280.984724) (xy 179.583103 -280.99836)
			(xy 179.529512 -281.004257) (xy 179.475633 -281.002288) (xy 179.422615 -280.992495) (xy 179.371588 -280.975087)
			(xy 179.32364 -280.950435) (xy 179.279792 -280.919065) (xy 179.240979 -280.881644) (xy 179.208027 -280.838971)
			(xy 179.181641 -280.791954) (xy 179.162381 -280.741597) (xy 179.150658 -280.688973) (xy 179.146723 -280.635202)
			(xy 177.881534 -280.635202) (xy 177.881534 -281.48534) (xy 183.246791 -281.48534) (xy 183.250726 -281.431569)
			(xy 183.262449 -281.378945) (xy 183.281709 -281.328588) (xy 183.308095 -281.281571) (xy 183.341047 -281.238898)
			(xy 183.37986 -281.201477) (xy 183.423708 -281.170107) (xy 183.471656 -281.145455) (xy 183.522683 -281.128047)
			(xy 183.575701 -281.118254) (xy 183.62958 -281.116285) (xy 183.683171 -281.122182) (xy 183.735332 -281.135818)
			(xy 183.784952 -281.156905) (xy 183.830973 -281.184991) (xy 183.872415 -281.219479) (xy 183.908393 -281.259633)
			(xy 183.938141 -281.304597) (xy 183.961026 -281.353414) (xy 183.976558 -281.405043) (xy 183.984408 -281.458383)
			(xy 183.9849 -281.48534) (xy 190.790845 -281.48534) (xy 190.79478 -281.431569) (xy 190.806503 -281.378945)
			(xy 190.825763 -281.328588) (xy 190.852149 -281.281571) (xy 190.885101 -281.238898) (xy 190.923914 -281.201477)
			(xy 190.967762 -281.170107) (xy 191.01571 -281.145455) (xy 191.066737 -281.128047) (xy 191.119755 -281.118254)
			(xy 191.173634 -281.116285) (xy 191.227225 -281.122182) (xy 191.279386 -281.135818) (xy 191.329006 -281.156905)
			(xy 191.375027 -281.184991) (xy 191.416469 -281.219479) (xy 191.452447 -281.259633) (xy 191.482195 -281.304597)
			(xy 191.50508 -281.353414) (xy 191.520612 -281.405043) (xy 191.528462 -281.458383) (xy 191.528954 -281.48534)
			(xy 198.334899 -281.48534) (xy 198.338834 -281.431569) (xy 198.350557 -281.378945) (xy 198.369817 -281.328588)
			(xy 198.396203 -281.281571) (xy 198.429155 -281.238898) (xy 198.467968 -281.201477) (xy 198.511816 -281.170107)
			(xy 198.559764 -281.145455) (xy 198.610791 -281.128047) (xy 198.663809 -281.118254) (xy 198.717688 -281.116285)
			(xy 198.771279 -281.122182) (xy 198.82344 -281.135818) (xy 198.87306 -281.156905) (xy 198.919081 -281.184991)
			(xy 198.960523 -281.219479) (xy 198.996501 -281.259633) (xy 199.026249 -281.304597) (xy 199.049134 -281.353414)
			(xy 199.064666 -281.405043) (xy 199.072516 -281.458383) (xy 199.073008 -281.48534) (xy 205.878699 -281.48534)
			(xy 205.882634 -281.431569) (xy 205.894357 -281.378945) (xy 205.913617 -281.328588) (xy 205.940003 -281.281571)
			(xy 205.972955 -281.238898) (xy 206.011768 -281.201477) (xy 206.055616 -281.170107) (xy 206.103564 -281.145455)
			(xy 206.154591 -281.128047) (xy 206.207609 -281.118254) (xy 206.261488 -281.116285) (xy 206.315079 -281.122182)
			(xy 206.36724 -281.135818) (xy 206.41686 -281.156905) (xy 206.462881 -281.184991) (xy 206.504323 -281.219479)
			(xy 206.540301 -281.259633) (xy 206.570049 -281.304597) (xy 206.592934 -281.353414) (xy 206.608466 -281.405043)
			(xy 206.616316 -281.458383) (xy 206.616808 -281.48534) (xy 206.616316 -281.512297) (xy 206.608466 -281.565637)
			(xy 206.592934 -281.617266) (xy 206.570049 -281.666083) (xy 206.540301 -281.711047) (xy 206.504323 -281.751201)
			(xy 206.462881 -281.785689) (xy 206.41686 -281.813775) (xy 206.36724 -281.834862) (xy 206.315079 -281.848498)
			(xy 206.261488 -281.854395) (xy 206.207609 -281.852426) (xy 206.154591 -281.842633) (xy 206.103564 -281.825225)
			(xy 206.055616 -281.800573) (xy 206.011768 -281.769203) (xy 205.972955 -281.731782) (xy 205.940003 -281.689109)
			(xy 205.913617 -281.642092) (xy 205.894357 -281.591735) (xy 205.882634 -281.539111) (xy 205.878699 -281.48534)
			(xy 199.073008 -281.48534) (xy 199.072516 -281.512297) (xy 199.064666 -281.565637) (xy 199.049134 -281.617266)
			(xy 199.026249 -281.666083) (xy 198.996501 -281.711047) (xy 198.960523 -281.751201) (xy 198.919081 -281.785689)
			(xy 198.87306 -281.813775) (xy 198.82344 -281.834862) (xy 198.771279 -281.848498) (xy 198.717688 -281.854395)
			(xy 198.663809 -281.852426) (xy 198.610791 -281.842633) (xy 198.559764 -281.825225) (xy 198.511816 -281.800573)
			(xy 198.467968 -281.769203) (xy 198.429155 -281.731782) (xy 198.396203 -281.689109) (xy 198.369817 -281.642092)
			(xy 198.350557 -281.591735) (xy 198.338834 -281.539111) (xy 198.334899 -281.48534) (xy 191.528954 -281.48534)
			(xy 191.528462 -281.512297) (xy 191.520612 -281.565637) (xy 191.50508 -281.617266) (xy 191.482195 -281.666083)
			(xy 191.452447 -281.711047) (xy 191.416469 -281.751201) (xy 191.375027 -281.785689) (xy 191.329006 -281.813775)
			(xy 191.279386 -281.834862) (xy 191.227225 -281.848498) (xy 191.173634 -281.854395) (xy 191.119755 -281.852426)
			(xy 191.066737 -281.842633) (xy 191.01571 -281.825225) (xy 190.967762 -281.800573) (xy 190.923914 -281.769203)
			(xy 190.885101 -281.731782) (xy 190.852149 -281.689109) (xy 190.825763 -281.642092) (xy 190.806503 -281.591735)
			(xy 190.79478 -281.539111) (xy 190.790845 -281.48534) (xy 183.9849 -281.48534) (xy 183.984408 -281.512297)
			(xy 183.976558 -281.565637) (xy 183.961026 -281.617266) (xy 183.938141 -281.666083) (xy 183.908393 -281.711047)
			(xy 183.872415 -281.751201) (xy 183.830973 -281.785689) (xy 183.784952 -281.813775) (xy 183.735332 -281.834862)
			(xy 183.683171 -281.848498) (xy 183.62958 -281.854395) (xy 183.575701 -281.852426) (xy 183.522683 -281.842633)
			(xy 183.471656 -281.825225) (xy 183.423708 -281.800573) (xy 183.37986 -281.769203) (xy 183.341047 -281.731782)
			(xy 183.308095 -281.689109) (xy 183.281709 -281.642092) (xy 183.262449 -281.591735) (xy 183.250726 -281.539111)
			(xy 183.246791 -281.48534) (xy 177.881534 -281.48534) (xy 177.881534 -282.335224) (xy 179.146723 -282.335224)
			(xy 179.150658 -282.281453) (xy 179.162381 -282.228829) (xy 179.181641 -282.178472) (xy 179.208027 -282.131455)
			(xy 179.240979 -282.088782) (xy 179.279792 -282.051361) (xy 179.32364 -282.019991) (xy 179.371588 -281.995339)
			(xy 179.422615 -281.977931) (xy 179.475633 -281.968138) (xy 179.529512 -281.966169) (xy 179.583103 -281.972066)
			(xy 179.635264 -281.985702) (xy 179.684884 -282.006789) (xy 179.730905 -282.034875) (xy 179.772347 -282.069363)
			(xy 179.808325 -282.109517) (xy 179.838073 -282.154481) (xy 179.860958 -282.203298) (xy 179.87649 -282.254927)
			(xy 179.88434 -282.308267) (xy 179.884832 -282.335224) (xy 186.690777 -282.335224) (xy 186.694712 -282.281453)
			(xy 186.706435 -282.228829) (xy 186.725695 -282.178472) (xy 186.752081 -282.131455) (xy 186.785033 -282.088782)
			(xy 186.823846 -282.051361) (xy 186.867694 -282.019991) (xy 186.915642 -281.995339) (xy 186.966669 -281.977931)
			(xy 187.019687 -281.968138) (xy 187.073566 -281.966169) (xy 187.127157 -281.972066) (xy 187.179318 -281.985702)
			(xy 187.228938 -282.006789) (xy 187.274959 -282.034875) (xy 187.316401 -282.069363) (xy 187.352379 -282.109517)
			(xy 187.382127 -282.154481) (xy 187.405012 -282.203298) (xy 187.420544 -282.254927) (xy 187.428394 -282.308267)
			(xy 187.428886 -282.335224) (xy 194.234831 -282.335224) (xy 194.238766 -282.281453) (xy 194.250489 -282.228829)
			(xy 194.269749 -282.178472) (xy 194.296135 -282.131455) (xy 194.329087 -282.088782) (xy 194.3679 -282.051361)
			(xy 194.411748 -282.019991) (xy 194.459696 -281.995339) (xy 194.510723 -281.977931) (xy 194.563741 -281.968138)
			(xy 194.61762 -281.966169) (xy 194.671211 -281.972066) (xy 194.723372 -281.985702) (xy 194.772992 -282.006789)
			(xy 194.819013 -282.034875) (xy 194.860455 -282.069363) (xy 194.896433 -282.109517) (xy 194.926181 -282.154481)
			(xy 194.949066 -282.203298) (xy 194.964598 -282.254927) (xy 194.972448 -282.308267) (xy 194.97294 -282.335224)
			(xy 201.778631 -282.335224) (xy 201.782566 -282.281453) (xy 201.794289 -282.228829) (xy 201.813549 -282.178472)
			(xy 201.839935 -282.131455) (xy 201.872887 -282.088782) (xy 201.9117 -282.051361) (xy 201.955548 -282.019991)
			(xy 202.003496 -281.995339) (xy 202.054523 -281.977931) (xy 202.107541 -281.968138) (xy 202.16142 -281.966169)
			(xy 202.215011 -281.972066) (xy 202.267172 -281.985702) (xy 202.316792 -282.006789) (xy 202.362813 -282.034875)
			(xy 202.404255 -282.069363) (xy 202.440233 -282.109517) (xy 202.469981 -282.154481) (xy 202.492866 -282.203298)
			(xy 202.508398 -282.254927) (xy 202.516248 -282.308267) (xy 202.51674 -282.335224) (xy 202.516248 -282.362181)
			(xy 202.508398 -282.415521) (xy 202.492866 -282.46715) (xy 202.469981 -282.515967) (xy 202.440233 -282.560931)
			(xy 202.404255 -282.601085) (xy 202.362813 -282.635573) (xy 202.316792 -282.663659) (xy 202.267172 -282.684746)
			(xy 202.215011 -282.698382) (xy 202.16142 -282.704279) (xy 202.107541 -282.70231) (xy 202.054523 -282.692517)
			(xy 202.003496 -282.675109) (xy 201.955548 -282.650457) (xy 201.9117 -282.619087) (xy 201.872887 -282.581666)
			(xy 201.839935 -282.538993) (xy 201.813549 -282.491976) (xy 201.794289 -282.441619) (xy 201.782566 -282.388995)
			(xy 201.778631 -282.335224) (xy 194.97294 -282.335224) (xy 194.972448 -282.362181) (xy 194.964598 -282.415521)
			(xy 194.949066 -282.46715) (xy 194.926181 -282.515967) (xy 194.896433 -282.560931) (xy 194.860455 -282.601085)
			(xy 194.819013 -282.635573) (xy 194.772992 -282.663659) (xy 194.723372 -282.684746) (xy 194.671211 -282.698382)
			(xy 194.61762 -282.704279) (xy 194.563741 -282.70231) (xy 194.510723 -282.692517) (xy 194.459696 -282.675109)
			(xy 194.411748 -282.650457) (xy 194.3679 -282.619087) (xy 194.329087 -282.581666) (xy 194.296135 -282.538993)
			(xy 194.269749 -282.491976) (xy 194.250489 -282.441619) (xy 194.238766 -282.388995) (xy 194.234831 -282.335224)
			(xy 187.428886 -282.335224) (xy 187.428394 -282.362181) (xy 187.420544 -282.415521) (xy 187.405012 -282.46715)
			(xy 187.382127 -282.515967) (xy 187.352379 -282.560931) (xy 187.316401 -282.601085) (xy 187.274959 -282.635573)
			(xy 187.228938 -282.663659) (xy 187.179318 -282.684746) (xy 187.127157 -282.698382) (xy 187.073566 -282.704279)
			(xy 187.019687 -282.70231) (xy 186.966669 -282.692517) (xy 186.915642 -282.675109) (xy 186.867694 -282.650457)
			(xy 186.823846 -282.619087) (xy 186.785033 -282.581666) (xy 186.752081 -282.538993) (xy 186.725695 -282.491976)
			(xy 186.706435 -282.441619) (xy 186.694712 -282.388995) (xy 186.690777 -282.335224) (xy 179.884832 -282.335224)
			(xy 179.88434 -282.362181) (xy 179.87649 -282.415521) (xy 179.860958 -282.46715) (xy 179.838073 -282.515967)
			(xy 179.808325 -282.560931) (xy 179.772347 -282.601085) (xy 179.730905 -282.635573) (xy 179.684884 -282.663659)
			(xy 179.635264 -282.684746) (xy 179.583103 -282.698382) (xy 179.529512 -282.704279) (xy 179.475633 -282.70231)
			(xy 179.422615 -282.692517) (xy 179.371588 -282.675109) (xy 179.32364 -282.650457) (xy 179.279792 -282.619087)
			(xy 179.240979 -282.581666) (xy 179.208027 -282.538993) (xy 179.181641 -282.491976) (xy 179.162381 -282.441619)
			(xy 179.150658 -282.388995) (xy 179.146723 -282.335224) (xy 177.881534 -282.335224) (xy 177.881534 -283.185362)
			(xy 183.246791 -283.185362) (xy 183.250726 -283.131591) (xy 183.262449 -283.078967) (xy 183.281709 -283.02861)
			(xy 183.308095 -282.981593) (xy 183.341047 -282.93892) (xy 183.37986 -282.901499) (xy 183.423708 -282.870129)
			(xy 183.471656 -282.845477) (xy 183.522683 -282.828069) (xy 183.575701 -282.818276) (xy 183.62958 -282.816307)
			(xy 183.683171 -282.822204) (xy 183.735332 -282.83584) (xy 183.784952 -282.856927) (xy 183.830973 -282.885013)
			(xy 183.872415 -282.919501) (xy 183.908393 -282.959655) (xy 183.938141 -283.004619) (xy 183.961026 -283.053436)
			(xy 183.976558 -283.105065) (xy 183.984408 -283.158405) (xy 183.9849 -283.185362) (xy 190.790845 -283.185362)
			(xy 190.79478 -283.131591) (xy 190.806503 -283.078967) (xy 190.825763 -283.02861) (xy 190.852149 -282.981593)
			(xy 190.885101 -282.93892) (xy 190.923914 -282.901499) (xy 190.967762 -282.870129) (xy 191.01571 -282.845477)
			(xy 191.066737 -282.828069) (xy 191.119755 -282.818276) (xy 191.173634 -282.816307) (xy 191.227225 -282.822204)
			(xy 191.279386 -282.83584) (xy 191.329006 -282.856927) (xy 191.375027 -282.885013) (xy 191.416469 -282.919501)
			(xy 191.452447 -282.959655) (xy 191.482195 -283.004619) (xy 191.50508 -283.053436) (xy 191.520612 -283.105065)
			(xy 191.528462 -283.158405) (xy 191.528954 -283.185362) (xy 198.334899 -283.185362) (xy 198.338834 -283.131591)
			(xy 198.350557 -283.078967) (xy 198.369817 -283.02861) (xy 198.396203 -282.981593) (xy 198.429155 -282.93892)
			(xy 198.467968 -282.901499) (xy 198.511816 -282.870129) (xy 198.559764 -282.845477) (xy 198.610791 -282.828069)
			(xy 198.663809 -282.818276) (xy 198.717688 -282.816307) (xy 198.771279 -282.822204) (xy 198.82344 -282.83584)
			(xy 198.87306 -282.856927) (xy 198.919081 -282.885013) (xy 198.960523 -282.919501) (xy 198.996501 -282.959655)
			(xy 199.026249 -283.004619) (xy 199.049134 -283.053436) (xy 199.064666 -283.105065) (xy 199.072516 -283.158405)
			(xy 199.073008 -283.185362) (xy 205.878699 -283.185362) (xy 205.882634 -283.131591) (xy 205.894357 -283.078967)
			(xy 205.913617 -283.02861) (xy 205.940003 -282.981593) (xy 205.972955 -282.93892) (xy 206.011768 -282.901499)
			(xy 206.055616 -282.870129) (xy 206.103564 -282.845477) (xy 206.154591 -282.828069) (xy 206.207609 -282.818276)
			(xy 206.261488 -282.816307) (xy 206.315079 -282.822204) (xy 206.36724 -282.83584) (xy 206.41686 -282.856927)
			(xy 206.462881 -282.885013) (xy 206.504323 -282.919501) (xy 206.540301 -282.959655) (xy 206.570049 -283.004619)
			(xy 206.592934 -283.053436) (xy 206.608466 -283.105065) (xy 206.616316 -283.158405) (xy 206.616808 -283.185362)
			(xy 206.616316 -283.212319) (xy 206.608466 -283.265659) (xy 206.592934 -283.317288) (xy 206.570049 -283.366105)
			(xy 206.540301 -283.411069) (xy 206.504323 -283.451223) (xy 206.462881 -283.485711) (xy 206.41686 -283.513797)
			(xy 206.36724 -283.534884) (xy 206.315079 -283.54852) (xy 206.261488 -283.554417) (xy 206.207609 -283.552448)
			(xy 206.154591 -283.542655) (xy 206.103564 -283.525247) (xy 206.055616 -283.500595) (xy 206.011768 -283.469225)
			(xy 205.972955 -283.431804) (xy 205.940003 -283.389131) (xy 205.913617 -283.342114) (xy 205.894357 -283.291757)
			(xy 205.882634 -283.239133) (xy 205.878699 -283.185362) (xy 199.073008 -283.185362) (xy 199.072516 -283.212319)
			(xy 199.064666 -283.265659) (xy 199.049134 -283.317288) (xy 199.026249 -283.366105) (xy 198.996501 -283.411069)
			(xy 198.960523 -283.451223) (xy 198.919081 -283.485711) (xy 198.87306 -283.513797) (xy 198.82344 -283.534884)
			(xy 198.771279 -283.54852) (xy 198.717688 -283.554417) (xy 198.663809 -283.552448) (xy 198.610791 -283.542655)
			(xy 198.559764 -283.525247) (xy 198.511816 -283.500595) (xy 198.467968 -283.469225) (xy 198.429155 -283.431804)
			(xy 198.396203 -283.389131) (xy 198.369817 -283.342114) (xy 198.350557 -283.291757) (xy 198.338834 -283.239133)
			(xy 198.334899 -283.185362) (xy 191.528954 -283.185362) (xy 191.528462 -283.212319) (xy 191.520612 -283.265659)
			(xy 191.50508 -283.317288) (xy 191.482195 -283.366105) (xy 191.452447 -283.411069) (xy 191.416469 -283.451223)
			(xy 191.375027 -283.485711) (xy 191.329006 -283.513797) (xy 191.279386 -283.534884) (xy 191.227225 -283.54852)
			(xy 191.173634 -283.554417) (xy 191.119755 -283.552448) (xy 191.066737 -283.542655) (xy 191.01571 -283.525247)
			(xy 190.967762 -283.500595) (xy 190.923914 -283.469225) (xy 190.885101 -283.431804) (xy 190.852149 -283.389131)
			(xy 190.825763 -283.342114) (xy 190.806503 -283.291757) (xy 190.79478 -283.239133) (xy 190.790845 -283.185362)
			(xy 183.9849 -283.185362) (xy 183.984408 -283.212319) (xy 183.976558 -283.265659) (xy 183.961026 -283.317288)
			(xy 183.938141 -283.366105) (xy 183.908393 -283.411069) (xy 183.872415 -283.451223) (xy 183.830973 -283.485711)
			(xy 183.784952 -283.513797) (xy 183.735332 -283.534884) (xy 183.683171 -283.54852) (xy 183.62958 -283.554417)
			(xy 183.575701 -283.552448) (xy 183.522683 -283.542655) (xy 183.471656 -283.525247) (xy 183.423708 -283.500595)
			(xy 183.37986 -283.469225) (xy 183.341047 -283.431804) (xy 183.308095 -283.389131) (xy 183.281709 -283.342114)
			(xy 183.262449 -283.291757) (xy 183.250726 -283.239133) (xy 183.246791 -283.185362) (xy 177.881534 -283.185362)
			(xy 177.881534 -284.035246) (xy 179.146723 -284.035246) (xy 179.150658 -283.981475) (xy 179.162381 -283.928851)
			(xy 179.181641 -283.878494) (xy 179.208027 -283.831477) (xy 179.240979 -283.788804) (xy 179.279792 -283.751383)
			(xy 179.32364 -283.720013) (xy 179.371588 -283.695361) (xy 179.422615 -283.677953) (xy 179.475633 -283.66816)
			(xy 179.529512 -283.666191) (xy 179.583103 -283.672088) (xy 179.635264 -283.685724) (xy 179.684884 -283.706811)
			(xy 179.730905 -283.734897) (xy 179.772347 -283.769385) (xy 179.808325 -283.809539) (xy 179.838073 -283.854503)
			(xy 179.860958 -283.90332) (xy 179.87649 -283.954949) (xy 179.88434 -284.008289) (xy 179.884832 -284.035246)
			(xy 186.690777 -284.035246) (xy 186.694712 -283.981475) (xy 186.706435 -283.928851) (xy 186.725695 -283.878494)
			(xy 186.752081 -283.831477) (xy 186.785033 -283.788804) (xy 186.823846 -283.751383) (xy 186.867694 -283.720013)
			(xy 186.915642 -283.695361) (xy 186.966669 -283.677953) (xy 187.019687 -283.66816) (xy 187.073566 -283.666191)
			(xy 187.127157 -283.672088) (xy 187.179318 -283.685724) (xy 187.228938 -283.706811) (xy 187.274959 -283.734897)
			(xy 187.316401 -283.769385) (xy 187.352379 -283.809539) (xy 187.382127 -283.854503) (xy 187.405012 -283.90332)
			(xy 187.420544 -283.954949) (xy 187.428394 -284.008289) (xy 187.428886 -284.035246) (xy 194.234831 -284.035246)
			(xy 194.238766 -283.981475) (xy 194.250489 -283.928851) (xy 194.269749 -283.878494) (xy 194.296135 -283.831477)
			(xy 194.329087 -283.788804) (xy 194.3679 -283.751383) (xy 194.411748 -283.720013) (xy 194.459696 -283.695361)
			(xy 194.510723 -283.677953) (xy 194.563741 -283.66816) (xy 194.61762 -283.666191) (xy 194.671211 -283.672088)
			(xy 194.723372 -283.685724) (xy 194.772992 -283.706811) (xy 194.819013 -283.734897) (xy 194.860455 -283.769385)
			(xy 194.896433 -283.809539) (xy 194.926181 -283.854503) (xy 194.949066 -283.90332) (xy 194.964598 -283.954949)
			(xy 194.972448 -284.008289) (xy 194.97294 -284.035246) (xy 201.778631 -284.035246) (xy 201.782566 -283.981475)
			(xy 201.794289 -283.928851) (xy 201.813549 -283.878494) (xy 201.839935 -283.831477) (xy 201.872887 -283.788804)
			(xy 201.9117 -283.751383) (xy 201.955548 -283.720013) (xy 202.003496 -283.695361) (xy 202.054523 -283.677953)
			(xy 202.107541 -283.66816) (xy 202.16142 -283.666191) (xy 202.215011 -283.672088) (xy 202.267172 -283.685724)
			(xy 202.316792 -283.706811) (xy 202.362813 -283.734897) (xy 202.404255 -283.769385) (xy 202.440233 -283.809539)
			(xy 202.469981 -283.854503) (xy 202.492866 -283.90332) (xy 202.508398 -283.954949) (xy 202.516248 -284.008289)
			(xy 202.51674 -284.035246) (xy 202.516248 -284.062203) (xy 202.508398 -284.115543) (xy 202.492866 -284.167172)
			(xy 202.469981 -284.215989) (xy 202.440233 -284.260953) (xy 202.404255 -284.301107) (xy 202.362813 -284.335595)
			(xy 202.316792 -284.363681) (xy 202.267172 -284.384768) (xy 202.215011 -284.398404) (xy 202.16142 -284.404301)
			(xy 202.107541 -284.402332) (xy 202.054523 -284.392539) (xy 202.003496 -284.375131) (xy 201.955548 -284.350479)
			(xy 201.9117 -284.319109) (xy 201.872887 -284.281688) (xy 201.839935 -284.239015) (xy 201.813549 -284.191998)
			(xy 201.794289 -284.141641) (xy 201.782566 -284.089017) (xy 201.778631 -284.035246) (xy 194.97294 -284.035246)
			(xy 194.972448 -284.062203) (xy 194.964598 -284.115543) (xy 194.949066 -284.167172) (xy 194.926181 -284.215989)
			(xy 194.896433 -284.260953) (xy 194.860455 -284.301107) (xy 194.819013 -284.335595) (xy 194.772992 -284.363681)
			(xy 194.723372 -284.384768) (xy 194.671211 -284.398404) (xy 194.61762 -284.404301) (xy 194.563741 -284.402332)
			(xy 194.510723 -284.392539) (xy 194.459696 -284.375131) (xy 194.411748 -284.350479) (xy 194.3679 -284.319109)
			(xy 194.329087 -284.281688) (xy 194.296135 -284.239015) (xy 194.269749 -284.191998) (xy 194.250489 -284.141641)
			(xy 194.238766 -284.089017) (xy 194.234831 -284.035246) (xy 187.428886 -284.035246) (xy 187.428394 -284.062203)
			(xy 187.420544 -284.115543) (xy 187.405012 -284.167172) (xy 187.382127 -284.215989) (xy 187.352379 -284.260953)
			(xy 187.316401 -284.301107) (xy 187.274959 -284.335595) (xy 187.228938 -284.363681) (xy 187.179318 -284.384768)
			(xy 187.127157 -284.398404) (xy 187.073566 -284.404301) (xy 187.019687 -284.402332) (xy 186.966669 -284.392539)
			(xy 186.915642 -284.375131) (xy 186.867694 -284.350479) (xy 186.823846 -284.319109) (xy 186.785033 -284.281688)
			(xy 186.752081 -284.239015) (xy 186.725695 -284.191998) (xy 186.706435 -284.141641) (xy 186.694712 -284.089017)
			(xy 186.690777 -284.035246) (xy 179.884832 -284.035246) (xy 179.88434 -284.062203) (xy 179.87649 -284.115543)
			(xy 179.860958 -284.167172) (xy 179.838073 -284.215989) (xy 179.808325 -284.260953) (xy 179.772347 -284.301107)
			(xy 179.730905 -284.335595) (xy 179.684884 -284.363681) (xy 179.635264 -284.384768) (xy 179.583103 -284.398404)
			(xy 179.529512 -284.404301) (xy 179.475633 -284.402332) (xy 179.422615 -284.392539) (xy 179.371588 -284.375131)
			(xy 179.32364 -284.350479) (xy 179.279792 -284.319109) (xy 179.240979 -284.281688) (xy 179.208027 -284.239015)
			(xy 179.181641 -284.191998) (xy 179.162381 -284.141641) (xy 179.150658 -284.089017) (xy 179.146723 -284.035246)
			(xy 177.881534 -284.035246) (xy 177.881534 -284.885384) (xy 183.246791 -284.885384) (xy 183.250726 -284.831613)
			(xy 183.262449 -284.778989) (xy 183.281709 -284.728632) (xy 183.308095 -284.681615) (xy 183.341047 -284.638942)
			(xy 183.37986 -284.601521) (xy 183.423708 -284.570151) (xy 183.471656 -284.545499) (xy 183.522683 -284.528091)
			(xy 183.575701 -284.518298) (xy 183.62958 -284.516329) (xy 183.683171 -284.522226) (xy 183.735332 -284.535862)
			(xy 183.784952 -284.556949) (xy 183.830973 -284.585035) (xy 183.872415 -284.619523) (xy 183.908393 -284.659677)
			(xy 183.938141 -284.704641) (xy 183.961026 -284.753458) (xy 183.976558 -284.805087) (xy 183.984408 -284.858427)
			(xy 183.9849 -284.885384) (xy 190.790845 -284.885384) (xy 190.79478 -284.831613) (xy 190.806503 -284.778989)
			(xy 190.825763 -284.728632) (xy 190.852149 -284.681615) (xy 190.885101 -284.638942) (xy 190.923914 -284.601521)
			(xy 190.967762 -284.570151) (xy 191.01571 -284.545499) (xy 191.066737 -284.528091) (xy 191.119755 -284.518298)
			(xy 191.173634 -284.516329) (xy 191.227225 -284.522226) (xy 191.279386 -284.535862) (xy 191.329006 -284.556949)
			(xy 191.375027 -284.585035) (xy 191.416469 -284.619523) (xy 191.452447 -284.659677) (xy 191.482195 -284.704641)
			(xy 191.50508 -284.753458) (xy 191.520612 -284.805087) (xy 191.528462 -284.858427) (xy 191.528954 -284.885384)
			(xy 198.334899 -284.885384) (xy 198.338834 -284.831613) (xy 198.350557 -284.778989) (xy 198.369817 -284.728632)
			(xy 198.396203 -284.681615) (xy 198.429155 -284.638942) (xy 198.467968 -284.601521) (xy 198.511816 -284.570151)
			(xy 198.559764 -284.545499) (xy 198.610791 -284.528091) (xy 198.663809 -284.518298) (xy 198.717688 -284.516329)
			(xy 198.771279 -284.522226) (xy 198.82344 -284.535862) (xy 198.87306 -284.556949) (xy 198.919081 -284.585035)
			(xy 198.960523 -284.619523) (xy 198.996501 -284.659677) (xy 199.026249 -284.704641) (xy 199.049134 -284.753458)
			(xy 199.064666 -284.805087) (xy 199.072516 -284.858427) (xy 199.073008 -284.885384) (xy 205.878699 -284.885384)
			(xy 205.882634 -284.831613) (xy 205.894357 -284.778989) (xy 205.913617 -284.728632) (xy 205.940003 -284.681615)
			(xy 205.972955 -284.638942) (xy 206.011768 -284.601521) (xy 206.055616 -284.570151) (xy 206.103564 -284.545499)
			(xy 206.154591 -284.528091) (xy 206.207609 -284.518298) (xy 206.261488 -284.516329) (xy 206.315079 -284.522226)
			(xy 206.36724 -284.535862) (xy 206.41686 -284.556949) (xy 206.462881 -284.585035) (xy 206.504323 -284.619523)
			(xy 206.540301 -284.659677) (xy 206.570049 -284.704641) (xy 206.592934 -284.753458) (xy 206.608466 -284.805087)
			(xy 206.616316 -284.858427) (xy 206.616808 -284.885384) (xy 206.616316 -284.912341) (xy 206.608466 -284.965681)
			(xy 206.592934 -285.01731) (xy 206.570049 -285.066127) (xy 206.540301 -285.111091) (xy 206.504323 -285.151245)
			(xy 206.462881 -285.185733) (xy 206.41686 -285.213819) (xy 206.36724 -285.234906) (xy 206.315079 -285.248542)
			(xy 206.261488 -285.254439) (xy 206.207609 -285.25247) (xy 206.154591 -285.242677) (xy 206.103564 -285.225269)
			(xy 206.055616 -285.200617) (xy 206.011768 -285.169247) (xy 205.972955 -285.131826) (xy 205.940003 -285.089153)
			(xy 205.913617 -285.042136) (xy 205.894357 -284.991779) (xy 205.882634 -284.939155) (xy 205.878699 -284.885384)
			(xy 199.073008 -284.885384) (xy 199.072516 -284.912341) (xy 199.064666 -284.965681) (xy 199.049134 -285.01731)
			(xy 199.026249 -285.066127) (xy 198.996501 -285.111091) (xy 198.960523 -285.151245) (xy 198.919081 -285.185733)
			(xy 198.87306 -285.213819) (xy 198.82344 -285.234906) (xy 198.771279 -285.248542) (xy 198.717688 -285.254439)
			(xy 198.663809 -285.25247) (xy 198.610791 -285.242677) (xy 198.559764 -285.225269) (xy 198.511816 -285.200617)
			(xy 198.467968 -285.169247) (xy 198.429155 -285.131826) (xy 198.396203 -285.089153) (xy 198.369817 -285.042136)
			(xy 198.350557 -284.991779) (xy 198.338834 -284.939155) (xy 198.334899 -284.885384) (xy 191.528954 -284.885384)
			(xy 191.528462 -284.912341) (xy 191.520612 -284.965681) (xy 191.50508 -285.01731) (xy 191.482195 -285.066127)
			(xy 191.452447 -285.111091) (xy 191.416469 -285.151245) (xy 191.375027 -285.185733) (xy 191.329006 -285.213819)
			(xy 191.279386 -285.234906) (xy 191.227225 -285.248542) (xy 191.173634 -285.254439) (xy 191.119755 -285.25247)
			(xy 191.066737 -285.242677) (xy 191.01571 -285.225269) (xy 190.967762 -285.200617) (xy 190.923914 -285.169247)
			(xy 190.885101 -285.131826) (xy 190.852149 -285.089153) (xy 190.825763 -285.042136) (xy 190.806503 -284.991779)
			(xy 190.79478 -284.939155) (xy 190.790845 -284.885384) (xy 183.9849 -284.885384) (xy 183.984408 -284.912341)
			(xy 183.976558 -284.965681) (xy 183.961026 -285.01731) (xy 183.938141 -285.066127) (xy 183.908393 -285.111091)
			(xy 183.872415 -285.151245) (xy 183.830973 -285.185733) (xy 183.784952 -285.213819) (xy 183.735332 -285.234906)
			(xy 183.683171 -285.248542) (xy 183.62958 -285.254439) (xy 183.575701 -285.25247) (xy 183.522683 -285.242677)
			(xy 183.471656 -285.225269) (xy 183.423708 -285.200617) (xy 183.37986 -285.169247) (xy 183.341047 -285.131826)
			(xy 183.308095 -285.089153) (xy 183.281709 -285.042136) (xy 183.262449 -284.991779) (xy 183.250726 -284.939155)
			(xy 183.246791 -284.885384) (xy 177.881534 -284.885384) (xy 177.881534 -285.735268) (xy 179.146723 -285.735268)
			(xy 179.150658 -285.681497) (xy 179.162381 -285.628873) (xy 179.181641 -285.578516) (xy 179.208027 -285.531499)
			(xy 179.240979 -285.488826) (xy 179.279792 -285.451405) (xy 179.32364 -285.420035) (xy 179.371588 -285.395383)
			(xy 179.422615 -285.377975) (xy 179.475633 -285.368182) (xy 179.529512 -285.366213) (xy 179.583103 -285.37211)
			(xy 179.635264 -285.385746) (xy 179.684884 -285.406833) (xy 179.730905 -285.434919) (xy 179.772347 -285.469407)
			(xy 179.808325 -285.509561) (xy 179.838073 -285.554525) (xy 179.860958 -285.603342) (xy 179.87649 -285.654971)
			(xy 179.88434 -285.708311) (xy 179.884832 -285.735268) (xy 183.246791 -285.735268) (xy 183.250726 -285.681497)
			(xy 183.262449 -285.628873) (xy 183.281709 -285.578516) (xy 183.308095 -285.531499) (xy 183.341047 -285.488826)
			(xy 183.37986 -285.451405) (xy 183.423708 -285.420035) (xy 183.471656 -285.395383) (xy 183.522683 -285.377975)
			(xy 183.575701 -285.368182) (xy 183.62958 -285.366213) (xy 183.683171 -285.37211) (xy 183.735332 -285.385746)
			(xy 183.784952 -285.406833) (xy 183.830973 -285.434919) (xy 183.872415 -285.469407) (xy 183.908393 -285.509561)
			(xy 183.938141 -285.554525) (xy 183.961026 -285.603342) (xy 183.976558 -285.654971) (xy 183.984408 -285.708311)
			(xy 183.9849 -285.735268) (xy 186.690777 -285.735268) (xy 186.694712 -285.681497) (xy 186.706435 -285.628873)
			(xy 186.725695 -285.578516) (xy 186.752081 -285.531499) (xy 186.785033 -285.488826) (xy 186.823846 -285.451405)
			(xy 186.867694 -285.420035) (xy 186.915642 -285.395383) (xy 186.966669 -285.377975) (xy 187.019687 -285.368182)
			(xy 187.073566 -285.366213) (xy 187.127157 -285.37211) (xy 187.179318 -285.385746) (xy 187.228938 -285.406833)
			(xy 187.274959 -285.434919) (xy 187.316401 -285.469407) (xy 187.352379 -285.509561) (xy 187.382127 -285.554525)
			(xy 187.405012 -285.603342) (xy 187.420544 -285.654971) (xy 187.428394 -285.708311) (xy 187.428886 -285.735268)
			(xy 190.790845 -285.735268) (xy 190.79478 -285.681497) (xy 190.806503 -285.628873) (xy 190.825763 -285.578516)
			(xy 190.852149 -285.531499) (xy 190.885101 -285.488826) (xy 190.923914 -285.451405) (xy 190.967762 -285.420035)
			(xy 191.01571 -285.395383) (xy 191.066737 -285.377975) (xy 191.119755 -285.368182) (xy 191.173634 -285.366213)
			(xy 191.227225 -285.37211) (xy 191.279386 -285.385746) (xy 191.329006 -285.406833) (xy 191.375027 -285.434919)
			(xy 191.416469 -285.469407) (xy 191.452447 -285.509561) (xy 191.482195 -285.554525) (xy 191.50508 -285.603342)
			(xy 191.520612 -285.654971) (xy 191.528462 -285.708311) (xy 191.528954 -285.735268) (xy 194.234831 -285.735268)
			(xy 194.238766 -285.681497) (xy 194.250489 -285.628873) (xy 194.269749 -285.578516) (xy 194.296135 -285.531499)
			(xy 194.329087 -285.488826) (xy 194.3679 -285.451405) (xy 194.411748 -285.420035) (xy 194.459696 -285.395383)
			(xy 194.510723 -285.377975) (xy 194.563741 -285.368182) (xy 194.61762 -285.366213) (xy 194.671211 -285.37211)
			(xy 194.723372 -285.385746) (xy 194.772992 -285.406833) (xy 194.819013 -285.434919) (xy 194.860455 -285.469407)
			(xy 194.896433 -285.509561) (xy 194.926181 -285.554525) (xy 194.949066 -285.603342) (xy 194.964598 -285.654971)
			(xy 194.972448 -285.708311) (xy 194.97294 -285.735268) (xy 198.334899 -285.735268) (xy 198.338834 -285.681497)
			(xy 198.350557 -285.628873) (xy 198.369817 -285.578516) (xy 198.396203 -285.531499) (xy 198.429155 -285.488826)
			(xy 198.467968 -285.451405) (xy 198.511816 -285.420035) (xy 198.559764 -285.395383) (xy 198.610791 -285.377975)
			(xy 198.663809 -285.368182) (xy 198.717688 -285.366213) (xy 198.771279 -285.37211) (xy 198.82344 -285.385746)
			(xy 198.87306 -285.406833) (xy 198.919081 -285.434919) (xy 198.960523 -285.469407) (xy 198.996501 -285.509561)
			(xy 199.026249 -285.554525) (xy 199.049134 -285.603342) (xy 199.064666 -285.654971) (xy 199.072516 -285.708311)
			(xy 199.073008 -285.735268) (xy 201.778631 -285.735268) (xy 201.782566 -285.681497) (xy 201.794289 -285.628873)
			(xy 201.813549 -285.578516) (xy 201.839935 -285.531499) (xy 201.872887 -285.488826) (xy 201.9117 -285.451405)
			(xy 201.955548 -285.420035) (xy 202.003496 -285.395383) (xy 202.054523 -285.377975) (xy 202.107541 -285.368182)
			(xy 202.16142 -285.366213) (xy 202.215011 -285.37211) (xy 202.267172 -285.385746) (xy 202.316792 -285.406833)
			(xy 202.362813 -285.434919) (xy 202.404255 -285.469407) (xy 202.440233 -285.509561) (xy 202.469981 -285.554525)
			(xy 202.492866 -285.603342) (xy 202.508398 -285.654971) (xy 202.516248 -285.708311) (xy 202.51674 -285.735268)
			(xy 205.878699 -285.735268) (xy 205.882634 -285.681497) (xy 205.894357 -285.628873) (xy 205.913617 -285.578516)
			(xy 205.940003 -285.531499) (xy 205.972955 -285.488826) (xy 206.011768 -285.451405) (xy 206.055616 -285.420035)
			(xy 206.103564 -285.395383) (xy 206.154591 -285.377975) (xy 206.207609 -285.368182) (xy 206.261488 -285.366213)
			(xy 206.315079 -285.37211) (xy 206.36724 -285.385746) (xy 206.41686 -285.406833) (xy 206.462881 -285.434919)
			(xy 206.504323 -285.469407) (xy 206.540301 -285.509561) (xy 206.570049 -285.554525) (xy 206.592934 -285.603342)
			(xy 206.608466 -285.654971) (xy 206.616316 -285.708311) (xy 206.616808 -285.735268) (xy 206.616316 -285.762225)
			(xy 206.608466 -285.815565) (xy 206.592934 -285.867194) (xy 206.570049 -285.916011) (xy 206.540301 -285.960975)
			(xy 206.504323 -286.001129) (xy 206.462881 -286.035617) (xy 206.41686 -286.063703) (xy 206.36724 -286.08479)
			(xy 206.315079 -286.098426) (xy 206.261488 -286.104323) (xy 206.207609 -286.102354) (xy 206.154591 -286.092561)
			(xy 206.103564 -286.075153) (xy 206.055616 -286.050501) (xy 206.011768 -286.019131) (xy 205.972955 -285.98171)
			(xy 205.940003 -285.939037) (xy 205.913617 -285.89202) (xy 205.894357 -285.841663) (xy 205.882634 -285.789039)
			(xy 205.878699 -285.735268) (xy 202.51674 -285.735268) (xy 202.516248 -285.762225) (xy 202.508398 -285.815565)
			(xy 202.492866 -285.867194) (xy 202.469981 -285.916011) (xy 202.440233 -285.960975) (xy 202.404255 -286.001129)
			(xy 202.362813 -286.035617) (xy 202.316792 -286.063703) (xy 202.267172 -286.08479) (xy 202.215011 -286.098426)
			(xy 202.16142 -286.104323) (xy 202.107541 -286.102354) (xy 202.054523 -286.092561) (xy 202.003496 -286.075153)
			(xy 201.955548 -286.050501) (xy 201.9117 -286.019131) (xy 201.872887 -285.98171) (xy 201.839935 -285.939037)
			(xy 201.813549 -285.89202) (xy 201.794289 -285.841663) (xy 201.782566 -285.789039) (xy 201.778631 -285.735268)
			(xy 199.073008 -285.735268) (xy 199.072516 -285.762225) (xy 199.064666 -285.815565) (xy 199.049134 -285.867194)
			(xy 199.026249 -285.916011) (xy 198.996501 -285.960975) (xy 198.960523 -286.001129) (xy 198.919081 -286.035617)
			(xy 198.87306 -286.063703) (xy 198.82344 -286.08479) (xy 198.771279 -286.098426) (xy 198.717688 -286.104323)
			(xy 198.663809 -286.102354) (xy 198.610791 -286.092561) (xy 198.559764 -286.075153) (xy 198.511816 -286.050501)
			(xy 198.467968 -286.019131) (xy 198.429155 -285.98171) (xy 198.396203 -285.939037) (xy 198.369817 -285.89202)
			(xy 198.350557 -285.841663) (xy 198.338834 -285.789039) (xy 198.334899 -285.735268) (xy 194.97294 -285.735268)
			(xy 194.972448 -285.762225) (xy 194.964598 -285.815565) (xy 194.949066 -285.867194) (xy 194.926181 -285.916011)
			(xy 194.896433 -285.960975) (xy 194.860455 -286.001129) (xy 194.819013 -286.035617) (xy 194.772992 -286.063703)
			(xy 194.723372 -286.08479) (xy 194.671211 -286.098426) (xy 194.61762 -286.104323) (xy 194.563741 -286.102354)
			(xy 194.510723 -286.092561) (xy 194.459696 -286.075153) (xy 194.411748 -286.050501) (xy 194.3679 -286.019131)
			(xy 194.329087 -285.98171) (xy 194.296135 -285.939037) (xy 194.269749 -285.89202) (xy 194.250489 -285.841663)
			(xy 194.238766 -285.789039) (xy 194.234831 -285.735268) (xy 191.528954 -285.735268) (xy 191.528462 -285.762225)
			(xy 191.520612 -285.815565) (xy 191.50508 -285.867194) (xy 191.482195 -285.916011) (xy 191.452447 -285.960975)
			(xy 191.416469 -286.001129) (xy 191.375027 -286.035617) (xy 191.329006 -286.063703) (xy 191.279386 -286.08479)
			(xy 191.227225 -286.098426) (xy 191.173634 -286.104323) (xy 191.119755 -286.102354) (xy 191.066737 -286.092561)
			(xy 191.01571 -286.075153) (xy 190.967762 -286.050501) (xy 190.923914 -286.019131) (xy 190.885101 -285.98171)
			(xy 190.852149 -285.939037) (xy 190.825763 -285.89202) (xy 190.806503 -285.841663) (xy 190.79478 -285.789039)
			(xy 190.790845 -285.735268) (xy 187.428886 -285.735268) (xy 187.428394 -285.762225) (xy 187.420544 -285.815565)
			(xy 187.405012 -285.867194) (xy 187.382127 -285.916011) (xy 187.352379 -285.960975) (xy 187.316401 -286.001129)
			(xy 187.274959 -286.035617) (xy 187.228938 -286.063703) (xy 187.179318 -286.08479) (xy 187.127157 -286.098426)
			(xy 187.073566 -286.104323) (xy 187.019687 -286.102354) (xy 186.966669 -286.092561) (xy 186.915642 -286.075153)
			(xy 186.867694 -286.050501) (xy 186.823846 -286.019131) (xy 186.785033 -285.98171) (xy 186.752081 -285.939037)
			(xy 186.725695 -285.89202) (xy 186.706435 -285.841663) (xy 186.694712 -285.789039) (xy 186.690777 -285.735268)
			(xy 183.9849 -285.735268) (xy 183.984408 -285.762225) (xy 183.976558 -285.815565) (xy 183.961026 -285.867194)
			(xy 183.938141 -285.916011) (xy 183.908393 -285.960975) (xy 183.872415 -286.001129) (xy 183.830973 -286.035617)
			(xy 183.784952 -286.063703) (xy 183.735332 -286.08479) (xy 183.683171 -286.098426) (xy 183.62958 -286.104323)
			(xy 183.575701 -286.102354) (xy 183.522683 -286.092561) (xy 183.471656 -286.075153) (xy 183.423708 -286.050501)
			(xy 183.37986 -286.019131) (xy 183.341047 -285.98171) (xy 183.308095 -285.939037) (xy 183.281709 -285.89202)
			(xy 183.262449 -285.841663) (xy 183.250726 -285.789039) (xy 183.246791 -285.735268) (xy 179.884832 -285.735268)
			(xy 179.88434 -285.762225) (xy 179.87649 -285.815565) (xy 179.860958 -285.867194) (xy 179.838073 -285.916011)
			(xy 179.808325 -285.960975) (xy 179.772347 -286.001129) (xy 179.730905 -286.035617) (xy 179.684884 -286.063703)
			(xy 179.635264 -286.08479) (xy 179.583103 -286.098426) (xy 179.529512 -286.104323) (xy 179.475633 -286.102354)
			(xy 179.422615 -286.092561) (xy 179.371588 -286.075153) (xy 179.32364 -286.050501) (xy 179.279792 -286.019131)
			(xy 179.240979 -285.98171) (xy 179.208027 -285.939037) (xy 179.181641 -285.89202) (xy 179.162381 -285.841663)
			(xy 179.150658 -285.789039) (xy 179.146723 -285.735268) (xy 177.881534 -285.735268) (xy 177.881534 -286.585406)
			(xy 179.146723 -286.585406) (xy 179.150658 -286.531635) (xy 179.162381 -286.479011) (xy 179.181641 -286.428654)
			(xy 179.208027 -286.381637) (xy 179.240979 -286.338964) (xy 179.279792 -286.301543) (xy 179.32364 -286.270173)
			(xy 179.371588 -286.245521) (xy 179.422615 -286.228113) (xy 179.475633 -286.21832) (xy 179.529512 -286.216351)
			(xy 179.583103 -286.222248) (xy 179.635264 -286.235884) (xy 179.684884 -286.256971) (xy 179.730905 -286.285057)
			(xy 179.772347 -286.319545) (xy 179.808325 -286.359699) (xy 179.838073 -286.404663) (xy 179.860958 -286.45348)
			(xy 179.87649 -286.505109) (xy 179.88434 -286.558449) (xy 179.884832 -286.585406) (xy 186.690777 -286.585406)
			(xy 186.694712 -286.531635) (xy 186.706435 -286.479011) (xy 186.725695 -286.428654) (xy 186.752081 -286.381637)
			(xy 186.785033 -286.338964) (xy 186.823846 -286.301543) (xy 186.867694 -286.270173) (xy 186.915642 -286.245521)
			(xy 186.966669 -286.228113) (xy 187.019687 -286.21832) (xy 187.073566 -286.216351) (xy 187.127157 -286.222248)
			(xy 187.179318 -286.235884) (xy 187.228938 -286.256971) (xy 187.274959 -286.285057) (xy 187.316401 -286.319545)
			(xy 187.352379 -286.359699) (xy 187.382127 -286.404663) (xy 187.405012 -286.45348) (xy 187.420544 -286.505109)
			(xy 187.428394 -286.558449) (xy 187.428886 -286.585406) (xy 194.234831 -286.585406) (xy 194.238766 -286.531635)
			(xy 194.250489 -286.479011) (xy 194.269749 -286.428654) (xy 194.296135 -286.381637) (xy 194.329087 -286.338964)
			(xy 194.3679 -286.301543) (xy 194.411748 -286.270173) (xy 194.459696 -286.245521) (xy 194.510723 -286.228113)
			(xy 194.563741 -286.21832) (xy 194.61762 -286.216351) (xy 194.671211 -286.222248) (xy 194.723372 -286.235884)
			(xy 194.772992 -286.256971) (xy 194.819013 -286.285057) (xy 194.860455 -286.319545) (xy 194.896433 -286.359699)
			(xy 194.926181 -286.404663) (xy 194.949066 -286.45348) (xy 194.964598 -286.505109) (xy 194.972448 -286.558449)
			(xy 194.97294 -286.585406) (xy 201.778631 -286.585406) (xy 201.782566 -286.531635) (xy 201.794289 -286.479011)
			(xy 201.813549 -286.428654) (xy 201.839935 -286.381637) (xy 201.872887 -286.338964) (xy 201.9117 -286.301543)
			(xy 201.955548 -286.270173) (xy 202.003496 -286.245521) (xy 202.054523 -286.228113) (xy 202.107541 -286.21832)
			(xy 202.16142 -286.216351) (xy 202.215011 -286.222248) (xy 202.267172 -286.235884) (xy 202.316792 -286.256971)
			(xy 202.362813 -286.285057) (xy 202.404255 -286.319545) (xy 202.440233 -286.359699) (xy 202.469981 -286.404663)
			(xy 202.492866 -286.45348) (xy 202.508398 -286.505109) (xy 202.516248 -286.558449) (xy 202.51674 -286.585406)
			(xy 202.516248 -286.612363) (xy 202.508398 -286.665703) (xy 202.492866 -286.717332) (xy 202.469981 -286.766149)
			(xy 202.440233 -286.811113) (xy 202.404255 -286.851267) (xy 202.362813 -286.885755) (xy 202.316792 -286.913841)
			(xy 202.267172 -286.934928) (xy 202.215011 -286.948564) (xy 202.16142 -286.954461) (xy 202.107541 -286.952492)
			(xy 202.054523 -286.942699) (xy 202.003496 -286.925291) (xy 201.955548 -286.900639) (xy 201.9117 -286.869269)
			(xy 201.872887 -286.831848) (xy 201.839935 -286.789175) (xy 201.813549 -286.742158) (xy 201.794289 -286.691801)
			(xy 201.782566 -286.639177) (xy 201.778631 -286.585406) (xy 194.97294 -286.585406) (xy 194.972448 -286.612363)
			(xy 194.964598 -286.665703) (xy 194.949066 -286.717332) (xy 194.926181 -286.766149) (xy 194.896433 -286.811113)
			(xy 194.860455 -286.851267) (xy 194.819013 -286.885755) (xy 194.772992 -286.913841) (xy 194.723372 -286.934928)
			(xy 194.671211 -286.948564) (xy 194.61762 -286.954461) (xy 194.563741 -286.952492) (xy 194.510723 -286.942699)
			(xy 194.459696 -286.925291) (xy 194.411748 -286.900639) (xy 194.3679 -286.869269) (xy 194.329087 -286.831848)
			(xy 194.296135 -286.789175) (xy 194.269749 -286.742158) (xy 194.250489 -286.691801) (xy 194.238766 -286.639177)
			(xy 194.234831 -286.585406) (xy 187.428886 -286.585406) (xy 187.428394 -286.612363) (xy 187.420544 -286.665703)
			(xy 187.405012 -286.717332) (xy 187.382127 -286.766149) (xy 187.352379 -286.811113) (xy 187.316401 -286.851267)
			(xy 187.274959 -286.885755) (xy 187.228938 -286.913841) (xy 187.179318 -286.934928) (xy 187.127157 -286.948564)
			(xy 187.073566 -286.954461) (xy 187.019687 -286.952492) (xy 186.966669 -286.942699) (xy 186.915642 -286.925291)
			(xy 186.867694 -286.900639) (xy 186.823846 -286.869269) (xy 186.785033 -286.831848) (xy 186.752081 -286.789175)
			(xy 186.725695 -286.742158) (xy 186.706435 -286.691801) (xy 186.694712 -286.639177) (xy 186.690777 -286.585406)
			(xy 179.884832 -286.585406) (xy 179.88434 -286.612363) (xy 179.87649 -286.665703) (xy 179.860958 -286.717332)
			(xy 179.838073 -286.766149) (xy 179.808325 -286.811113) (xy 179.772347 -286.851267) (xy 179.730905 -286.885755)
			(xy 179.684884 -286.913841) (xy 179.635264 -286.934928) (xy 179.583103 -286.948564) (xy 179.529512 -286.954461)
			(xy 179.475633 -286.952492) (xy 179.422615 -286.942699) (xy 179.371588 -286.925291) (xy 179.32364 -286.900639)
			(xy 179.279792 -286.869269) (xy 179.240979 -286.831848) (xy 179.208027 -286.789175) (xy 179.181641 -286.742158)
			(xy 179.162381 -286.691801) (xy 179.150658 -286.639177) (xy 179.146723 -286.585406) (xy 177.881534 -286.585406)
			(xy 177.881534 -287.43529) (xy 183.246791 -287.43529) (xy 183.250726 -287.381519) (xy 183.262449 -287.328895)
			(xy 183.281709 -287.278538) (xy 183.308095 -287.231521) (xy 183.341047 -287.188848) (xy 183.37986 -287.151427)
			(xy 183.423708 -287.120057) (xy 183.471656 -287.095405) (xy 183.522683 -287.077997) (xy 183.575701 -287.068204)
			(xy 183.62958 -287.066235) (xy 183.683171 -287.072132) (xy 183.735332 -287.085768) (xy 183.784952 -287.106855)
			(xy 183.830973 -287.134941) (xy 183.872415 -287.169429) (xy 183.908393 -287.209583) (xy 183.938141 -287.254547)
			(xy 183.961026 -287.303364) (xy 183.976558 -287.354993) (xy 183.984408 -287.408333) (xy 183.9849 -287.43529)
			(xy 190.790845 -287.43529) (xy 190.79478 -287.381519) (xy 190.806503 -287.328895) (xy 190.825763 -287.278538)
			(xy 190.852149 -287.231521) (xy 190.885101 -287.188848) (xy 190.923914 -287.151427) (xy 190.967762 -287.120057)
			(xy 191.01571 -287.095405) (xy 191.066737 -287.077997) (xy 191.119755 -287.068204) (xy 191.173634 -287.066235)
			(xy 191.227225 -287.072132) (xy 191.279386 -287.085768) (xy 191.329006 -287.106855) (xy 191.375027 -287.134941)
			(xy 191.416469 -287.169429) (xy 191.452447 -287.209583) (xy 191.482195 -287.254547) (xy 191.50508 -287.303364)
			(xy 191.520612 -287.354993) (xy 191.528462 -287.408333) (xy 191.528954 -287.43529) (xy 198.334899 -287.43529)
			(xy 198.338834 -287.381519) (xy 198.350557 -287.328895) (xy 198.369817 -287.278538) (xy 198.396203 -287.231521)
			(xy 198.429155 -287.188848) (xy 198.467968 -287.151427) (xy 198.511816 -287.120057) (xy 198.559764 -287.095405)
			(xy 198.610791 -287.077997) (xy 198.663809 -287.068204) (xy 198.717688 -287.066235) (xy 198.771279 -287.072132)
			(xy 198.82344 -287.085768) (xy 198.87306 -287.106855) (xy 198.919081 -287.134941) (xy 198.960523 -287.169429)
			(xy 198.996501 -287.209583) (xy 199.026249 -287.254547) (xy 199.049134 -287.303364) (xy 199.064666 -287.354993)
			(xy 199.072516 -287.408333) (xy 199.073008 -287.43529) (xy 205.878699 -287.43529) (xy 205.882634 -287.381519)
			(xy 205.894357 -287.328895) (xy 205.913617 -287.278538) (xy 205.940003 -287.231521) (xy 205.972955 -287.188848)
			(xy 206.011768 -287.151427) (xy 206.055616 -287.120057) (xy 206.103564 -287.095405) (xy 206.154591 -287.077997)
			(xy 206.207609 -287.068204) (xy 206.261488 -287.066235) (xy 206.315079 -287.072132) (xy 206.36724 -287.085768)
			(xy 206.41686 -287.106855) (xy 206.462881 -287.134941) (xy 206.504323 -287.169429) (xy 206.540301 -287.209583)
			(xy 206.570049 -287.254547) (xy 206.592934 -287.303364) (xy 206.608466 -287.354993) (xy 206.616316 -287.408333)
			(xy 206.616808 -287.43529) (xy 206.616316 -287.462247) (xy 206.608466 -287.515587) (xy 206.592934 -287.567216)
			(xy 206.570049 -287.616033) (xy 206.540301 -287.660997) (xy 206.504323 -287.701151) (xy 206.462881 -287.735639)
			(xy 206.41686 -287.763725) (xy 206.36724 -287.784812) (xy 206.315079 -287.798448) (xy 206.261488 -287.804345)
			(xy 206.207609 -287.802376) (xy 206.154591 -287.792583) (xy 206.103564 -287.775175) (xy 206.055616 -287.750523)
			(xy 206.011768 -287.719153) (xy 205.972955 -287.681732) (xy 205.940003 -287.639059) (xy 205.913617 -287.592042)
			(xy 205.894357 -287.541685) (xy 205.882634 -287.489061) (xy 205.878699 -287.43529) (xy 199.073008 -287.43529)
			(xy 199.072516 -287.462247) (xy 199.064666 -287.515587) (xy 199.049134 -287.567216) (xy 199.026249 -287.616033)
			(xy 198.996501 -287.660997) (xy 198.960523 -287.701151) (xy 198.919081 -287.735639) (xy 198.87306 -287.763725)
			(xy 198.82344 -287.784812) (xy 198.771279 -287.798448) (xy 198.717688 -287.804345) (xy 198.663809 -287.802376)
			(xy 198.610791 -287.792583) (xy 198.559764 -287.775175) (xy 198.511816 -287.750523) (xy 198.467968 -287.719153)
			(xy 198.429155 -287.681732) (xy 198.396203 -287.639059) (xy 198.369817 -287.592042) (xy 198.350557 -287.541685)
			(xy 198.338834 -287.489061) (xy 198.334899 -287.43529) (xy 191.528954 -287.43529) (xy 191.528462 -287.462247)
			(xy 191.520612 -287.515587) (xy 191.50508 -287.567216) (xy 191.482195 -287.616033) (xy 191.452447 -287.660997)
			(xy 191.416469 -287.701151) (xy 191.375027 -287.735639) (xy 191.329006 -287.763725) (xy 191.279386 -287.784812)
			(xy 191.227225 -287.798448) (xy 191.173634 -287.804345) (xy 191.119755 -287.802376) (xy 191.066737 -287.792583)
			(xy 191.01571 -287.775175) (xy 190.967762 -287.750523) (xy 190.923914 -287.719153) (xy 190.885101 -287.681732)
			(xy 190.852149 -287.639059) (xy 190.825763 -287.592042) (xy 190.806503 -287.541685) (xy 190.79478 -287.489061)
			(xy 190.790845 -287.43529) (xy 183.9849 -287.43529) (xy 183.984408 -287.462247) (xy 183.976558 -287.515587)
			(xy 183.961026 -287.567216) (xy 183.938141 -287.616033) (xy 183.908393 -287.660997) (xy 183.872415 -287.701151)
			(xy 183.830973 -287.735639) (xy 183.784952 -287.763725) (xy 183.735332 -287.784812) (xy 183.683171 -287.798448)
			(xy 183.62958 -287.804345) (xy 183.575701 -287.802376) (xy 183.522683 -287.792583) (xy 183.471656 -287.775175)
			(xy 183.423708 -287.750523) (xy 183.37986 -287.719153) (xy 183.341047 -287.681732) (xy 183.308095 -287.639059)
			(xy 183.281709 -287.592042) (xy 183.262449 -287.541685) (xy 183.250726 -287.489061) (xy 183.246791 -287.43529)
			(xy 177.881534 -287.43529) (xy 177.881534 -288.285428) (xy 179.146723 -288.285428) (xy 179.150658 -288.231657)
			(xy 179.162381 -288.179033) (xy 179.181641 -288.128676) (xy 179.208027 -288.081659) (xy 179.240979 -288.038986)
			(xy 179.279792 -288.001565) (xy 179.32364 -287.970195) (xy 179.371588 -287.945543) (xy 179.422615 -287.928135)
			(xy 179.475633 -287.918342) (xy 179.529512 -287.916373) (xy 179.583103 -287.92227) (xy 179.635264 -287.935906)
			(xy 179.684884 -287.956993) (xy 179.730905 -287.985079) (xy 179.772347 -288.019567) (xy 179.808325 -288.059721)
			(xy 179.838073 -288.104685) (xy 179.860958 -288.153502) (xy 179.87649 -288.205131) (xy 179.88434 -288.258471)
			(xy 179.884832 -288.285428) (xy 186.690777 -288.285428) (xy 186.694712 -288.231657) (xy 186.706435 -288.179033)
			(xy 186.725695 -288.128676) (xy 186.752081 -288.081659) (xy 186.785033 -288.038986) (xy 186.823846 -288.001565)
			(xy 186.867694 -287.970195) (xy 186.915642 -287.945543) (xy 186.966669 -287.928135) (xy 187.019687 -287.918342)
			(xy 187.073566 -287.916373) (xy 187.127157 -287.92227) (xy 187.179318 -287.935906) (xy 187.228938 -287.956993)
			(xy 187.274959 -287.985079) (xy 187.316401 -288.019567) (xy 187.352379 -288.059721) (xy 187.382127 -288.104685)
			(xy 187.405012 -288.153502) (xy 187.420544 -288.205131) (xy 187.428394 -288.258471) (xy 187.428886 -288.285428)
			(xy 194.234831 -288.285428) (xy 194.238766 -288.231657) (xy 194.250489 -288.179033) (xy 194.269749 -288.128676)
			(xy 194.296135 -288.081659) (xy 194.329087 -288.038986) (xy 194.3679 -288.001565) (xy 194.411748 -287.970195)
			(xy 194.459696 -287.945543) (xy 194.510723 -287.928135) (xy 194.563741 -287.918342) (xy 194.61762 -287.916373)
			(xy 194.671211 -287.92227) (xy 194.723372 -287.935906) (xy 194.772992 -287.956993) (xy 194.819013 -287.985079)
			(xy 194.860455 -288.019567) (xy 194.896433 -288.059721) (xy 194.926181 -288.104685) (xy 194.949066 -288.153502)
			(xy 194.964598 -288.205131) (xy 194.972448 -288.258471) (xy 194.97294 -288.285428) (xy 201.778631 -288.285428)
			(xy 201.782566 -288.231657) (xy 201.794289 -288.179033) (xy 201.813549 -288.128676) (xy 201.839935 -288.081659)
			(xy 201.872887 -288.038986) (xy 201.9117 -288.001565) (xy 201.955548 -287.970195) (xy 202.003496 -287.945543)
			(xy 202.054523 -287.928135) (xy 202.107541 -287.918342) (xy 202.16142 -287.916373) (xy 202.215011 -287.92227)
			(xy 202.267172 -287.935906) (xy 202.316792 -287.956993) (xy 202.362813 -287.985079) (xy 202.404255 -288.019567)
			(xy 202.440233 -288.059721) (xy 202.469981 -288.104685) (xy 202.492866 -288.153502) (xy 202.508398 -288.205131)
			(xy 202.516248 -288.258471) (xy 202.51674 -288.285428) (xy 202.516248 -288.312385) (xy 202.508398 -288.365725)
			(xy 202.492866 -288.417354) (xy 202.469981 -288.466171) (xy 202.440233 -288.511135) (xy 202.404255 -288.551289)
			(xy 202.362813 -288.585777) (xy 202.316792 -288.613863) (xy 202.267172 -288.63495) (xy 202.215011 -288.648586)
			(xy 202.16142 -288.654483) (xy 202.107541 -288.652514) (xy 202.054523 -288.642721) (xy 202.003496 -288.625313)
			(xy 201.955548 -288.600661) (xy 201.9117 -288.569291) (xy 201.872887 -288.53187) (xy 201.839935 -288.489197)
			(xy 201.813549 -288.44218) (xy 201.794289 -288.391823) (xy 201.782566 -288.339199) (xy 201.778631 -288.285428)
			(xy 194.97294 -288.285428) (xy 194.972448 -288.312385) (xy 194.964598 -288.365725) (xy 194.949066 -288.417354)
			(xy 194.926181 -288.466171) (xy 194.896433 -288.511135) (xy 194.860455 -288.551289) (xy 194.819013 -288.585777)
			(xy 194.772992 -288.613863) (xy 194.723372 -288.63495) (xy 194.671211 -288.648586) (xy 194.61762 -288.654483)
			(xy 194.563741 -288.652514) (xy 194.510723 -288.642721) (xy 194.459696 -288.625313) (xy 194.411748 -288.600661)
			(xy 194.3679 -288.569291) (xy 194.329087 -288.53187) (xy 194.296135 -288.489197) (xy 194.269749 -288.44218)
			(xy 194.250489 -288.391823) (xy 194.238766 -288.339199) (xy 194.234831 -288.285428) (xy 187.428886 -288.285428)
			(xy 187.428394 -288.312385) (xy 187.420544 -288.365725) (xy 187.405012 -288.417354) (xy 187.382127 -288.466171)
			(xy 187.352379 -288.511135) (xy 187.316401 -288.551289) (xy 187.274959 -288.585777) (xy 187.228938 -288.613863)
			(xy 187.179318 -288.63495) (xy 187.127157 -288.648586) (xy 187.073566 -288.654483) (xy 187.019687 -288.652514)
			(xy 186.966669 -288.642721) (xy 186.915642 -288.625313) (xy 186.867694 -288.600661) (xy 186.823846 -288.569291)
			(xy 186.785033 -288.53187) (xy 186.752081 -288.489197) (xy 186.725695 -288.44218) (xy 186.706435 -288.391823)
			(xy 186.694712 -288.339199) (xy 186.690777 -288.285428) (xy 179.884832 -288.285428) (xy 179.88434 -288.312385)
			(xy 179.87649 -288.365725) (xy 179.860958 -288.417354) (xy 179.838073 -288.466171) (xy 179.808325 -288.511135)
			(xy 179.772347 -288.551289) (xy 179.730905 -288.585777) (xy 179.684884 -288.613863) (xy 179.635264 -288.63495)
			(xy 179.583103 -288.648586) (xy 179.529512 -288.654483) (xy 179.475633 -288.652514) (xy 179.422615 -288.642721)
			(xy 179.371588 -288.625313) (xy 179.32364 -288.600661) (xy 179.279792 -288.569291) (xy 179.240979 -288.53187)
			(xy 179.208027 -288.489197) (xy 179.181641 -288.44218) (xy 179.162381 -288.391823) (xy 179.150658 -288.339199)
			(xy 179.146723 -288.285428) (xy 177.881534 -288.285428) (xy 177.881534 -289.135312) (xy 183.246791 -289.135312)
			(xy 183.250726 -289.081541) (xy 183.262449 -289.028917) (xy 183.281709 -288.97856) (xy 183.308095 -288.931543)
			(xy 183.341047 -288.88887) (xy 183.37986 -288.851449) (xy 183.423708 -288.820079) (xy 183.471656 -288.795427)
			(xy 183.522683 -288.778019) (xy 183.575701 -288.768226) (xy 183.62958 -288.766257) (xy 183.683171 -288.772154)
			(xy 183.735332 -288.78579) (xy 183.784952 -288.806877) (xy 183.830973 -288.834963) (xy 183.872415 -288.869451)
			(xy 183.908393 -288.909605) (xy 183.938141 -288.954569) (xy 183.961026 -289.003386) (xy 183.976558 -289.055015)
			(xy 183.984408 -289.108355) (xy 183.9849 -289.135312) (xy 190.790845 -289.135312) (xy 190.79478 -289.081541)
			(xy 190.806503 -289.028917) (xy 190.825763 -288.97856) (xy 190.852149 -288.931543) (xy 190.885101 -288.88887)
			(xy 190.923914 -288.851449) (xy 190.967762 -288.820079) (xy 191.01571 -288.795427) (xy 191.066737 -288.778019)
			(xy 191.119755 -288.768226) (xy 191.173634 -288.766257) (xy 191.227225 -288.772154) (xy 191.279386 -288.78579)
			(xy 191.329006 -288.806877) (xy 191.375027 -288.834963) (xy 191.416469 -288.869451) (xy 191.452447 -288.909605)
			(xy 191.482195 -288.954569) (xy 191.50508 -289.003386) (xy 191.520612 -289.055015) (xy 191.528462 -289.108355)
			(xy 191.528954 -289.135312) (xy 198.334899 -289.135312) (xy 198.338834 -289.081541) (xy 198.350557 -289.028917)
			(xy 198.369817 -288.97856) (xy 198.396203 -288.931543) (xy 198.429155 -288.88887) (xy 198.467968 -288.851449)
			(xy 198.511816 -288.820079) (xy 198.559764 -288.795427) (xy 198.610791 -288.778019) (xy 198.663809 -288.768226)
			(xy 198.717688 -288.766257) (xy 198.771279 -288.772154) (xy 198.82344 -288.78579) (xy 198.87306 -288.806877)
			(xy 198.919081 -288.834963) (xy 198.960523 -288.869451) (xy 198.996501 -288.909605) (xy 199.026249 -288.954569)
			(xy 199.049134 -289.003386) (xy 199.064666 -289.055015) (xy 199.072516 -289.108355) (xy 199.073008 -289.135312)
			(xy 205.878699 -289.135312) (xy 205.882634 -289.081541) (xy 205.894357 -289.028917) (xy 205.913617 -288.97856)
			(xy 205.940003 -288.931543) (xy 205.972955 -288.88887) (xy 206.011768 -288.851449) (xy 206.055616 -288.820079)
			(xy 206.103564 -288.795427) (xy 206.154591 -288.778019) (xy 206.207609 -288.768226) (xy 206.261488 -288.766257)
			(xy 206.315079 -288.772154) (xy 206.36724 -288.78579) (xy 206.41686 -288.806877) (xy 206.462881 -288.834963)
			(xy 206.504323 -288.869451) (xy 206.540301 -288.909605) (xy 206.570049 -288.954569) (xy 206.592934 -289.003386)
			(xy 206.608466 -289.055015) (xy 206.616316 -289.108355) (xy 206.616808 -289.135312) (xy 206.616316 -289.162269)
			(xy 206.608466 -289.215609) (xy 206.592934 -289.267238) (xy 206.570049 -289.316055) (xy 206.540301 -289.361019)
			(xy 206.504323 -289.401173) (xy 206.462881 -289.435661) (xy 206.41686 -289.463747) (xy 206.36724 -289.484834)
			(xy 206.315079 -289.49847) (xy 206.261488 -289.504367) (xy 206.207609 -289.502398) (xy 206.154591 -289.492605)
			(xy 206.103564 -289.475197) (xy 206.055616 -289.450545) (xy 206.011768 -289.419175) (xy 205.972955 -289.381754)
			(xy 205.940003 -289.339081) (xy 205.913617 -289.292064) (xy 205.894357 -289.241707) (xy 205.882634 -289.189083)
			(xy 205.878699 -289.135312) (xy 199.073008 -289.135312) (xy 199.072516 -289.162269) (xy 199.064666 -289.215609)
			(xy 199.049134 -289.267238) (xy 199.026249 -289.316055) (xy 198.996501 -289.361019) (xy 198.960523 -289.401173)
			(xy 198.919081 -289.435661) (xy 198.87306 -289.463747) (xy 198.82344 -289.484834) (xy 198.771279 -289.49847)
			(xy 198.717688 -289.504367) (xy 198.663809 -289.502398) (xy 198.610791 -289.492605) (xy 198.559764 -289.475197)
			(xy 198.511816 -289.450545) (xy 198.467968 -289.419175) (xy 198.429155 -289.381754) (xy 198.396203 -289.339081)
			(xy 198.369817 -289.292064) (xy 198.350557 -289.241707) (xy 198.338834 -289.189083) (xy 198.334899 -289.135312)
			(xy 191.528954 -289.135312) (xy 191.528462 -289.162269) (xy 191.520612 -289.215609) (xy 191.50508 -289.267238)
			(xy 191.482195 -289.316055) (xy 191.452447 -289.361019) (xy 191.416469 -289.401173) (xy 191.375027 -289.435661)
			(xy 191.329006 -289.463747) (xy 191.279386 -289.484834) (xy 191.227225 -289.49847) (xy 191.173634 -289.504367)
			(xy 191.119755 -289.502398) (xy 191.066737 -289.492605) (xy 191.01571 -289.475197) (xy 190.967762 -289.450545)
			(xy 190.923914 -289.419175) (xy 190.885101 -289.381754) (xy 190.852149 -289.339081) (xy 190.825763 -289.292064)
			(xy 190.806503 -289.241707) (xy 190.79478 -289.189083) (xy 190.790845 -289.135312) (xy 183.9849 -289.135312)
			(xy 183.984408 -289.162269) (xy 183.976558 -289.215609) (xy 183.961026 -289.267238) (xy 183.938141 -289.316055)
			(xy 183.908393 -289.361019) (xy 183.872415 -289.401173) (xy 183.830973 -289.435661) (xy 183.784952 -289.463747)
			(xy 183.735332 -289.484834) (xy 183.683171 -289.49847) (xy 183.62958 -289.504367) (xy 183.575701 -289.502398)
			(xy 183.522683 -289.492605) (xy 183.471656 -289.475197) (xy 183.423708 -289.450545) (xy 183.37986 -289.419175)
			(xy 183.341047 -289.381754) (xy 183.308095 -289.339081) (xy 183.281709 -289.292064) (xy 183.262449 -289.241707)
			(xy 183.250726 -289.189083) (xy 183.246791 -289.135312) (xy 177.881534 -289.135312) (xy 177.881534 -289.98545)
			(xy 179.146723 -289.98545) (xy 179.150658 -289.931679) (xy 179.162381 -289.879055) (xy 179.181641 -289.828698)
			(xy 179.208027 -289.781681) (xy 179.240979 -289.739008) (xy 179.279792 -289.701587) (xy 179.32364 -289.670217)
			(xy 179.371588 -289.645565) (xy 179.422615 -289.628157) (xy 179.475633 -289.618364) (xy 179.529512 -289.616395)
			(xy 179.583103 -289.622292) (xy 179.635264 -289.635928) (xy 179.684884 -289.657015) (xy 179.730905 -289.685101)
			(xy 179.772347 -289.719589) (xy 179.808325 -289.759743) (xy 179.838073 -289.804707) (xy 179.860958 -289.853524)
			(xy 179.87649 -289.905153) (xy 179.88434 -289.958493) (xy 179.884832 -289.98545) (xy 186.690777 -289.98545)
			(xy 186.694712 -289.931679) (xy 186.706435 -289.879055) (xy 186.725695 -289.828698) (xy 186.752081 -289.781681)
			(xy 186.785033 -289.739008) (xy 186.823846 -289.701587) (xy 186.867694 -289.670217) (xy 186.915642 -289.645565)
			(xy 186.966669 -289.628157) (xy 187.019687 -289.618364) (xy 187.073566 -289.616395) (xy 187.127157 -289.622292)
			(xy 187.179318 -289.635928) (xy 187.228938 -289.657015) (xy 187.274959 -289.685101) (xy 187.316401 -289.719589)
			(xy 187.352379 -289.759743) (xy 187.382127 -289.804707) (xy 187.405012 -289.853524) (xy 187.420544 -289.905153)
			(xy 187.428394 -289.958493) (xy 187.428886 -289.98545) (xy 194.234831 -289.98545) (xy 194.238766 -289.931679)
			(xy 194.250489 -289.879055) (xy 194.269749 -289.828698) (xy 194.296135 -289.781681) (xy 194.329087 -289.739008)
			(xy 194.3679 -289.701587) (xy 194.411748 -289.670217) (xy 194.459696 -289.645565) (xy 194.510723 -289.628157)
			(xy 194.563741 -289.618364) (xy 194.61762 -289.616395) (xy 194.671211 -289.622292) (xy 194.723372 -289.635928)
			(xy 194.772992 -289.657015) (xy 194.819013 -289.685101) (xy 194.860455 -289.719589) (xy 194.896433 -289.759743)
			(xy 194.926181 -289.804707) (xy 194.949066 -289.853524) (xy 194.964598 -289.905153) (xy 194.972448 -289.958493)
			(xy 194.97294 -289.98545) (xy 201.778631 -289.98545) (xy 201.782566 -289.931679) (xy 201.794289 -289.879055)
			(xy 201.813549 -289.828698) (xy 201.839935 -289.781681) (xy 201.872887 -289.739008) (xy 201.9117 -289.701587)
			(xy 201.955548 -289.670217) (xy 202.003496 -289.645565) (xy 202.054523 -289.628157) (xy 202.107541 -289.618364)
			(xy 202.16142 -289.616395) (xy 202.215011 -289.622292) (xy 202.267172 -289.635928) (xy 202.316792 -289.657015)
			(xy 202.362813 -289.685101) (xy 202.404255 -289.719589) (xy 202.440233 -289.759743) (xy 202.469981 -289.804707)
			(xy 202.492866 -289.853524) (xy 202.508398 -289.905153) (xy 202.516248 -289.958493) (xy 202.51674 -289.98545)
			(xy 202.516248 -290.012407) (xy 202.508398 -290.065747) (xy 202.492866 -290.117376) (xy 202.469981 -290.166193)
			(xy 202.440233 -290.211157) (xy 202.404255 -290.251311) (xy 202.362813 -290.285799) (xy 202.316792 -290.313885)
			(xy 202.267172 -290.334972) (xy 202.215011 -290.348608) (xy 202.16142 -290.354505) (xy 202.107541 -290.352536)
			(xy 202.054523 -290.342743) (xy 202.003496 -290.325335) (xy 201.955548 -290.300683) (xy 201.9117 -290.269313)
			(xy 201.872887 -290.231892) (xy 201.839935 -290.189219) (xy 201.813549 -290.142202) (xy 201.794289 -290.091845)
			(xy 201.782566 -290.039221) (xy 201.778631 -289.98545) (xy 194.97294 -289.98545) (xy 194.972448 -290.012407)
			(xy 194.964598 -290.065747) (xy 194.949066 -290.117376) (xy 194.926181 -290.166193) (xy 194.896433 -290.211157)
			(xy 194.860455 -290.251311) (xy 194.819013 -290.285799) (xy 194.772992 -290.313885) (xy 194.723372 -290.334972)
			(xy 194.671211 -290.348608) (xy 194.61762 -290.354505) (xy 194.563741 -290.352536) (xy 194.510723 -290.342743)
			(xy 194.459696 -290.325335) (xy 194.411748 -290.300683) (xy 194.3679 -290.269313) (xy 194.329087 -290.231892)
			(xy 194.296135 -290.189219) (xy 194.269749 -290.142202) (xy 194.250489 -290.091845) (xy 194.238766 -290.039221)
			(xy 194.234831 -289.98545) (xy 187.428886 -289.98545) (xy 187.428394 -290.012407) (xy 187.420544 -290.065747)
			(xy 187.405012 -290.117376) (xy 187.382127 -290.166193) (xy 187.352379 -290.211157) (xy 187.316401 -290.251311)
			(xy 187.274959 -290.285799) (xy 187.228938 -290.313885) (xy 187.179318 -290.334972) (xy 187.127157 -290.348608)
			(xy 187.073566 -290.354505) (xy 187.019687 -290.352536) (xy 186.966669 -290.342743) (xy 186.915642 -290.325335)
			(xy 186.867694 -290.300683) (xy 186.823846 -290.269313) (xy 186.785033 -290.231892) (xy 186.752081 -290.189219)
			(xy 186.725695 -290.142202) (xy 186.706435 -290.091845) (xy 186.694712 -290.039221) (xy 186.690777 -289.98545)
			(xy 179.884832 -289.98545) (xy 179.88434 -290.012407) (xy 179.87649 -290.065747) (xy 179.860958 -290.117376)
			(xy 179.838073 -290.166193) (xy 179.808325 -290.211157) (xy 179.772347 -290.251311) (xy 179.730905 -290.285799)
			(xy 179.684884 -290.313885) (xy 179.635264 -290.334972) (xy 179.583103 -290.348608) (xy 179.529512 -290.354505)
			(xy 179.475633 -290.352536) (xy 179.422615 -290.342743) (xy 179.371588 -290.325335) (xy 179.32364 -290.300683)
			(xy 179.279792 -290.269313) (xy 179.240979 -290.231892) (xy 179.208027 -290.189219) (xy 179.181641 -290.142202)
			(xy 179.162381 -290.091845) (xy 179.150658 -290.039221) (xy 179.146723 -289.98545) (xy 177.881534 -289.98545)
			(xy 177.881534 -290.835334) (xy 183.246791 -290.835334) (xy 183.250726 -290.781563) (xy 183.262449 -290.728939)
			(xy 183.281709 -290.678582) (xy 183.308095 -290.631565) (xy 183.341047 -290.588892) (xy 183.37986 -290.551471)
			(xy 183.423708 -290.520101) (xy 183.471656 -290.495449) (xy 183.522683 -290.478041) (xy 183.575701 -290.468248)
			(xy 183.62958 -290.466279) (xy 183.683171 -290.472176) (xy 183.735332 -290.485812) (xy 183.784952 -290.506899)
			(xy 183.830973 -290.534985) (xy 183.872415 -290.569473) (xy 183.908393 -290.609627) (xy 183.938141 -290.654591)
			(xy 183.961026 -290.703408) (xy 183.976558 -290.755037) (xy 183.984408 -290.808377) (xy 183.9849 -290.835334)
			(xy 190.790845 -290.835334) (xy 190.79478 -290.781563) (xy 190.806503 -290.728939) (xy 190.825763 -290.678582)
			(xy 190.852149 -290.631565) (xy 190.885101 -290.588892) (xy 190.923914 -290.551471) (xy 190.967762 -290.520101)
			(xy 191.01571 -290.495449) (xy 191.066737 -290.478041) (xy 191.119755 -290.468248) (xy 191.173634 -290.466279)
			(xy 191.227225 -290.472176) (xy 191.279386 -290.485812) (xy 191.329006 -290.506899) (xy 191.375027 -290.534985)
			(xy 191.416469 -290.569473) (xy 191.452447 -290.609627) (xy 191.482195 -290.654591) (xy 191.50508 -290.703408)
			(xy 191.520612 -290.755037) (xy 191.528462 -290.808377) (xy 191.528954 -290.835334) (xy 198.334899 -290.835334)
			(xy 198.338834 -290.781563) (xy 198.350557 -290.728939) (xy 198.369817 -290.678582) (xy 198.396203 -290.631565)
			(xy 198.429155 -290.588892) (xy 198.467968 -290.551471) (xy 198.511816 -290.520101) (xy 198.559764 -290.495449)
			(xy 198.610791 -290.478041) (xy 198.663809 -290.468248) (xy 198.717688 -290.466279) (xy 198.771279 -290.472176)
			(xy 198.82344 -290.485812) (xy 198.87306 -290.506899) (xy 198.919081 -290.534985) (xy 198.960523 -290.569473)
			(xy 198.996501 -290.609627) (xy 199.026249 -290.654591) (xy 199.049134 -290.703408) (xy 199.064666 -290.755037)
			(xy 199.072516 -290.808377) (xy 199.073008 -290.835334) (xy 205.878699 -290.835334) (xy 205.882634 -290.781563)
			(xy 205.894357 -290.728939) (xy 205.913617 -290.678582) (xy 205.940003 -290.631565) (xy 205.972955 -290.588892)
			(xy 206.011768 -290.551471) (xy 206.055616 -290.520101) (xy 206.103564 -290.495449) (xy 206.154591 -290.478041)
			(xy 206.207609 -290.468248) (xy 206.261488 -290.466279) (xy 206.315079 -290.472176) (xy 206.36724 -290.485812)
			(xy 206.41686 -290.506899) (xy 206.462881 -290.534985) (xy 206.504323 -290.569473) (xy 206.540301 -290.609627)
			(xy 206.570049 -290.654591) (xy 206.592934 -290.703408) (xy 206.608466 -290.755037) (xy 206.616316 -290.808377)
			(xy 206.616808 -290.835334) (xy 206.616316 -290.862291) (xy 206.608466 -290.915631) (xy 206.592934 -290.96726)
			(xy 206.570049 -291.016077) (xy 206.540301 -291.061041) (xy 206.504323 -291.101195) (xy 206.462881 -291.135683)
			(xy 206.41686 -291.163769) (xy 206.36724 -291.184856) (xy 206.315079 -291.198492) (xy 206.261488 -291.204389)
			(xy 206.207609 -291.20242) (xy 206.154591 -291.192627) (xy 206.103564 -291.175219) (xy 206.055616 -291.150567)
			(xy 206.011768 -291.119197) (xy 205.972955 -291.081776) (xy 205.940003 -291.039103) (xy 205.913617 -290.992086)
			(xy 205.894357 -290.941729) (xy 205.882634 -290.889105) (xy 205.878699 -290.835334) (xy 199.073008 -290.835334)
			(xy 199.072516 -290.862291) (xy 199.064666 -290.915631) (xy 199.049134 -290.96726) (xy 199.026249 -291.016077)
			(xy 198.996501 -291.061041) (xy 198.960523 -291.101195) (xy 198.919081 -291.135683) (xy 198.87306 -291.163769)
			(xy 198.82344 -291.184856) (xy 198.771279 -291.198492) (xy 198.717688 -291.204389) (xy 198.663809 -291.20242)
			(xy 198.610791 -291.192627) (xy 198.559764 -291.175219) (xy 198.511816 -291.150567) (xy 198.467968 -291.119197)
			(xy 198.429155 -291.081776) (xy 198.396203 -291.039103) (xy 198.369817 -290.992086) (xy 198.350557 -290.941729)
			(xy 198.338834 -290.889105) (xy 198.334899 -290.835334) (xy 191.528954 -290.835334) (xy 191.528462 -290.862291)
			(xy 191.520612 -290.915631) (xy 191.50508 -290.96726) (xy 191.482195 -291.016077) (xy 191.452447 -291.061041)
			(xy 191.416469 -291.101195) (xy 191.375027 -291.135683) (xy 191.329006 -291.163769) (xy 191.279386 -291.184856)
			(xy 191.227225 -291.198492) (xy 191.173634 -291.204389) (xy 191.119755 -291.20242) (xy 191.066737 -291.192627)
			(xy 191.01571 -291.175219) (xy 190.967762 -291.150567) (xy 190.923914 -291.119197) (xy 190.885101 -291.081776)
			(xy 190.852149 -291.039103) (xy 190.825763 -290.992086) (xy 190.806503 -290.941729) (xy 190.79478 -290.889105)
			(xy 190.790845 -290.835334) (xy 183.9849 -290.835334) (xy 183.984408 -290.862291) (xy 183.976558 -290.915631)
			(xy 183.961026 -290.96726) (xy 183.938141 -291.016077) (xy 183.908393 -291.061041) (xy 183.872415 -291.101195)
			(xy 183.830973 -291.135683) (xy 183.784952 -291.163769) (xy 183.735332 -291.184856) (xy 183.683171 -291.198492)
			(xy 183.62958 -291.204389) (xy 183.575701 -291.20242) (xy 183.522683 -291.192627) (xy 183.471656 -291.175219)
			(xy 183.423708 -291.150567) (xy 183.37986 -291.119197) (xy 183.341047 -291.081776) (xy 183.308095 -291.039103)
			(xy 183.281709 -290.992086) (xy 183.262449 -290.941729) (xy 183.250726 -290.889105) (xy 183.246791 -290.835334)
			(xy 177.881534 -290.835334) (xy 177.881534 -291.685218) (xy 179.146723 -291.685218) (xy 179.150658 -291.631447)
			(xy 179.162381 -291.578823) (xy 179.181641 -291.528466) (xy 179.208027 -291.481449) (xy 179.240979 -291.438776)
			(xy 179.279792 -291.401355) (xy 179.32364 -291.369985) (xy 179.371588 -291.345333) (xy 179.422615 -291.327925)
			(xy 179.475633 -291.318132) (xy 179.529512 -291.316163) (xy 179.583103 -291.32206) (xy 179.635264 -291.335696)
			(xy 179.684884 -291.356783) (xy 179.730905 -291.384869) (xy 179.772347 -291.419357) (xy 179.808325 -291.459511)
			(xy 179.838073 -291.504475) (xy 179.860958 -291.553292) (xy 179.87649 -291.604921) (xy 179.88434 -291.658261)
			(xy 179.884832 -291.685218) (xy 186.690777 -291.685218) (xy 186.694712 -291.631447) (xy 186.706435 -291.578823)
			(xy 186.725695 -291.528466) (xy 186.752081 -291.481449) (xy 186.785033 -291.438776) (xy 186.823846 -291.401355)
			(xy 186.867694 -291.369985) (xy 186.915642 -291.345333) (xy 186.966669 -291.327925) (xy 187.019687 -291.318132)
			(xy 187.073566 -291.316163) (xy 187.127157 -291.32206) (xy 187.179318 -291.335696) (xy 187.228938 -291.356783)
			(xy 187.274959 -291.384869) (xy 187.316401 -291.419357) (xy 187.352379 -291.459511) (xy 187.382127 -291.504475)
			(xy 187.405012 -291.553292) (xy 187.420544 -291.604921) (xy 187.428394 -291.658261) (xy 187.428886 -291.685218)
			(xy 194.234831 -291.685218) (xy 194.238766 -291.631447) (xy 194.250489 -291.578823) (xy 194.269749 -291.528466)
			(xy 194.296135 -291.481449) (xy 194.329087 -291.438776) (xy 194.3679 -291.401355) (xy 194.411748 -291.369985)
			(xy 194.459696 -291.345333) (xy 194.510723 -291.327925) (xy 194.563741 -291.318132) (xy 194.61762 -291.316163)
			(xy 194.671211 -291.32206) (xy 194.723372 -291.335696) (xy 194.772992 -291.356783) (xy 194.819013 -291.384869)
			(xy 194.860455 -291.419357) (xy 194.896433 -291.459511) (xy 194.926181 -291.504475) (xy 194.949066 -291.553292)
			(xy 194.964598 -291.604921) (xy 194.972448 -291.658261) (xy 194.97294 -291.685218) (xy 201.778631 -291.685218)
			(xy 201.782566 -291.631447) (xy 201.794289 -291.578823) (xy 201.813549 -291.528466) (xy 201.839935 -291.481449)
			(xy 201.872887 -291.438776) (xy 201.9117 -291.401355) (xy 201.955548 -291.369985) (xy 202.003496 -291.345333)
			(xy 202.054523 -291.327925) (xy 202.107541 -291.318132) (xy 202.16142 -291.316163) (xy 202.215011 -291.32206)
			(xy 202.267172 -291.335696) (xy 202.316792 -291.356783) (xy 202.362813 -291.384869) (xy 202.404255 -291.419357)
			(xy 202.440233 -291.459511) (xy 202.469981 -291.504475) (xy 202.492866 -291.553292) (xy 202.508398 -291.604921)
			(xy 202.516248 -291.658261) (xy 202.51674 -291.685218) (xy 202.516248 -291.712175) (xy 202.508398 -291.765515)
			(xy 202.492866 -291.817144) (xy 202.469981 -291.865961) (xy 202.440233 -291.910925) (xy 202.404255 -291.951079)
			(xy 202.362813 -291.985567) (xy 202.316792 -292.013653) (xy 202.267172 -292.03474) (xy 202.215011 -292.048376)
			(xy 202.16142 -292.054273) (xy 202.107541 -292.052304) (xy 202.054523 -292.042511) (xy 202.003496 -292.025103)
			(xy 201.955548 -292.000451) (xy 201.9117 -291.969081) (xy 201.872887 -291.93166) (xy 201.839935 -291.888987)
			(xy 201.813549 -291.84197) (xy 201.794289 -291.791613) (xy 201.782566 -291.738989) (xy 201.778631 -291.685218)
			(xy 194.97294 -291.685218) (xy 194.972448 -291.712175) (xy 194.964598 -291.765515) (xy 194.949066 -291.817144)
			(xy 194.926181 -291.865961) (xy 194.896433 -291.910925) (xy 194.860455 -291.951079) (xy 194.819013 -291.985567)
			(xy 194.772992 -292.013653) (xy 194.723372 -292.03474) (xy 194.671211 -292.048376) (xy 194.61762 -292.054273)
			(xy 194.563741 -292.052304) (xy 194.510723 -292.042511) (xy 194.459696 -292.025103) (xy 194.411748 -292.000451)
			(xy 194.3679 -291.969081) (xy 194.329087 -291.93166) (xy 194.296135 -291.888987) (xy 194.269749 -291.84197)
			(xy 194.250489 -291.791613) (xy 194.238766 -291.738989) (xy 194.234831 -291.685218) (xy 187.428886 -291.685218)
			(xy 187.428394 -291.712175) (xy 187.420544 -291.765515) (xy 187.405012 -291.817144) (xy 187.382127 -291.865961)
			(xy 187.352379 -291.910925) (xy 187.316401 -291.951079) (xy 187.274959 -291.985567) (xy 187.228938 -292.013653)
			(xy 187.179318 -292.03474) (xy 187.127157 -292.048376) (xy 187.073566 -292.054273) (xy 187.019687 -292.052304)
			(xy 186.966669 -292.042511) (xy 186.915642 -292.025103) (xy 186.867694 -292.000451) (xy 186.823846 -291.969081)
			(xy 186.785033 -291.93166) (xy 186.752081 -291.888987) (xy 186.725695 -291.84197) (xy 186.706435 -291.791613)
			(xy 186.694712 -291.738989) (xy 186.690777 -291.685218) (xy 179.884832 -291.685218) (xy 179.88434 -291.712175)
			(xy 179.87649 -291.765515) (xy 179.860958 -291.817144) (xy 179.838073 -291.865961) (xy 179.808325 -291.910925)
			(xy 179.772347 -291.951079) (xy 179.730905 -291.985567) (xy 179.684884 -292.013653) (xy 179.635264 -292.03474)
			(xy 179.583103 -292.048376) (xy 179.529512 -292.054273) (xy 179.475633 -292.052304) (xy 179.422615 -292.042511)
			(xy 179.371588 -292.025103) (xy 179.32364 -292.000451) (xy 179.279792 -291.969081) (xy 179.240979 -291.93166)
			(xy 179.208027 -291.888987) (xy 179.181641 -291.84197) (xy 179.162381 -291.791613) (xy 179.150658 -291.738989)
			(xy 179.146723 -291.685218) (xy 177.881534 -291.685218) (xy 177.881534 -292.535356) (xy 183.246791 -292.535356)
			(xy 183.250726 -292.481585) (xy 183.262449 -292.428961) (xy 183.281709 -292.378604) (xy 183.308095 -292.331587)
			(xy 183.341047 -292.288914) (xy 183.37986 -292.251493) (xy 183.423708 -292.220123) (xy 183.471656 -292.195471)
			(xy 183.522683 -292.178063) (xy 183.575701 -292.16827) (xy 183.62958 -292.166301) (xy 183.683171 -292.172198)
			(xy 183.735332 -292.185834) (xy 183.784952 -292.206921) (xy 183.830973 -292.235007) (xy 183.872415 -292.269495)
			(xy 183.908393 -292.309649) (xy 183.938141 -292.354613) (xy 183.961026 -292.40343) (xy 183.976558 -292.455059)
			(xy 183.984408 -292.508399) (xy 183.9849 -292.535356) (xy 190.790845 -292.535356) (xy 190.79478 -292.481585)
			(xy 190.806503 -292.428961) (xy 190.825763 -292.378604) (xy 190.852149 -292.331587) (xy 190.885101 -292.288914)
			(xy 190.923914 -292.251493) (xy 190.967762 -292.220123) (xy 191.01571 -292.195471) (xy 191.066737 -292.178063)
			(xy 191.119755 -292.16827) (xy 191.173634 -292.166301) (xy 191.227225 -292.172198) (xy 191.279386 -292.185834)
			(xy 191.329006 -292.206921) (xy 191.375027 -292.235007) (xy 191.416469 -292.269495) (xy 191.452447 -292.309649)
			(xy 191.482195 -292.354613) (xy 191.50508 -292.40343) (xy 191.520612 -292.455059) (xy 191.528462 -292.508399)
			(xy 191.528954 -292.535356) (xy 198.334899 -292.535356) (xy 198.338834 -292.481585) (xy 198.350557 -292.428961)
			(xy 198.369817 -292.378604) (xy 198.396203 -292.331587) (xy 198.429155 -292.288914) (xy 198.467968 -292.251493)
			(xy 198.511816 -292.220123) (xy 198.559764 -292.195471) (xy 198.610791 -292.178063) (xy 198.663809 -292.16827)
			(xy 198.717688 -292.166301) (xy 198.771279 -292.172198) (xy 198.82344 -292.185834) (xy 198.87306 -292.206921)
			(xy 198.919081 -292.235007) (xy 198.960523 -292.269495) (xy 198.996501 -292.309649) (xy 199.026249 -292.354613)
			(xy 199.049134 -292.40343) (xy 199.064666 -292.455059) (xy 199.072516 -292.508399) (xy 199.073008 -292.535356)
			(xy 205.878699 -292.535356) (xy 205.882634 -292.481585) (xy 205.894357 -292.428961) (xy 205.913617 -292.378604)
			(xy 205.940003 -292.331587) (xy 205.972955 -292.288914) (xy 206.011768 -292.251493) (xy 206.055616 -292.220123)
			(xy 206.103564 -292.195471) (xy 206.154591 -292.178063) (xy 206.207609 -292.16827) (xy 206.261488 -292.166301)
			(xy 206.315079 -292.172198) (xy 206.36724 -292.185834) (xy 206.41686 -292.206921) (xy 206.462881 -292.235007)
			(xy 206.504323 -292.269495) (xy 206.540301 -292.309649) (xy 206.570049 -292.354613) (xy 206.592934 -292.40343)
			(xy 206.608466 -292.455059) (xy 206.616316 -292.508399) (xy 206.616808 -292.535356) (xy 206.616316 -292.562313)
			(xy 206.608466 -292.615653) (xy 206.592934 -292.667282) (xy 206.570049 -292.716099) (xy 206.540301 -292.761063)
			(xy 206.504323 -292.801217) (xy 206.462881 -292.835705) (xy 206.41686 -292.863791) (xy 206.36724 -292.884878)
			(xy 206.315079 -292.898514) (xy 206.261488 -292.904411) (xy 206.207609 -292.902442) (xy 206.154591 -292.892649)
			(xy 206.103564 -292.875241) (xy 206.055616 -292.850589) (xy 206.011768 -292.819219) (xy 205.972955 -292.781798)
			(xy 205.940003 -292.739125) (xy 205.913617 -292.692108) (xy 205.894357 -292.641751) (xy 205.882634 -292.589127)
			(xy 205.878699 -292.535356) (xy 199.073008 -292.535356) (xy 199.072516 -292.562313) (xy 199.064666 -292.615653)
			(xy 199.049134 -292.667282) (xy 199.026249 -292.716099) (xy 198.996501 -292.761063) (xy 198.960523 -292.801217)
			(xy 198.919081 -292.835705) (xy 198.87306 -292.863791) (xy 198.82344 -292.884878) (xy 198.771279 -292.898514)
			(xy 198.717688 -292.904411) (xy 198.663809 -292.902442) (xy 198.610791 -292.892649) (xy 198.559764 -292.875241)
			(xy 198.511816 -292.850589) (xy 198.467968 -292.819219) (xy 198.429155 -292.781798) (xy 198.396203 -292.739125)
			(xy 198.369817 -292.692108) (xy 198.350557 -292.641751) (xy 198.338834 -292.589127) (xy 198.334899 -292.535356)
			(xy 191.528954 -292.535356) (xy 191.528462 -292.562313) (xy 191.520612 -292.615653) (xy 191.50508 -292.667282)
			(xy 191.482195 -292.716099) (xy 191.452447 -292.761063) (xy 191.416469 -292.801217) (xy 191.375027 -292.835705)
			(xy 191.329006 -292.863791) (xy 191.279386 -292.884878) (xy 191.227225 -292.898514) (xy 191.173634 -292.904411)
			(xy 191.119755 -292.902442) (xy 191.066737 -292.892649) (xy 191.01571 -292.875241) (xy 190.967762 -292.850589)
			(xy 190.923914 -292.819219) (xy 190.885101 -292.781798) (xy 190.852149 -292.739125) (xy 190.825763 -292.692108)
			(xy 190.806503 -292.641751) (xy 190.79478 -292.589127) (xy 190.790845 -292.535356) (xy 183.9849 -292.535356)
			(xy 183.984408 -292.562313) (xy 183.976558 -292.615653) (xy 183.961026 -292.667282) (xy 183.938141 -292.716099)
			(xy 183.908393 -292.761063) (xy 183.872415 -292.801217) (xy 183.830973 -292.835705) (xy 183.784952 -292.863791)
			(xy 183.735332 -292.884878) (xy 183.683171 -292.898514) (xy 183.62958 -292.904411) (xy 183.575701 -292.902442)
			(xy 183.522683 -292.892649) (xy 183.471656 -292.875241) (xy 183.423708 -292.850589) (xy 183.37986 -292.819219)
			(xy 183.341047 -292.781798) (xy 183.308095 -292.739125) (xy 183.281709 -292.692108) (xy 183.262449 -292.641751)
			(xy 183.250726 -292.589127) (xy 183.246791 -292.535356) (xy 177.881534 -292.535356) (xy 177.881534 -293.38524)
			(xy 179.146723 -293.38524) (xy 179.150658 -293.331469) (xy 179.162381 -293.278845) (xy 179.181641 -293.228488)
			(xy 179.208027 -293.181471) (xy 179.240979 -293.138798) (xy 179.279792 -293.101377) (xy 179.32364 -293.070007)
			(xy 179.371588 -293.045355) (xy 179.422615 -293.027947) (xy 179.475633 -293.018154) (xy 179.529512 -293.016185)
			(xy 179.583103 -293.022082) (xy 179.635264 -293.035718) (xy 179.684884 -293.056805) (xy 179.730905 -293.084891)
			(xy 179.772347 -293.119379) (xy 179.808325 -293.159533) (xy 179.838073 -293.204497) (xy 179.860958 -293.253314)
			(xy 179.87649 -293.304943) (xy 179.88434 -293.358283) (xy 179.884832 -293.38524) (xy 186.690777 -293.38524)
			(xy 186.694712 -293.331469) (xy 186.706435 -293.278845) (xy 186.725695 -293.228488) (xy 186.752081 -293.181471)
			(xy 186.785033 -293.138798) (xy 186.823846 -293.101377) (xy 186.867694 -293.070007) (xy 186.915642 -293.045355)
			(xy 186.966669 -293.027947) (xy 187.019687 -293.018154) (xy 187.073566 -293.016185) (xy 187.127157 -293.022082)
			(xy 187.179318 -293.035718) (xy 187.228938 -293.056805) (xy 187.274959 -293.084891) (xy 187.316401 -293.119379)
			(xy 187.352379 -293.159533) (xy 187.382127 -293.204497) (xy 187.405012 -293.253314) (xy 187.420544 -293.304943)
			(xy 187.428394 -293.358283) (xy 187.428886 -293.38524) (xy 194.234831 -293.38524) (xy 194.238766 -293.331469)
			(xy 194.250489 -293.278845) (xy 194.269749 -293.228488) (xy 194.296135 -293.181471) (xy 194.329087 -293.138798)
			(xy 194.3679 -293.101377) (xy 194.411748 -293.070007) (xy 194.459696 -293.045355) (xy 194.510723 -293.027947)
			(xy 194.563741 -293.018154) (xy 194.61762 -293.016185) (xy 194.671211 -293.022082) (xy 194.723372 -293.035718)
			(xy 194.772992 -293.056805) (xy 194.819013 -293.084891) (xy 194.860455 -293.119379) (xy 194.896433 -293.159533)
			(xy 194.926181 -293.204497) (xy 194.949066 -293.253314) (xy 194.964598 -293.304943) (xy 194.972448 -293.358283)
			(xy 194.97294 -293.38524) (xy 201.778631 -293.38524) (xy 201.782566 -293.331469) (xy 201.794289 -293.278845)
			(xy 201.813549 -293.228488) (xy 201.839935 -293.181471) (xy 201.872887 -293.138798) (xy 201.9117 -293.101377)
			(xy 201.955548 -293.070007) (xy 202.003496 -293.045355) (xy 202.054523 -293.027947) (xy 202.107541 -293.018154)
			(xy 202.16142 -293.016185) (xy 202.215011 -293.022082) (xy 202.267172 -293.035718) (xy 202.316792 -293.056805)
			(xy 202.362813 -293.084891) (xy 202.404255 -293.119379) (xy 202.440233 -293.159533) (xy 202.469981 -293.204497)
			(xy 202.492866 -293.253314) (xy 202.508398 -293.304943) (xy 202.516248 -293.358283) (xy 202.51674 -293.38524)
			(xy 202.516248 -293.412197) (xy 202.508398 -293.465537) (xy 202.492866 -293.517166) (xy 202.469981 -293.565983)
			(xy 202.440233 -293.610947) (xy 202.404255 -293.651101) (xy 202.362813 -293.685589) (xy 202.316792 -293.713675)
			(xy 202.267172 -293.734762) (xy 202.215011 -293.748398) (xy 202.16142 -293.754295) (xy 202.107541 -293.752326)
			(xy 202.054523 -293.742533) (xy 202.003496 -293.725125) (xy 201.955548 -293.700473) (xy 201.9117 -293.669103)
			(xy 201.872887 -293.631682) (xy 201.839935 -293.589009) (xy 201.813549 -293.541992) (xy 201.794289 -293.491635)
			(xy 201.782566 -293.439011) (xy 201.778631 -293.38524) (xy 194.97294 -293.38524) (xy 194.972448 -293.412197)
			(xy 194.964598 -293.465537) (xy 194.949066 -293.517166) (xy 194.926181 -293.565983) (xy 194.896433 -293.610947)
			(xy 194.860455 -293.651101) (xy 194.819013 -293.685589) (xy 194.772992 -293.713675) (xy 194.723372 -293.734762)
			(xy 194.671211 -293.748398) (xy 194.61762 -293.754295) (xy 194.563741 -293.752326) (xy 194.510723 -293.742533)
			(xy 194.459696 -293.725125) (xy 194.411748 -293.700473) (xy 194.3679 -293.669103) (xy 194.329087 -293.631682)
			(xy 194.296135 -293.589009) (xy 194.269749 -293.541992) (xy 194.250489 -293.491635) (xy 194.238766 -293.439011)
			(xy 194.234831 -293.38524) (xy 187.428886 -293.38524) (xy 187.428394 -293.412197) (xy 187.420544 -293.465537)
			(xy 187.405012 -293.517166) (xy 187.382127 -293.565983) (xy 187.352379 -293.610947) (xy 187.316401 -293.651101)
			(xy 187.274959 -293.685589) (xy 187.228938 -293.713675) (xy 187.179318 -293.734762) (xy 187.127157 -293.748398)
			(xy 187.073566 -293.754295) (xy 187.019687 -293.752326) (xy 186.966669 -293.742533) (xy 186.915642 -293.725125)
			(xy 186.867694 -293.700473) (xy 186.823846 -293.669103) (xy 186.785033 -293.631682) (xy 186.752081 -293.589009)
			(xy 186.725695 -293.541992) (xy 186.706435 -293.491635) (xy 186.694712 -293.439011) (xy 186.690777 -293.38524)
			(xy 179.884832 -293.38524) (xy 179.88434 -293.412197) (xy 179.87649 -293.465537) (xy 179.860958 -293.517166)
			(xy 179.838073 -293.565983) (xy 179.808325 -293.610947) (xy 179.772347 -293.651101) (xy 179.730905 -293.685589)
			(xy 179.684884 -293.713675) (xy 179.635264 -293.734762) (xy 179.583103 -293.748398) (xy 179.529512 -293.754295)
			(xy 179.475633 -293.752326) (xy 179.422615 -293.742533) (xy 179.371588 -293.725125) (xy 179.32364 -293.700473)
			(xy 179.279792 -293.669103) (xy 179.240979 -293.631682) (xy 179.208027 -293.589009) (xy 179.181641 -293.541992)
			(xy 179.162381 -293.491635) (xy 179.150658 -293.439011) (xy 179.146723 -293.38524) (xy 177.881534 -293.38524)
			(xy 177.881534 -294.235378) (xy 183.246791 -294.235378) (xy 183.250726 -294.181607) (xy 183.262449 -294.128983)
			(xy 183.281709 -294.078626) (xy 183.308095 -294.031609) (xy 183.341047 -293.988936) (xy 183.37986 -293.951515)
			(xy 183.423708 -293.920145) (xy 183.471656 -293.895493) (xy 183.522683 -293.878085) (xy 183.575701 -293.868292)
			(xy 183.62958 -293.866323) (xy 183.683171 -293.87222) (xy 183.735332 -293.885856) (xy 183.784952 -293.906943)
			(xy 183.830973 -293.935029) (xy 183.872415 -293.969517) (xy 183.908393 -294.009671) (xy 183.938141 -294.054635)
			(xy 183.961026 -294.103452) (xy 183.976558 -294.155081) (xy 183.984408 -294.208421) (xy 183.9849 -294.235378)
			(xy 190.790845 -294.235378) (xy 190.79478 -294.181607) (xy 190.806503 -294.128983) (xy 190.825763 -294.078626)
			(xy 190.852149 -294.031609) (xy 190.885101 -293.988936) (xy 190.923914 -293.951515) (xy 190.967762 -293.920145)
			(xy 191.01571 -293.895493) (xy 191.066737 -293.878085) (xy 191.119755 -293.868292) (xy 191.173634 -293.866323)
			(xy 191.227225 -293.87222) (xy 191.279386 -293.885856) (xy 191.329006 -293.906943) (xy 191.375027 -293.935029)
			(xy 191.416469 -293.969517) (xy 191.452447 -294.009671) (xy 191.482195 -294.054635) (xy 191.50508 -294.103452)
			(xy 191.520612 -294.155081) (xy 191.528462 -294.208421) (xy 191.528954 -294.235378) (xy 198.334899 -294.235378)
			(xy 198.338834 -294.181607) (xy 198.350557 -294.128983) (xy 198.369817 -294.078626) (xy 198.396203 -294.031609)
			(xy 198.429155 -293.988936) (xy 198.467968 -293.951515) (xy 198.511816 -293.920145) (xy 198.559764 -293.895493)
			(xy 198.610791 -293.878085) (xy 198.663809 -293.868292) (xy 198.717688 -293.866323) (xy 198.771279 -293.87222)
			(xy 198.82344 -293.885856) (xy 198.87306 -293.906943) (xy 198.919081 -293.935029) (xy 198.960523 -293.969517)
			(xy 198.996501 -294.009671) (xy 199.026249 -294.054635) (xy 199.049134 -294.103452) (xy 199.064666 -294.155081)
			(xy 199.072516 -294.208421) (xy 199.073008 -294.235378) (xy 205.878699 -294.235378) (xy 205.882634 -294.181607)
			(xy 205.894357 -294.128983) (xy 205.913617 -294.078626) (xy 205.940003 -294.031609) (xy 205.972955 -293.988936)
			(xy 206.011768 -293.951515) (xy 206.055616 -293.920145) (xy 206.103564 -293.895493) (xy 206.154591 -293.878085)
			(xy 206.207609 -293.868292) (xy 206.261488 -293.866323) (xy 206.315079 -293.87222) (xy 206.36724 -293.885856)
			(xy 206.41686 -293.906943) (xy 206.462881 -293.935029) (xy 206.504323 -293.969517) (xy 206.540301 -294.009671)
			(xy 206.570049 -294.054635) (xy 206.592934 -294.103452) (xy 206.608466 -294.155081) (xy 206.616316 -294.208421)
			(xy 206.616808 -294.235378) (xy 206.616316 -294.262335) (xy 206.608466 -294.315675) (xy 206.592934 -294.367304)
			(xy 206.570049 -294.416121) (xy 206.540301 -294.461085) (xy 206.504323 -294.501239) (xy 206.462881 -294.535727)
			(xy 206.41686 -294.563813) (xy 206.36724 -294.5849) (xy 206.315079 -294.598536) (xy 206.261488 -294.604433)
			(xy 206.207609 -294.602464) (xy 206.154591 -294.592671) (xy 206.103564 -294.575263) (xy 206.055616 -294.550611)
			(xy 206.011768 -294.519241) (xy 205.972955 -294.48182) (xy 205.940003 -294.439147) (xy 205.913617 -294.39213)
			(xy 205.894357 -294.341773) (xy 205.882634 -294.289149) (xy 205.878699 -294.235378) (xy 199.073008 -294.235378)
			(xy 199.072516 -294.262335) (xy 199.064666 -294.315675) (xy 199.049134 -294.367304) (xy 199.026249 -294.416121)
			(xy 198.996501 -294.461085) (xy 198.960523 -294.501239) (xy 198.919081 -294.535727) (xy 198.87306 -294.563813)
			(xy 198.82344 -294.5849) (xy 198.771279 -294.598536) (xy 198.717688 -294.604433) (xy 198.663809 -294.602464)
			(xy 198.610791 -294.592671) (xy 198.559764 -294.575263) (xy 198.511816 -294.550611) (xy 198.467968 -294.519241)
			(xy 198.429155 -294.48182) (xy 198.396203 -294.439147) (xy 198.369817 -294.39213) (xy 198.350557 -294.341773)
			(xy 198.338834 -294.289149) (xy 198.334899 -294.235378) (xy 191.528954 -294.235378) (xy 191.528462 -294.262335)
			(xy 191.520612 -294.315675) (xy 191.50508 -294.367304) (xy 191.482195 -294.416121) (xy 191.452447 -294.461085)
			(xy 191.416469 -294.501239) (xy 191.375027 -294.535727) (xy 191.329006 -294.563813) (xy 191.279386 -294.5849)
			(xy 191.227225 -294.598536) (xy 191.173634 -294.604433) (xy 191.119755 -294.602464) (xy 191.066737 -294.592671)
			(xy 191.01571 -294.575263) (xy 190.967762 -294.550611) (xy 190.923914 -294.519241) (xy 190.885101 -294.48182)
			(xy 190.852149 -294.439147) (xy 190.825763 -294.39213) (xy 190.806503 -294.341773) (xy 190.79478 -294.289149)
			(xy 190.790845 -294.235378) (xy 183.9849 -294.235378) (xy 183.984408 -294.262335) (xy 183.976558 -294.315675)
			(xy 183.961026 -294.367304) (xy 183.938141 -294.416121) (xy 183.908393 -294.461085) (xy 183.872415 -294.501239)
			(xy 183.830973 -294.535727) (xy 183.784952 -294.563813) (xy 183.735332 -294.5849) (xy 183.683171 -294.598536)
			(xy 183.62958 -294.604433) (xy 183.575701 -294.602464) (xy 183.522683 -294.592671) (xy 183.471656 -294.575263)
			(xy 183.423708 -294.550611) (xy 183.37986 -294.519241) (xy 183.341047 -294.48182) (xy 183.308095 -294.439147)
			(xy 183.281709 -294.39213) (xy 183.262449 -294.341773) (xy 183.250726 -294.289149) (xy 183.246791 -294.235378)
			(xy 177.881534 -294.235378) (xy 177.881534 -295.085262) (xy 179.146723 -295.085262) (xy 179.150658 -295.031491)
			(xy 179.162381 -294.978867) (xy 179.181641 -294.92851) (xy 179.208027 -294.881493) (xy 179.240979 -294.83882)
			(xy 179.279792 -294.801399) (xy 179.32364 -294.770029) (xy 179.371588 -294.745377) (xy 179.422615 -294.727969)
			(xy 179.475633 -294.718176) (xy 179.529512 -294.716207) (xy 179.583103 -294.722104) (xy 179.635264 -294.73574)
			(xy 179.684884 -294.756827) (xy 179.730905 -294.784913) (xy 179.772347 -294.819401) (xy 179.808325 -294.859555)
			(xy 179.838073 -294.904519) (xy 179.860958 -294.953336) (xy 179.87649 -295.004965) (xy 179.88434 -295.058305)
			(xy 179.884832 -295.085262) (xy 183.246791 -295.085262) (xy 183.250726 -295.031491) (xy 183.262449 -294.978867)
			(xy 183.281709 -294.92851) (xy 183.308095 -294.881493) (xy 183.341047 -294.83882) (xy 183.37986 -294.801399)
			(xy 183.423708 -294.770029) (xy 183.471656 -294.745377) (xy 183.522683 -294.727969) (xy 183.575701 -294.718176)
			(xy 183.62958 -294.716207) (xy 183.683171 -294.722104) (xy 183.735332 -294.73574) (xy 183.784952 -294.756827)
			(xy 183.830973 -294.784913) (xy 183.872415 -294.819401) (xy 183.908393 -294.859555) (xy 183.938141 -294.904519)
			(xy 183.961026 -294.953336) (xy 183.976558 -295.004965) (xy 183.984408 -295.058305) (xy 183.9849 -295.085262)
			(xy 186.690777 -295.085262) (xy 186.694712 -295.031491) (xy 186.706435 -294.978867) (xy 186.725695 -294.92851)
			(xy 186.752081 -294.881493) (xy 186.785033 -294.83882) (xy 186.823846 -294.801399) (xy 186.867694 -294.770029)
			(xy 186.915642 -294.745377) (xy 186.966669 -294.727969) (xy 187.019687 -294.718176) (xy 187.073566 -294.716207)
			(xy 187.127157 -294.722104) (xy 187.179318 -294.73574) (xy 187.228938 -294.756827) (xy 187.274959 -294.784913)
			(xy 187.316401 -294.819401) (xy 187.352379 -294.859555) (xy 187.382127 -294.904519) (xy 187.405012 -294.953336)
			(xy 187.420544 -295.004965) (xy 187.428394 -295.058305) (xy 187.428886 -295.085262) (xy 190.790845 -295.085262)
			(xy 190.79478 -295.031491) (xy 190.806503 -294.978867) (xy 190.825763 -294.92851) (xy 190.852149 -294.881493)
			(xy 190.885101 -294.83882) (xy 190.923914 -294.801399) (xy 190.967762 -294.770029) (xy 191.01571 -294.745377)
			(xy 191.066737 -294.727969) (xy 191.119755 -294.718176) (xy 191.173634 -294.716207) (xy 191.227225 -294.722104)
			(xy 191.279386 -294.73574) (xy 191.329006 -294.756827) (xy 191.375027 -294.784913) (xy 191.416469 -294.819401)
			(xy 191.452447 -294.859555) (xy 191.482195 -294.904519) (xy 191.50508 -294.953336) (xy 191.520612 -295.004965)
			(xy 191.528462 -295.058305) (xy 191.528954 -295.085262) (xy 194.234831 -295.085262) (xy 194.238766 -295.031491)
			(xy 194.250489 -294.978867) (xy 194.269749 -294.92851) (xy 194.296135 -294.881493) (xy 194.329087 -294.83882)
			(xy 194.3679 -294.801399) (xy 194.411748 -294.770029) (xy 194.459696 -294.745377) (xy 194.510723 -294.727969)
			(xy 194.563741 -294.718176) (xy 194.61762 -294.716207) (xy 194.671211 -294.722104) (xy 194.723372 -294.73574)
			(xy 194.772992 -294.756827) (xy 194.819013 -294.784913) (xy 194.860455 -294.819401) (xy 194.896433 -294.859555)
			(xy 194.926181 -294.904519) (xy 194.949066 -294.953336) (xy 194.964598 -295.004965) (xy 194.972448 -295.058305)
			(xy 194.97294 -295.085262) (xy 198.334899 -295.085262) (xy 198.338834 -295.031491) (xy 198.350557 -294.978867)
			(xy 198.369817 -294.92851) (xy 198.396203 -294.881493) (xy 198.429155 -294.83882) (xy 198.467968 -294.801399)
			(xy 198.511816 -294.770029) (xy 198.559764 -294.745377) (xy 198.610791 -294.727969) (xy 198.663809 -294.718176)
			(xy 198.717688 -294.716207) (xy 198.771279 -294.722104) (xy 198.82344 -294.73574) (xy 198.87306 -294.756827)
			(xy 198.919081 -294.784913) (xy 198.960523 -294.819401) (xy 198.996501 -294.859555) (xy 199.026249 -294.904519)
			(xy 199.049134 -294.953336) (xy 199.064666 -295.004965) (xy 199.072516 -295.058305) (xy 199.073008 -295.085262)
			(xy 201.778631 -295.085262) (xy 201.782566 -295.031491) (xy 201.794289 -294.978867) (xy 201.813549 -294.92851)
			(xy 201.839935 -294.881493) (xy 201.872887 -294.83882) (xy 201.9117 -294.801399) (xy 201.955548 -294.770029)
			(xy 202.003496 -294.745377) (xy 202.054523 -294.727969) (xy 202.107541 -294.718176) (xy 202.16142 -294.716207)
			(xy 202.215011 -294.722104) (xy 202.267172 -294.73574) (xy 202.316792 -294.756827) (xy 202.362813 -294.784913)
			(xy 202.404255 -294.819401) (xy 202.440233 -294.859555) (xy 202.469981 -294.904519) (xy 202.492866 -294.953336)
			(xy 202.508398 -295.004965) (xy 202.516248 -295.058305) (xy 202.51674 -295.085262) (xy 205.878699 -295.085262)
			(xy 205.882634 -295.031491) (xy 205.894357 -294.978867) (xy 205.913617 -294.92851) (xy 205.940003 -294.881493)
			(xy 205.972955 -294.83882) (xy 206.011768 -294.801399) (xy 206.055616 -294.770029) (xy 206.103564 -294.745377)
			(xy 206.154591 -294.727969) (xy 206.207609 -294.718176) (xy 206.261488 -294.716207) (xy 206.315079 -294.722104)
			(xy 206.36724 -294.73574) (xy 206.41686 -294.756827) (xy 206.462881 -294.784913) (xy 206.504323 -294.819401)
			(xy 206.540301 -294.859555) (xy 206.570049 -294.904519) (xy 206.592934 -294.953336) (xy 206.608466 -295.004965)
			(xy 206.616316 -295.058305) (xy 206.616808 -295.085262) (xy 206.616316 -295.112219) (xy 206.608466 -295.165559)
			(xy 206.592934 -295.217188) (xy 206.570049 -295.266005) (xy 206.540301 -295.310969) (xy 206.504323 -295.351123)
			(xy 206.462881 -295.385611) (xy 206.41686 -295.413697) (xy 206.36724 -295.434784) (xy 206.315079 -295.44842)
			(xy 206.261488 -295.454317) (xy 206.207609 -295.452348) (xy 206.154591 -295.442555) (xy 206.103564 -295.425147)
			(xy 206.055616 -295.400495) (xy 206.011768 -295.369125) (xy 205.972955 -295.331704) (xy 205.940003 -295.289031)
			(xy 205.913617 -295.242014) (xy 205.894357 -295.191657) (xy 205.882634 -295.139033) (xy 205.878699 -295.085262)
			(xy 202.51674 -295.085262) (xy 202.516248 -295.112219) (xy 202.508398 -295.165559) (xy 202.492866 -295.217188)
			(xy 202.469981 -295.266005) (xy 202.440233 -295.310969) (xy 202.404255 -295.351123) (xy 202.362813 -295.385611)
			(xy 202.316792 -295.413697) (xy 202.267172 -295.434784) (xy 202.215011 -295.44842) (xy 202.16142 -295.454317)
			(xy 202.107541 -295.452348) (xy 202.054523 -295.442555) (xy 202.003496 -295.425147) (xy 201.955548 -295.400495)
			(xy 201.9117 -295.369125) (xy 201.872887 -295.331704) (xy 201.839935 -295.289031) (xy 201.813549 -295.242014)
			(xy 201.794289 -295.191657) (xy 201.782566 -295.139033) (xy 201.778631 -295.085262) (xy 199.073008 -295.085262)
			(xy 199.072516 -295.112219) (xy 199.064666 -295.165559) (xy 199.049134 -295.217188) (xy 199.026249 -295.266005)
			(xy 198.996501 -295.310969) (xy 198.960523 -295.351123) (xy 198.919081 -295.385611) (xy 198.87306 -295.413697)
			(xy 198.82344 -295.434784) (xy 198.771279 -295.44842) (xy 198.717688 -295.454317) (xy 198.663809 -295.452348)
			(xy 198.610791 -295.442555) (xy 198.559764 -295.425147) (xy 198.511816 -295.400495) (xy 198.467968 -295.369125)
			(xy 198.429155 -295.331704) (xy 198.396203 -295.289031) (xy 198.369817 -295.242014) (xy 198.350557 -295.191657)
			(xy 198.338834 -295.139033) (xy 198.334899 -295.085262) (xy 194.97294 -295.085262) (xy 194.972448 -295.112219)
			(xy 194.964598 -295.165559) (xy 194.949066 -295.217188) (xy 194.926181 -295.266005) (xy 194.896433 -295.310969)
			(xy 194.860455 -295.351123) (xy 194.819013 -295.385611) (xy 194.772992 -295.413697) (xy 194.723372 -295.434784)
			(xy 194.671211 -295.44842) (xy 194.61762 -295.454317) (xy 194.563741 -295.452348) (xy 194.510723 -295.442555)
			(xy 194.459696 -295.425147) (xy 194.411748 -295.400495) (xy 194.3679 -295.369125) (xy 194.329087 -295.331704)
			(xy 194.296135 -295.289031) (xy 194.269749 -295.242014) (xy 194.250489 -295.191657) (xy 194.238766 -295.139033)
			(xy 194.234831 -295.085262) (xy 191.528954 -295.085262) (xy 191.528462 -295.112219) (xy 191.520612 -295.165559)
			(xy 191.50508 -295.217188) (xy 191.482195 -295.266005) (xy 191.452447 -295.310969) (xy 191.416469 -295.351123)
			(xy 191.375027 -295.385611) (xy 191.329006 -295.413697) (xy 191.279386 -295.434784) (xy 191.227225 -295.44842)
			(xy 191.173634 -295.454317) (xy 191.119755 -295.452348) (xy 191.066737 -295.442555) (xy 191.01571 -295.425147)
			(xy 190.967762 -295.400495) (xy 190.923914 -295.369125) (xy 190.885101 -295.331704) (xy 190.852149 -295.289031)
			(xy 190.825763 -295.242014) (xy 190.806503 -295.191657) (xy 190.79478 -295.139033) (xy 190.790845 -295.085262)
			(xy 187.428886 -295.085262) (xy 187.428394 -295.112219) (xy 187.420544 -295.165559) (xy 187.405012 -295.217188)
			(xy 187.382127 -295.266005) (xy 187.352379 -295.310969) (xy 187.316401 -295.351123) (xy 187.274959 -295.385611)
			(xy 187.228938 -295.413697) (xy 187.179318 -295.434784) (xy 187.127157 -295.44842) (xy 187.073566 -295.454317)
			(xy 187.019687 -295.452348) (xy 186.966669 -295.442555) (xy 186.915642 -295.425147) (xy 186.867694 -295.400495)
			(xy 186.823846 -295.369125) (xy 186.785033 -295.331704) (xy 186.752081 -295.289031) (xy 186.725695 -295.242014)
			(xy 186.706435 -295.191657) (xy 186.694712 -295.139033) (xy 186.690777 -295.085262) (xy 183.9849 -295.085262)
			(xy 183.984408 -295.112219) (xy 183.976558 -295.165559) (xy 183.961026 -295.217188) (xy 183.938141 -295.266005)
			(xy 183.908393 -295.310969) (xy 183.872415 -295.351123) (xy 183.830973 -295.385611) (xy 183.784952 -295.413697)
			(xy 183.735332 -295.434784) (xy 183.683171 -295.44842) (xy 183.62958 -295.454317) (xy 183.575701 -295.452348)
			(xy 183.522683 -295.442555) (xy 183.471656 -295.425147) (xy 183.423708 -295.400495) (xy 183.37986 -295.369125)
			(xy 183.341047 -295.331704) (xy 183.308095 -295.289031) (xy 183.281709 -295.242014) (xy 183.262449 -295.191657)
			(xy 183.250726 -295.139033) (xy 183.246791 -295.085262) (xy 179.884832 -295.085262) (xy 179.88434 -295.112219)
			(xy 179.87649 -295.165559) (xy 179.860958 -295.217188) (xy 179.838073 -295.266005) (xy 179.808325 -295.310969)
			(xy 179.772347 -295.351123) (xy 179.730905 -295.385611) (xy 179.684884 -295.413697) (xy 179.635264 -295.434784)
			(xy 179.583103 -295.44842) (xy 179.529512 -295.454317) (xy 179.475633 -295.452348) (xy 179.422615 -295.442555)
			(xy 179.371588 -295.425147) (xy 179.32364 -295.400495) (xy 179.279792 -295.369125) (xy 179.240979 -295.331704)
			(xy 179.208027 -295.289031) (xy 179.181641 -295.242014) (xy 179.162381 -295.191657) (xy 179.150658 -295.139033)
			(xy 179.146723 -295.085262) (xy 177.881534 -295.085262) (xy 177.881534 -295.9354) (xy 179.146723 -295.9354)
			(xy 179.150658 -295.881629) (xy 179.162381 -295.829005) (xy 179.181641 -295.778648) (xy 179.208027 -295.731631)
			(xy 179.240979 -295.688958) (xy 179.279792 -295.651537) (xy 179.32364 -295.620167) (xy 179.371588 -295.595515)
			(xy 179.422615 -295.578107) (xy 179.475633 -295.568314) (xy 179.529512 -295.566345) (xy 179.583103 -295.572242)
			(xy 179.635264 -295.585878) (xy 179.684884 -295.606965) (xy 179.730905 -295.635051) (xy 179.772347 -295.669539)
			(xy 179.808325 -295.709693) (xy 179.838073 -295.754657) (xy 179.860958 -295.803474) (xy 179.87649 -295.855103)
			(xy 179.88434 -295.908443) (xy 179.884832 -295.9354) (xy 186.690777 -295.9354) (xy 186.694712 -295.881629)
			(xy 186.706435 -295.829005) (xy 186.725695 -295.778648) (xy 186.752081 -295.731631) (xy 186.785033 -295.688958)
			(xy 186.823846 -295.651537) (xy 186.867694 -295.620167) (xy 186.915642 -295.595515) (xy 186.966669 -295.578107)
			(xy 187.019687 -295.568314) (xy 187.073566 -295.566345) (xy 187.127157 -295.572242) (xy 187.179318 -295.585878)
			(xy 187.228938 -295.606965) (xy 187.274959 -295.635051) (xy 187.316401 -295.669539) (xy 187.352379 -295.709693)
			(xy 187.382127 -295.754657) (xy 187.405012 -295.803474) (xy 187.420544 -295.855103) (xy 187.428394 -295.908443)
			(xy 187.428886 -295.9354) (xy 194.234831 -295.9354) (xy 194.238766 -295.881629) (xy 194.250489 -295.829005)
			(xy 194.269749 -295.778648) (xy 194.296135 -295.731631) (xy 194.329087 -295.688958) (xy 194.3679 -295.651537)
			(xy 194.411748 -295.620167) (xy 194.459696 -295.595515) (xy 194.510723 -295.578107) (xy 194.563741 -295.568314)
			(xy 194.61762 -295.566345) (xy 194.671211 -295.572242) (xy 194.723372 -295.585878) (xy 194.772992 -295.606965)
			(xy 194.819013 -295.635051) (xy 194.860455 -295.669539) (xy 194.896433 -295.709693) (xy 194.926181 -295.754657)
			(xy 194.949066 -295.803474) (xy 194.964598 -295.855103) (xy 194.972448 -295.908443) (xy 194.97294 -295.9354)
			(xy 201.778631 -295.9354) (xy 201.782566 -295.881629) (xy 201.794289 -295.829005) (xy 201.813549 -295.778648)
			(xy 201.839935 -295.731631) (xy 201.872887 -295.688958) (xy 201.9117 -295.651537) (xy 201.955548 -295.620167)
			(xy 202.003496 -295.595515) (xy 202.054523 -295.578107) (xy 202.107541 -295.568314) (xy 202.16142 -295.566345)
			(xy 202.215011 -295.572242) (xy 202.267172 -295.585878) (xy 202.316792 -295.606965) (xy 202.362813 -295.635051)
			(xy 202.404255 -295.669539) (xy 202.440233 -295.709693) (xy 202.469981 -295.754657) (xy 202.492866 -295.803474)
			(xy 202.508398 -295.855103) (xy 202.516248 -295.908443) (xy 202.51674 -295.9354) (xy 202.516248 -295.962357)
			(xy 202.508398 -296.015697) (xy 202.492866 -296.067326) (xy 202.469981 -296.116143) (xy 202.440233 -296.161107)
			(xy 202.404255 -296.201261) (xy 202.362813 -296.235749) (xy 202.316792 -296.263835) (xy 202.267172 -296.284922)
			(xy 202.215011 -296.298558) (xy 202.16142 -296.304455) (xy 202.107541 -296.302486) (xy 202.054523 -296.292693)
			(xy 202.003496 -296.275285) (xy 201.955548 -296.250633) (xy 201.9117 -296.219263) (xy 201.872887 -296.181842)
			(xy 201.839935 -296.139169) (xy 201.813549 -296.092152) (xy 201.794289 -296.041795) (xy 201.782566 -295.989171)
			(xy 201.778631 -295.9354) (xy 194.97294 -295.9354) (xy 194.972448 -295.962357) (xy 194.964598 -296.015697)
			(xy 194.949066 -296.067326) (xy 194.926181 -296.116143) (xy 194.896433 -296.161107) (xy 194.860455 -296.201261)
			(xy 194.819013 -296.235749) (xy 194.772992 -296.263835) (xy 194.723372 -296.284922) (xy 194.671211 -296.298558)
			(xy 194.61762 -296.304455) (xy 194.563741 -296.302486) (xy 194.510723 -296.292693) (xy 194.459696 -296.275285)
			(xy 194.411748 -296.250633) (xy 194.3679 -296.219263) (xy 194.329087 -296.181842) (xy 194.296135 -296.139169)
			(xy 194.269749 -296.092152) (xy 194.250489 -296.041795) (xy 194.238766 -295.989171) (xy 194.234831 -295.9354)
			(xy 187.428886 -295.9354) (xy 187.428394 -295.962357) (xy 187.420544 -296.015697) (xy 187.405012 -296.067326)
			(xy 187.382127 -296.116143) (xy 187.352379 -296.161107) (xy 187.316401 -296.201261) (xy 187.274959 -296.235749)
			(xy 187.228938 -296.263835) (xy 187.179318 -296.284922) (xy 187.127157 -296.298558) (xy 187.073566 -296.304455)
			(xy 187.019687 -296.302486) (xy 186.966669 -296.292693) (xy 186.915642 -296.275285) (xy 186.867694 -296.250633)
			(xy 186.823846 -296.219263) (xy 186.785033 -296.181842) (xy 186.752081 -296.139169) (xy 186.725695 -296.092152)
			(xy 186.706435 -296.041795) (xy 186.694712 -295.989171) (xy 186.690777 -295.9354) (xy 179.884832 -295.9354)
			(xy 179.88434 -295.962357) (xy 179.87649 -296.015697) (xy 179.860958 -296.067326) (xy 179.838073 -296.116143)
			(xy 179.808325 -296.161107) (xy 179.772347 -296.201261) (xy 179.730905 -296.235749) (xy 179.684884 -296.263835)
			(xy 179.635264 -296.284922) (xy 179.583103 -296.298558) (xy 179.529512 -296.304455) (xy 179.475633 -296.302486)
			(xy 179.422615 -296.292693) (xy 179.371588 -296.275285) (xy 179.32364 -296.250633) (xy 179.279792 -296.219263)
			(xy 179.240979 -296.181842) (xy 179.208027 -296.139169) (xy 179.181641 -296.092152) (xy 179.162381 -296.041795)
			(xy 179.150658 -295.989171) (xy 179.146723 -295.9354) (xy 177.881534 -295.9354) (xy 177.881534 -296.785284)
			(xy 183.246791 -296.785284) (xy 183.250726 -296.731513) (xy 183.262449 -296.678889) (xy 183.281709 -296.628532)
			(xy 183.308095 -296.581515) (xy 183.341047 -296.538842) (xy 183.37986 -296.501421) (xy 183.423708 -296.470051)
			(xy 183.471656 -296.445399) (xy 183.522683 -296.427991) (xy 183.575701 -296.418198) (xy 183.62958 -296.416229)
			(xy 183.683171 -296.422126) (xy 183.735332 -296.435762) (xy 183.784952 -296.456849) (xy 183.830973 -296.484935)
			(xy 183.872415 -296.519423) (xy 183.908393 -296.559577) (xy 183.938141 -296.604541) (xy 183.961026 -296.653358)
			(xy 183.976558 -296.704987) (xy 183.984408 -296.758327) (xy 183.9849 -296.785284) (xy 190.790845 -296.785284)
			(xy 190.79478 -296.731513) (xy 190.806503 -296.678889) (xy 190.825763 -296.628532) (xy 190.852149 -296.581515)
			(xy 190.885101 -296.538842) (xy 190.923914 -296.501421) (xy 190.967762 -296.470051) (xy 191.01571 -296.445399)
			(xy 191.066737 -296.427991) (xy 191.119755 -296.418198) (xy 191.173634 -296.416229) (xy 191.227225 -296.422126)
			(xy 191.279386 -296.435762) (xy 191.329006 -296.456849) (xy 191.375027 -296.484935) (xy 191.416469 -296.519423)
			(xy 191.452447 -296.559577) (xy 191.482195 -296.604541) (xy 191.50508 -296.653358) (xy 191.520612 -296.704987)
			(xy 191.528462 -296.758327) (xy 191.528954 -296.785284) (xy 198.334899 -296.785284) (xy 198.338834 -296.731513)
			(xy 198.350557 -296.678889) (xy 198.369817 -296.628532) (xy 198.396203 -296.581515) (xy 198.429155 -296.538842)
			(xy 198.467968 -296.501421) (xy 198.511816 -296.470051) (xy 198.559764 -296.445399) (xy 198.610791 -296.427991)
			(xy 198.663809 -296.418198) (xy 198.717688 -296.416229) (xy 198.771279 -296.422126) (xy 198.82344 -296.435762)
			(xy 198.87306 -296.456849) (xy 198.919081 -296.484935) (xy 198.960523 -296.519423) (xy 198.996501 -296.559577)
			(xy 199.026249 -296.604541) (xy 199.049134 -296.653358) (xy 199.064666 -296.704987) (xy 199.072516 -296.758327)
			(xy 199.073008 -296.785284) (xy 205.878699 -296.785284) (xy 205.882634 -296.731513) (xy 205.894357 -296.678889)
			(xy 205.913617 -296.628532) (xy 205.940003 -296.581515) (xy 205.972955 -296.538842) (xy 206.011768 -296.501421)
			(xy 206.055616 -296.470051) (xy 206.103564 -296.445399) (xy 206.154591 -296.427991) (xy 206.207609 -296.418198)
			(xy 206.261488 -296.416229) (xy 206.315079 -296.422126) (xy 206.36724 -296.435762) (xy 206.41686 -296.456849)
			(xy 206.462881 -296.484935) (xy 206.504323 -296.519423) (xy 206.540301 -296.559577) (xy 206.570049 -296.604541)
			(xy 206.592934 -296.653358) (xy 206.608466 -296.704987) (xy 206.616316 -296.758327) (xy 206.616808 -296.785284)
			(xy 206.616316 -296.812241) (xy 206.608466 -296.865581) (xy 206.592934 -296.91721) (xy 206.570049 -296.966027)
			(xy 206.540301 -297.010991) (xy 206.504323 -297.051145) (xy 206.462881 -297.085633) (xy 206.41686 -297.113719)
			(xy 206.36724 -297.134806) (xy 206.315079 -297.148442) (xy 206.261488 -297.154339) (xy 206.207609 -297.15237)
			(xy 206.154591 -297.142577) (xy 206.103564 -297.125169) (xy 206.055616 -297.100517) (xy 206.011768 -297.069147)
			(xy 205.972955 -297.031726) (xy 205.940003 -296.989053) (xy 205.913617 -296.942036) (xy 205.894357 -296.891679)
			(xy 205.882634 -296.839055) (xy 205.878699 -296.785284) (xy 199.073008 -296.785284) (xy 199.072516 -296.812241)
			(xy 199.064666 -296.865581) (xy 199.049134 -296.91721) (xy 199.026249 -296.966027) (xy 198.996501 -297.010991)
			(xy 198.960523 -297.051145) (xy 198.919081 -297.085633) (xy 198.87306 -297.113719) (xy 198.82344 -297.134806)
			(xy 198.771279 -297.148442) (xy 198.717688 -297.154339) (xy 198.663809 -297.15237) (xy 198.610791 -297.142577)
			(xy 198.559764 -297.125169) (xy 198.511816 -297.100517) (xy 198.467968 -297.069147) (xy 198.429155 -297.031726)
			(xy 198.396203 -296.989053) (xy 198.369817 -296.942036) (xy 198.350557 -296.891679) (xy 198.338834 -296.839055)
			(xy 198.334899 -296.785284) (xy 191.528954 -296.785284) (xy 191.528462 -296.812241) (xy 191.520612 -296.865581)
			(xy 191.50508 -296.91721) (xy 191.482195 -296.966027) (xy 191.452447 -297.010991) (xy 191.416469 -297.051145)
			(xy 191.375027 -297.085633) (xy 191.329006 -297.113719) (xy 191.279386 -297.134806) (xy 191.227225 -297.148442)
			(xy 191.173634 -297.154339) (xy 191.119755 -297.15237) (xy 191.066737 -297.142577) (xy 191.01571 -297.125169)
			(xy 190.967762 -297.100517) (xy 190.923914 -297.069147) (xy 190.885101 -297.031726) (xy 190.852149 -296.989053)
			(xy 190.825763 -296.942036) (xy 190.806503 -296.891679) (xy 190.79478 -296.839055) (xy 190.790845 -296.785284)
			(xy 183.9849 -296.785284) (xy 183.984408 -296.812241) (xy 183.976558 -296.865581) (xy 183.961026 -296.91721)
			(xy 183.938141 -296.966027) (xy 183.908393 -297.010991) (xy 183.872415 -297.051145) (xy 183.830973 -297.085633)
			(xy 183.784952 -297.113719) (xy 183.735332 -297.134806) (xy 183.683171 -297.148442) (xy 183.62958 -297.154339)
			(xy 183.575701 -297.15237) (xy 183.522683 -297.142577) (xy 183.471656 -297.125169) (xy 183.423708 -297.100517)
			(xy 183.37986 -297.069147) (xy 183.341047 -297.031726) (xy 183.308095 -296.989053) (xy 183.281709 -296.942036)
			(xy 183.262449 -296.891679) (xy 183.250726 -296.839055) (xy 183.246791 -296.785284) (xy 177.881534 -296.785284)
			(xy 177.881534 -297.635422) (xy 179.146723 -297.635422) (xy 179.150658 -297.581651) (xy 179.162381 -297.529027)
			(xy 179.181641 -297.47867) (xy 179.208027 -297.431653) (xy 179.240979 -297.38898) (xy 179.279792 -297.351559)
			(xy 179.32364 -297.320189) (xy 179.371588 -297.295537) (xy 179.422615 -297.278129) (xy 179.475633 -297.268336)
			(xy 179.529512 -297.266367) (xy 179.583103 -297.272264) (xy 179.635264 -297.2859) (xy 179.684884 -297.306987)
			(xy 179.730905 -297.335073) (xy 179.772347 -297.369561) (xy 179.808325 -297.409715) (xy 179.838073 -297.454679)
			(xy 179.860958 -297.503496) (xy 179.87649 -297.555125) (xy 179.88434 -297.608465) (xy 179.884832 -297.635422)
			(xy 186.690777 -297.635422) (xy 186.694712 -297.581651) (xy 186.706435 -297.529027) (xy 186.725695 -297.47867)
			(xy 186.752081 -297.431653) (xy 186.785033 -297.38898) (xy 186.823846 -297.351559) (xy 186.867694 -297.320189)
			(xy 186.915642 -297.295537) (xy 186.966669 -297.278129) (xy 187.019687 -297.268336) (xy 187.073566 -297.266367)
			(xy 187.127157 -297.272264) (xy 187.179318 -297.2859) (xy 187.228938 -297.306987) (xy 187.274959 -297.335073)
			(xy 187.316401 -297.369561) (xy 187.352379 -297.409715) (xy 187.382127 -297.454679) (xy 187.405012 -297.503496)
			(xy 187.420544 -297.555125) (xy 187.428394 -297.608465) (xy 187.428886 -297.635422) (xy 194.234831 -297.635422)
			(xy 194.238766 -297.581651) (xy 194.250489 -297.529027) (xy 194.269749 -297.47867) (xy 194.296135 -297.431653)
			(xy 194.329087 -297.38898) (xy 194.3679 -297.351559) (xy 194.411748 -297.320189) (xy 194.459696 -297.295537)
			(xy 194.510723 -297.278129) (xy 194.563741 -297.268336) (xy 194.61762 -297.266367) (xy 194.671211 -297.272264)
			(xy 194.723372 -297.2859) (xy 194.772992 -297.306987) (xy 194.819013 -297.335073) (xy 194.860455 -297.369561)
			(xy 194.896433 -297.409715) (xy 194.926181 -297.454679) (xy 194.949066 -297.503496) (xy 194.964598 -297.555125)
			(xy 194.972448 -297.608465) (xy 194.97294 -297.635422) (xy 201.778631 -297.635422) (xy 201.782566 -297.581651)
			(xy 201.794289 -297.529027) (xy 201.813549 -297.47867) (xy 201.839935 -297.431653) (xy 201.872887 -297.38898)
			(xy 201.9117 -297.351559) (xy 201.955548 -297.320189) (xy 202.003496 -297.295537) (xy 202.054523 -297.278129)
			(xy 202.107541 -297.268336) (xy 202.16142 -297.266367) (xy 202.215011 -297.272264) (xy 202.267172 -297.2859)
			(xy 202.316792 -297.306987) (xy 202.362813 -297.335073) (xy 202.404255 -297.369561) (xy 202.440233 -297.409715)
			(xy 202.469981 -297.454679) (xy 202.492866 -297.503496) (xy 202.508398 -297.555125) (xy 202.516248 -297.608465)
			(xy 202.51674 -297.635422) (xy 202.516248 -297.662379) (xy 202.508398 -297.715719) (xy 202.492866 -297.767348)
			(xy 202.469981 -297.816165) (xy 202.440233 -297.861129) (xy 202.404255 -297.901283) (xy 202.362813 -297.935771)
			(xy 202.316792 -297.963857) (xy 202.267172 -297.984944) (xy 202.215011 -297.99858) (xy 202.16142 -298.004477)
			(xy 202.107541 -298.002508) (xy 202.054523 -297.992715) (xy 202.003496 -297.975307) (xy 201.955548 -297.950655)
			(xy 201.9117 -297.919285) (xy 201.872887 -297.881864) (xy 201.839935 -297.839191) (xy 201.813549 -297.792174)
			(xy 201.794289 -297.741817) (xy 201.782566 -297.689193) (xy 201.778631 -297.635422) (xy 194.97294 -297.635422)
			(xy 194.972448 -297.662379) (xy 194.964598 -297.715719) (xy 194.949066 -297.767348) (xy 194.926181 -297.816165)
			(xy 194.896433 -297.861129) (xy 194.860455 -297.901283) (xy 194.819013 -297.935771) (xy 194.772992 -297.963857)
			(xy 194.723372 -297.984944) (xy 194.671211 -297.99858) (xy 194.61762 -298.004477) (xy 194.563741 -298.002508)
			(xy 194.510723 -297.992715) (xy 194.459696 -297.975307) (xy 194.411748 -297.950655) (xy 194.3679 -297.919285)
			(xy 194.329087 -297.881864) (xy 194.296135 -297.839191) (xy 194.269749 -297.792174) (xy 194.250489 -297.741817)
			(xy 194.238766 -297.689193) (xy 194.234831 -297.635422) (xy 187.428886 -297.635422) (xy 187.428394 -297.662379)
			(xy 187.420544 -297.715719) (xy 187.405012 -297.767348) (xy 187.382127 -297.816165) (xy 187.352379 -297.861129)
			(xy 187.316401 -297.901283) (xy 187.274959 -297.935771) (xy 187.228938 -297.963857) (xy 187.179318 -297.984944)
			(xy 187.127157 -297.99858) (xy 187.073566 -298.004477) (xy 187.019687 -298.002508) (xy 186.966669 -297.992715)
			(xy 186.915642 -297.975307) (xy 186.867694 -297.950655) (xy 186.823846 -297.919285) (xy 186.785033 -297.881864)
			(xy 186.752081 -297.839191) (xy 186.725695 -297.792174) (xy 186.706435 -297.741817) (xy 186.694712 -297.689193)
			(xy 186.690777 -297.635422) (xy 179.884832 -297.635422) (xy 179.88434 -297.662379) (xy 179.87649 -297.715719)
			(xy 179.860958 -297.767348) (xy 179.838073 -297.816165) (xy 179.808325 -297.861129) (xy 179.772347 -297.901283)
			(xy 179.730905 -297.935771) (xy 179.684884 -297.963857) (xy 179.635264 -297.984944) (xy 179.583103 -297.99858)
			(xy 179.529512 -298.004477) (xy 179.475633 -298.002508) (xy 179.422615 -297.992715) (xy 179.371588 -297.975307)
			(xy 179.32364 -297.950655) (xy 179.279792 -297.919285) (xy 179.240979 -297.881864) (xy 179.208027 -297.839191)
			(xy 179.181641 -297.792174) (xy 179.162381 -297.741817) (xy 179.150658 -297.689193) (xy 179.146723 -297.635422)
			(xy 177.881534 -297.635422) (xy 177.881534 -298.485306) (xy 183.246791 -298.485306) (xy 183.250726 -298.431535)
			(xy 183.262449 -298.378911) (xy 183.281709 -298.328554) (xy 183.308095 -298.281537) (xy 183.341047 -298.238864)
			(xy 183.37986 -298.201443) (xy 183.423708 -298.170073) (xy 183.471656 -298.145421) (xy 183.522683 -298.128013)
			(xy 183.575701 -298.11822) (xy 183.62958 -298.116251) (xy 183.683171 -298.122148) (xy 183.735332 -298.135784)
			(xy 183.784952 -298.156871) (xy 183.830973 -298.184957) (xy 183.872415 -298.219445) (xy 183.908393 -298.259599)
			(xy 183.938141 -298.304563) (xy 183.961026 -298.35338) (xy 183.976558 -298.405009) (xy 183.984408 -298.458349)
			(xy 183.9849 -298.485306) (xy 190.790845 -298.485306) (xy 190.79478 -298.431535) (xy 190.806503 -298.378911)
			(xy 190.825763 -298.328554) (xy 190.852149 -298.281537) (xy 190.885101 -298.238864) (xy 190.923914 -298.201443)
			(xy 190.967762 -298.170073) (xy 191.01571 -298.145421) (xy 191.066737 -298.128013) (xy 191.119755 -298.11822)
			(xy 191.173634 -298.116251) (xy 191.227225 -298.122148) (xy 191.279386 -298.135784) (xy 191.329006 -298.156871)
			(xy 191.375027 -298.184957) (xy 191.416469 -298.219445) (xy 191.452447 -298.259599) (xy 191.482195 -298.304563)
			(xy 191.50508 -298.35338) (xy 191.520612 -298.405009) (xy 191.528462 -298.458349) (xy 191.528954 -298.485306)
			(xy 198.334899 -298.485306) (xy 198.338834 -298.431535) (xy 198.350557 -298.378911) (xy 198.369817 -298.328554)
			(xy 198.396203 -298.281537) (xy 198.429155 -298.238864) (xy 198.467968 -298.201443) (xy 198.511816 -298.170073)
			(xy 198.559764 -298.145421) (xy 198.610791 -298.128013) (xy 198.663809 -298.11822) (xy 198.717688 -298.116251)
			(xy 198.771279 -298.122148) (xy 198.82344 -298.135784) (xy 198.87306 -298.156871) (xy 198.919081 -298.184957)
			(xy 198.960523 -298.219445) (xy 198.996501 -298.259599) (xy 199.026249 -298.304563) (xy 199.049134 -298.35338)
			(xy 199.064666 -298.405009) (xy 199.072516 -298.458349) (xy 199.073008 -298.485306) (xy 205.878699 -298.485306)
			(xy 205.882634 -298.431535) (xy 205.894357 -298.378911) (xy 205.913617 -298.328554) (xy 205.940003 -298.281537)
			(xy 205.972955 -298.238864) (xy 206.011768 -298.201443) (xy 206.055616 -298.170073) (xy 206.103564 -298.145421)
			(xy 206.154591 -298.128013) (xy 206.207609 -298.11822) (xy 206.261488 -298.116251) (xy 206.315079 -298.122148)
			(xy 206.36724 -298.135784) (xy 206.41686 -298.156871) (xy 206.462881 -298.184957) (xy 206.504323 -298.219445)
			(xy 206.540301 -298.259599) (xy 206.570049 -298.304563) (xy 206.592934 -298.35338) (xy 206.608466 -298.405009)
			(xy 206.616316 -298.458349) (xy 206.616808 -298.485306) (xy 206.616316 -298.512263) (xy 206.608466 -298.565603)
			(xy 206.592934 -298.617232) (xy 206.570049 -298.666049) (xy 206.540301 -298.711013) (xy 206.504323 -298.751167)
			(xy 206.462881 -298.785655) (xy 206.41686 -298.813741) (xy 206.36724 -298.834828) (xy 206.315079 -298.848464)
			(xy 206.261488 -298.854361) (xy 206.207609 -298.852392) (xy 206.154591 -298.842599) (xy 206.103564 -298.825191)
			(xy 206.055616 -298.800539) (xy 206.011768 -298.769169) (xy 205.972955 -298.731748) (xy 205.940003 -298.689075)
			(xy 205.913617 -298.642058) (xy 205.894357 -298.591701) (xy 205.882634 -298.539077) (xy 205.878699 -298.485306)
			(xy 199.073008 -298.485306) (xy 199.072516 -298.512263) (xy 199.064666 -298.565603) (xy 199.049134 -298.617232)
			(xy 199.026249 -298.666049) (xy 198.996501 -298.711013) (xy 198.960523 -298.751167) (xy 198.919081 -298.785655)
			(xy 198.87306 -298.813741) (xy 198.82344 -298.834828) (xy 198.771279 -298.848464) (xy 198.717688 -298.854361)
			(xy 198.663809 -298.852392) (xy 198.610791 -298.842599) (xy 198.559764 -298.825191) (xy 198.511816 -298.800539)
			(xy 198.467968 -298.769169) (xy 198.429155 -298.731748) (xy 198.396203 -298.689075) (xy 198.369817 -298.642058)
			(xy 198.350557 -298.591701) (xy 198.338834 -298.539077) (xy 198.334899 -298.485306) (xy 191.528954 -298.485306)
			(xy 191.528462 -298.512263) (xy 191.520612 -298.565603) (xy 191.50508 -298.617232) (xy 191.482195 -298.666049)
			(xy 191.452447 -298.711013) (xy 191.416469 -298.751167) (xy 191.375027 -298.785655) (xy 191.329006 -298.813741)
			(xy 191.279386 -298.834828) (xy 191.227225 -298.848464) (xy 191.173634 -298.854361) (xy 191.119755 -298.852392)
			(xy 191.066737 -298.842599) (xy 191.01571 -298.825191) (xy 190.967762 -298.800539) (xy 190.923914 -298.769169)
			(xy 190.885101 -298.731748) (xy 190.852149 -298.689075) (xy 190.825763 -298.642058) (xy 190.806503 -298.591701)
			(xy 190.79478 -298.539077) (xy 190.790845 -298.485306) (xy 183.9849 -298.485306) (xy 183.984408 -298.512263)
			(xy 183.976558 -298.565603) (xy 183.961026 -298.617232) (xy 183.938141 -298.666049) (xy 183.908393 -298.711013)
			(xy 183.872415 -298.751167) (xy 183.830973 -298.785655) (xy 183.784952 -298.813741) (xy 183.735332 -298.834828)
			(xy 183.683171 -298.848464) (xy 183.62958 -298.854361) (xy 183.575701 -298.852392) (xy 183.522683 -298.842599)
			(xy 183.471656 -298.825191) (xy 183.423708 -298.800539) (xy 183.37986 -298.769169) (xy 183.341047 -298.731748)
			(xy 183.308095 -298.689075) (xy 183.281709 -298.642058) (xy 183.262449 -298.591701) (xy 183.250726 -298.539077)
			(xy 183.246791 -298.485306) (xy 177.881534 -298.485306) (xy 177.881534 -299.335444) (xy 179.146723 -299.335444)
			(xy 179.150658 -299.281673) (xy 179.162381 -299.229049) (xy 179.181641 -299.178692) (xy 179.208027 -299.131675)
			(xy 179.240979 -299.089002) (xy 179.279792 -299.051581) (xy 179.32364 -299.020211) (xy 179.371588 -298.995559)
			(xy 179.422615 -298.978151) (xy 179.475633 -298.968358) (xy 179.529512 -298.966389) (xy 179.583103 -298.972286)
			(xy 179.635264 -298.985922) (xy 179.684884 -299.007009) (xy 179.730905 -299.035095) (xy 179.772347 -299.069583)
			(xy 179.808325 -299.109737) (xy 179.838073 -299.154701) (xy 179.860958 -299.203518) (xy 179.87649 -299.255147)
			(xy 179.88434 -299.308487) (xy 179.884832 -299.335444) (xy 186.690777 -299.335444) (xy 186.694712 -299.281673)
			(xy 186.706435 -299.229049) (xy 186.725695 -299.178692) (xy 186.752081 -299.131675) (xy 186.785033 -299.089002)
			(xy 186.823846 -299.051581) (xy 186.867694 -299.020211) (xy 186.915642 -298.995559) (xy 186.966669 -298.978151)
			(xy 187.019687 -298.968358) (xy 187.073566 -298.966389) (xy 187.127157 -298.972286) (xy 187.179318 -298.985922)
			(xy 187.228938 -299.007009) (xy 187.274959 -299.035095) (xy 187.316401 -299.069583) (xy 187.352379 -299.109737)
			(xy 187.382127 -299.154701) (xy 187.405012 -299.203518) (xy 187.420544 -299.255147) (xy 187.428394 -299.308487)
			(xy 187.428886 -299.335444) (xy 194.234831 -299.335444) (xy 194.238766 -299.281673) (xy 194.250489 -299.229049)
			(xy 194.269749 -299.178692) (xy 194.296135 -299.131675) (xy 194.329087 -299.089002) (xy 194.3679 -299.051581)
			(xy 194.411748 -299.020211) (xy 194.459696 -298.995559) (xy 194.510723 -298.978151) (xy 194.563741 -298.968358)
			(xy 194.61762 -298.966389) (xy 194.671211 -298.972286) (xy 194.723372 -298.985922) (xy 194.772992 -299.007009)
			(xy 194.819013 -299.035095) (xy 194.860455 -299.069583) (xy 194.896433 -299.109737) (xy 194.926181 -299.154701)
			(xy 194.949066 -299.203518) (xy 194.964598 -299.255147) (xy 194.972448 -299.308487) (xy 194.97294 -299.335444)
			(xy 201.778631 -299.335444) (xy 201.782566 -299.281673) (xy 201.794289 -299.229049) (xy 201.813549 -299.178692)
			(xy 201.839935 -299.131675) (xy 201.872887 -299.089002) (xy 201.9117 -299.051581) (xy 201.955548 -299.020211)
			(xy 202.003496 -298.995559) (xy 202.054523 -298.978151) (xy 202.107541 -298.968358) (xy 202.16142 -298.966389)
			(xy 202.215011 -298.972286) (xy 202.267172 -298.985922) (xy 202.316792 -299.007009) (xy 202.362813 -299.035095)
			(xy 202.404255 -299.069583) (xy 202.440233 -299.109737) (xy 202.469981 -299.154701) (xy 202.492866 -299.203518)
			(xy 202.508398 -299.255147) (xy 202.516248 -299.308487) (xy 202.51674 -299.335444) (xy 202.516248 -299.362401)
			(xy 202.508398 -299.415741) (xy 202.492866 -299.46737) (xy 202.469981 -299.516187) (xy 202.440233 -299.561151)
			(xy 202.404255 -299.601305) (xy 202.362813 -299.635793) (xy 202.316792 -299.663879) (xy 202.267172 -299.684966)
			(xy 202.215011 -299.698602) (xy 202.16142 -299.704499) (xy 202.107541 -299.70253) (xy 202.054523 -299.692737)
			(xy 202.003496 -299.675329) (xy 201.955548 -299.650677) (xy 201.9117 -299.619307) (xy 201.872887 -299.581886)
			(xy 201.839935 -299.539213) (xy 201.813549 -299.492196) (xy 201.794289 -299.441839) (xy 201.782566 -299.389215)
			(xy 201.778631 -299.335444) (xy 194.97294 -299.335444) (xy 194.972448 -299.362401) (xy 194.964598 -299.415741)
			(xy 194.949066 -299.46737) (xy 194.926181 -299.516187) (xy 194.896433 -299.561151) (xy 194.860455 -299.601305)
			(xy 194.819013 -299.635793) (xy 194.772992 -299.663879) (xy 194.723372 -299.684966) (xy 194.671211 -299.698602)
			(xy 194.61762 -299.704499) (xy 194.563741 -299.70253) (xy 194.510723 -299.692737) (xy 194.459696 -299.675329)
			(xy 194.411748 -299.650677) (xy 194.3679 -299.619307) (xy 194.329087 -299.581886) (xy 194.296135 -299.539213)
			(xy 194.269749 -299.492196) (xy 194.250489 -299.441839) (xy 194.238766 -299.389215) (xy 194.234831 -299.335444)
			(xy 187.428886 -299.335444) (xy 187.428394 -299.362401) (xy 187.420544 -299.415741) (xy 187.405012 -299.46737)
			(xy 187.382127 -299.516187) (xy 187.352379 -299.561151) (xy 187.316401 -299.601305) (xy 187.274959 -299.635793)
			(xy 187.228938 -299.663879) (xy 187.179318 -299.684966) (xy 187.127157 -299.698602) (xy 187.073566 -299.704499)
			(xy 187.019687 -299.70253) (xy 186.966669 -299.692737) (xy 186.915642 -299.675329) (xy 186.867694 -299.650677)
			(xy 186.823846 -299.619307) (xy 186.785033 -299.581886) (xy 186.752081 -299.539213) (xy 186.725695 -299.492196)
			(xy 186.706435 -299.441839) (xy 186.694712 -299.389215) (xy 186.690777 -299.335444) (xy 179.884832 -299.335444)
			(xy 179.88434 -299.362401) (xy 179.87649 -299.415741) (xy 179.860958 -299.46737) (xy 179.838073 -299.516187)
			(xy 179.808325 -299.561151) (xy 179.772347 -299.601305) (xy 179.730905 -299.635793) (xy 179.684884 -299.663879)
			(xy 179.635264 -299.684966) (xy 179.583103 -299.698602) (xy 179.529512 -299.704499) (xy 179.475633 -299.70253)
			(xy 179.422615 -299.692737) (xy 179.371588 -299.675329) (xy 179.32364 -299.650677) (xy 179.279792 -299.619307)
			(xy 179.240979 -299.581886) (xy 179.208027 -299.539213) (xy 179.181641 -299.492196) (xy 179.162381 -299.441839)
			(xy 179.150658 -299.389215) (xy 179.146723 -299.335444) (xy 177.881534 -299.335444) (xy 177.881534 -300.185328)
			(xy 183.246791 -300.185328) (xy 183.250726 -300.131557) (xy 183.262449 -300.078933) (xy 183.281709 -300.028576)
			(xy 183.308095 -299.981559) (xy 183.341047 -299.938886) (xy 183.37986 -299.901465) (xy 183.423708 -299.870095)
			(xy 183.471656 -299.845443) (xy 183.522683 -299.828035) (xy 183.575701 -299.818242) (xy 183.62958 -299.816273)
			(xy 183.683171 -299.82217) (xy 183.735332 -299.835806) (xy 183.784952 -299.856893) (xy 183.830973 -299.884979)
			(xy 183.872415 -299.919467) (xy 183.908393 -299.959621) (xy 183.938141 -300.004585) (xy 183.961026 -300.053402)
			(xy 183.976558 -300.105031) (xy 183.984408 -300.158371) (xy 183.9849 -300.185328) (xy 190.790845 -300.185328)
			(xy 190.79478 -300.131557) (xy 190.806503 -300.078933) (xy 190.825763 -300.028576) (xy 190.852149 -299.981559)
			(xy 190.885101 -299.938886) (xy 190.923914 -299.901465) (xy 190.967762 -299.870095) (xy 191.01571 -299.845443)
			(xy 191.066737 -299.828035) (xy 191.119755 -299.818242) (xy 191.173634 -299.816273) (xy 191.227225 -299.82217)
			(xy 191.279386 -299.835806) (xy 191.329006 -299.856893) (xy 191.375027 -299.884979) (xy 191.416469 -299.919467)
			(xy 191.452447 -299.959621) (xy 191.482195 -300.004585) (xy 191.50508 -300.053402) (xy 191.520612 -300.105031)
			(xy 191.528462 -300.158371) (xy 191.528954 -300.185328) (xy 198.334899 -300.185328) (xy 198.338834 -300.131557)
			(xy 198.350557 -300.078933) (xy 198.369817 -300.028576) (xy 198.396203 -299.981559) (xy 198.429155 -299.938886)
			(xy 198.467968 -299.901465) (xy 198.511816 -299.870095) (xy 198.559764 -299.845443) (xy 198.610791 -299.828035)
			(xy 198.663809 -299.818242) (xy 198.717688 -299.816273) (xy 198.771279 -299.82217) (xy 198.82344 -299.835806)
			(xy 198.87306 -299.856893) (xy 198.919081 -299.884979) (xy 198.960523 -299.919467) (xy 198.996501 -299.959621)
			(xy 199.026249 -300.004585) (xy 199.049134 -300.053402) (xy 199.064666 -300.105031) (xy 199.072516 -300.158371)
			(xy 199.073008 -300.185328) (xy 205.878699 -300.185328) (xy 205.882634 -300.131557) (xy 205.894357 -300.078933)
			(xy 205.913617 -300.028576) (xy 205.940003 -299.981559) (xy 205.972955 -299.938886) (xy 206.011768 -299.901465)
			(xy 206.055616 -299.870095) (xy 206.103564 -299.845443) (xy 206.154591 -299.828035) (xy 206.207609 -299.818242)
			(xy 206.261488 -299.816273) (xy 206.315079 -299.82217) (xy 206.36724 -299.835806) (xy 206.41686 -299.856893)
			(xy 206.462881 -299.884979) (xy 206.504323 -299.919467) (xy 206.540301 -299.959621) (xy 206.570049 -300.004585)
			(xy 206.592934 -300.053402) (xy 206.608466 -300.105031) (xy 206.616316 -300.158371) (xy 206.616808 -300.185328)
			(xy 206.616316 -300.212285) (xy 206.608466 -300.265625) (xy 206.592934 -300.317254) (xy 206.570049 -300.366071)
			(xy 206.540301 -300.411035) (xy 206.504323 -300.451189) (xy 206.462881 -300.485677) (xy 206.41686 -300.513763)
			(xy 206.36724 -300.53485) (xy 206.315079 -300.548486) (xy 206.261488 -300.554383) (xy 206.207609 -300.552414)
			(xy 206.154591 -300.542621) (xy 206.103564 -300.525213) (xy 206.055616 -300.500561) (xy 206.011768 -300.469191)
			(xy 205.972955 -300.43177) (xy 205.940003 -300.389097) (xy 205.913617 -300.34208) (xy 205.894357 -300.291723)
			(xy 205.882634 -300.239099) (xy 205.878699 -300.185328) (xy 199.073008 -300.185328) (xy 199.072516 -300.212285)
			(xy 199.064666 -300.265625) (xy 199.049134 -300.317254) (xy 199.026249 -300.366071) (xy 198.996501 -300.411035)
			(xy 198.960523 -300.451189) (xy 198.919081 -300.485677) (xy 198.87306 -300.513763) (xy 198.82344 -300.53485)
			(xy 198.771279 -300.548486) (xy 198.717688 -300.554383) (xy 198.663809 -300.552414) (xy 198.610791 -300.542621)
			(xy 198.559764 -300.525213) (xy 198.511816 -300.500561) (xy 198.467968 -300.469191) (xy 198.429155 -300.43177)
			(xy 198.396203 -300.389097) (xy 198.369817 -300.34208) (xy 198.350557 -300.291723) (xy 198.338834 -300.239099)
			(xy 198.334899 -300.185328) (xy 191.528954 -300.185328) (xy 191.528462 -300.212285) (xy 191.520612 -300.265625)
			(xy 191.50508 -300.317254) (xy 191.482195 -300.366071) (xy 191.452447 -300.411035) (xy 191.416469 -300.451189)
			(xy 191.375027 -300.485677) (xy 191.329006 -300.513763) (xy 191.279386 -300.53485) (xy 191.227225 -300.548486)
			(xy 191.173634 -300.554383) (xy 191.119755 -300.552414) (xy 191.066737 -300.542621) (xy 191.01571 -300.525213)
			(xy 190.967762 -300.500561) (xy 190.923914 -300.469191) (xy 190.885101 -300.43177) (xy 190.852149 -300.389097)
			(xy 190.825763 -300.34208) (xy 190.806503 -300.291723) (xy 190.79478 -300.239099) (xy 190.790845 -300.185328)
			(xy 183.9849 -300.185328) (xy 183.984408 -300.212285) (xy 183.976558 -300.265625) (xy 183.961026 -300.317254)
			(xy 183.938141 -300.366071) (xy 183.908393 -300.411035) (xy 183.872415 -300.451189) (xy 183.830973 -300.485677)
			(xy 183.784952 -300.513763) (xy 183.735332 -300.53485) (xy 183.683171 -300.548486) (xy 183.62958 -300.554383)
			(xy 183.575701 -300.552414) (xy 183.522683 -300.542621) (xy 183.471656 -300.525213) (xy 183.423708 -300.500561)
			(xy 183.37986 -300.469191) (xy 183.341047 -300.43177) (xy 183.308095 -300.389097) (xy 183.281709 -300.34208)
			(xy 183.262449 -300.291723) (xy 183.250726 -300.239099) (xy 183.246791 -300.185328) (xy 177.881534 -300.185328)
			(xy 177.881534 -301.035212) (xy 179.146723 -301.035212) (xy 179.150658 -300.981441) (xy 179.162381 -300.928817)
			(xy 179.181641 -300.87846) (xy 179.208027 -300.831443) (xy 179.240979 -300.78877) (xy 179.279792 -300.751349)
			(xy 179.32364 -300.719979) (xy 179.371588 -300.695327) (xy 179.422615 -300.677919) (xy 179.475633 -300.668126)
			(xy 179.529512 -300.666157) (xy 179.583103 -300.672054) (xy 179.635264 -300.68569) (xy 179.684884 -300.706777)
			(xy 179.730905 -300.734863) (xy 179.772347 -300.769351) (xy 179.808325 -300.809505) (xy 179.838073 -300.854469)
			(xy 179.860958 -300.903286) (xy 179.87649 -300.954915) (xy 179.88434 -301.008255) (xy 179.884832 -301.035212)
			(xy 186.690777 -301.035212) (xy 186.694712 -300.981441) (xy 186.706435 -300.928817) (xy 186.725695 -300.87846)
			(xy 186.752081 -300.831443) (xy 186.785033 -300.78877) (xy 186.823846 -300.751349) (xy 186.867694 -300.719979)
			(xy 186.915642 -300.695327) (xy 186.966669 -300.677919) (xy 187.019687 -300.668126) (xy 187.073566 -300.666157)
			(xy 187.127157 -300.672054) (xy 187.179318 -300.68569) (xy 187.228938 -300.706777) (xy 187.274959 -300.734863)
			(xy 187.316401 -300.769351) (xy 187.352379 -300.809505) (xy 187.382127 -300.854469) (xy 187.405012 -300.903286)
			(xy 187.420544 -300.954915) (xy 187.428394 -301.008255) (xy 187.428886 -301.035212) (xy 194.234831 -301.035212)
			(xy 194.238766 -300.981441) (xy 194.250489 -300.928817) (xy 194.269749 -300.87846) (xy 194.296135 -300.831443)
			(xy 194.329087 -300.78877) (xy 194.3679 -300.751349) (xy 194.411748 -300.719979) (xy 194.459696 -300.695327)
			(xy 194.510723 -300.677919) (xy 194.563741 -300.668126) (xy 194.61762 -300.666157) (xy 194.671211 -300.672054)
			(xy 194.723372 -300.68569) (xy 194.772992 -300.706777) (xy 194.819013 -300.734863) (xy 194.860455 -300.769351)
			(xy 194.896433 -300.809505) (xy 194.926181 -300.854469) (xy 194.949066 -300.903286) (xy 194.964598 -300.954915)
			(xy 194.972448 -301.008255) (xy 194.97294 -301.035212) (xy 201.778631 -301.035212) (xy 201.782566 -300.981441)
			(xy 201.794289 -300.928817) (xy 201.813549 -300.87846) (xy 201.839935 -300.831443) (xy 201.872887 -300.78877)
			(xy 201.9117 -300.751349) (xy 201.955548 -300.719979) (xy 202.003496 -300.695327) (xy 202.054523 -300.677919)
			(xy 202.107541 -300.668126) (xy 202.16142 -300.666157) (xy 202.215011 -300.672054) (xy 202.267172 -300.68569)
			(xy 202.316792 -300.706777) (xy 202.362813 -300.734863) (xy 202.404255 -300.769351) (xy 202.440233 -300.809505)
			(xy 202.469981 -300.854469) (xy 202.492866 -300.903286) (xy 202.508398 -300.954915) (xy 202.516248 -301.008255)
			(xy 202.51674 -301.035212) (xy 202.516248 -301.062169) (xy 202.508398 -301.115509) (xy 202.492866 -301.167138)
			(xy 202.469981 -301.215955) (xy 202.440233 -301.260919) (xy 202.404255 -301.301073) (xy 202.362813 -301.335561)
			(xy 202.316792 -301.363647) (xy 202.267172 -301.384734) (xy 202.215011 -301.39837) (xy 202.16142 -301.404267)
			(xy 202.107541 -301.402298) (xy 202.054523 -301.392505) (xy 202.003496 -301.375097) (xy 201.955548 -301.350445)
			(xy 201.9117 -301.319075) (xy 201.872887 -301.281654) (xy 201.839935 -301.238981) (xy 201.813549 -301.191964)
			(xy 201.794289 -301.141607) (xy 201.782566 -301.088983) (xy 201.778631 -301.035212) (xy 194.97294 -301.035212)
			(xy 194.972448 -301.062169) (xy 194.964598 -301.115509) (xy 194.949066 -301.167138) (xy 194.926181 -301.215955)
			(xy 194.896433 -301.260919) (xy 194.860455 -301.301073) (xy 194.819013 -301.335561) (xy 194.772992 -301.363647)
			(xy 194.723372 -301.384734) (xy 194.671211 -301.39837) (xy 194.61762 -301.404267) (xy 194.563741 -301.402298)
			(xy 194.510723 -301.392505) (xy 194.459696 -301.375097) (xy 194.411748 -301.350445) (xy 194.3679 -301.319075)
			(xy 194.329087 -301.281654) (xy 194.296135 -301.238981) (xy 194.269749 -301.191964) (xy 194.250489 -301.141607)
			(xy 194.238766 -301.088983) (xy 194.234831 -301.035212) (xy 187.428886 -301.035212) (xy 187.428394 -301.062169)
			(xy 187.420544 -301.115509) (xy 187.405012 -301.167138) (xy 187.382127 -301.215955) (xy 187.352379 -301.260919)
			(xy 187.316401 -301.301073) (xy 187.274959 -301.335561) (xy 187.228938 -301.363647) (xy 187.179318 -301.384734)
			(xy 187.127157 -301.39837) (xy 187.073566 -301.404267) (xy 187.019687 -301.402298) (xy 186.966669 -301.392505)
			(xy 186.915642 -301.375097) (xy 186.867694 -301.350445) (xy 186.823846 -301.319075) (xy 186.785033 -301.281654)
			(xy 186.752081 -301.238981) (xy 186.725695 -301.191964) (xy 186.706435 -301.141607) (xy 186.694712 -301.088983)
			(xy 186.690777 -301.035212) (xy 179.884832 -301.035212) (xy 179.88434 -301.062169) (xy 179.87649 -301.115509)
			(xy 179.860958 -301.167138) (xy 179.838073 -301.215955) (xy 179.808325 -301.260919) (xy 179.772347 -301.301073)
			(xy 179.730905 -301.335561) (xy 179.684884 -301.363647) (xy 179.635264 -301.384734) (xy 179.583103 -301.39837)
			(xy 179.529512 -301.404267) (xy 179.475633 -301.402298) (xy 179.422615 -301.392505) (xy 179.371588 -301.375097)
			(xy 179.32364 -301.350445) (xy 179.279792 -301.319075) (xy 179.240979 -301.281654) (xy 179.208027 -301.238981)
			(xy 179.181641 -301.191964) (xy 179.162381 -301.141607) (xy 179.150658 -301.088983) (xy 179.146723 -301.035212)
			(xy 177.881534 -301.035212) (xy 177.881534 -301.88535) (xy 183.246791 -301.88535) (xy 183.250726 -301.831579)
			(xy 183.262449 -301.778955) (xy 183.281709 -301.728598) (xy 183.308095 -301.681581) (xy 183.341047 -301.638908)
			(xy 183.37986 -301.601487) (xy 183.423708 -301.570117) (xy 183.471656 -301.545465) (xy 183.522683 -301.528057)
			(xy 183.575701 -301.518264) (xy 183.62958 -301.516295) (xy 183.683171 -301.522192) (xy 183.735332 -301.535828)
			(xy 183.784952 -301.556915) (xy 183.830973 -301.585001) (xy 183.872415 -301.619489) (xy 183.908393 -301.659643)
			(xy 183.938141 -301.704607) (xy 183.961026 -301.753424) (xy 183.976558 -301.805053) (xy 183.984408 -301.858393)
			(xy 183.9849 -301.88535) (xy 190.790845 -301.88535) (xy 190.79478 -301.831579) (xy 190.806503 -301.778955)
			(xy 190.825763 -301.728598) (xy 190.852149 -301.681581) (xy 190.885101 -301.638908) (xy 190.923914 -301.601487)
			(xy 190.967762 -301.570117) (xy 191.01571 -301.545465) (xy 191.066737 -301.528057) (xy 191.119755 -301.518264)
			(xy 191.173634 -301.516295) (xy 191.227225 -301.522192) (xy 191.279386 -301.535828) (xy 191.329006 -301.556915)
			(xy 191.375027 -301.585001) (xy 191.416469 -301.619489) (xy 191.452447 -301.659643) (xy 191.482195 -301.704607)
			(xy 191.50508 -301.753424) (xy 191.520612 -301.805053) (xy 191.528462 -301.858393) (xy 191.528954 -301.88535)
			(xy 198.334899 -301.88535) (xy 198.338834 -301.831579) (xy 198.350557 -301.778955) (xy 198.369817 -301.728598)
			(xy 198.396203 -301.681581) (xy 198.429155 -301.638908) (xy 198.467968 -301.601487) (xy 198.511816 -301.570117)
			(xy 198.559764 -301.545465) (xy 198.610791 -301.528057) (xy 198.663809 -301.518264) (xy 198.717688 -301.516295)
			(xy 198.771279 -301.522192) (xy 198.82344 -301.535828) (xy 198.87306 -301.556915) (xy 198.919081 -301.585001)
			(xy 198.960523 -301.619489) (xy 198.996501 -301.659643) (xy 199.026249 -301.704607) (xy 199.049134 -301.753424)
			(xy 199.064666 -301.805053) (xy 199.072516 -301.858393) (xy 199.073008 -301.88535) (xy 205.878699 -301.88535)
			(xy 205.882634 -301.831579) (xy 205.894357 -301.778955) (xy 205.913617 -301.728598) (xy 205.940003 -301.681581)
			(xy 205.972955 -301.638908) (xy 206.011768 -301.601487) (xy 206.055616 -301.570117) (xy 206.103564 -301.545465)
			(xy 206.154591 -301.528057) (xy 206.207609 -301.518264) (xy 206.261488 -301.516295) (xy 206.315079 -301.522192)
			(xy 206.36724 -301.535828) (xy 206.41686 -301.556915) (xy 206.462881 -301.585001) (xy 206.504323 -301.619489)
			(xy 206.540301 -301.659643) (xy 206.570049 -301.704607) (xy 206.592934 -301.753424) (xy 206.608466 -301.805053)
			(xy 206.616316 -301.858393) (xy 206.616808 -301.88535) (xy 206.616316 -301.912307) (xy 206.608466 -301.965647)
			(xy 206.592934 -302.017276) (xy 206.570049 -302.066093) (xy 206.540301 -302.111057) (xy 206.504323 -302.151211)
			(xy 206.462881 -302.185699) (xy 206.41686 -302.213785) (xy 206.36724 -302.234872) (xy 206.315079 -302.248508)
			(xy 206.261488 -302.254405) (xy 206.207609 -302.252436) (xy 206.154591 -302.242643) (xy 206.103564 -302.225235)
			(xy 206.055616 -302.200583) (xy 206.011768 -302.169213) (xy 205.972955 -302.131792) (xy 205.940003 -302.089119)
			(xy 205.913617 -302.042102) (xy 205.894357 -301.991745) (xy 205.882634 -301.939121) (xy 205.878699 -301.88535)
			(xy 199.073008 -301.88535) (xy 199.072516 -301.912307) (xy 199.064666 -301.965647) (xy 199.049134 -302.017276)
			(xy 199.026249 -302.066093) (xy 198.996501 -302.111057) (xy 198.960523 -302.151211) (xy 198.919081 -302.185699)
			(xy 198.87306 -302.213785) (xy 198.82344 -302.234872) (xy 198.771279 -302.248508) (xy 198.717688 -302.254405)
			(xy 198.663809 -302.252436) (xy 198.610791 -302.242643) (xy 198.559764 -302.225235) (xy 198.511816 -302.200583)
			(xy 198.467968 -302.169213) (xy 198.429155 -302.131792) (xy 198.396203 -302.089119) (xy 198.369817 -302.042102)
			(xy 198.350557 -301.991745) (xy 198.338834 -301.939121) (xy 198.334899 -301.88535) (xy 191.528954 -301.88535)
			(xy 191.528462 -301.912307) (xy 191.520612 -301.965647) (xy 191.50508 -302.017276) (xy 191.482195 -302.066093)
			(xy 191.452447 -302.111057) (xy 191.416469 -302.151211) (xy 191.375027 -302.185699) (xy 191.329006 -302.213785)
			(xy 191.279386 -302.234872) (xy 191.227225 -302.248508) (xy 191.173634 -302.254405) (xy 191.119755 -302.252436)
			(xy 191.066737 -302.242643) (xy 191.01571 -302.225235) (xy 190.967762 -302.200583) (xy 190.923914 -302.169213)
			(xy 190.885101 -302.131792) (xy 190.852149 -302.089119) (xy 190.825763 -302.042102) (xy 190.806503 -301.991745)
			(xy 190.79478 -301.939121) (xy 190.790845 -301.88535) (xy 183.9849 -301.88535) (xy 183.984408 -301.912307)
			(xy 183.976558 -301.965647) (xy 183.961026 -302.017276) (xy 183.938141 -302.066093) (xy 183.908393 -302.111057)
			(xy 183.872415 -302.151211) (xy 183.830973 -302.185699) (xy 183.784952 -302.213785) (xy 183.735332 -302.234872)
			(xy 183.683171 -302.248508) (xy 183.62958 -302.254405) (xy 183.575701 -302.252436) (xy 183.522683 -302.242643)
			(xy 183.471656 -302.225235) (xy 183.423708 -302.200583) (xy 183.37986 -302.169213) (xy 183.341047 -302.131792)
			(xy 183.308095 -302.089119) (xy 183.281709 -302.042102) (xy 183.262449 -301.991745) (xy 183.250726 -301.939121)
			(xy 183.246791 -301.88535) (xy 177.881534 -301.88535) (xy 177.881534 -302.735234) (xy 179.146723 -302.735234)
			(xy 179.150658 -302.681463) (xy 179.162381 -302.628839) (xy 179.181641 -302.578482) (xy 179.208027 -302.531465)
			(xy 179.240979 -302.488792) (xy 179.279792 -302.451371) (xy 179.32364 -302.420001) (xy 179.371588 -302.395349)
			(xy 179.422615 -302.377941) (xy 179.475633 -302.368148) (xy 179.529512 -302.366179) (xy 179.583103 -302.372076)
			(xy 179.635264 -302.385712) (xy 179.684884 -302.406799) (xy 179.730905 -302.434885) (xy 179.772347 -302.469373)
			(xy 179.808325 -302.509527) (xy 179.838073 -302.554491) (xy 179.860958 -302.603308) (xy 179.87649 -302.654937)
			(xy 179.88434 -302.708277) (xy 179.884832 -302.735234) (xy 186.690777 -302.735234) (xy 186.694712 -302.681463)
			(xy 186.706435 -302.628839) (xy 186.725695 -302.578482) (xy 186.752081 -302.531465) (xy 186.785033 -302.488792)
			(xy 186.823846 -302.451371) (xy 186.867694 -302.420001) (xy 186.915642 -302.395349) (xy 186.966669 -302.377941)
			(xy 187.019687 -302.368148) (xy 187.073566 -302.366179) (xy 187.127157 -302.372076) (xy 187.179318 -302.385712)
			(xy 187.228938 -302.406799) (xy 187.274959 -302.434885) (xy 187.316401 -302.469373) (xy 187.352379 -302.509527)
			(xy 187.382127 -302.554491) (xy 187.405012 -302.603308) (xy 187.420544 -302.654937) (xy 187.428394 -302.708277)
			(xy 187.428886 -302.735234) (xy 194.234831 -302.735234) (xy 194.238766 -302.681463) (xy 194.250489 -302.628839)
			(xy 194.269749 -302.578482) (xy 194.296135 -302.531465) (xy 194.329087 -302.488792) (xy 194.3679 -302.451371)
			(xy 194.411748 -302.420001) (xy 194.459696 -302.395349) (xy 194.510723 -302.377941) (xy 194.563741 -302.368148)
			(xy 194.61762 -302.366179) (xy 194.671211 -302.372076) (xy 194.723372 -302.385712) (xy 194.772992 -302.406799)
			(xy 194.819013 -302.434885) (xy 194.860455 -302.469373) (xy 194.896433 -302.509527) (xy 194.926181 -302.554491)
			(xy 194.949066 -302.603308) (xy 194.964598 -302.654937) (xy 194.972448 -302.708277) (xy 194.97294 -302.735234)
			(xy 201.778631 -302.735234) (xy 201.782566 -302.681463) (xy 201.794289 -302.628839) (xy 201.813549 -302.578482)
			(xy 201.839935 -302.531465) (xy 201.872887 -302.488792) (xy 201.9117 -302.451371) (xy 201.955548 -302.420001)
			(xy 202.003496 -302.395349) (xy 202.054523 -302.377941) (xy 202.107541 -302.368148) (xy 202.16142 -302.366179)
			(xy 202.215011 -302.372076) (xy 202.267172 -302.385712) (xy 202.316792 -302.406799) (xy 202.362813 -302.434885)
			(xy 202.404255 -302.469373) (xy 202.440233 -302.509527) (xy 202.469981 -302.554491) (xy 202.492866 -302.603308)
			(xy 202.508398 -302.654937) (xy 202.516248 -302.708277) (xy 202.51674 -302.735234) (xy 202.516248 -302.762191)
			(xy 202.508398 -302.815531) (xy 202.492866 -302.86716) (xy 202.469981 -302.915977) (xy 202.440233 -302.960941)
			(xy 202.404255 -303.001095) (xy 202.362813 -303.035583) (xy 202.316792 -303.063669) (xy 202.267172 -303.084756)
			(xy 202.215011 -303.098392) (xy 202.16142 -303.104289) (xy 202.107541 -303.10232) (xy 202.054523 -303.092527)
			(xy 202.003496 -303.075119) (xy 201.955548 -303.050467) (xy 201.9117 -303.019097) (xy 201.872887 -302.981676)
			(xy 201.839935 -302.939003) (xy 201.813549 -302.891986) (xy 201.794289 -302.841629) (xy 201.782566 -302.789005)
			(xy 201.778631 -302.735234) (xy 194.97294 -302.735234) (xy 194.972448 -302.762191) (xy 194.964598 -302.815531)
			(xy 194.949066 -302.86716) (xy 194.926181 -302.915977) (xy 194.896433 -302.960941) (xy 194.860455 -303.001095)
			(xy 194.819013 -303.035583) (xy 194.772992 -303.063669) (xy 194.723372 -303.084756) (xy 194.671211 -303.098392)
			(xy 194.61762 -303.104289) (xy 194.563741 -303.10232) (xy 194.510723 -303.092527) (xy 194.459696 -303.075119)
			(xy 194.411748 -303.050467) (xy 194.3679 -303.019097) (xy 194.329087 -302.981676) (xy 194.296135 -302.939003)
			(xy 194.269749 -302.891986) (xy 194.250489 -302.841629) (xy 194.238766 -302.789005) (xy 194.234831 -302.735234)
			(xy 187.428886 -302.735234) (xy 187.428394 -302.762191) (xy 187.420544 -302.815531) (xy 187.405012 -302.86716)
			(xy 187.382127 -302.915977) (xy 187.352379 -302.960941) (xy 187.316401 -303.001095) (xy 187.274959 -303.035583)
			(xy 187.228938 -303.063669) (xy 187.179318 -303.084756) (xy 187.127157 -303.098392) (xy 187.073566 -303.104289)
			(xy 187.019687 -303.10232) (xy 186.966669 -303.092527) (xy 186.915642 -303.075119) (xy 186.867694 -303.050467)
			(xy 186.823846 -303.019097) (xy 186.785033 -302.981676) (xy 186.752081 -302.939003) (xy 186.725695 -302.891986)
			(xy 186.706435 -302.841629) (xy 186.694712 -302.789005) (xy 186.690777 -302.735234) (xy 179.884832 -302.735234)
			(xy 179.88434 -302.762191) (xy 179.87649 -302.815531) (xy 179.860958 -302.86716) (xy 179.838073 -302.915977)
			(xy 179.808325 -302.960941) (xy 179.772347 -303.001095) (xy 179.730905 -303.035583) (xy 179.684884 -303.063669)
			(xy 179.635264 -303.084756) (xy 179.583103 -303.098392) (xy 179.529512 -303.104289) (xy 179.475633 -303.10232)
			(xy 179.422615 -303.092527) (xy 179.371588 -303.075119) (xy 179.32364 -303.050467) (xy 179.279792 -303.019097)
			(xy 179.240979 -302.981676) (xy 179.208027 -302.939003) (xy 179.181641 -302.891986) (xy 179.162381 -302.841629)
			(xy 179.150658 -302.789005) (xy 179.146723 -302.735234) (xy 177.881534 -302.735234) (xy 177.881534 -303.585372)
			(xy 183.246791 -303.585372) (xy 183.250726 -303.531601) (xy 183.262449 -303.478977) (xy 183.281709 -303.42862)
			(xy 183.308095 -303.381603) (xy 183.341047 -303.33893) (xy 183.37986 -303.301509) (xy 183.423708 -303.270139)
			(xy 183.471656 -303.245487) (xy 183.522683 -303.228079) (xy 183.575701 -303.218286) (xy 183.62958 -303.216317)
			(xy 183.683171 -303.222214) (xy 183.735332 -303.23585) (xy 183.784952 -303.256937) (xy 183.830973 -303.285023)
			(xy 183.872415 -303.319511) (xy 183.908393 -303.359665) (xy 183.938141 -303.404629) (xy 183.961026 -303.453446)
			(xy 183.976558 -303.505075) (xy 183.984408 -303.558415) (xy 183.9849 -303.585372) (xy 190.790845 -303.585372)
			(xy 190.79478 -303.531601) (xy 190.806503 -303.478977) (xy 190.825763 -303.42862) (xy 190.852149 -303.381603)
			(xy 190.885101 -303.33893) (xy 190.923914 -303.301509) (xy 190.967762 -303.270139) (xy 191.01571 -303.245487)
			(xy 191.066737 -303.228079) (xy 191.119755 -303.218286) (xy 191.173634 -303.216317) (xy 191.227225 -303.222214)
			(xy 191.279386 -303.23585) (xy 191.329006 -303.256937) (xy 191.375027 -303.285023) (xy 191.416469 -303.319511)
			(xy 191.452447 -303.359665) (xy 191.482195 -303.404629) (xy 191.50508 -303.453446) (xy 191.520612 -303.505075)
			(xy 191.528462 -303.558415) (xy 191.528954 -303.585372) (xy 198.334899 -303.585372) (xy 198.338834 -303.531601)
			(xy 198.350557 -303.478977) (xy 198.369817 -303.42862) (xy 198.396203 -303.381603) (xy 198.429155 -303.33893)
			(xy 198.467968 -303.301509) (xy 198.511816 -303.270139) (xy 198.559764 -303.245487) (xy 198.610791 -303.228079)
			(xy 198.663809 -303.218286) (xy 198.717688 -303.216317) (xy 198.771279 -303.222214) (xy 198.82344 -303.23585)
			(xy 198.87306 -303.256937) (xy 198.919081 -303.285023) (xy 198.960523 -303.319511) (xy 198.996501 -303.359665)
			(xy 199.026249 -303.404629) (xy 199.049134 -303.453446) (xy 199.064666 -303.505075) (xy 199.072516 -303.558415)
			(xy 199.073008 -303.585372) (xy 205.878699 -303.585372) (xy 205.882634 -303.531601) (xy 205.894357 -303.478977)
			(xy 205.913617 -303.42862) (xy 205.940003 -303.381603) (xy 205.972955 -303.33893) (xy 206.011768 -303.301509)
			(xy 206.055616 -303.270139) (xy 206.103564 -303.245487) (xy 206.154591 -303.228079) (xy 206.207609 -303.218286)
			(xy 206.261488 -303.216317) (xy 206.315079 -303.222214) (xy 206.36724 -303.23585) (xy 206.41686 -303.256937)
			(xy 206.462881 -303.285023) (xy 206.504323 -303.319511) (xy 206.540301 -303.359665) (xy 206.570049 -303.404629)
			(xy 206.592934 -303.453446) (xy 206.608466 -303.505075) (xy 206.616316 -303.558415) (xy 206.616808 -303.585372)
			(xy 206.616316 -303.612329) (xy 206.608466 -303.665669) (xy 206.592934 -303.717298) (xy 206.570049 -303.766115)
			(xy 206.540301 -303.811079) (xy 206.504323 -303.851233) (xy 206.462881 -303.885721) (xy 206.41686 -303.913807)
			(xy 206.36724 -303.934894) (xy 206.315079 -303.94853) (xy 206.261488 -303.954427) (xy 206.207609 -303.952458)
			(xy 206.154591 -303.942665) (xy 206.103564 -303.925257) (xy 206.055616 -303.900605) (xy 206.011768 -303.869235)
			(xy 205.972955 -303.831814) (xy 205.940003 -303.789141) (xy 205.913617 -303.742124) (xy 205.894357 -303.691767)
			(xy 205.882634 -303.639143) (xy 205.878699 -303.585372) (xy 199.073008 -303.585372) (xy 199.072516 -303.612329)
			(xy 199.064666 -303.665669) (xy 199.049134 -303.717298) (xy 199.026249 -303.766115) (xy 198.996501 -303.811079)
			(xy 198.960523 -303.851233) (xy 198.919081 -303.885721) (xy 198.87306 -303.913807) (xy 198.82344 -303.934894)
			(xy 198.771279 -303.94853) (xy 198.717688 -303.954427) (xy 198.663809 -303.952458) (xy 198.610791 -303.942665)
			(xy 198.559764 -303.925257) (xy 198.511816 -303.900605) (xy 198.467968 -303.869235) (xy 198.429155 -303.831814)
			(xy 198.396203 -303.789141) (xy 198.369817 -303.742124) (xy 198.350557 -303.691767) (xy 198.338834 -303.639143)
			(xy 198.334899 -303.585372) (xy 191.528954 -303.585372) (xy 191.528462 -303.612329) (xy 191.520612 -303.665669)
			(xy 191.50508 -303.717298) (xy 191.482195 -303.766115) (xy 191.452447 -303.811079) (xy 191.416469 -303.851233)
			(xy 191.375027 -303.885721) (xy 191.329006 -303.913807) (xy 191.279386 -303.934894) (xy 191.227225 -303.94853)
			(xy 191.173634 -303.954427) (xy 191.119755 -303.952458) (xy 191.066737 -303.942665) (xy 191.01571 -303.925257)
			(xy 190.967762 -303.900605) (xy 190.923914 -303.869235) (xy 190.885101 -303.831814) (xy 190.852149 -303.789141)
			(xy 190.825763 -303.742124) (xy 190.806503 -303.691767) (xy 190.79478 -303.639143) (xy 190.790845 -303.585372)
			(xy 183.9849 -303.585372) (xy 183.984408 -303.612329) (xy 183.976558 -303.665669) (xy 183.961026 -303.717298)
			(xy 183.938141 -303.766115) (xy 183.908393 -303.811079) (xy 183.872415 -303.851233) (xy 183.830973 -303.885721)
			(xy 183.784952 -303.913807) (xy 183.735332 -303.934894) (xy 183.683171 -303.94853) (xy 183.62958 -303.954427)
			(xy 183.575701 -303.952458) (xy 183.522683 -303.942665) (xy 183.471656 -303.925257) (xy 183.423708 -303.900605)
			(xy 183.37986 -303.869235) (xy 183.341047 -303.831814) (xy 183.308095 -303.789141) (xy 183.281709 -303.742124)
			(xy 183.262449 -303.691767) (xy 183.250726 -303.639143) (xy 183.246791 -303.585372) (xy 177.881534 -303.585372)
			(xy 177.881534 -304.435256) (xy 179.146723 -304.435256) (xy 179.150658 -304.381485) (xy 179.162381 -304.328861)
			(xy 179.181641 -304.278504) (xy 179.208027 -304.231487) (xy 179.240979 -304.188814) (xy 179.279792 -304.151393)
			(xy 179.32364 -304.120023) (xy 179.371588 -304.095371) (xy 179.422615 -304.077963) (xy 179.475633 -304.06817)
			(xy 179.529512 -304.066201) (xy 179.583103 -304.072098) (xy 179.635264 -304.085734) (xy 179.684884 -304.106821)
			(xy 179.730905 -304.134907) (xy 179.772347 -304.169395) (xy 179.808325 -304.209549) (xy 179.838073 -304.254513)
			(xy 179.860958 -304.30333) (xy 179.87649 -304.354959) (xy 179.88434 -304.408299) (xy 179.884832 -304.435256)
			(xy 183.246791 -304.435256) (xy 183.250726 -304.381485) (xy 183.262449 -304.328861) (xy 183.281709 -304.278504)
			(xy 183.308095 -304.231487) (xy 183.341047 -304.188814) (xy 183.37986 -304.151393) (xy 183.423708 -304.120023)
			(xy 183.471656 -304.095371) (xy 183.522683 -304.077963) (xy 183.575701 -304.06817) (xy 183.62958 -304.066201)
			(xy 183.683171 -304.072098) (xy 183.735332 -304.085734) (xy 183.784952 -304.106821) (xy 183.830973 -304.134907)
			(xy 183.872415 -304.169395) (xy 183.908393 -304.209549) (xy 183.938141 -304.254513) (xy 183.961026 -304.30333)
			(xy 183.976558 -304.354959) (xy 183.984408 -304.408299) (xy 183.9849 -304.435256) (xy 186.690777 -304.435256)
			(xy 186.694712 -304.381485) (xy 186.706435 -304.328861) (xy 186.725695 -304.278504) (xy 186.752081 -304.231487)
			(xy 186.785033 -304.188814) (xy 186.823846 -304.151393) (xy 186.867694 -304.120023) (xy 186.915642 -304.095371)
			(xy 186.966669 -304.077963) (xy 187.019687 -304.06817) (xy 187.073566 -304.066201) (xy 187.127157 -304.072098)
			(xy 187.179318 -304.085734) (xy 187.228938 -304.106821) (xy 187.274959 -304.134907) (xy 187.316401 -304.169395)
			(xy 187.352379 -304.209549) (xy 187.382127 -304.254513) (xy 187.405012 -304.30333) (xy 187.420544 -304.354959)
			(xy 187.428394 -304.408299) (xy 187.428886 -304.435256) (xy 190.790845 -304.435256) (xy 190.79478 -304.381485)
			(xy 190.806503 -304.328861) (xy 190.825763 -304.278504) (xy 190.852149 -304.231487) (xy 190.885101 -304.188814)
			(xy 190.923914 -304.151393) (xy 190.967762 -304.120023) (xy 191.01571 -304.095371) (xy 191.066737 -304.077963)
			(xy 191.119755 -304.06817) (xy 191.173634 -304.066201) (xy 191.227225 -304.072098) (xy 191.279386 -304.085734)
			(xy 191.329006 -304.106821) (xy 191.375027 -304.134907) (xy 191.416469 -304.169395) (xy 191.452447 -304.209549)
			(xy 191.482195 -304.254513) (xy 191.50508 -304.30333) (xy 191.520612 -304.354959) (xy 191.528462 -304.408299)
			(xy 191.528954 -304.435256) (xy 194.234831 -304.435256) (xy 194.238766 -304.381485) (xy 194.250489 -304.328861)
			(xy 194.269749 -304.278504) (xy 194.296135 -304.231487) (xy 194.329087 -304.188814) (xy 194.3679 -304.151393)
			(xy 194.411748 -304.120023) (xy 194.459696 -304.095371) (xy 194.510723 -304.077963) (xy 194.563741 -304.06817)
			(xy 194.61762 -304.066201) (xy 194.671211 -304.072098) (xy 194.723372 -304.085734) (xy 194.772992 -304.106821)
			(xy 194.819013 -304.134907) (xy 194.860455 -304.169395) (xy 194.896433 -304.209549) (xy 194.926181 -304.254513)
			(xy 194.949066 -304.30333) (xy 194.964598 -304.354959) (xy 194.972448 -304.408299) (xy 194.97294 -304.435256)
			(xy 198.334899 -304.435256) (xy 198.338834 -304.381485) (xy 198.350557 -304.328861) (xy 198.369817 -304.278504)
			(xy 198.396203 -304.231487) (xy 198.429155 -304.188814) (xy 198.467968 -304.151393) (xy 198.511816 -304.120023)
			(xy 198.559764 -304.095371) (xy 198.610791 -304.077963) (xy 198.663809 -304.06817) (xy 198.717688 -304.066201)
			(xy 198.771279 -304.072098) (xy 198.82344 -304.085734) (xy 198.87306 -304.106821) (xy 198.919081 -304.134907)
			(xy 198.960523 -304.169395) (xy 198.996501 -304.209549) (xy 199.026249 -304.254513) (xy 199.049134 -304.30333)
			(xy 199.064666 -304.354959) (xy 199.072516 -304.408299) (xy 199.073008 -304.435256) (xy 201.778631 -304.435256)
			(xy 201.782566 -304.381485) (xy 201.794289 -304.328861) (xy 201.813549 -304.278504) (xy 201.839935 -304.231487)
			(xy 201.872887 -304.188814) (xy 201.9117 -304.151393) (xy 201.955548 -304.120023) (xy 202.003496 -304.095371)
			(xy 202.054523 -304.077963) (xy 202.107541 -304.06817) (xy 202.16142 -304.066201) (xy 202.215011 -304.072098)
			(xy 202.267172 -304.085734) (xy 202.316792 -304.106821) (xy 202.362813 -304.134907) (xy 202.404255 -304.169395)
			(xy 202.440233 -304.209549) (xy 202.469981 -304.254513) (xy 202.492866 -304.30333) (xy 202.508398 -304.354959)
			(xy 202.516248 -304.408299) (xy 202.51674 -304.435256) (xy 205.878699 -304.435256) (xy 205.882634 -304.381485)
			(xy 205.894357 -304.328861) (xy 205.913617 -304.278504) (xy 205.940003 -304.231487) (xy 205.972955 -304.188814)
			(xy 206.011768 -304.151393) (xy 206.055616 -304.120023) (xy 206.103564 -304.095371) (xy 206.154591 -304.077963)
			(xy 206.207609 -304.06817) (xy 206.261488 -304.066201) (xy 206.315079 -304.072098) (xy 206.36724 -304.085734)
			(xy 206.41686 -304.106821) (xy 206.462881 -304.134907) (xy 206.504323 -304.169395) (xy 206.540301 -304.209549)
			(xy 206.570049 -304.254513) (xy 206.592934 -304.30333) (xy 206.608466 -304.354959) (xy 206.616316 -304.408299)
			(xy 206.616808 -304.435256) (xy 206.616316 -304.462213) (xy 206.608466 -304.515553) (xy 206.592934 -304.567182)
			(xy 206.570049 -304.615999) (xy 206.540301 -304.660963) (xy 206.504323 -304.701117) (xy 206.462881 -304.735605)
			(xy 206.41686 -304.763691) (xy 206.36724 -304.784778) (xy 206.315079 -304.798414) (xy 206.261488 -304.804311)
			(xy 206.207609 -304.802342) (xy 206.154591 -304.792549) (xy 206.103564 -304.775141) (xy 206.055616 -304.750489)
			(xy 206.011768 -304.719119) (xy 205.972955 -304.681698) (xy 205.940003 -304.639025) (xy 205.913617 -304.592008)
			(xy 205.894357 -304.541651) (xy 205.882634 -304.489027) (xy 205.878699 -304.435256) (xy 202.51674 -304.435256)
			(xy 202.516248 -304.462213) (xy 202.508398 -304.515553) (xy 202.492866 -304.567182) (xy 202.469981 -304.615999)
			(xy 202.440233 -304.660963) (xy 202.404255 -304.701117) (xy 202.362813 -304.735605) (xy 202.316792 -304.763691)
			(xy 202.267172 -304.784778) (xy 202.215011 -304.798414) (xy 202.16142 -304.804311) (xy 202.107541 -304.802342)
			(xy 202.054523 -304.792549) (xy 202.003496 -304.775141) (xy 201.955548 -304.750489) (xy 201.9117 -304.719119)
			(xy 201.872887 -304.681698) (xy 201.839935 -304.639025) (xy 201.813549 -304.592008) (xy 201.794289 -304.541651)
			(xy 201.782566 -304.489027) (xy 201.778631 -304.435256) (xy 199.073008 -304.435256) (xy 199.072516 -304.462213)
			(xy 199.064666 -304.515553) (xy 199.049134 -304.567182) (xy 199.026249 -304.615999) (xy 198.996501 -304.660963)
			(xy 198.960523 -304.701117) (xy 198.919081 -304.735605) (xy 198.87306 -304.763691) (xy 198.82344 -304.784778)
			(xy 198.771279 -304.798414) (xy 198.717688 -304.804311) (xy 198.663809 -304.802342) (xy 198.610791 -304.792549)
			(xy 198.559764 -304.775141) (xy 198.511816 -304.750489) (xy 198.467968 -304.719119) (xy 198.429155 -304.681698)
			(xy 198.396203 -304.639025) (xy 198.369817 -304.592008) (xy 198.350557 -304.541651) (xy 198.338834 -304.489027)
			(xy 198.334899 -304.435256) (xy 194.97294 -304.435256) (xy 194.972448 -304.462213) (xy 194.964598 -304.515553)
			(xy 194.949066 -304.567182) (xy 194.926181 -304.615999) (xy 194.896433 -304.660963) (xy 194.860455 -304.701117)
			(xy 194.819013 -304.735605) (xy 194.772992 -304.763691) (xy 194.723372 -304.784778) (xy 194.671211 -304.798414)
			(xy 194.61762 -304.804311) (xy 194.563741 -304.802342) (xy 194.510723 -304.792549) (xy 194.459696 -304.775141)
			(xy 194.411748 -304.750489) (xy 194.3679 -304.719119) (xy 194.329087 -304.681698) (xy 194.296135 -304.639025)
			(xy 194.269749 -304.592008) (xy 194.250489 -304.541651) (xy 194.238766 -304.489027) (xy 194.234831 -304.435256)
			(xy 191.528954 -304.435256) (xy 191.528462 -304.462213) (xy 191.520612 -304.515553) (xy 191.50508 -304.567182)
			(xy 191.482195 -304.615999) (xy 191.452447 -304.660963) (xy 191.416469 -304.701117) (xy 191.375027 -304.735605)
			(xy 191.329006 -304.763691) (xy 191.279386 -304.784778) (xy 191.227225 -304.798414) (xy 191.173634 -304.804311)
			(xy 191.119755 -304.802342) (xy 191.066737 -304.792549) (xy 191.01571 -304.775141) (xy 190.967762 -304.750489)
			(xy 190.923914 -304.719119) (xy 190.885101 -304.681698) (xy 190.852149 -304.639025) (xy 190.825763 -304.592008)
			(xy 190.806503 -304.541651) (xy 190.79478 -304.489027) (xy 190.790845 -304.435256) (xy 187.428886 -304.435256)
			(xy 187.428394 -304.462213) (xy 187.420544 -304.515553) (xy 187.405012 -304.567182) (xy 187.382127 -304.615999)
			(xy 187.352379 -304.660963) (xy 187.316401 -304.701117) (xy 187.274959 -304.735605) (xy 187.228938 -304.763691)
			(xy 187.179318 -304.784778) (xy 187.127157 -304.798414) (xy 187.073566 -304.804311) (xy 187.019687 -304.802342)
			(xy 186.966669 -304.792549) (xy 186.915642 -304.775141) (xy 186.867694 -304.750489) (xy 186.823846 -304.719119)
			(xy 186.785033 -304.681698) (xy 186.752081 -304.639025) (xy 186.725695 -304.592008) (xy 186.706435 -304.541651)
			(xy 186.694712 -304.489027) (xy 186.690777 -304.435256) (xy 183.9849 -304.435256) (xy 183.984408 -304.462213)
			(xy 183.976558 -304.515553) (xy 183.961026 -304.567182) (xy 183.938141 -304.615999) (xy 183.908393 -304.660963)
			(xy 183.872415 -304.701117) (xy 183.830973 -304.735605) (xy 183.784952 -304.763691) (xy 183.735332 -304.784778)
			(xy 183.683171 -304.798414) (xy 183.62958 -304.804311) (xy 183.575701 -304.802342) (xy 183.522683 -304.792549)
			(xy 183.471656 -304.775141) (xy 183.423708 -304.750489) (xy 183.37986 -304.719119) (xy 183.341047 -304.681698)
			(xy 183.308095 -304.639025) (xy 183.281709 -304.592008) (xy 183.262449 -304.541651) (xy 183.250726 -304.489027)
			(xy 183.246791 -304.435256) (xy 179.884832 -304.435256) (xy 179.88434 -304.462213) (xy 179.87649 -304.515553)
			(xy 179.860958 -304.567182) (xy 179.838073 -304.615999) (xy 179.808325 -304.660963) (xy 179.772347 -304.701117)
			(xy 179.730905 -304.735605) (xy 179.684884 -304.763691) (xy 179.635264 -304.784778) (xy 179.583103 -304.798414)
			(xy 179.529512 -304.804311) (xy 179.475633 -304.802342) (xy 179.422615 -304.792549) (xy 179.371588 -304.775141)
			(xy 179.32364 -304.750489) (xy 179.279792 -304.719119) (xy 179.240979 -304.681698) (xy 179.208027 -304.639025)
			(xy 179.181641 -304.592008) (xy 179.162381 -304.541651) (xy 179.150658 -304.489027) (xy 179.146723 -304.435256)
			(xy 177.881534 -304.435256) (xy 177.881534 -305.285394) (xy 179.146723 -305.285394) (xy 179.150658 -305.231623)
			(xy 179.162381 -305.178999) (xy 179.181641 -305.128642) (xy 179.208027 -305.081625) (xy 179.240979 -305.038952)
			(xy 179.279792 -305.001531) (xy 179.32364 -304.970161) (xy 179.371588 -304.945509) (xy 179.422615 -304.928101)
			(xy 179.475633 -304.918308) (xy 179.529512 -304.916339) (xy 179.583103 -304.922236) (xy 179.635264 -304.935872)
			(xy 179.684884 -304.956959) (xy 179.730905 -304.985045) (xy 179.772347 -305.019533) (xy 179.808325 -305.059687)
			(xy 179.838073 -305.104651) (xy 179.860958 -305.153468) (xy 179.87649 -305.205097) (xy 179.88434 -305.258437)
			(xy 179.884832 -305.285394) (xy 186.690777 -305.285394) (xy 186.694712 -305.231623) (xy 186.706435 -305.178999)
			(xy 186.725695 -305.128642) (xy 186.752081 -305.081625) (xy 186.785033 -305.038952) (xy 186.823846 -305.001531)
			(xy 186.867694 -304.970161) (xy 186.915642 -304.945509) (xy 186.966669 -304.928101) (xy 187.019687 -304.918308)
			(xy 187.073566 -304.916339) (xy 187.127157 -304.922236) (xy 187.179318 -304.935872) (xy 187.228938 -304.956959)
			(xy 187.274959 -304.985045) (xy 187.316401 -305.019533) (xy 187.352379 -305.059687) (xy 187.382127 -305.104651)
			(xy 187.405012 -305.153468) (xy 187.420544 -305.205097) (xy 187.428394 -305.258437) (xy 187.428886 -305.285394)
			(xy 194.234831 -305.285394) (xy 194.238766 -305.231623) (xy 194.250489 -305.178999) (xy 194.269749 -305.128642)
			(xy 194.296135 -305.081625) (xy 194.329087 -305.038952) (xy 194.3679 -305.001531) (xy 194.411748 -304.970161)
			(xy 194.459696 -304.945509) (xy 194.510723 -304.928101) (xy 194.563741 -304.918308) (xy 194.61762 -304.916339)
			(xy 194.671211 -304.922236) (xy 194.723372 -304.935872) (xy 194.772992 -304.956959) (xy 194.819013 -304.985045)
			(xy 194.860455 -305.019533) (xy 194.896433 -305.059687) (xy 194.926181 -305.104651) (xy 194.949066 -305.153468)
			(xy 194.964598 -305.205097) (xy 194.972448 -305.258437) (xy 194.97294 -305.285394) (xy 201.778631 -305.285394)
			(xy 201.782566 -305.231623) (xy 201.794289 -305.178999) (xy 201.813549 -305.128642) (xy 201.839935 -305.081625)
			(xy 201.872887 -305.038952) (xy 201.9117 -305.001531) (xy 201.955548 -304.970161) (xy 202.003496 -304.945509)
			(xy 202.054523 -304.928101) (xy 202.107541 -304.918308) (xy 202.16142 -304.916339) (xy 202.215011 -304.922236)
			(xy 202.267172 -304.935872) (xy 202.316792 -304.956959) (xy 202.362813 -304.985045) (xy 202.404255 -305.019533)
			(xy 202.440233 -305.059687) (xy 202.469981 -305.104651) (xy 202.492866 -305.153468) (xy 202.508398 -305.205097)
			(xy 202.516248 -305.258437) (xy 202.51674 -305.285394) (xy 202.516248 -305.312351) (xy 202.508398 -305.365691)
			(xy 202.492866 -305.41732) (xy 202.469981 -305.466137) (xy 202.440233 -305.511101) (xy 202.404255 -305.551255)
			(xy 202.362813 -305.585743) (xy 202.316792 -305.613829) (xy 202.267172 -305.634916) (xy 202.215011 -305.648552)
			(xy 202.16142 -305.654449) (xy 202.107541 -305.65248) (xy 202.054523 -305.642687) (xy 202.003496 -305.625279)
			(xy 201.955548 -305.600627) (xy 201.9117 -305.569257) (xy 201.872887 -305.531836) (xy 201.839935 -305.489163)
			(xy 201.813549 -305.442146) (xy 201.794289 -305.391789) (xy 201.782566 -305.339165) (xy 201.778631 -305.285394)
			(xy 194.97294 -305.285394) (xy 194.972448 -305.312351) (xy 194.964598 -305.365691) (xy 194.949066 -305.41732)
			(xy 194.926181 -305.466137) (xy 194.896433 -305.511101) (xy 194.860455 -305.551255) (xy 194.819013 -305.585743)
			(xy 194.772992 -305.613829) (xy 194.723372 -305.634916) (xy 194.671211 -305.648552) (xy 194.61762 -305.654449)
			(xy 194.563741 -305.65248) (xy 194.510723 -305.642687) (xy 194.459696 -305.625279) (xy 194.411748 -305.600627)
			(xy 194.3679 -305.569257) (xy 194.329087 -305.531836) (xy 194.296135 -305.489163) (xy 194.269749 -305.442146)
			(xy 194.250489 -305.391789) (xy 194.238766 -305.339165) (xy 194.234831 -305.285394) (xy 187.428886 -305.285394)
			(xy 187.428394 -305.312351) (xy 187.420544 -305.365691) (xy 187.405012 -305.41732) (xy 187.382127 -305.466137)
			(xy 187.352379 -305.511101) (xy 187.316401 -305.551255) (xy 187.274959 -305.585743) (xy 187.228938 -305.613829)
			(xy 187.179318 -305.634916) (xy 187.127157 -305.648552) (xy 187.073566 -305.654449) (xy 187.019687 -305.65248)
			(xy 186.966669 -305.642687) (xy 186.915642 -305.625279) (xy 186.867694 -305.600627) (xy 186.823846 -305.569257)
			(xy 186.785033 -305.531836) (xy 186.752081 -305.489163) (xy 186.725695 -305.442146) (xy 186.706435 -305.391789)
			(xy 186.694712 -305.339165) (xy 186.690777 -305.285394) (xy 179.884832 -305.285394) (xy 179.88434 -305.312351)
			(xy 179.87649 -305.365691) (xy 179.860958 -305.41732) (xy 179.838073 -305.466137) (xy 179.808325 -305.511101)
			(xy 179.772347 -305.551255) (xy 179.730905 -305.585743) (xy 179.684884 -305.613829) (xy 179.635264 -305.634916)
			(xy 179.583103 -305.648552) (xy 179.529512 -305.654449) (xy 179.475633 -305.65248) (xy 179.422615 -305.642687)
			(xy 179.371588 -305.625279) (xy 179.32364 -305.600627) (xy 179.279792 -305.569257) (xy 179.240979 -305.531836)
			(xy 179.208027 -305.489163) (xy 179.181641 -305.442146) (xy 179.162381 -305.391789) (xy 179.150658 -305.339165)
			(xy 179.146723 -305.285394) (xy 177.881534 -305.285394) (xy 177.881534 -306.135278) (xy 183.246791 -306.135278)
			(xy 183.250726 -306.081507) (xy 183.262449 -306.028883) (xy 183.281709 -305.978526) (xy 183.308095 -305.931509)
			(xy 183.341047 -305.888836) (xy 183.37986 -305.851415) (xy 183.423708 -305.820045) (xy 183.471656 -305.795393)
			(xy 183.522683 -305.777985) (xy 183.575701 -305.768192) (xy 183.62958 -305.766223) (xy 183.683171 -305.77212)
			(xy 183.735332 -305.785756) (xy 183.784952 -305.806843) (xy 183.830973 -305.834929) (xy 183.872415 -305.869417)
			(xy 183.908393 -305.909571) (xy 183.938141 -305.954535) (xy 183.961026 -306.003352) (xy 183.976558 -306.054981)
			(xy 183.984408 -306.108321) (xy 183.9849 -306.135278) (xy 190.790845 -306.135278) (xy 190.79478 -306.081507)
			(xy 190.806503 -306.028883) (xy 190.825763 -305.978526) (xy 190.852149 -305.931509) (xy 190.885101 -305.888836)
			(xy 190.923914 -305.851415) (xy 190.967762 -305.820045) (xy 191.01571 -305.795393) (xy 191.066737 -305.777985)
			(xy 191.119755 -305.768192) (xy 191.173634 -305.766223) (xy 191.227225 -305.77212) (xy 191.279386 -305.785756)
			(xy 191.329006 -305.806843) (xy 191.375027 -305.834929) (xy 191.416469 -305.869417) (xy 191.452447 -305.909571)
			(xy 191.482195 -305.954535) (xy 191.50508 -306.003352) (xy 191.520612 -306.054981) (xy 191.528462 -306.108321)
			(xy 191.528954 -306.135278) (xy 198.334899 -306.135278) (xy 198.338834 -306.081507) (xy 198.350557 -306.028883)
			(xy 198.369817 -305.978526) (xy 198.396203 -305.931509) (xy 198.429155 -305.888836) (xy 198.467968 -305.851415)
			(xy 198.511816 -305.820045) (xy 198.559764 -305.795393) (xy 198.610791 -305.777985) (xy 198.663809 -305.768192)
			(xy 198.717688 -305.766223) (xy 198.771279 -305.77212) (xy 198.82344 -305.785756) (xy 198.87306 -305.806843)
			(xy 198.919081 -305.834929) (xy 198.960523 -305.869417) (xy 198.996501 -305.909571) (xy 199.026249 -305.954535)
			(xy 199.049134 -306.003352) (xy 199.064666 -306.054981) (xy 199.072516 -306.108321) (xy 199.073008 -306.135278)
			(xy 205.878699 -306.135278) (xy 205.882634 -306.081507) (xy 205.894357 -306.028883) (xy 205.913617 -305.978526)
			(xy 205.940003 -305.931509) (xy 205.972955 -305.888836) (xy 206.011768 -305.851415) (xy 206.055616 -305.820045)
			(xy 206.103564 -305.795393) (xy 206.154591 -305.777985) (xy 206.207609 -305.768192) (xy 206.261488 -305.766223)
			(xy 206.315079 -305.77212) (xy 206.36724 -305.785756) (xy 206.41686 -305.806843) (xy 206.462881 -305.834929)
			(xy 206.504323 -305.869417) (xy 206.540301 -305.909571) (xy 206.570049 -305.954535) (xy 206.592934 -306.003352)
			(xy 206.608466 -306.054981) (xy 206.616316 -306.108321) (xy 206.616808 -306.135278) (xy 206.616316 -306.162235)
			(xy 206.608466 -306.215575) (xy 206.592934 -306.267204) (xy 206.570049 -306.316021) (xy 206.540301 -306.360985)
			(xy 206.504323 -306.401139) (xy 206.462881 -306.435627) (xy 206.41686 -306.463713) (xy 206.36724 -306.4848)
			(xy 206.315079 -306.498436) (xy 206.261488 -306.504333) (xy 206.207609 -306.502364) (xy 206.154591 -306.492571)
			(xy 206.103564 -306.475163) (xy 206.055616 -306.450511) (xy 206.011768 -306.419141) (xy 205.972955 -306.38172)
			(xy 205.940003 -306.339047) (xy 205.913617 -306.29203) (xy 205.894357 -306.241673) (xy 205.882634 -306.189049)
			(xy 205.878699 -306.135278) (xy 199.073008 -306.135278) (xy 199.072516 -306.162235) (xy 199.064666 -306.215575)
			(xy 199.049134 -306.267204) (xy 199.026249 -306.316021) (xy 198.996501 -306.360985) (xy 198.960523 -306.401139)
			(xy 198.919081 -306.435627) (xy 198.87306 -306.463713) (xy 198.82344 -306.4848) (xy 198.771279 -306.498436)
			(xy 198.717688 -306.504333) (xy 198.663809 -306.502364) (xy 198.610791 -306.492571) (xy 198.559764 -306.475163)
			(xy 198.511816 -306.450511) (xy 198.467968 -306.419141) (xy 198.429155 -306.38172) (xy 198.396203 -306.339047)
			(xy 198.369817 -306.29203) (xy 198.350557 -306.241673) (xy 198.338834 -306.189049) (xy 198.334899 -306.135278)
			(xy 191.528954 -306.135278) (xy 191.528462 -306.162235) (xy 191.520612 -306.215575) (xy 191.50508 -306.267204)
			(xy 191.482195 -306.316021) (xy 191.452447 -306.360985) (xy 191.416469 -306.401139) (xy 191.375027 -306.435627)
			(xy 191.329006 -306.463713) (xy 191.279386 -306.4848) (xy 191.227225 -306.498436) (xy 191.173634 -306.504333)
			(xy 191.119755 -306.502364) (xy 191.066737 -306.492571) (xy 191.01571 -306.475163) (xy 190.967762 -306.450511)
			(xy 190.923914 -306.419141) (xy 190.885101 -306.38172) (xy 190.852149 -306.339047) (xy 190.825763 -306.29203)
			(xy 190.806503 -306.241673) (xy 190.79478 -306.189049) (xy 190.790845 -306.135278) (xy 183.9849 -306.135278)
			(xy 183.984408 -306.162235) (xy 183.976558 -306.215575) (xy 183.961026 -306.267204) (xy 183.938141 -306.316021)
			(xy 183.908393 -306.360985) (xy 183.872415 -306.401139) (xy 183.830973 -306.435627) (xy 183.784952 -306.463713)
			(xy 183.735332 -306.4848) (xy 183.683171 -306.498436) (xy 183.62958 -306.504333) (xy 183.575701 -306.502364)
			(xy 183.522683 -306.492571) (xy 183.471656 -306.475163) (xy 183.423708 -306.450511) (xy 183.37986 -306.419141)
			(xy 183.341047 -306.38172) (xy 183.308095 -306.339047) (xy 183.281709 -306.29203) (xy 183.262449 -306.241673)
			(xy 183.250726 -306.189049) (xy 183.246791 -306.135278) (xy 177.881534 -306.135278) (xy 177.881534 -306.985416)
			(xy 179.146723 -306.985416) (xy 179.150658 -306.931645) (xy 179.162381 -306.879021) (xy 179.181641 -306.828664)
			(xy 179.208027 -306.781647) (xy 179.240979 -306.738974) (xy 179.279792 -306.701553) (xy 179.32364 -306.670183)
			(xy 179.371588 -306.645531) (xy 179.422615 -306.628123) (xy 179.475633 -306.61833) (xy 179.529512 -306.616361)
			(xy 179.583103 -306.622258) (xy 179.635264 -306.635894) (xy 179.684884 -306.656981) (xy 179.730905 -306.685067)
			(xy 179.772347 -306.719555) (xy 179.808325 -306.759709) (xy 179.838073 -306.804673) (xy 179.860958 -306.85349)
			(xy 179.87649 -306.905119) (xy 179.88434 -306.958459) (xy 179.884832 -306.985416) (xy 186.690777 -306.985416)
			(xy 186.694712 -306.931645) (xy 186.706435 -306.879021) (xy 186.725695 -306.828664) (xy 186.752081 -306.781647)
			(xy 186.785033 -306.738974) (xy 186.823846 -306.701553) (xy 186.867694 -306.670183) (xy 186.915642 -306.645531)
			(xy 186.966669 -306.628123) (xy 187.019687 -306.61833) (xy 187.073566 -306.616361) (xy 187.127157 -306.622258)
			(xy 187.179318 -306.635894) (xy 187.228938 -306.656981) (xy 187.274959 -306.685067) (xy 187.316401 -306.719555)
			(xy 187.352379 -306.759709) (xy 187.382127 -306.804673) (xy 187.405012 -306.85349) (xy 187.420544 -306.905119)
			(xy 187.428394 -306.958459) (xy 187.428886 -306.985416) (xy 194.234831 -306.985416) (xy 194.238766 -306.931645)
			(xy 194.250489 -306.879021) (xy 194.269749 -306.828664) (xy 194.296135 -306.781647) (xy 194.329087 -306.738974)
			(xy 194.3679 -306.701553) (xy 194.411748 -306.670183) (xy 194.459696 -306.645531) (xy 194.510723 -306.628123)
			(xy 194.563741 -306.61833) (xy 194.61762 -306.616361) (xy 194.671211 -306.622258) (xy 194.723372 -306.635894)
			(xy 194.772992 -306.656981) (xy 194.819013 -306.685067) (xy 194.860455 -306.719555) (xy 194.896433 -306.759709)
			(xy 194.926181 -306.804673) (xy 194.949066 -306.85349) (xy 194.964598 -306.905119) (xy 194.972448 -306.958459)
			(xy 194.97294 -306.985416) (xy 201.778631 -306.985416) (xy 201.782566 -306.931645) (xy 201.794289 -306.879021)
			(xy 201.813549 -306.828664) (xy 201.839935 -306.781647) (xy 201.872887 -306.738974) (xy 201.9117 -306.701553)
			(xy 201.955548 -306.670183) (xy 202.003496 -306.645531) (xy 202.054523 -306.628123) (xy 202.107541 -306.61833)
			(xy 202.16142 -306.616361) (xy 202.215011 -306.622258) (xy 202.267172 -306.635894) (xy 202.316792 -306.656981)
			(xy 202.362813 -306.685067) (xy 202.404255 -306.719555) (xy 202.440233 -306.759709) (xy 202.469981 -306.804673)
			(xy 202.492866 -306.85349) (xy 202.508398 -306.905119) (xy 202.516248 -306.958459) (xy 202.51674 -306.985416)
			(xy 202.516248 -307.012373) (xy 202.508398 -307.065713) (xy 202.492866 -307.117342) (xy 202.469981 -307.166159)
			(xy 202.440233 -307.211123) (xy 202.404255 -307.251277) (xy 202.362813 -307.285765) (xy 202.316792 -307.313851)
			(xy 202.267172 -307.334938) (xy 202.215011 -307.348574) (xy 202.16142 -307.354471) (xy 202.107541 -307.352502)
			(xy 202.054523 -307.342709) (xy 202.003496 -307.325301) (xy 201.955548 -307.300649) (xy 201.9117 -307.269279)
			(xy 201.872887 -307.231858) (xy 201.839935 -307.189185) (xy 201.813549 -307.142168) (xy 201.794289 -307.091811)
			(xy 201.782566 -307.039187) (xy 201.778631 -306.985416) (xy 194.97294 -306.985416) (xy 194.972448 -307.012373)
			(xy 194.964598 -307.065713) (xy 194.949066 -307.117342) (xy 194.926181 -307.166159) (xy 194.896433 -307.211123)
			(xy 194.860455 -307.251277) (xy 194.819013 -307.285765) (xy 194.772992 -307.313851) (xy 194.723372 -307.334938)
			(xy 194.671211 -307.348574) (xy 194.61762 -307.354471) (xy 194.563741 -307.352502) (xy 194.510723 -307.342709)
			(xy 194.459696 -307.325301) (xy 194.411748 -307.300649) (xy 194.3679 -307.269279) (xy 194.329087 -307.231858)
			(xy 194.296135 -307.189185) (xy 194.269749 -307.142168) (xy 194.250489 -307.091811) (xy 194.238766 -307.039187)
			(xy 194.234831 -306.985416) (xy 187.428886 -306.985416) (xy 187.428394 -307.012373) (xy 187.420544 -307.065713)
			(xy 187.405012 -307.117342) (xy 187.382127 -307.166159) (xy 187.352379 -307.211123) (xy 187.316401 -307.251277)
			(xy 187.274959 -307.285765) (xy 187.228938 -307.313851) (xy 187.179318 -307.334938) (xy 187.127157 -307.348574)
			(xy 187.073566 -307.354471) (xy 187.019687 -307.352502) (xy 186.966669 -307.342709) (xy 186.915642 -307.325301)
			(xy 186.867694 -307.300649) (xy 186.823846 -307.269279) (xy 186.785033 -307.231858) (xy 186.752081 -307.189185)
			(xy 186.725695 -307.142168) (xy 186.706435 -307.091811) (xy 186.694712 -307.039187) (xy 186.690777 -306.985416)
			(xy 179.884832 -306.985416) (xy 179.88434 -307.012373) (xy 179.87649 -307.065713) (xy 179.860958 -307.117342)
			(xy 179.838073 -307.166159) (xy 179.808325 -307.211123) (xy 179.772347 -307.251277) (xy 179.730905 -307.285765)
			(xy 179.684884 -307.313851) (xy 179.635264 -307.334938) (xy 179.583103 -307.348574) (xy 179.529512 -307.354471)
			(xy 179.475633 -307.352502) (xy 179.422615 -307.342709) (xy 179.371588 -307.325301) (xy 179.32364 -307.300649)
			(xy 179.279792 -307.269279) (xy 179.240979 -307.231858) (xy 179.208027 -307.189185) (xy 179.181641 -307.142168)
			(xy 179.162381 -307.091811) (xy 179.150658 -307.039187) (xy 179.146723 -306.985416) (xy 177.881534 -306.985416)
			(xy 177.881534 -307.8353) (xy 183.246791 -307.8353) (xy 183.250726 -307.781529) (xy 183.262449 -307.728905)
			(xy 183.281709 -307.678548) (xy 183.308095 -307.631531) (xy 183.341047 -307.588858) (xy 183.37986 -307.551437)
			(xy 183.423708 -307.520067) (xy 183.471656 -307.495415) (xy 183.522683 -307.478007) (xy 183.575701 -307.468214)
			(xy 183.62958 -307.466245) (xy 183.683171 -307.472142) (xy 183.735332 -307.485778) (xy 183.784952 -307.506865)
			(xy 183.830973 -307.534951) (xy 183.872415 -307.569439) (xy 183.908393 -307.609593) (xy 183.938141 -307.654557)
			(xy 183.961026 -307.703374) (xy 183.976558 -307.755003) (xy 183.984408 -307.808343) (xy 183.9849 -307.8353)
			(xy 190.790845 -307.8353) (xy 190.79478 -307.781529) (xy 190.806503 -307.728905) (xy 190.825763 -307.678548)
			(xy 190.852149 -307.631531) (xy 190.885101 -307.588858) (xy 190.923914 -307.551437) (xy 190.967762 -307.520067)
			(xy 191.01571 -307.495415) (xy 191.066737 -307.478007) (xy 191.119755 -307.468214) (xy 191.173634 -307.466245)
			(xy 191.227225 -307.472142) (xy 191.279386 -307.485778) (xy 191.329006 -307.506865) (xy 191.375027 -307.534951)
			(xy 191.416469 -307.569439) (xy 191.452447 -307.609593) (xy 191.482195 -307.654557) (xy 191.50508 -307.703374)
			(xy 191.520612 -307.755003) (xy 191.528462 -307.808343) (xy 191.528954 -307.8353) (xy 198.334899 -307.8353)
			(xy 198.338834 -307.781529) (xy 198.350557 -307.728905) (xy 198.369817 -307.678548) (xy 198.396203 -307.631531)
			(xy 198.429155 -307.588858) (xy 198.467968 -307.551437) (xy 198.511816 -307.520067) (xy 198.559764 -307.495415)
			(xy 198.610791 -307.478007) (xy 198.663809 -307.468214) (xy 198.717688 -307.466245) (xy 198.771279 -307.472142)
			(xy 198.82344 -307.485778) (xy 198.87306 -307.506865) (xy 198.919081 -307.534951) (xy 198.960523 -307.569439)
			(xy 198.996501 -307.609593) (xy 199.026249 -307.654557) (xy 199.049134 -307.703374) (xy 199.064666 -307.755003)
			(xy 199.072516 -307.808343) (xy 199.073008 -307.8353) (xy 205.878699 -307.8353) (xy 205.882634 -307.781529)
			(xy 205.894357 -307.728905) (xy 205.913617 -307.678548) (xy 205.940003 -307.631531) (xy 205.972955 -307.588858)
			(xy 206.011768 -307.551437) (xy 206.055616 -307.520067) (xy 206.103564 -307.495415) (xy 206.154591 -307.478007)
			(xy 206.207609 -307.468214) (xy 206.261488 -307.466245) (xy 206.315079 -307.472142) (xy 206.36724 -307.485778)
			(xy 206.41686 -307.506865) (xy 206.462881 -307.534951) (xy 206.504323 -307.569439) (xy 206.540301 -307.609593)
			(xy 206.570049 -307.654557) (xy 206.592934 -307.703374) (xy 206.608466 -307.755003) (xy 206.616316 -307.808343)
			(xy 206.616808 -307.8353) (xy 206.616316 -307.862257) (xy 206.608466 -307.915597) (xy 206.592934 -307.967226)
			(xy 206.570049 -308.016043) (xy 206.540301 -308.061007) (xy 206.504323 -308.101161) (xy 206.462881 -308.135649)
			(xy 206.41686 -308.163735) (xy 206.36724 -308.184822) (xy 206.315079 -308.198458) (xy 206.261488 -308.204355)
			(xy 206.207609 -308.202386) (xy 206.154591 -308.192593) (xy 206.103564 -308.175185) (xy 206.055616 -308.150533)
			(xy 206.011768 -308.119163) (xy 205.972955 -308.081742) (xy 205.940003 -308.039069) (xy 205.913617 -307.992052)
			(xy 205.894357 -307.941695) (xy 205.882634 -307.889071) (xy 205.878699 -307.8353) (xy 199.073008 -307.8353)
			(xy 199.072516 -307.862257) (xy 199.064666 -307.915597) (xy 199.049134 -307.967226) (xy 199.026249 -308.016043)
			(xy 198.996501 -308.061007) (xy 198.960523 -308.101161) (xy 198.919081 -308.135649) (xy 198.87306 -308.163735)
			(xy 198.82344 -308.184822) (xy 198.771279 -308.198458) (xy 198.717688 -308.204355) (xy 198.663809 -308.202386)
			(xy 198.610791 -308.192593) (xy 198.559764 -308.175185) (xy 198.511816 -308.150533) (xy 198.467968 -308.119163)
			(xy 198.429155 -308.081742) (xy 198.396203 -308.039069) (xy 198.369817 -307.992052) (xy 198.350557 -307.941695)
			(xy 198.338834 -307.889071) (xy 198.334899 -307.8353) (xy 191.528954 -307.8353) (xy 191.528462 -307.862257)
			(xy 191.520612 -307.915597) (xy 191.50508 -307.967226) (xy 191.482195 -308.016043) (xy 191.452447 -308.061007)
			(xy 191.416469 -308.101161) (xy 191.375027 -308.135649) (xy 191.329006 -308.163735) (xy 191.279386 -308.184822)
			(xy 191.227225 -308.198458) (xy 191.173634 -308.204355) (xy 191.119755 -308.202386) (xy 191.066737 -308.192593)
			(xy 191.01571 -308.175185) (xy 190.967762 -308.150533) (xy 190.923914 -308.119163) (xy 190.885101 -308.081742)
			(xy 190.852149 -308.039069) (xy 190.825763 -307.992052) (xy 190.806503 -307.941695) (xy 190.79478 -307.889071)
			(xy 190.790845 -307.8353) (xy 183.9849 -307.8353) (xy 183.984408 -307.862257) (xy 183.976558 -307.915597)
			(xy 183.961026 -307.967226) (xy 183.938141 -308.016043) (xy 183.908393 -308.061007) (xy 183.872415 -308.101161)
			(xy 183.830973 -308.135649) (xy 183.784952 -308.163735) (xy 183.735332 -308.184822) (xy 183.683171 -308.198458)
			(xy 183.62958 -308.204355) (xy 183.575701 -308.202386) (xy 183.522683 -308.192593) (xy 183.471656 -308.175185)
			(xy 183.423708 -308.150533) (xy 183.37986 -308.119163) (xy 183.341047 -308.081742) (xy 183.308095 -308.039069)
			(xy 183.281709 -307.992052) (xy 183.262449 -307.941695) (xy 183.250726 -307.889071) (xy 183.246791 -307.8353)
			(xy 177.881534 -307.8353) (xy 177.881534 -308.685438) (xy 179.146723 -308.685438) (xy 179.150658 -308.631667)
			(xy 179.162381 -308.579043) (xy 179.181641 -308.528686) (xy 179.208027 -308.481669) (xy 179.240979 -308.438996)
			(xy 179.279792 -308.401575) (xy 179.32364 -308.370205) (xy 179.371588 -308.345553) (xy 179.422615 -308.328145)
			(xy 179.475633 -308.318352) (xy 179.529512 -308.316383) (xy 179.583103 -308.32228) (xy 179.635264 -308.335916)
			(xy 179.684884 -308.357003) (xy 179.730905 -308.385089) (xy 179.772347 -308.419577) (xy 179.808325 -308.459731)
			(xy 179.838073 -308.504695) (xy 179.860958 -308.553512) (xy 179.87649 -308.605141) (xy 179.88434 -308.658481)
			(xy 179.884832 -308.685438) (xy 186.690777 -308.685438) (xy 186.694712 -308.631667) (xy 186.706435 -308.579043)
			(xy 186.725695 -308.528686) (xy 186.752081 -308.481669) (xy 186.785033 -308.438996) (xy 186.823846 -308.401575)
			(xy 186.867694 -308.370205) (xy 186.915642 -308.345553) (xy 186.966669 -308.328145) (xy 187.019687 -308.318352)
			(xy 187.073566 -308.316383) (xy 187.127157 -308.32228) (xy 187.179318 -308.335916) (xy 187.228938 -308.357003)
			(xy 187.274959 -308.385089) (xy 187.316401 -308.419577) (xy 187.352379 -308.459731) (xy 187.382127 -308.504695)
			(xy 187.405012 -308.553512) (xy 187.420544 -308.605141) (xy 187.428394 -308.658481) (xy 187.428886 -308.685438)
			(xy 194.234831 -308.685438) (xy 194.238766 -308.631667) (xy 194.250489 -308.579043) (xy 194.269749 -308.528686)
			(xy 194.296135 -308.481669) (xy 194.329087 -308.438996) (xy 194.3679 -308.401575) (xy 194.411748 -308.370205)
			(xy 194.459696 -308.345553) (xy 194.510723 -308.328145) (xy 194.563741 -308.318352) (xy 194.61762 -308.316383)
			(xy 194.671211 -308.32228) (xy 194.723372 -308.335916) (xy 194.772992 -308.357003) (xy 194.819013 -308.385089)
			(xy 194.860455 -308.419577) (xy 194.896433 -308.459731) (xy 194.926181 -308.504695) (xy 194.949066 -308.553512)
			(xy 194.964598 -308.605141) (xy 194.972448 -308.658481) (xy 194.97294 -308.685438) (xy 201.778631 -308.685438)
			(xy 201.782566 -308.631667) (xy 201.794289 -308.579043) (xy 201.813549 -308.528686) (xy 201.839935 -308.481669)
			(xy 201.872887 -308.438996) (xy 201.9117 -308.401575) (xy 201.955548 -308.370205) (xy 202.003496 -308.345553)
			(xy 202.054523 -308.328145) (xy 202.107541 -308.318352) (xy 202.16142 -308.316383) (xy 202.215011 -308.32228)
			(xy 202.267172 -308.335916) (xy 202.316792 -308.357003) (xy 202.362813 -308.385089) (xy 202.404255 -308.419577)
			(xy 202.440233 -308.459731) (xy 202.469981 -308.504695) (xy 202.492866 -308.553512) (xy 202.508398 -308.605141)
			(xy 202.516248 -308.658481) (xy 202.51674 -308.685438) (xy 202.516248 -308.712395) (xy 202.508398 -308.765735)
			(xy 202.492866 -308.817364) (xy 202.469981 -308.866181) (xy 202.440233 -308.911145) (xy 202.404255 -308.951299)
			(xy 202.362813 -308.985787) (xy 202.316792 -309.013873) (xy 202.267172 -309.03496) (xy 202.215011 -309.048596)
			(xy 202.16142 -309.054493) (xy 202.107541 -309.052524) (xy 202.054523 -309.042731) (xy 202.003496 -309.025323)
			(xy 201.955548 -309.000671) (xy 201.9117 -308.969301) (xy 201.872887 -308.93188) (xy 201.839935 -308.889207)
			(xy 201.813549 -308.84219) (xy 201.794289 -308.791833) (xy 201.782566 -308.739209) (xy 201.778631 -308.685438)
			(xy 194.97294 -308.685438) (xy 194.972448 -308.712395) (xy 194.964598 -308.765735) (xy 194.949066 -308.817364)
			(xy 194.926181 -308.866181) (xy 194.896433 -308.911145) (xy 194.860455 -308.951299) (xy 194.819013 -308.985787)
			(xy 194.772992 -309.013873) (xy 194.723372 -309.03496) (xy 194.671211 -309.048596) (xy 194.61762 -309.054493)
			(xy 194.563741 -309.052524) (xy 194.510723 -309.042731) (xy 194.459696 -309.025323) (xy 194.411748 -309.000671)
			(xy 194.3679 -308.969301) (xy 194.329087 -308.93188) (xy 194.296135 -308.889207) (xy 194.269749 -308.84219)
			(xy 194.250489 -308.791833) (xy 194.238766 -308.739209) (xy 194.234831 -308.685438) (xy 187.428886 -308.685438)
			(xy 187.428394 -308.712395) (xy 187.420544 -308.765735) (xy 187.405012 -308.817364) (xy 187.382127 -308.866181)
			(xy 187.352379 -308.911145) (xy 187.316401 -308.951299) (xy 187.274959 -308.985787) (xy 187.228938 -309.013873)
			(xy 187.179318 -309.03496) (xy 187.127157 -309.048596) (xy 187.073566 -309.054493) (xy 187.019687 -309.052524)
			(xy 186.966669 -309.042731) (xy 186.915642 -309.025323) (xy 186.867694 -309.000671) (xy 186.823846 -308.969301)
			(xy 186.785033 -308.93188) (xy 186.752081 -308.889207) (xy 186.725695 -308.84219) (xy 186.706435 -308.791833)
			(xy 186.694712 -308.739209) (xy 186.690777 -308.685438) (xy 179.884832 -308.685438) (xy 179.88434 -308.712395)
			(xy 179.87649 -308.765735) (xy 179.860958 -308.817364) (xy 179.838073 -308.866181) (xy 179.808325 -308.911145)
			(xy 179.772347 -308.951299) (xy 179.730905 -308.985787) (xy 179.684884 -309.013873) (xy 179.635264 -309.03496)
			(xy 179.583103 -309.048596) (xy 179.529512 -309.054493) (xy 179.475633 -309.052524) (xy 179.422615 -309.042731)
			(xy 179.371588 -309.025323) (xy 179.32364 -309.000671) (xy 179.279792 -308.969301) (xy 179.240979 -308.93188)
			(xy 179.208027 -308.889207) (xy 179.181641 -308.84219) (xy 179.162381 -308.791833) (xy 179.150658 -308.739209)
			(xy 179.146723 -308.685438) (xy 177.881534 -308.685438) (xy 177.881534 -309.535322) (xy 183.246791 -309.535322)
			(xy 183.250726 -309.481551) (xy 183.262449 -309.428927) (xy 183.281709 -309.37857) (xy 183.308095 -309.331553)
			(xy 183.341047 -309.28888) (xy 183.37986 -309.251459) (xy 183.423708 -309.220089) (xy 183.471656 -309.195437)
			(xy 183.522683 -309.178029) (xy 183.575701 -309.168236) (xy 183.62958 -309.166267) (xy 183.683171 -309.172164)
			(xy 183.735332 -309.1858) (xy 183.784952 -309.206887) (xy 183.830973 -309.234973) (xy 183.872415 -309.269461)
			(xy 183.908393 -309.309615) (xy 183.938141 -309.354579) (xy 183.961026 -309.403396) (xy 183.976558 -309.455025)
			(xy 183.984408 -309.508365) (xy 183.9849 -309.535322) (xy 190.790845 -309.535322) (xy 190.79478 -309.481551)
			(xy 190.806503 -309.428927) (xy 190.825763 -309.37857) (xy 190.852149 -309.331553) (xy 190.885101 -309.28888)
			(xy 190.923914 -309.251459) (xy 190.967762 -309.220089) (xy 191.01571 -309.195437) (xy 191.066737 -309.178029)
			(xy 191.119755 -309.168236) (xy 191.173634 -309.166267) (xy 191.227225 -309.172164) (xy 191.279386 -309.1858)
			(xy 191.329006 -309.206887) (xy 191.375027 -309.234973) (xy 191.416469 -309.269461) (xy 191.452447 -309.309615)
			(xy 191.482195 -309.354579) (xy 191.50508 -309.403396) (xy 191.520612 -309.455025) (xy 191.528462 -309.508365)
			(xy 191.528954 -309.535322) (xy 198.334899 -309.535322) (xy 198.338834 -309.481551) (xy 198.350557 -309.428927)
			(xy 198.369817 -309.37857) (xy 198.396203 -309.331553) (xy 198.429155 -309.28888) (xy 198.467968 -309.251459)
			(xy 198.511816 -309.220089) (xy 198.559764 -309.195437) (xy 198.610791 -309.178029) (xy 198.663809 -309.168236)
			(xy 198.717688 -309.166267) (xy 198.771279 -309.172164) (xy 198.82344 -309.1858) (xy 198.87306 -309.206887)
			(xy 198.919081 -309.234973) (xy 198.960523 -309.269461) (xy 198.996501 -309.309615) (xy 199.026249 -309.354579)
			(xy 199.049134 -309.403396) (xy 199.064666 -309.455025) (xy 199.072516 -309.508365) (xy 199.073008 -309.535322)
			(xy 205.878699 -309.535322) (xy 205.882634 -309.481551) (xy 205.894357 -309.428927) (xy 205.913617 -309.37857)
			(xy 205.940003 -309.331553) (xy 205.972955 -309.28888) (xy 206.011768 -309.251459) (xy 206.055616 -309.220089)
			(xy 206.103564 -309.195437) (xy 206.154591 -309.178029) (xy 206.207609 -309.168236) (xy 206.261488 -309.166267)
			(xy 206.315079 -309.172164) (xy 206.36724 -309.1858) (xy 206.41686 -309.206887) (xy 206.462881 -309.234973)
			(xy 206.504323 -309.269461) (xy 206.540301 -309.309615) (xy 206.570049 -309.354579) (xy 206.592934 -309.403396)
			(xy 206.608466 -309.455025) (xy 206.616316 -309.508365) (xy 206.616808 -309.535322) (xy 206.616316 -309.562279)
			(xy 206.608466 -309.615619) (xy 206.592934 -309.667248) (xy 206.570049 -309.716065) (xy 206.540301 -309.761029)
			(xy 206.504323 -309.801183) (xy 206.462881 -309.835671) (xy 206.41686 -309.863757) (xy 206.36724 -309.884844)
			(xy 206.315079 -309.89848) (xy 206.261488 -309.904377) (xy 206.207609 -309.902408) (xy 206.154591 -309.892615)
			(xy 206.103564 -309.875207) (xy 206.055616 -309.850555) (xy 206.011768 -309.819185) (xy 205.972955 -309.781764)
			(xy 205.940003 -309.739091) (xy 205.913617 -309.692074) (xy 205.894357 -309.641717) (xy 205.882634 -309.589093)
			(xy 205.878699 -309.535322) (xy 199.073008 -309.535322) (xy 199.072516 -309.562279) (xy 199.064666 -309.615619)
			(xy 199.049134 -309.667248) (xy 199.026249 -309.716065) (xy 198.996501 -309.761029) (xy 198.960523 -309.801183)
			(xy 198.919081 -309.835671) (xy 198.87306 -309.863757) (xy 198.82344 -309.884844) (xy 198.771279 -309.89848)
			(xy 198.717688 -309.904377) (xy 198.663809 -309.902408) (xy 198.610791 -309.892615) (xy 198.559764 -309.875207)
			(xy 198.511816 -309.850555) (xy 198.467968 -309.819185) (xy 198.429155 -309.781764) (xy 198.396203 -309.739091)
			(xy 198.369817 -309.692074) (xy 198.350557 -309.641717) (xy 198.338834 -309.589093) (xy 198.334899 -309.535322)
			(xy 191.528954 -309.535322) (xy 191.528462 -309.562279) (xy 191.520612 -309.615619) (xy 191.50508 -309.667248)
			(xy 191.482195 -309.716065) (xy 191.452447 -309.761029) (xy 191.416469 -309.801183) (xy 191.375027 -309.835671)
			(xy 191.329006 -309.863757) (xy 191.279386 -309.884844) (xy 191.227225 -309.89848) (xy 191.173634 -309.904377)
			(xy 191.119755 -309.902408) (xy 191.066737 -309.892615) (xy 191.01571 -309.875207) (xy 190.967762 -309.850555)
			(xy 190.923914 -309.819185) (xy 190.885101 -309.781764) (xy 190.852149 -309.739091) (xy 190.825763 -309.692074)
			(xy 190.806503 -309.641717) (xy 190.79478 -309.589093) (xy 190.790845 -309.535322) (xy 183.9849 -309.535322)
			(xy 183.984408 -309.562279) (xy 183.976558 -309.615619) (xy 183.961026 -309.667248) (xy 183.938141 -309.716065)
			(xy 183.908393 -309.761029) (xy 183.872415 -309.801183) (xy 183.830973 -309.835671) (xy 183.784952 -309.863757)
			(xy 183.735332 -309.884844) (xy 183.683171 -309.89848) (xy 183.62958 -309.904377) (xy 183.575701 -309.902408)
			(xy 183.522683 -309.892615) (xy 183.471656 -309.875207) (xy 183.423708 -309.850555) (xy 183.37986 -309.819185)
			(xy 183.341047 -309.781764) (xy 183.308095 -309.739091) (xy 183.281709 -309.692074) (xy 183.262449 -309.641717)
			(xy 183.250726 -309.589093) (xy 183.246791 -309.535322) (xy 177.881534 -309.535322) (xy 177.881534 -310.385206)
			(xy 179.146723 -310.385206) (xy 179.150658 -310.331435) (xy 179.162381 -310.278811) (xy 179.181641 -310.228454)
			(xy 179.208027 -310.181437) (xy 179.240979 -310.138764) (xy 179.279792 -310.101343) (xy 179.32364 -310.069973)
			(xy 179.371588 -310.045321) (xy 179.422615 -310.027913) (xy 179.475633 -310.01812) (xy 179.529512 -310.016151)
			(xy 179.583103 -310.022048) (xy 179.635264 -310.035684) (xy 179.684884 -310.056771) (xy 179.730905 -310.084857)
			(xy 179.772347 -310.119345) (xy 179.808325 -310.159499) (xy 179.838073 -310.204463) (xy 179.860958 -310.25328)
			(xy 179.87649 -310.304909) (xy 179.88434 -310.358249) (xy 179.884832 -310.385206) (xy 186.690777 -310.385206)
			(xy 186.694712 -310.331435) (xy 186.706435 -310.278811) (xy 186.725695 -310.228454) (xy 186.752081 -310.181437)
			(xy 186.785033 -310.138764) (xy 186.823846 -310.101343) (xy 186.867694 -310.069973) (xy 186.915642 -310.045321)
			(xy 186.966669 -310.027913) (xy 187.019687 -310.01812) (xy 187.073566 -310.016151) (xy 187.127157 -310.022048)
			(xy 187.179318 -310.035684) (xy 187.228938 -310.056771) (xy 187.274959 -310.084857) (xy 187.316401 -310.119345)
			(xy 187.352379 -310.159499) (xy 187.382127 -310.204463) (xy 187.405012 -310.25328) (xy 187.420544 -310.304909)
			(xy 187.428394 -310.358249) (xy 187.428886 -310.385206) (xy 194.234831 -310.385206) (xy 194.238766 -310.331435)
			(xy 194.250489 -310.278811) (xy 194.269749 -310.228454) (xy 194.296135 -310.181437) (xy 194.329087 -310.138764)
			(xy 194.3679 -310.101343) (xy 194.411748 -310.069973) (xy 194.459696 -310.045321) (xy 194.510723 -310.027913)
			(xy 194.563741 -310.01812) (xy 194.61762 -310.016151) (xy 194.671211 -310.022048) (xy 194.723372 -310.035684)
			(xy 194.772992 -310.056771) (xy 194.819013 -310.084857) (xy 194.860455 -310.119345) (xy 194.896433 -310.159499)
			(xy 194.926181 -310.204463) (xy 194.949066 -310.25328) (xy 194.964598 -310.304909) (xy 194.972448 -310.358249)
			(xy 194.97294 -310.385206) (xy 201.778631 -310.385206) (xy 201.782566 -310.331435) (xy 201.794289 -310.278811)
			(xy 201.813549 -310.228454) (xy 201.839935 -310.181437) (xy 201.872887 -310.138764) (xy 201.9117 -310.101343)
			(xy 201.955548 -310.069973) (xy 202.003496 -310.045321) (xy 202.054523 -310.027913) (xy 202.107541 -310.01812)
			(xy 202.16142 -310.016151) (xy 202.215011 -310.022048) (xy 202.267172 -310.035684) (xy 202.316792 -310.056771)
			(xy 202.362813 -310.084857) (xy 202.404255 -310.119345) (xy 202.440233 -310.159499) (xy 202.469981 -310.204463)
			(xy 202.492866 -310.25328) (xy 202.508398 -310.304909) (xy 202.516248 -310.358249) (xy 202.51674 -310.385206)
			(xy 202.516248 -310.412163) (xy 202.508398 -310.465503) (xy 202.492866 -310.517132) (xy 202.469981 -310.565949)
			(xy 202.440233 -310.610913) (xy 202.404255 -310.651067) (xy 202.362813 -310.685555) (xy 202.316792 -310.713641)
			(xy 202.267172 -310.734728) (xy 202.215011 -310.748364) (xy 202.16142 -310.754261) (xy 202.107541 -310.752292)
			(xy 202.054523 -310.742499) (xy 202.003496 -310.725091) (xy 201.955548 -310.700439) (xy 201.9117 -310.669069)
			(xy 201.872887 -310.631648) (xy 201.839935 -310.588975) (xy 201.813549 -310.541958) (xy 201.794289 -310.491601)
			(xy 201.782566 -310.438977) (xy 201.778631 -310.385206) (xy 194.97294 -310.385206) (xy 194.972448 -310.412163)
			(xy 194.964598 -310.465503) (xy 194.949066 -310.517132) (xy 194.926181 -310.565949) (xy 194.896433 -310.610913)
			(xy 194.860455 -310.651067) (xy 194.819013 -310.685555) (xy 194.772992 -310.713641) (xy 194.723372 -310.734728)
			(xy 194.671211 -310.748364) (xy 194.61762 -310.754261) (xy 194.563741 -310.752292) (xy 194.510723 -310.742499)
			(xy 194.459696 -310.725091) (xy 194.411748 -310.700439) (xy 194.3679 -310.669069) (xy 194.329087 -310.631648)
			(xy 194.296135 -310.588975) (xy 194.269749 -310.541958) (xy 194.250489 -310.491601) (xy 194.238766 -310.438977)
			(xy 194.234831 -310.385206) (xy 187.428886 -310.385206) (xy 187.428394 -310.412163) (xy 187.420544 -310.465503)
			(xy 187.405012 -310.517132) (xy 187.382127 -310.565949) (xy 187.352379 -310.610913) (xy 187.316401 -310.651067)
			(xy 187.274959 -310.685555) (xy 187.228938 -310.713641) (xy 187.179318 -310.734728) (xy 187.127157 -310.748364)
			(xy 187.073566 -310.754261) (xy 187.019687 -310.752292) (xy 186.966669 -310.742499) (xy 186.915642 -310.725091)
			(xy 186.867694 -310.700439) (xy 186.823846 -310.669069) (xy 186.785033 -310.631648) (xy 186.752081 -310.588975)
			(xy 186.725695 -310.541958) (xy 186.706435 -310.491601) (xy 186.694712 -310.438977) (xy 186.690777 -310.385206)
			(xy 179.884832 -310.385206) (xy 179.88434 -310.412163) (xy 179.87649 -310.465503) (xy 179.860958 -310.517132)
			(xy 179.838073 -310.565949) (xy 179.808325 -310.610913) (xy 179.772347 -310.651067) (xy 179.730905 -310.685555)
			(xy 179.684884 -310.713641) (xy 179.635264 -310.734728) (xy 179.583103 -310.748364) (xy 179.529512 -310.754261)
			(xy 179.475633 -310.752292) (xy 179.422615 -310.742499) (xy 179.371588 -310.725091) (xy 179.32364 -310.700439)
			(xy 179.279792 -310.669069) (xy 179.240979 -310.631648) (xy 179.208027 -310.588975) (xy 179.181641 -310.541958)
			(xy 179.162381 -310.491601) (xy 179.150658 -310.438977) (xy 179.146723 -310.385206) (xy 177.881534 -310.385206)
			(xy 177.881534 -311.235344) (xy 183.246791 -311.235344) (xy 183.250726 -311.181573) (xy 183.262449 -311.128949)
			(xy 183.281709 -311.078592) (xy 183.308095 -311.031575) (xy 183.341047 -310.988902) (xy 183.37986 -310.951481)
			(xy 183.423708 -310.920111) (xy 183.471656 -310.895459) (xy 183.522683 -310.878051) (xy 183.575701 -310.868258)
			(xy 183.62958 -310.866289) (xy 183.683171 -310.872186) (xy 183.735332 -310.885822) (xy 183.784952 -310.906909)
			(xy 183.830973 -310.934995) (xy 183.872415 -310.969483) (xy 183.908393 -311.009637) (xy 183.938141 -311.054601)
			(xy 183.961026 -311.103418) (xy 183.976558 -311.155047) (xy 183.984408 -311.208387) (xy 183.9849 -311.235344)
			(xy 190.790845 -311.235344) (xy 190.79478 -311.181573) (xy 190.806503 -311.128949) (xy 190.825763 -311.078592)
			(xy 190.852149 -311.031575) (xy 190.885101 -310.988902) (xy 190.923914 -310.951481) (xy 190.967762 -310.920111)
			(xy 191.01571 -310.895459) (xy 191.066737 -310.878051) (xy 191.119755 -310.868258) (xy 191.173634 -310.866289)
			(xy 191.227225 -310.872186) (xy 191.279386 -310.885822) (xy 191.329006 -310.906909) (xy 191.375027 -310.934995)
			(xy 191.416469 -310.969483) (xy 191.452447 -311.009637) (xy 191.482195 -311.054601) (xy 191.50508 -311.103418)
			(xy 191.520612 -311.155047) (xy 191.528462 -311.208387) (xy 191.528954 -311.235344) (xy 198.334899 -311.235344)
			(xy 198.338834 -311.181573) (xy 198.350557 -311.128949) (xy 198.369817 -311.078592) (xy 198.396203 -311.031575)
			(xy 198.429155 -310.988902) (xy 198.467968 -310.951481) (xy 198.511816 -310.920111) (xy 198.559764 -310.895459)
			(xy 198.610791 -310.878051) (xy 198.663809 -310.868258) (xy 198.717688 -310.866289) (xy 198.771279 -310.872186)
			(xy 198.82344 -310.885822) (xy 198.87306 -310.906909) (xy 198.919081 -310.934995) (xy 198.960523 -310.969483)
			(xy 198.996501 -311.009637) (xy 199.026249 -311.054601) (xy 199.049134 -311.103418) (xy 199.064666 -311.155047)
			(xy 199.072516 -311.208387) (xy 199.073008 -311.235344) (xy 205.878699 -311.235344) (xy 205.882634 -311.181573)
			(xy 205.894357 -311.128949) (xy 205.913617 -311.078592) (xy 205.940003 -311.031575) (xy 205.972955 -310.988902)
			(xy 206.011768 -310.951481) (xy 206.055616 -310.920111) (xy 206.103564 -310.895459) (xy 206.154591 -310.878051)
			(xy 206.207609 -310.868258) (xy 206.261488 -310.866289) (xy 206.315079 -310.872186) (xy 206.36724 -310.885822)
			(xy 206.41686 -310.906909) (xy 206.462881 -310.934995) (xy 206.504323 -310.969483) (xy 206.540301 -311.009637)
			(xy 206.570049 -311.054601) (xy 206.592934 -311.103418) (xy 206.608466 -311.155047) (xy 206.616316 -311.208387)
			(xy 206.616808 -311.235344) (xy 206.616316 -311.262301) (xy 206.608466 -311.315641) (xy 206.592934 -311.36727)
			(xy 206.570049 -311.416087) (xy 206.540301 -311.461051) (xy 206.504323 -311.501205) (xy 206.462881 -311.535693)
			(xy 206.41686 -311.563779) (xy 206.36724 -311.584866) (xy 206.315079 -311.598502) (xy 206.261488 -311.604399)
			(xy 206.207609 -311.60243) (xy 206.154591 -311.592637) (xy 206.103564 -311.575229) (xy 206.055616 -311.550577)
			(xy 206.011768 -311.519207) (xy 205.972955 -311.481786) (xy 205.940003 -311.439113) (xy 205.913617 -311.392096)
			(xy 205.894357 -311.341739) (xy 205.882634 -311.289115) (xy 205.878699 -311.235344) (xy 199.073008 -311.235344)
			(xy 199.072516 -311.262301) (xy 199.064666 -311.315641) (xy 199.049134 -311.36727) (xy 199.026249 -311.416087)
			(xy 198.996501 -311.461051) (xy 198.960523 -311.501205) (xy 198.919081 -311.535693) (xy 198.87306 -311.563779)
			(xy 198.82344 -311.584866) (xy 198.771279 -311.598502) (xy 198.717688 -311.604399) (xy 198.663809 -311.60243)
			(xy 198.610791 -311.592637) (xy 198.559764 -311.575229) (xy 198.511816 -311.550577) (xy 198.467968 -311.519207)
			(xy 198.429155 -311.481786) (xy 198.396203 -311.439113) (xy 198.369817 -311.392096) (xy 198.350557 -311.341739)
			(xy 198.338834 -311.289115) (xy 198.334899 -311.235344) (xy 191.528954 -311.235344) (xy 191.528462 -311.262301)
			(xy 191.520612 -311.315641) (xy 191.50508 -311.36727) (xy 191.482195 -311.416087) (xy 191.452447 -311.461051)
			(xy 191.416469 -311.501205) (xy 191.375027 -311.535693) (xy 191.329006 -311.563779) (xy 191.279386 -311.584866)
			(xy 191.227225 -311.598502) (xy 191.173634 -311.604399) (xy 191.119755 -311.60243) (xy 191.066737 -311.592637)
			(xy 191.01571 -311.575229) (xy 190.967762 -311.550577) (xy 190.923914 -311.519207) (xy 190.885101 -311.481786)
			(xy 190.852149 -311.439113) (xy 190.825763 -311.392096) (xy 190.806503 -311.341739) (xy 190.79478 -311.289115)
			(xy 190.790845 -311.235344) (xy 183.9849 -311.235344) (xy 183.984408 -311.262301) (xy 183.976558 -311.315641)
			(xy 183.961026 -311.36727) (xy 183.938141 -311.416087) (xy 183.908393 -311.461051) (xy 183.872415 -311.501205)
			(xy 183.830973 -311.535693) (xy 183.784952 -311.563779) (xy 183.735332 -311.584866) (xy 183.683171 -311.598502)
			(xy 183.62958 -311.604399) (xy 183.575701 -311.60243) (xy 183.522683 -311.592637) (xy 183.471656 -311.575229)
			(xy 183.423708 -311.550577) (xy 183.37986 -311.519207) (xy 183.341047 -311.481786) (xy 183.308095 -311.439113)
			(xy 183.281709 -311.392096) (xy 183.262449 -311.341739) (xy 183.250726 -311.289115) (xy 183.246791 -311.235344)
			(xy 177.881534 -311.235344) (xy 177.881534 -312.085228) (xy 179.146723 -312.085228) (xy 179.150658 -312.031457)
			(xy 179.162381 -311.978833) (xy 179.181641 -311.928476) (xy 179.208027 -311.881459) (xy 179.240979 -311.838786)
			(xy 179.279792 -311.801365) (xy 179.32364 -311.769995) (xy 179.371588 -311.745343) (xy 179.422615 -311.727935)
			(xy 179.475633 -311.718142) (xy 179.529512 -311.716173) (xy 179.583103 -311.72207) (xy 179.635264 -311.735706)
			(xy 179.684884 -311.756793) (xy 179.730905 -311.784879) (xy 179.772347 -311.819367) (xy 179.808325 -311.859521)
			(xy 179.838073 -311.904485) (xy 179.860958 -311.953302) (xy 179.87649 -312.004931) (xy 179.88434 -312.058271)
			(xy 179.884832 -312.085228) (xy 186.690777 -312.085228) (xy 186.694712 -312.031457) (xy 186.706435 -311.978833)
			(xy 186.725695 -311.928476) (xy 186.752081 -311.881459) (xy 186.785033 -311.838786) (xy 186.823846 -311.801365)
			(xy 186.867694 -311.769995) (xy 186.915642 -311.745343) (xy 186.966669 -311.727935) (xy 187.019687 -311.718142)
			(xy 187.073566 -311.716173) (xy 187.127157 -311.72207) (xy 187.179318 -311.735706) (xy 187.228938 -311.756793)
			(xy 187.274959 -311.784879) (xy 187.316401 -311.819367) (xy 187.352379 -311.859521) (xy 187.382127 -311.904485)
			(xy 187.405012 -311.953302) (xy 187.420544 -312.004931) (xy 187.428394 -312.058271) (xy 187.428886 -312.085228)
			(xy 194.234831 -312.085228) (xy 194.238766 -312.031457) (xy 194.250489 -311.978833) (xy 194.269749 -311.928476)
			(xy 194.296135 -311.881459) (xy 194.329087 -311.838786) (xy 194.3679 -311.801365) (xy 194.411748 -311.769995)
			(xy 194.459696 -311.745343) (xy 194.510723 -311.727935) (xy 194.563741 -311.718142) (xy 194.61762 -311.716173)
			(xy 194.671211 -311.72207) (xy 194.723372 -311.735706) (xy 194.772992 -311.756793) (xy 194.819013 -311.784879)
			(xy 194.860455 -311.819367) (xy 194.896433 -311.859521) (xy 194.926181 -311.904485) (xy 194.949066 -311.953302)
			(xy 194.964598 -312.004931) (xy 194.972448 -312.058271) (xy 194.97294 -312.085228) (xy 201.778631 -312.085228)
			(xy 201.782566 -312.031457) (xy 201.794289 -311.978833) (xy 201.813549 -311.928476) (xy 201.839935 -311.881459)
			(xy 201.872887 -311.838786) (xy 201.9117 -311.801365) (xy 201.955548 -311.769995) (xy 202.003496 -311.745343)
			(xy 202.054523 -311.727935) (xy 202.107541 -311.718142) (xy 202.16142 -311.716173) (xy 202.215011 -311.72207)
			(xy 202.267172 -311.735706) (xy 202.316792 -311.756793) (xy 202.362813 -311.784879) (xy 202.404255 -311.819367)
			(xy 202.440233 -311.859521) (xy 202.469981 -311.904485) (xy 202.492866 -311.953302) (xy 202.508398 -312.004931)
			(xy 202.516248 -312.058271) (xy 202.51674 -312.085228) (xy 202.516248 -312.112185) (xy 202.508398 -312.165525)
			(xy 202.492866 -312.217154) (xy 202.469981 -312.265971) (xy 202.440233 -312.310935) (xy 202.404255 -312.351089)
			(xy 202.362813 -312.385577) (xy 202.316792 -312.413663) (xy 202.267172 -312.43475) (xy 202.215011 -312.448386)
			(xy 202.16142 -312.454283) (xy 202.107541 -312.452314) (xy 202.054523 -312.442521) (xy 202.003496 -312.425113)
			(xy 201.955548 -312.400461) (xy 201.9117 -312.369091) (xy 201.872887 -312.33167) (xy 201.839935 -312.288997)
			(xy 201.813549 -312.24198) (xy 201.794289 -312.191623) (xy 201.782566 -312.138999) (xy 201.778631 -312.085228)
			(xy 194.97294 -312.085228) (xy 194.972448 -312.112185) (xy 194.964598 -312.165525) (xy 194.949066 -312.217154)
			(xy 194.926181 -312.265971) (xy 194.896433 -312.310935) (xy 194.860455 -312.351089) (xy 194.819013 -312.385577)
			(xy 194.772992 -312.413663) (xy 194.723372 -312.43475) (xy 194.671211 -312.448386) (xy 194.61762 -312.454283)
			(xy 194.563741 -312.452314) (xy 194.510723 -312.442521) (xy 194.459696 -312.425113) (xy 194.411748 -312.400461)
			(xy 194.3679 -312.369091) (xy 194.329087 -312.33167) (xy 194.296135 -312.288997) (xy 194.269749 -312.24198)
			(xy 194.250489 -312.191623) (xy 194.238766 -312.138999) (xy 194.234831 -312.085228) (xy 187.428886 -312.085228)
			(xy 187.428394 -312.112185) (xy 187.420544 -312.165525) (xy 187.405012 -312.217154) (xy 187.382127 -312.265971)
			(xy 187.352379 -312.310935) (xy 187.316401 -312.351089) (xy 187.274959 -312.385577) (xy 187.228938 -312.413663)
			(xy 187.179318 -312.43475) (xy 187.127157 -312.448386) (xy 187.073566 -312.454283) (xy 187.019687 -312.452314)
			(xy 186.966669 -312.442521) (xy 186.915642 -312.425113) (xy 186.867694 -312.400461) (xy 186.823846 -312.369091)
			(xy 186.785033 -312.33167) (xy 186.752081 -312.288997) (xy 186.725695 -312.24198) (xy 186.706435 -312.191623)
			(xy 186.694712 -312.138999) (xy 186.690777 -312.085228) (xy 179.884832 -312.085228) (xy 179.88434 -312.112185)
			(xy 179.87649 -312.165525) (xy 179.860958 -312.217154) (xy 179.838073 -312.265971) (xy 179.808325 -312.310935)
			(xy 179.772347 -312.351089) (xy 179.730905 -312.385577) (xy 179.684884 -312.413663) (xy 179.635264 -312.43475)
			(xy 179.583103 -312.448386) (xy 179.529512 -312.454283) (xy 179.475633 -312.452314) (xy 179.422615 -312.442521)
			(xy 179.371588 -312.425113) (xy 179.32364 -312.400461) (xy 179.279792 -312.369091) (xy 179.240979 -312.33167)
			(xy 179.208027 -312.288997) (xy 179.181641 -312.24198) (xy 179.162381 -312.191623) (xy 179.150658 -312.138999)
			(xy 179.146723 -312.085228) (xy 177.881534 -312.085228) (xy 177.881534 -312.935366) (xy 183.246791 -312.935366)
			(xy 183.250726 -312.881595) (xy 183.262449 -312.828971) (xy 183.281709 -312.778614) (xy 183.308095 -312.731597)
			(xy 183.341047 -312.688924) (xy 183.37986 -312.651503) (xy 183.423708 -312.620133) (xy 183.471656 -312.595481)
			(xy 183.522683 -312.578073) (xy 183.575701 -312.56828) (xy 183.62958 -312.566311) (xy 183.683171 -312.572208)
			(xy 183.735332 -312.585844) (xy 183.784952 -312.606931) (xy 183.830973 -312.635017) (xy 183.872415 -312.669505)
			(xy 183.908393 -312.709659) (xy 183.938141 -312.754623) (xy 183.961026 -312.80344) (xy 183.976558 -312.855069)
			(xy 183.984408 -312.908409) (xy 183.9849 -312.935366) (xy 190.790845 -312.935366) (xy 190.79478 -312.881595)
			(xy 190.806503 -312.828971) (xy 190.825763 -312.778614) (xy 190.852149 -312.731597) (xy 190.885101 -312.688924)
			(xy 190.923914 -312.651503) (xy 190.967762 -312.620133) (xy 191.01571 -312.595481) (xy 191.066737 -312.578073)
			(xy 191.119755 -312.56828) (xy 191.173634 -312.566311) (xy 191.227225 -312.572208) (xy 191.279386 -312.585844)
			(xy 191.329006 -312.606931) (xy 191.375027 -312.635017) (xy 191.416469 -312.669505) (xy 191.452447 -312.709659)
			(xy 191.482195 -312.754623) (xy 191.50508 -312.80344) (xy 191.520612 -312.855069) (xy 191.528462 -312.908409)
			(xy 191.528954 -312.935366) (xy 198.334899 -312.935366) (xy 198.338834 -312.881595) (xy 198.350557 -312.828971)
			(xy 198.369817 -312.778614) (xy 198.396203 -312.731597) (xy 198.429155 -312.688924) (xy 198.467968 -312.651503)
			(xy 198.511816 -312.620133) (xy 198.559764 -312.595481) (xy 198.610791 -312.578073) (xy 198.663809 -312.56828)
			(xy 198.717688 -312.566311) (xy 198.771279 -312.572208) (xy 198.82344 -312.585844) (xy 198.87306 -312.606931)
			(xy 198.919081 -312.635017) (xy 198.960523 -312.669505) (xy 198.996501 -312.709659) (xy 199.026249 -312.754623)
			(xy 199.049134 -312.80344) (xy 199.064666 -312.855069) (xy 199.072516 -312.908409) (xy 199.073008 -312.935366)
			(xy 205.878699 -312.935366) (xy 205.882634 -312.881595) (xy 205.894357 -312.828971) (xy 205.913617 -312.778614)
			(xy 205.940003 -312.731597) (xy 205.972955 -312.688924) (xy 206.011768 -312.651503) (xy 206.055616 -312.620133)
			(xy 206.103564 -312.595481) (xy 206.154591 -312.578073) (xy 206.207609 -312.56828) (xy 206.261488 -312.566311)
			(xy 206.315079 -312.572208) (xy 206.36724 -312.585844) (xy 206.41686 -312.606931) (xy 206.462881 -312.635017)
			(xy 206.504323 -312.669505) (xy 206.540301 -312.709659) (xy 206.570049 -312.754623) (xy 206.592934 -312.80344)
			(xy 206.608466 -312.855069) (xy 206.616316 -312.908409) (xy 206.616808 -312.935366) (xy 206.616316 -312.962323)
			(xy 206.608466 -313.015663) (xy 206.592934 -313.067292) (xy 206.570049 -313.116109) (xy 206.540301 -313.161073)
			(xy 206.504323 -313.201227) (xy 206.462881 -313.235715) (xy 206.41686 -313.263801) (xy 206.36724 -313.284888)
			(xy 206.315079 -313.298524) (xy 206.261488 -313.304421) (xy 206.207609 -313.302452) (xy 206.154591 -313.292659)
			(xy 206.103564 -313.275251) (xy 206.055616 -313.250599) (xy 206.011768 -313.219229) (xy 205.972955 -313.181808)
			(xy 205.940003 -313.139135) (xy 205.913617 -313.092118) (xy 205.894357 -313.041761) (xy 205.882634 -312.989137)
			(xy 205.878699 -312.935366) (xy 199.073008 -312.935366) (xy 199.072516 -312.962323) (xy 199.064666 -313.015663)
			(xy 199.049134 -313.067292) (xy 199.026249 -313.116109) (xy 198.996501 -313.161073) (xy 198.960523 -313.201227)
			(xy 198.919081 -313.235715) (xy 198.87306 -313.263801) (xy 198.82344 -313.284888) (xy 198.771279 -313.298524)
			(xy 198.717688 -313.304421) (xy 198.663809 -313.302452) (xy 198.610791 -313.292659) (xy 198.559764 -313.275251)
			(xy 198.511816 -313.250599) (xy 198.467968 -313.219229) (xy 198.429155 -313.181808) (xy 198.396203 -313.139135)
			(xy 198.369817 -313.092118) (xy 198.350557 -313.041761) (xy 198.338834 -312.989137) (xy 198.334899 -312.935366)
			(xy 191.528954 -312.935366) (xy 191.528462 -312.962323) (xy 191.520612 -313.015663) (xy 191.50508 -313.067292)
			(xy 191.482195 -313.116109) (xy 191.452447 -313.161073) (xy 191.416469 -313.201227) (xy 191.375027 -313.235715)
			(xy 191.329006 -313.263801) (xy 191.279386 -313.284888) (xy 191.227225 -313.298524) (xy 191.173634 -313.304421)
			(xy 191.119755 -313.302452) (xy 191.066737 -313.292659) (xy 191.01571 -313.275251) (xy 190.967762 -313.250599)
			(xy 190.923914 -313.219229) (xy 190.885101 -313.181808) (xy 190.852149 -313.139135) (xy 190.825763 -313.092118)
			(xy 190.806503 -313.041761) (xy 190.79478 -312.989137) (xy 190.790845 -312.935366) (xy 183.9849 -312.935366)
			(xy 183.984408 -312.962323) (xy 183.976558 -313.015663) (xy 183.961026 -313.067292) (xy 183.938141 -313.116109)
			(xy 183.908393 -313.161073) (xy 183.872415 -313.201227) (xy 183.830973 -313.235715) (xy 183.784952 -313.263801)
			(xy 183.735332 -313.284888) (xy 183.683171 -313.298524) (xy 183.62958 -313.304421) (xy 183.575701 -313.302452)
			(xy 183.522683 -313.292659) (xy 183.471656 -313.275251) (xy 183.423708 -313.250599) (xy 183.37986 -313.219229)
			(xy 183.341047 -313.181808) (xy 183.308095 -313.139135) (xy 183.281709 -313.092118) (xy 183.262449 -313.041761)
			(xy 183.250726 -312.989137) (xy 183.246791 -312.935366) (xy 177.881534 -312.935366) (xy 177.881534 -313.78525)
			(xy 179.146723 -313.78525) (xy 179.150658 -313.731479) (xy 179.162381 -313.678855) (xy 179.181641 -313.628498)
			(xy 179.208027 -313.581481) (xy 179.240979 -313.538808) (xy 179.279792 -313.501387) (xy 179.32364 -313.470017)
			(xy 179.371588 -313.445365) (xy 179.422615 -313.427957) (xy 179.475633 -313.418164) (xy 179.529512 -313.416195)
			(xy 179.583103 -313.422092) (xy 179.635264 -313.435728) (xy 179.684884 -313.456815) (xy 179.730905 -313.484901)
			(xy 179.772347 -313.519389) (xy 179.808325 -313.559543) (xy 179.838073 -313.604507) (xy 179.860958 -313.653324)
			(xy 179.87649 -313.704953) (xy 179.88434 -313.758293) (xy 179.884832 -313.78525) (xy 183.246791 -313.78525)
			(xy 183.250726 -313.731479) (xy 183.262449 -313.678855) (xy 183.281709 -313.628498) (xy 183.308095 -313.581481)
			(xy 183.341047 -313.538808) (xy 183.37986 -313.501387) (xy 183.423708 -313.470017) (xy 183.471656 -313.445365)
			(xy 183.522683 -313.427957) (xy 183.575701 -313.418164) (xy 183.62958 -313.416195) (xy 183.683171 -313.422092)
			(xy 183.735332 -313.435728) (xy 183.784952 -313.456815) (xy 183.830973 -313.484901) (xy 183.872415 -313.519389)
			(xy 183.908393 -313.559543) (xy 183.938141 -313.604507) (xy 183.961026 -313.653324) (xy 183.976558 -313.704953)
			(xy 183.984408 -313.758293) (xy 183.9849 -313.78525) (xy 186.690777 -313.78525) (xy 186.694712 -313.731479)
			(xy 186.706435 -313.678855) (xy 186.725695 -313.628498) (xy 186.752081 -313.581481) (xy 186.785033 -313.538808)
			(xy 186.823846 -313.501387) (xy 186.867694 -313.470017) (xy 186.915642 -313.445365) (xy 186.966669 -313.427957)
			(xy 187.019687 -313.418164) (xy 187.073566 -313.416195) (xy 187.127157 -313.422092) (xy 187.179318 -313.435728)
			(xy 187.228938 -313.456815) (xy 187.274959 -313.484901) (xy 187.316401 -313.519389) (xy 187.352379 -313.559543)
			(xy 187.382127 -313.604507) (xy 187.405012 -313.653324) (xy 187.420544 -313.704953) (xy 187.428394 -313.758293)
			(xy 187.428886 -313.78525) (xy 190.790845 -313.78525) (xy 190.79478 -313.731479) (xy 190.806503 -313.678855)
			(xy 190.825763 -313.628498) (xy 190.852149 -313.581481) (xy 190.885101 -313.538808) (xy 190.923914 -313.501387)
			(xy 190.967762 -313.470017) (xy 191.01571 -313.445365) (xy 191.066737 -313.427957) (xy 191.119755 -313.418164)
			(xy 191.173634 -313.416195) (xy 191.227225 -313.422092) (xy 191.279386 -313.435728) (xy 191.329006 -313.456815)
			(xy 191.375027 -313.484901) (xy 191.416469 -313.519389) (xy 191.452447 -313.559543) (xy 191.482195 -313.604507)
			(xy 191.50508 -313.653324) (xy 191.520612 -313.704953) (xy 191.528462 -313.758293) (xy 191.528954 -313.78525)
			(xy 194.234831 -313.78525) (xy 194.238766 -313.731479) (xy 194.250489 -313.678855) (xy 194.269749 -313.628498)
			(xy 194.296135 -313.581481) (xy 194.329087 -313.538808) (xy 194.3679 -313.501387) (xy 194.411748 -313.470017)
			(xy 194.459696 -313.445365) (xy 194.510723 -313.427957) (xy 194.563741 -313.418164) (xy 194.61762 -313.416195)
			(xy 194.671211 -313.422092) (xy 194.723372 -313.435728) (xy 194.772992 -313.456815) (xy 194.819013 -313.484901)
			(xy 194.860455 -313.519389) (xy 194.896433 -313.559543) (xy 194.926181 -313.604507) (xy 194.949066 -313.653324)
			(xy 194.964598 -313.704953) (xy 194.972448 -313.758293) (xy 194.97294 -313.78525) (xy 198.334899 -313.78525)
			(xy 198.338834 -313.731479) (xy 198.350557 -313.678855) (xy 198.369817 -313.628498) (xy 198.396203 -313.581481)
			(xy 198.429155 -313.538808) (xy 198.467968 -313.501387) (xy 198.511816 -313.470017) (xy 198.559764 -313.445365)
			(xy 198.610791 -313.427957) (xy 198.663809 -313.418164) (xy 198.717688 -313.416195) (xy 198.771279 -313.422092)
			(xy 198.82344 -313.435728) (xy 198.87306 -313.456815) (xy 198.919081 -313.484901) (xy 198.960523 -313.519389)
			(xy 198.996501 -313.559543) (xy 199.026249 -313.604507) (xy 199.049134 -313.653324) (xy 199.064666 -313.704953)
			(xy 199.072516 -313.758293) (xy 199.073008 -313.78525) (xy 201.778631 -313.78525) (xy 201.782566 -313.731479)
			(xy 201.794289 -313.678855) (xy 201.813549 -313.628498) (xy 201.839935 -313.581481) (xy 201.872887 -313.538808)
			(xy 201.9117 -313.501387) (xy 201.955548 -313.470017) (xy 202.003496 -313.445365) (xy 202.054523 -313.427957)
			(xy 202.107541 -313.418164) (xy 202.16142 -313.416195) (xy 202.215011 -313.422092) (xy 202.267172 -313.435728)
			(xy 202.316792 -313.456815) (xy 202.362813 -313.484901) (xy 202.404255 -313.519389) (xy 202.440233 -313.559543)
			(xy 202.469981 -313.604507) (xy 202.492866 -313.653324) (xy 202.508398 -313.704953) (xy 202.516248 -313.758293)
			(xy 202.51674 -313.78525) (xy 205.878699 -313.78525) (xy 205.882634 -313.731479) (xy 205.894357 -313.678855)
			(xy 205.913617 -313.628498) (xy 205.940003 -313.581481) (xy 205.972955 -313.538808) (xy 206.011768 -313.501387)
			(xy 206.055616 -313.470017) (xy 206.103564 -313.445365) (xy 206.154591 -313.427957) (xy 206.207609 -313.418164)
			(xy 206.261488 -313.416195) (xy 206.315079 -313.422092) (xy 206.36724 -313.435728) (xy 206.41686 -313.456815)
			(xy 206.462881 -313.484901) (xy 206.504323 -313.519389) (xy 206.540301 -313.559543) (xy 206.570049 -313.604507)
			(xy 206.592934 -313.653324) (xy 206.608466 -313.704953) (xy 206.616316 -313.758293) (xy 206.616808 -313.78525)
			(xy 206.616316 -313.812207) (xy 206.608466 -313.865547) (xy 206.592934 -313.917176) (xy 206.570049 -313.965993)
			(xy 206.540301 -314.010957) (xy 206.504323 -314.051111) (xy 206.462881 -314.085599) (xy 206.41686 -314.113685)
			(xy 206.36724 -314.134772) (xy 206.315079 -314.148408) (xy 206.261488 -314.154305) (xy 206.207609 -314.152336)
			(xy 206.154591 -314.142543) (xy 206.103564 -314.125135) (xy 206.055616 -314.100483) (xy 206.011768 -314.069113)
			(xy 205.972955 -314.031692) (xy 205.940003 -313.989019) (xy 205.913617 -313.942002) (xy 205.894357 -313.891645)
			(xy 205.882634 -313.839021) (xy 205.878699 -313.78525) (xy 202.51674 -313.78525) (xy 202.516248 -313.812207)
			(xy 202.508398 -313.865547) (xy 202.492866 -313.917176) (xy 202.469981 -313.965993) (xy 202.440233 -314.010957)
			(xy 202.404255 -314.051111) (xy 202.362813 -314.085599) (xy 202.316792 -314.113685) (xy 202.267172 -314.134772)
			(xy 202.215011 -314.148408) (xy 202.16142 -314.154305) (xy 202.107541 -314.152336) (xy 202.054523 -314.142543)
			(xy 202.003496 -314.125135) (xy 201.955548 -314.100483) (xy 201.9117 -314.069113) (xy 201.872887 -314.031692)
			(xy 201.839935 -313.989019) (xy 201.813549 -313.942002) (xy 201.794289 -313.891645) (xy 201.782566 -313.839021)
			(xy 201.778631 -313.78525) (xy 199.073008 -313.78525) (xy 199.072516 -313.812207) (xy 199.064666 -313.865547)
			(xy 199.049134 -313.917176) (xy 199.026249 -313.965993) (xy 198.996501 -314.010957) (xy 198.960523 -314.051111)
			(xy 198.919081 -314.085599) (xy 198.87306 -314.113685) (xy 198.82344 -314.134772) (xy 198.771279 -314.148408)
			(xy 198.717688 -314.154305) (xy 198.663809 -314.152336) (xy 198.610791 -314.142543) (xy 198.559764 -314.125135)
			(xy 198.511816 -314.100483) (xy 198.467968 -314.069113) (xy 198.429155 -314.031692) (xy 198.396203 -313.989019)
			(xy 198.369817 -313.942002) (xy 198.350557 -313.891645) (xy 198.338834 -313.839021) (xy 198.334899 -313.78525)
			(xy 194.97294 -313.78525) (xy 194.972448 -313.812207) (xy 194.964598 -313.865547) (xy 194.949066 -313.917176)
			(xy 194.926181 -313.965993) (xy 194.896433 -314.010957) (xy 194.860455 -314.051111) (xy 194.819013 -314.085599)
			(xy 194.772992 -314.113685) (xy 194.723372 -314.134772) (xy 194.671211 -314.148408) (xy 194.61762 -314.154305)
			(xy 194.563741 -314.152336) (xy 194.510723 -314.142543) (xy 194.459696 -314.125135) (xy 194.411748 -314.100483)
			(xy 194.3679 -314.069113) (xy 194.329087 -314.031692) (xy 194.296135 -313.989019) (xy 194.269749 -313.942002)
			(xy 194.250489 -313.891645) (xy 194.238766 -313.839021) (xy 194.234831 -313.78525) (xy 191.528954 -313.78525)
			(xy 191.528462 -313.812207) (xy 191.520612 -313.865547) (xy 191.50508 -313.917176) (xy 191.482195 -313.965993)
			(xy 191.452447 -314.010957) (xy 191.416469 -314.051111) (xy 191.375027 -314.085599) (xy 191.329006 -314.113685)
			(xy 191.279386 -314.134772) (xy 191.227225 -314.148408) (xy 191.173634 -314.154305) (xy 191.119755 -314.152336)
			(xy 191.066737 -314.142543) (xy 191.01571 -314.125135) (xy 190.967762 -314.100483) (xy 190.923914 -314.069113)
			(xy 190.885101 -314.031692) (xy 190.852149 -313.989019) (xy 190.825763 -313.942002) (xy 190.806503 -313.891645)
			(xy 190.79478 -313.839021) (xy 190.790845 -313.78525) (xy 187.428886 -313.78525) (xy 187.428394 -313.812207)
			(xy 187.420544 -313.865547) (xy 187.405012 -313.917176) (xy 187.382127 -313.965993) (xy 187.352379 -314.010957)
			(xy 187.316401 -314.051111) (xy 187.274959 -314.085599) (xy 187.228938 -314.113685) (xy 187.179318 -314.134772)
			(xy 187.127157 -314.148408) (xy 187.073566 -314.154305) (xy 187.019687 -314.152336) (xy 186.966669 -314.142543)
			(xy 186.915642 -314.125135) (xy 186.867694 -314.100483) (xy 186.823846 -314.069113) (xy 186.785033 -314.031692)
			(xy 186.752081 -313.989019) (xy 186.725695 -313.942002) (xy 186.706435 -313.891645) (xy 186.694712 -313.839021)
			(xy 186.690777 -313.78525) (xy 183.9849 -313.78525) (xy 183.984408 -313.812207) (xy 183.976558 -313.865547)
			(xy 183.961026 -313.917176) (xy 183.938141 -313.965993) (xy 183.908393 -314.010957) (xy 183.872415 -314.051111)
			(xy 183.830973 -314.085599) (xy 183.784952 -314.113685) (xy 183.735332 -314.134772) (xy 183.683171 -314.148408)
			(xy 183.62958 -314.154305) (xy 183.575701 -314.152336) (xy 183.522683 -314.142543) (xy 183.471656 -314.125135)
			(xy 183.423708 -314.100483) (xy 183.37986 -314.069113) (xy 183.341047 -314.031692) (xy 183.308095 -313.989019)
			(xy 183.281709 -313.942002) (xy 183.262449 -313.891645) (xy 183.250726 -313.839021) (xy 183.246791 -313.78525)
			(xy 179.884832 -313.78525) (xy 179.88434 -313.812207) (xy 179.87649 -313.865547) (xy 179.860958 -313.917176)
			(xy 179.838073 -313.965993) (xy 179.808325 -314.010957) (xy 179.772347 -314.051111) (xy 179.730905 -314.085599)
			(xy 179.684884 -314.113685) (xy 179.635264 -314.134772) (xy 179.583103 -314.148408) (xy 179.529512 -314.154305)
			(xy 179.475633 -314.152336) (xy 179.422615 -314.142543) (xy 179.371588 -314.125135) (xy 179.32364 -314.100483)
			(xy 179.279792 -314.069113) (xy 179.240979 -314.031692) (xy 179.208027 -313.989019) (xy 179.181641 -313.942002)
			(xy 179.162381 -313.891645) (xy 179.150658 -313.839021) (xy 179.146723 -313.78525) (xy 177.881534 -313.78525)
			(xy 177.881534 -314.635388) (xy 179.146723 -314.635388) (xy 179.150658 -314.581617) (xy 179.162381 -314.528993)
			(xy 179.181641 -314.478636) (xy 179.208027 -314.431619) (xy 179.240979 -314.388946) (xy 179.279792 -314.351525)
			(xy 179.32364 -314.320155) (xy 179.371588 -314.295503) (xy 179.422615 -314.278095) (xy 179.475633 -314.268302)
			(xy 179.529512 -314.266333) (xy 179.583103 -314.27223) (xy 179.635264 -314.285866) (xy 179.684884 -314.306953)
			(xy 179.730905 -314.335039) (xy 179.772347 -314.369527) (xy 179.808325 -314.409681) (xy 179.838073 -314.454645)
			(xy 179.860958 -314.503462) (xy 179.87649 -314.555091) (xy 179.88434 -314.608431) (xy 179.884832 -314.635388)
			(xy 186.690777 -314.635388) (xy 186.694712 -314.581617) (xy 186.706435 -314.528993) (xy 186.725695 -314.478636)
			(xy 186.752081 -314.431619) (xy 186.785033 -314.388946) (xy 186.823846 -314.351525) (xy 186.867694 -314.320155)
			(xy 186.915642 -314.295503) (xy 186.966669 -314.278095) (xy 187.019687 -314.268302) (xy 187.073566 -314.266333)
			(xy 187.127157 -314.27223) (xy 187.179318 -314.285866) (xy 187.228938 -314.306953) (xy 187.274959 -314.335039)
			(xy 187.316401 -314.369527) (xy 187.352379 -314.409681) (xy 187.382127 -314.454645) (xy 187.405012 -314.503462)
			(xy 187.420544 -314.555091) (xy 187.428394 -314.608431) (xy 187.428886 -314.635388) (xy 194.234831 -314.635388)
			(xy 194.238766 -314.581617) (xy 194.250489 -314.528993) (xy 194.269749 -314.478636) (xy 194.296135 -314.431619)
			(xy 194.329087 -314.388946) (xy 194.3679 -314.351525) (xy 194.411748 -314.320155) (xy 194.459696 -314.295503)
			(xy 194.510723 -314.278095) (xy 194.563741 -314.268302) (xy 194.61762 -314.266333) (xy 194.671211 -314.27223)
			(xy 194.723372 -314.285866) (xy 194.772992 -314.306953) (xy 194.819013 -314.335039) (xy 194.860455 -314.369527)
			(xy 194.896433 -314.409681) (xy 194.926181 -314.454645) (xy 194.949066 -314.503462) (xy 194.964598 -314.555091)
			(xy 194.972448 -314.608431) (xy 194.97294 -314.635388) (xy 201.778631 -314.635388) (xy 201.782566 -314.581617)
			(xy 201.794289 -314.528993) (xy 201.813549 -314.478636) (xy 201.839935 -314.431619) (xy 201.872887 -314.388946)
			(xy 201.9117 -314.351525) (xy 201.955548 -314.320155) (xy 202.003496 -314.295503) (xy 202.054523 -314.278095)
			(xy 202.107541 -314.268302) (xy 202.16142 -314.266333) (xy 202.215011 -314.27223) (xy 202.267172 -314.285866)
			(xy 202.316792 -314.306953) (xy 202.362813 -314.335039) (xy 202.404255 -314.369527) (xy 202.440233 -314.409681)
			(xy 202.469981 -314.454645) (xy 202.492866 -314.503462) (xy 202.508398 -314.555091) (xy 202.516248 -314.608431)
			(xy 202.51674 -314.635388) (xy 202.516248 -314.662345) (xy 202.508398 -314.715685) (xy 202.492866 -314.767314)
			(xy 202.469981 -314.816131) (xy 202.440233 -314.861095) (xy 202.404255 -314.901249) (xy 202.362813 -314.935737)
			(xy 202.316792 -314.963823) (xy 202.267172 -314.98491) (xy 202.215011 -314.998546) (xy 202.16142 -315.004443)
			(xy 202.107541 -315.002474) (xy 202.054523 -314.992681) (xy 202.003496 -314.975273) (xy 201.955548 -314.950621)
			(xy 201.9117 -314.919251) (xy 201.872887 -314.88183) (xy 201.839935 -314.839157) (xy 201.813549 -314.79214)
			(xy 201.794289 -314.741783) (xy 201.782566 -314.689159) (xy 201.778631 -314.635388) (xy 194.97294 -314.635388)
			(xy 194.972448 -314.662345) (xy 194.964598 -314.715685) (xy 194.949066 -314.767314) (xy 194.926181 -314.816131)
			(xy 194.896433 -314.861095) (xy 194.860455 -314.901249) (xy 194.819013 -314.935737) (xy 194.772992 -314.963823)
			(xy 194.723372 -314.98491) (xy 194.671211 -314.998546) (xy 194.61762 -315.004443) (xy 194.563741 -315.002474)
			(xy 194.510723 -314.992681) (xy 194.459696 -314.975273) (xy 194.411748 -314.950621) (xy 194.3679 -314.919251)
			(xy 194.329087 -314.88183) (xy 194.296135 -314.839157) (xy 194.269749 -314.79214) (xy 194.250489 -314.741783)
			(xy 194.238766 -314.689159) (xy 194.234831 -314.635388) (xy 187.428886 -314.635388) (xy 187.428394 -314.662345)
			(xy 187.420544 -314.715685) (xy 187.405012 -314.767314) (xy 187.382127 -314.816131) (xy 187.352379 -314.861095)
			(xy 187.316401 -314.901249) (xy 187.274959 -314.935737) (xy 187.228938 -314.963823) (xy 187.179318 -314.98491)
			(xy 187.127157 -314.998546) (xy 187.073566 -315.004443) (xy 187.019687 -315.002474) (xy 186.966669 -314.992681)
			(xy 186.915642 -314.975273) (xy 186.867694 -314.950621) (xy 186.823846 -314.919251) (xy 186.785033 -314.88183)
			(xy 186.752081 -314.839157) (xy 186.725695 -314.79214) (xy 186.706435 -314.741783) (xy 186.694712 -314.689159)
			(xy 186.690777 -314.635388) (xy 179.884832 -314.635388) (xy 179.88434 -314.662345) (xy 179.87649 -314.715685)
			(xy 179.860958 -314.767314) (xy 179.838073 -314.816131) (xy 179.808325 -314.861095) (xy 179.772347 -314.901249)
			(xy 179.730905 -314.935737) (xy 179.684884 -314.963823) (xy 179.635264 -314.98491) (xy 179.583103 -314.998546)
			(xy 179.529512 -315.004443) (xy 179.475633 -315.002474) (xy 179.422615 -314.992681) (xy 179.371588 -314.975273)
			(xy 179.32364 -314.950621) (xy 179.279792 -314.919251) (xy 179.240979 -314.88183) (xy 179.208027 -314.839157)
			(xy 179.181641 -314.79214) (xy 179.162381 -314.741783) (xy 179.150658 -314.689159) (xy 179.146723 -314.635388)
			(xy 177.881534 -314.635388) (xy 177.881534 -315.485272) (xy 183.246791 -315.485272) (xy 183.250726 -315.431501)
			(xy 183.262449 -315.378877) (xy 183.281709 -315.32852) (xy 183.308095 -315.281503) (xy 183.341047 -315.23883)
			(xy 183.37986 -315.201409) (xy 183.423708 -315.170039) (xy 183.471656 -315.145387) (xy 183.522683 -315.127979)
			(xy 183.575701 -315.118186) (xy 183.62958 -315.116217) (xy 183.683171 -315.122114) (xy 183.735332 -315.13575)
			(xy 183.784952 -315.156837) (xy 183.830973 -315.184923) (xy 183.872415 -315.219411) (xy 183.908393 -315.259565)
			(xy 183.938141 -315.304529) (xy 183.961026 -315.353346) (xy 183.976558 -315.404975) (xy 183.984408 -315.458315)
			(xy 183.9849 -315.485272) (xy 190.790845 -315.485272) (xy 190.79478 -315.431501) (xy 190.806503 -315.378877)
			(xy 190.825763 -315.32852) (xy 190.852149 -315.281503) (xy 190.885101 -315.23883) (xy 190.923914 -315.201409)
			(xy 190.967762 -315.170039) (xy 191.01571 -315.145387) (xy 191.066737 -315.127979) (xy 191.119755 -315.118186)
			(xy 191.173634 -315.116217) (xy 191.227225 -315.122114) (xy 191.279386 -315.13575) (xy 191.329006 -315.156837)
			(xy 191.375027 -315.184923) (xy 191.416469 -315.219411) (xy 191.452447 -315.259565) (xy 191.482195 -315.304529)
			(xy 191.50508 -315.353346) (xy 191.520612 -315.404975) (xy 191.528462 -315.458315) (xy 191.528954 -315.485272)
			(xy 198.334899 -315.485272) (xy 198.338834 -315.431501) (xy 198.350557 -315.378877) (xy 198.369817 -315.32852)
			(xy 198.396203 -315.281503) (xy 198.429155 -315.23883) (xy 198.467968 -315.201409) (xy 198.511816 -315.170039)
			(xy 198.559764 -315.145387) (xy 198.610791 -315.127979) (xy 198.663809 -315.118186) (xy 198.717688 -315.116217)
			(xy 198.771279 -315.122114) (xy 198.82344 -315.13575) (xy 198.87306 -315.156837) (xy 198.919081 -315.184923)
			(xy 198.960523 -315.219411) (xy 198.996501 -315.259565) (xy 199.026249 -315.304529) (xy 199.049134 -315.353346)
			(xy 199.064666 -315.404975) (xy 199.072516 -315.458315) (xy 199.073008 -315.485272) (xy 205.878699 -315.485272)
			(xy 205.882634 -315.431501) (xy 205.894357 -315.378877) (xy 205.913617 -315.32852) (xy 205.940003 -315.281503)
			(xy 205.972955 -315.23883) (xy 206.011768 -315.201409) (xy 206.055616 -315.170039) (xy 206.103564 -315.145387)
			(xy 206.154591 -315.127979) (xy 206.207609 -315.118186) (xy 206.261488 -315.116217) (xy 206.315079 -315.122114)
			(xy 206.36724 -315.13575) (xy 206.41686 -315.156837) (xy 206.462881 -315.184923) (xy 206.504323 -315.219411)
			(xy 206.540301 -315.259565) (xy 206.570049 -315.304529) (xy 206.592934 -315.353346) (xy 206.608466 -315.404975)
			(xy 206.616316 -315.458315) (xy 206.616808 -315.485272) (xy 206.616316 -315.512229) (xy 206.608466 -315.565569)
			(xy 206.592934 -315.617198) (xy 206.570049 -315.666015) (xy 206.540301 -315.710979) (xy 206.504323 -315.751133)
			(xy 206.462881 -315.785621) (xy 206.41686 -315.813707) (xy 206.36724 -315.834794) (xy 206.315079 -315.84843)
			(xy 206.261488 -315.854327) (xy 206.207609 -315.852358) (xy 206.154591 -315.842565) (xy 206.103564 -315.825157)
			(xy 206.055616 -315.800505) (xy 206.011768 -315.769135) (xy 205.972955 -315.731714) (xy 205.940003 -315.689041)
			(xy 205.913617 -315.642024) (xy 205.894357 -315.591667) (xy 205.882634 -315.539043) (xy 205.878699 -315.485272)
			(xy 199.073008 -315.485272) (xy 199.072516 -315.512229) (xy 199.064666 -315.565569) (xy 199.049134 -315.617198)
			(xy 199.026249 -315.666015) (xy 198.996501 -315.710979) (xy 198.960523 -315.751133) (xy 198.919081 -315.785621)
			(xy 198.87306 -315.813707) (xy 198.82344 -315.834794) (xy 198.771279 -315.84843) (xy 198.717688 -315.854327)
			(xy 198.663809 -315.852358) (xy 198.610791 -315.842565) (xy 198.559764 -315.825157) (xy 198.511816 -315.800505)
			(xy 198.467968 -315.769135) (xy 198.429155 -315.731714) (xy 198.396203 -315.689041) (xy 198.369817 -315.642024)
			(xy 198.350557 -315.591667) (xy 198.338834 -315.539043) (xy 198.334899 -315.485272) (xy 191.528954 -315.485272)
			(xy 191.528462 -315.512229) (xy 191.520612 -315.565569) (xy 191.50508 -315.617198) (xy 191.482195 -315.666015)
			(xy 191.452447 -315.710979) (xy 191.416469 -315.751133) (xy 191.375027 -315.785621) (xy 191.329006 -315.813707)
			(xy 191.279386 -315.834794) (xy 191.227225 -315.84843) (xy 191.173634 -315.854327) (xy 191.119755 -315.852358)
			(xy 191.066737 -315.842565) (xy 191.01571 -315.825157) (xy 190.967762 -315.800505) (xy 190.923914 -315.769135)
			(xy 190.885101 -315.731714) (xy 190.852149 -315.689041) (xy 190.825763 -315.642024) (xy 190.806503 -315.591667)
			(xy 190.79478 -315.539043) (xy 190.790845 -315.485272) (xy 183.9849 -315.485272) (xy 183.984408 -315.512229)
			(xy 183.976558 -315.565569) (xy 183.961026 -315.617198) (xy 183.938141 -315.666015) (xy 183.908393 -315.710979)
			(xy 183.872415 -315.751133) (xy 183.830973 -315.785621) (xy 183.784952 -315.813707) (xy 183.735332 -315.834794)
			(xy 183.683171 -315.84843) (xy 183.62958 -315.854327) (xy 183.575701 -315.852358) (xy 183.522683 -315.842565)
			(xy 183.471656 -315.825157) (xy 183.423708 -315.800505) (xy 183.37986 -315.769135) (xy 183.341047 -315.731714)
			(xy 183.308095 -315.689041) (xy 183.281709 -315.642024) (xy 183.262449 -315.591667) (xy 183.250726 -315.539043)
			(xy 183.246791 -315.485272) (xy 177.881534 -315.485272) (xy 177.881534 -316.33541) (xy 179.146723 -316.33541)
			(xy 179.150658 -316.281639) (xy 179.162381 -316.229015) (xy 179.181641 -316.178658) (xy 179.208027 -316.131641)
			(xy 179.240979 -316.088968) (xy 179.279792 -316.051547) (xy 179.32364 -316.020177) (xy 179.371588 -315.995525)
			(xy 179.422615 -315.978117) (xy 179.475633 -315.968324) (xy 179.529512 -315.966355) (xy 179.583103 -315.972252)
			(xy 179.635264 -315.985888) (xy 179.684884 -316.006975) (xy 179.730905 -316.035061) (xy 179.772347 -316.069549)
			(xy 179.808325 -316.109703) (xy 179.838073 -316.154667) (xy 179.860958 -316.203484) (xy 179.87649 -316.255113)
			(xy 179.88434 -316.308453) (xy 179.884832 -316.33541) (xy 186.690777 -316.33541) (xy 186.694712 -316.281639)
			(xy 186.706435 -316.229015) (xy 186.725695 -316.178658) (xy 186.752081 -316.131641) (xy 186.785033 -316.088968)
			(xy 186.823846 -316.051547) (xy 186.867694 -316.020177) (xy 186.915642 -315.995525) (xy 186.966669 -315.978117)
			(xy 187.019687 -315.968324) (xy 187.073566 -315.966355) (xy 187.127157 -315.972252) (xy 187.179318 -315.985888)
			(xy 187.228938 -316.006975) (xy 187.274959 -316.035061) (xy 187.316401 -316.069549) (xy 187.352379 -316.109703)
			(xy 187.382127 -316.154667) (xy 187.405012 -316.203484) (xy 187.420544 -316.255113) (xy 187.428394 -316.308453)
			(xy 187.428886 -316.33541) (xy 194.234831 -316.33541) (xy 194.238766 -316.281639) (xy 194.250489 -316.229015)
			(xy 194.269749 -316.178658) (xy 194.296135 -316.131641) (xy 194.329087 -316.088968) (xy 194.3679 -316.051547)
			(xy 194.411748 -316.020177) (xy 194.459696 -315.995525) (xy 194.510723 -315.978117) (xy 194.563741 -315.968324)
			(xy 194.61762 -315.966355) (xy 194.671211 -315.972252) (xy 194.723372 -315.985888) (xy 194.772992 -316.006975)
			(xy 194.819013 -316.035061) (xy 194.860455 -316.069549) (xy 194.896433 -316.109703) (xy 194.926181 -316.154667)
			(xy 194.949066 -316.203484) (xy 194.964598 -316.255113) (xy 194.972448 -316.308453) (xy 194.97294 -316.33541)
			(xy 201.778631 -316.33541) (xy 201.782566 -316.281639) (xy 201.794289 -316.229015) (xy 201.813549 -316.178658)
			(xy 201.839935 -316.131641) (xy 201.872887 -316.088968) (xy 201.9117 -316.051547) (xy 201.955548 -316.020177)
			(xy 202.003496 -315.995525) (xy 202.054523 -315.978117) (xy 202.107541 -315.968324) (xy 202.16142 -315.966355)
			(xy 202.215011 -315.972252) (xy 202.267172 -315.985888) (xy 202.316792 -316.006975) (xy 202.362813 -316.035061)
			(xy 202.404255 -316.069549) (xy 202.440233 -316.109703) (xy 202.469981 -316.154667) (xy 202.492866 -316.203484)
			(xy 202.508398 -316.255113) (xy 202.516248 -316.308453) (xy 202.51674 -316.33541) (xy 202.516248 -316.362367)
			(xy 202.508398 -316.415707) (xy 202.492866 -316.467336) (xy 202.469981 -316.516153) (xy 202.440233 -316.561117)
			(xy 202.404255 -316.601271) (xy 202.362813 -316.635759) (xy 202.316792 -316.663845) (xy 202.267172 -316.684932)
			(xy 202.215011 -316.698568) (xy 202.16142 -316.704465) (xy 202.107541 -316.702496) (xy 202.054523 -316.692703)
			(xy 202.003496 -316.675295) (xy 201.955548 -316.650643) (xy 201.9117 -316.619273) (xy 201.872887 -316.581852)
			(xy 201.839935 -316.539179) (xy 201.813549 -316.492162) (xy 201.794289 -316.441805) (xy 201.782566 -316.389181)
			(xy 201.778631 -316.33541) (xy 194.97294 -316.33541) (xy 194.972448 -316.362367) (xy 194.964598 -316.415707)
			(xy 194.949066 -316.467336) (xy 194.926181 -316.516153) (xy 194.896433 -316.561117) (xy 194.860455 -316.601271)
			(xy 194.819013 -316.635759) (xy 194.772992 -316.663845) (xy 194.723372 -316.684932) (xy 194.671211 -316.698568)
			(xy 194.61762 -316.704465) (xy 194.563741 -316.702496) (xy 194.510723 -316.692703) (xy 194.459696 -316.675295)
			(xy 194.411748 -316.650643) (xy 194.3679 -316.619273) (xy 194.329087 -316.581852) (xy 194.296135 -316.539179)
			(xy 194.269749 -316.492162) (xy 194.250489 -316.441805) (xy 194.238766 -316.389181) (xy 194.234831 -316.33541)
			(xy 187.428886 -316.33541) (xy 187.428394 -316.362367) (xy 187.420544 -316.415707) (xy 187.405012 -316.467336)
			(xy 187.382127 -316.516153) (xy 187.352379 -316.561117) (xy 187.316401 -316.601271) (xy 187.274959 -316.635759)
			(xy 187.228938 -316.663845) (xy 187.179318 -316.684932) (xy 187.127157 -316.698568) (xy 187.073566 -316.704465)
			(xy 187.019687 -316.702496) (xy 186.966669 -316.692703) (xy 186.915642 -316.675295) (xy 186.867694 -316.650643)
			(xy 186.823846 -316.619273) (xy 186.785033 -316.581852) (xy 186.752081 -316.539179) (xy 186.725695 -316.492162)
			(xy 186.706435 -316.441805) (xy 186.694712 -316.389181) (xy 186.690777 -316.33541) (xy 179.884832 -316.33541)
			(xy 179.88434 -316.362367) (xy 179.87649 -316.415707) (xy 179.860958 -316.467336) (xy 179.838073 -316.516153)
			(xy 179.808325 -316.561117) (xy 179.772347 -316.601271) (xy 179.730905 -316.635759) (xy 179.684884 -316.663845)
			(xy 179.635264 -316.684932) (xy 179.583103 -316.698568) (xy 179.529512 -316.704465) (xy 179.475633 -316.702496)
			(xy 179.422615 -316.692703) (xy 179.371588 -316.675295) (xy 179.32364 -316.650643) (xy 179.279792 -316.619273)
			(xy 179.240979 -316.581852) (xy 179.208027 -316.539179) (xy 179.181641 -316.492162) (xy 179.162381 -316.441805)
			(xy 179.150658 -316.389181) (xy 179.146723 -316.33541) (xy 177.881534 -316.33541) (xy 177.881534 -317.185294)
			(xy 183.246791 -317.185294) (xy 183.250726 -317.131523) (xy 183.262449 -317.078899) (xy 183.281709 -317.028542)
			(xy 183.308095 -316.981525) (xy 183.341047 -316.938852) (xy 183.37986 -316.901431) (xy 183.423708 -316.870061)
			(xy 183.471656 -316.845409) (xy 183.522683 -316.828001) (xy 183.575701 -316.818208) (xy 183.62958 -316.816239)
			(xy 183.683171 -316.822136) (xy 183.735332 -316.835772) (xy 183.784952 -316.856859) (xy 183.830973 -316.884945)
			(xy 183.872415 -316.919433) (xy 183.908393 -316.959587) (xy 183.938141 -317.004551) (xy 183.961026 -317.053368)
			(xy 183.976558 -317.104997) (xy 183.984408 -317.158337) (xy 183.9849 -317.185294) (xy 190.790845 -317.185294)
			(xy 190.79478 -317.131523) (xy 190.806503 -317.078899) (xy 190.825763 -317.028542) (xy 190.852149 -316.981525)
			(xy 190.885101 -316.938852) (xy 190.923914 -316.901431) (xy 190.967762 -316.870061) (xy 191.01571 -316.845409)
			(xy 191.066737 -316.828001) (xy 191.119755 -316.818208) (xy 191.173634 -316.816239) (xy 191.227225 -316.822136)
			(xy 191.279386 -316.835772) (xy 191.329006 -316.856859) (xy 191.375027 -316.884945) (xy 191.416469 -316.919433)
			(xy 191.452447 -316.959587) (xy 191.482195 -317.004551) (xy 191.50508 -317.053368) (xy 191.520612 -317.104997)
			(xy 191.528462 -317.158337) (xy 191.528954 -317.185294) (xy 198.334899 -317.185294) (xy 198.338834 -317.131523)
			(xy 198.350557 -317.078899) (xy 198.369817 -317.028542) (xy 198.396203 -316.981525) (xy 198.429155 -316.938852)
			(xy 198.467968 -316.901431) (xy 198.511816 -316.870061) (xy 198.559764 -316.845409) (xy 198.610791 -316.828001)
			(xy 198.663809 -316.818208) (xy 198.717688 -316.816239) (xy 198.771279 -316.822136) (xy 198.82344 -316.835772)
			(xy 198.87306 -316.856859) (xy 198.919081 -316.884945) (xy 198.960523 -316.919433) (xy 198.996501 -316.959587)
			(xy 199.026249 -317.004551) (xy 199.049134 -317.053368) (xy 199.064666 -317.104997) (xy 199.072516 -317.158337)
			(xy 199.073008 -317.185294) (xy 205.878699 -317.185294) (xy 205.882634 -317.131523) (xy 205.894357 -317.078899)
			(xy 205.913617 -317.028542) (xy 205.940003 -316.981525) (xy 205.972955 -316.938852) (xy 206.011768 -316.901431)
			(xy 206.055616 -316.870061) (xy 206.103564 -316.845409) (xy 206.154591 -316.828001) (xy 206.207609 -316.818208)
			(xy 206.261488 -316.816239) (xy 206.315079 -316.822136) (xy 206.36724 -316.835772) (xy 206.41686 -316.856859)
			(xy 206.462881 -316.884945) (xy 206.504323 -316.919433) (xy 206.540301 -316.959587) (xy 206.570049 -317.004551)
			(xy 206.592934 -317.053368) (xy 206.608466 -317.104997) (xy 206.616316 -317.158337) (xy 206.616808 -317.185294)
			(xy 206.616316 -317.212251) (xy 206.608466 -317.265591) (xy 206.592934 -317.31722) (xy 206.570049 -317.366037)
			(xy 206.540301 -317.411001) (xy 206.504323 -317.451155) (xy 206.462881 -317.485643) (xy 206.41686 -317.513729)
			(xy 206.36724 -317.534816) (xy 206.315079 -317.548452) (xy 206.261488 -317.554349) (xy 206.207609 -317.55238)
			(xy 206.154591 -317.542587) (xy 206.103564 -317.525179) (xy 206.055616 -317.500527) (xy 206.011768 -317.469157)
			(xy 205.972955 -317.431736) (xy 205.940003 -317.389063) (xy 205.913617 -317.342046) (xy 205.894357 -317.291689)
			(xy 205.882634 -317.239065) (xy 205.878699 -317.185294) (xy 199.073008 -317.185294) (xy 199.072516 -317.212251)
			(xy 199.064666 -317.265591) (xy 199.049134 -317.31722) (xy 199.026249 -317.366037) (xy 198.996501 -317.411001)
			(xy 198.960523 -317.451155) (xy 198.919081 -317.485643) (xy 198.87306 -317.513729) (xy 198.82344 -317.534816)
			(xy 198.771279 -317.548452) (xy 198.717688 -317.554349) (xy 198.663809 -317.55238) (xy 198.610791 -317.542587)
			(xy 198.559764 -317.525179) (xy 198.511816 -317.500527) (xy 198.467968 -317.469157) (xy 198.429155 -317.431736)
			(xy 198.396203 -317.389063) (xy 198.369817 -317.342046) (xy 198.350557 -317.291689) (xy 198.338834 -317.239065)
			(xy 198.334899 -317.185294) (xy 191.528954 -317.185294) (xy 191.528462 -317.212251) (xy 191.520612 -317.265591)
			(xy 191.50508 -317.31722) (xy 191.482195 -317.366037) (xy 191.452447 -317.411001) (xy 191.416469 -317.451155)
			(xy 191.375027 -317.485643) (xy 191.329006 -317.513729) (xy 191.279386 -317.534816) (xy 191.227225 -317.548452)
			(xy 191.173634 -317.554349) (xy 191.119755 -317.55238) (xy 191.066737 -317.542587) (xy 191.01571 -317.525179)
			(xy 190.967762 -317.500527) (xy 190.923914 -317.469157) (xy 190.885101 -317.431736) (xy 190.852149 -317.389063)
			(xy 190.825763 -317.342046) (xy 190.806503 -317.291689) (xy 190.79478 -317.239065) (xy 190.790845 -317.185294)
			(xy 183.9849 -317.185294) (xy 183.984408 -317.212251) (xy 183.976558 -317.265591) (xy 183.961026 -317.31722)
			(xy 183.938141 -317.366037) (xy 183.908393 -317.411001) (xy 183.872415 -317.451155) (xy 183.830973 -317.485643)
			(xy 183.784952 -317.513729) (xy 183.735332 -317.534816) (xy 183.683171 -317.548452) (xy 183.62958 -317.554349)
			(xy 183.575701 -317.55238) (xy 183.522683 -317.542587) (xy 183.471656 -317.525179) (xy 183.423708 -317.500527)
			(xy 183.37986 -317.469157) (xy 183.341047 -317.431736) (xy 183.308095 -317.389063) (xy 183.281709 -317.342046)
			(xy 183.262449 -317.291689) (xy 183.250726 -317.239065) (xy 183.246791 -317.185294) (xy 177.881534 -317.185294)
			(xy 177.881534 -318.035432) (xy 179.146723 -318.035432) (xy 179.150658 -317.981661) (xy 179.162381 -317.929037)
			(xy 179.181641 -317.87868) (xy 179.208027 -317.831663) (xy 179.240979 -317.78899) (xy 179.279792 -317.751569)
			(xy 179.32364 -317.720199) (xy 179.371588 -317.695547) (xy 179.422615 -317.678139) (xy 179.475633 -317.668346)
			(xy 179.529512 -317.666377) (xy 179.583103 -317.672274) (xy 179.635264 -317.68591) (xy 179.684884 -317.706997)
			(xy 179.730905 -317.735083) (xy 179.772347 -317.769571) (xy 179.808325 -317.809725) (xy 179.838073 -317.854689)
			(xy 179.860958 -317.903506) (xy 179.87649 -317.955135) (xy 179.88434 -318.008475) (xy 179.884832 -318.035432)
			(xy 186.690777 -318.035432) (xy 186.694712 -317.981661) (xy 186.706435 -317.929037) (xy 186.725695 -317.87868)
			(xy 186.752081 -317.831663) (xy 186.785033 -317.78899) (xy 186.823846 -317.751569) (xy 186.867694 -317.720199)
			(xy 186.915642 -317.695547) (xy 186.966669 -317.678139) (xy 187.019687 -317.668346) (xy 187.073566 -317.666377)
			(xy 187.127157 -317.672274) (xy 187.179318 -317.68591) (xy 187.228938 -317.706997) (xy 187.274959 -317.735083)
			(xy 187.316401 -317.769571) (xy 187.352379 -317.809725) (xy 187.382127 -317.854689) (xy 187.405012 -317.903506)
			(xy 187.420544 -317.955135) (xy 187.428394 -318.008475) (xy 187.428886 -318.035432) (xy 194.234831 -318.035432)
			(xy 194.238766 -317.981661) (xy 194.250489 -317.929037) (xy 194.269749 -317.87868) (xy 194.296135 -317.831663)
			(xy 194.329087 -317.78899) (xy 194.3679 -317.751569) (xy 194.411748 -317.720199) (xy 194.459696 -317.695547)
			(xy 194.510723 -317.678139) (xy 194.563741 -317.668346) (xy 194.61762 -317.666377) (xy 194.671211 -317.672274)
			(xy 194.723372 -317.68591) (xy 194.772992 -317.706997) (xy 194.819013 -317.735083) (xy 194.860455 -317.769571)
			(xy 194.896433 -317.809725) (xy 194.926181 -317.854689) (xy 194.949066 -317.903506) (xy 194.964598 -317.955135)
			(xy 194.972448 -318.008475) (xy 194.97294 -318.035432) (xy 201.778631 -318.035432) (xy 201.782566 -317.981661)
			(xy 201.794289 -317.929037) (xy 201.813549 -317.87868) (xy 201.839935 -317.831663) (xy 201.872887 -317.78899)
			(xy 201.9117 -317.751569) (xy 201.955548 -317.720199) (xy 202.003496 -317.695547) (xy 202.054523 -317.678139)
			(xy 202.107541 -317.668346) (xy 202.16142 -317.666377) (xy 202.215011 -317.672274) (xy 202.267172 -317.68591)
			(xy 202.316792 -317.706997) (xy 202.362813 -317.735083) (xy 202.404255 -317.769571) (xy 202.440233 -317.809725)
			(xy 202.469981 -317.854689) (xy 202.492866 -317.903506) (xy 202.508398 -317.955135) (xy 202.516248 -318.008475)
			(xy 202.51674 -318.035432) (xy 202.516248 -318.062389) (xy 202.508398 -318.115729) (xy 202.492866 -318.167358)
			(xy 202.469981 -318.216175) (xy 202.440233 -318.261139) (xy 202.404255 -318.301293) (xy 202.362813 -318.335781)
			(xy 202.316792 -318.363867) (xy 202.267172 -318.384954) (xy 202.215011 -318.39859) (xy 202.16142 -318.404487)
			(xy 202.107541 -318.402518) (xy 202.054523 -318.392725) (xy 202.003496 -318.375317) (xy 201.955548 -318.350665)
			(xy 201.9117 -318.319295) (xy 201.872887 -318.281874) (xy 201.839935 -318.239201) (xy 201.813549 -318.192184)
			(xy 201.794289 -318.141827) (xy 201.782566 -318.089203) (xy 201.778631 -318.035432) (xy 194.97294 -318.035432)
			(xy 194.972448 -318.062389) (xy 194.964598 -318.115729) (xy 194.949066 -318.167358) (xy 194.926181 -318.216175)
			(xy 194.896433 -318.261139) (xy 194.860455 -318.301293) (xy 194.819013 -318.335781) (xy 194.772992 -318.363867)
			(xy 194.723372 -318.384954) (xy 194.671211 -318.39859) (xy 194.61762 -318.404487) (xy 194.563741 -318.402518)
			(xy 194.510723 -318.392725) (xy 194.459696 -318.375317) (xy 194.411748 -318.350665) (xy 194.3679 -318.319295)
			(xy 194.329087 -318.281874) (xy 194.296135 -318.239201) (xy 194.269749 -318.192184) (xy 194.250489 -318.141827)
			(xy 194.238766 -318.089203) (xy 194.234831 -318.035432) (xy 187.428886 -318.035432) (xy 187.428394 -318.062389)
			(xy 187.420544 -318.115729) (xy 187.405012 -318.167358) (xy 187.382127 -318.216175) (xy 187.352379 -318.261139)
			(xy 187.316401 -318.301293) (xy 187.274959 -318.335781) (xy 187.228938 -318.363867) (xy 187.179318 -318.384954)
			(xy 187.127157 -318.39859) (xy 187.073566 -318.404487) (xy 187.019687 -318.402518) (xy 186.966669 -318.392725)
			(xy 186.915642 -318.375317) (xy 186.867694 -318.350665) (xy 186.823846 -318.319295) (xy 186.785033 -318.281874)
			(xy 186.752081 -318.239201) (xy 186.725695 -318.192184) (xy 186.706435 -318.141827) (xy 186.694712 -318.089203)
			(xy 186.690777 -318.035432) (xy 179.884832 -318.035432) (xy 179.88434 -318.062389) (xy 179.87649 -318.115729)
			(xy 179.860958 -318.167358) (xy 179.838073 -318.216175) (xy 179.808325 -318.261139) (xy 179.772347 -318.301293)
			(xy 179.730905 -318.335781) (xy 179.684884 -318.363867) (xy 179.635264 -318.384954) (xy 179.583103 -318.39859)
			(xy 179.529512 -318.404487) (xy 179.475633 -318.402518) (xy 179.422615 -318.392725) (xy 179.371588 -318.375317)
			(xy 179.32364 -318.350665) (xy 179.279792 -318.319295) (xy 179.240979 -318.281874) (xy 179.208027 -318.239201)
			(xy 179.181641 -318.192184) (xy 179.162381 -318.141827) (xy 179.150658 -318.089203) (xy 179.146723 -318.035432)
			(xy 177.881534 -318.035432) (xy 177.881534 -325.915274) (xy 177.88201 -325.925137) (xy 177.889549 -325.943365)
			(xy 177.903489 -325.957321) (xy 177.921709 -325.96488) (xy 177.931572 -325.965312)
		)
		(stroke
			(width 0)
			(type solid)
		)
		(fill yes)
		(layer "B.Cu")
		(net "GND")
	)
	(gr_poly
		(pts
			(xy 454.740264 -319.135252) (xy 454.750103 -319.134718) (xy 454.768271 -319.127139) (xy 454.77557 -319.12052)
			(xy 455.576686 -318.319404) (xy 455.583404 -318.312168) (xy 455.591009 -318.293963) (xy 455.591418 -318.284098)
			(xy 455.591418 -198.85787) (xy 455.59099 -198.847802) (xy 455.58327 -198.829204) (xy 455.576432 -198.821802)
			(xy 455.477626 -198.722996) (xy 455.470223 -198.716161) (xy 455.451625 -198.708455) (xy 455.441558 -198.70801)
			(xy 454.600818 -198.70801) (xy 454.585755 -198.70855) (xy 454.556938 -198.717332) (xy 454.531934 -198.734136)
			(xy 454.512919 -198.757501) (xy 454.501545 -198.785397) (xy 454.498801 -198.815398) (xy 454.504927 -198.844894)
			(xy 454.511664 -198.858378) (xy 454.525862 -198.885661) (xy 454.545994 -198.943772) (xy 454.556238 -199.004413)
			(xy 454.556876 -199.035162) (xy 454.55636 -199.062762) (xy 454.548133 -199.117345) (xy 454.531863 -199.170092)
			(xy 454.507913 -199.219825) (xy 454.476818 -199.265432) (xy 454.439273 -199.305896) (xy 454.396116 -199.340313)
			(xy 454.348312 -199.367912) (xy 454.296928 -199.388079) (xy 454.243113 -199.400362) (xy 454.188068 -199.404487)
			(xy 454.133023 -199.400362) (xy 454.079208 -199.388079) (xy 454.027824 -199.367912) (xy 453.98002 -199.340313)
			(xy 453.936863 -199.305896) (xy 453.899318 -199.265432) (xy 453.868223 -199.219825) (xy 453.844273 -199.170092)
			(xy 453.828003 -199.117345) (xy 453.819776 -199.062762) (xy 453.81926 -199.035162) (xy 453.819868 -199.004408)
			(xy 453.830077 -198.943755) (xy 453.850238 -198.885646) (xy 453.864472 -198.858378) (xy 453.871227 -198.844899)
			(xy 453.877351 -198.815395) (xy 453.874606 -198.785387) (xy 453.863231 -198.757483) (xy 453.844213 -198.734109)
			(xy 453.819207 -198.717295) (xy 453.790385 -198.708504) (xy 453.775318 -198.70801) (xy 447.057018 -198.70801)
			(xy 447.041955 -198.70855) (xy 447.013138 -198.717332) (xy 446.988134 -198.734136) (xy 446.969119 -198.757501)
			(xy 446.957745 -198.785397) (xy 446.955001 -198.815398) (xy 446.961127 -198.844894) (xy 446.967864 -198.858378)
			(xy 446.982062 -198.885661) (xy 447.002194 -198.943772) (xy 447.012438 -199.004413) (xy 447.013076 -199.035162)
			(xy 447.01256 -199.062762) (xy 447.004333 -199.117345) (xy 446.988063 -199.170092) (xy 446.964113 -199.219825)
			(xy 446.933018 -199.265432) (xy 446.895473 -199.305896) (xy 446.852316 -199.340313) (xy 446.804512 -199.367912)
			(xy 446.753128 -199.388079) (xy 446.699313 -199.400362) (xy 446.644268 -199.404487) (xy 446.589223 -199.400362)
			(xy 446.535408 -199.388079) (xy 446.484024 -199.367912) (xy 446.43622 -199.340313) (xy 446.393063 -199.305896)
			(xy 446.355518 -199.265432) (xy 446.324423 -199.219825) (xy 446.300473 -199.170092) (xy 446.284203 -199.117345)
			(xy 446.275976 -199.062762) (xy 446.27546 -199.035162) (xy 446.276068 -199.004408) (xy 446.286277 -198.943755)
			(xy 446.306438 -198.885646) (xy 446.320672 -198.858378) (xy 446.327427 -198.844899) (xy 446.333551 -198.815395)
			(xy 446.330806 -198.785387) (xy 446.319431 -198.757483) (xy 446.300413 -198.734109) (xy 446.275407 -198.717295)
			(xy 446.246585 -198.708504) (xy 446.231518 -198.70801) (xy 439.512964 -198.70801) (xy 439.497907 -198.708558)
			(xy 439.469104 -198.717347) (xy 439.444115 -198.734153) (xy 439.425111 -198.757514) (xy 439.413744 -198.7854)
			(xy 439.411001 -198.815389) (xy 439.41712 -198.844875) (xy 439.42381 -198.858378) (xy 439.43801 -198.88566)
			(xy 439.458145 -198.943771) (xy 439.46839 -199.004412) (xy 439.469022 -199.035162) (xy 439.468506 -199.062762)
			(xy 439.460279 -199.117345) (xy 439.444009 -199.170092) (xy 439.420059 -199.219825) (xy 439.388964 -199.265432)
			(xy 439.351419 -199.305896) (xy 439.308262 -199.340313) (xy 439.260458 -199.367912) (xy 439.209074 -199.388079)
			(xy 439.155259 -199.400362) (xy 439.100214 -199.404487) (xy 439.045169 -199.400362) (xy 438.991354 -199.388079)
			(xy 438.93997 -199.367912) (xy 438.892166 -199.340313) (xy 438.849009 -199.305896) (xy 438.811464 -199.265432)
			(xy 438.780369 -199.219825) (xy 438.756419 -199.170092) (xy 438.740149 -199.117345) (xy 438.731922 -199.062762)
			(xy 438.731406 -199.035162) (xy 438.732014 -199.004408) (xy 438.742222 -198.943754) (xy 438.762379 -198.885644)
			(xy 438.776618 -198.858378) (xy 438.783375 -198.844902) (xy 438.789503 -198.815401) (xy 438.786759 -198.785396)
			(xy 438.775383 -198.757495) (xy 438.756362 -198.734127) (xy 438.731353 -198.717322) (xy 438.70253 -198.708544)
			(xy 438.687464 -198.70801) (xy 431.96891 -198.70801) (xy 431.953848 -198.708551) (xy 431.925033 -198.717334)
			(xy 431.900031 -198.734138) (xy 431.881018 -198.757503) (xy 431.869645 -198.785398) (xy 431.866901 -198.815397)
			(xy 431.873026 -198.844891) (xy 431.879756 -198.858378) (xy 431.893954 -198.885661) (xy 431.914087 -198.943772)
			(xy 431.924331 -199.004413) (xy 431.924968 -199.035162) (xy 431.924452 -199.062762) (xy 431.916225 -199.117345)
			(xy 431.899955 -199.170092) (xy 431.876005 -199.219825) (xy 431.84491 -199.265432) (xy 431.807365 -199.305896)
			(xy 431.764208 -199.340313) (xy 431.716404 -199.367912) (xy 431.66502 -199.388079) (xy 431.611205 -199.400362)
			(xy 431.55616 -199.404487) (xy 431.501115 -199.400362) (xy 431.4473 -199.388079) (xy 431.395916 -199.367912)
			(xy 431.348112 -199.340313) (xy 431.304955 -199.305896) (xy 431.26741 -199.265432) (xy 431.236315 -199.219825)
			(xy 431.212365 -199.170092) (xy 431.196095 -199.117345) (xy 431.187868 -199.062762) (xy 431.187352 -199.035162)
			(xy 431.18796 -199.004408) (xy 431.198169 -198.943755) (xy 431.218329 -198.885646) (xy 431.232564 -198.858378)
			(xy 431.239319 -198.8449) (xy 431.245444 -198.815396) (xy 431.242699 -198.785388) (xy 431.231324 -198.757485)
			(xy 431.212306 -198.734112) (xy 431.187299 -198.717299) (xy 431.158476 -198.70851) (xy 431.14341 -198.70801)
			(xy 426.149262 -198.70801) (xy 426.139195 -198.70844) (xy 426.120602 -198.716166) (xy 426.113194 -198.722996)
			(xy 426.000164 -198.836026) (xy 425.993315 -198.843423) (xy 425.98558 -198.862022) (xy 425.985178 -198.872094)
			(xy 425.985178 -199.885046) (xy 427.086791 -199.885046) (xy 427.090726 -199.831275) (xy 427.102449 -199.778651)
			(xy 427.121709 -199.728294) (xy 427.148095 -199.681277) (xy 427.181047 -199.638604) (xy 427.21986 -199.601183)
			(xy 427.263708 -199.569813) (xy 427.311656 -199.545161) (xy 427.362683 -199.527753) (xy 427.415701 -199.51796)
			(xy 427.46958 -199.515991) (xy 427.523171 -199.521888) (xy 427.575332 -199.535524) (xy 427.624952 -199.556611)
			(xy 427.670973 -199.584697) (xy 427.712415 -199.619185) (xy 427.748393 -199.659339) (xy 427.778141 -199.704303)
			(xy 427.801026 -199.75312) (xy 427.816558 -199.804749) (xy 427.824408 -199.858089) (xy 427.8249 -199.885046)
			(xy 434.630845 -199.885046) (xy 434.63478 -199.831275) (xy 434.646503 -199.778651) (xy 434.665763 -199.728294)
			(xy 434.692149 -199.681277) (xy 434.725101 -199.638604) (xy 434.763914 -199.601183) (xy 434.807762 -199.569813)
			(xy 434.85571 -199.545161) (xy 434.906737 -199.527753) (xy 434.959755 -199.51796) (xy 435.013634 -199.515991)
			(xy 435.067225 -199.521888) (xy 435.119386 -199.535524) (xy 435.169006 -199.556611) (xy 435.215027 -199.584697)
			(xy 435.256469 -199.619185) (xy 435.292447 -199.659339) (xy 435.322195 -199.704303) (xy 435.34508 -199.75312)
			(xy 435.360612 -199.804749) (xy 435.368462 -199.858089) (xy 435.368954 -199.885046) (xy 442.174899 -199.885046)
			(xy 442.178834 -199.831275) (xy 442.190557 -199.778651) (xy 442.209817 -199.728294) (xy 442.236203 -199.681277)
			(xy 442.269155 -199.638604) (xy 442.307968 -199.601183) (xy 442.351816 -199.569813) (xy 442.399764 -199.545161)
			(xy 442.450791 -199.527753) (xy 442.503809 -199.51796) (xy 442.557688 -199.515991) (xy 442.611279 -199.521888)
			(xy 442.66344 -199.535524) (xy 442.71306 -199.556611) (xy 442.759081 -199.584697) (xy 442.800523 -199.619185)
			(xy 442.836501 -199.659339) (xy 442.866249 -199.704303) (xy 442.889134 -199.75312) (xy 442.904666 -199.804749)
			(xy 442.912516 -199.858089) (xy 442.913008 -199.885046) (xy 449.718699 -199.885046) (xy 449.722634 -199.831275)
			(xy 449.734357 -199.778651) (xy 449.753617 -199.728294) (xy 449.780003 -199.681277) (xy 449.812955 -199.638604)
			(xy 449.851768 -199.601183) (xy 449.895616 -199.569813) (xy 449.943564 -199.545161) (xy 449.994591 -199.527753)
			(xy 450.047609 -199.51796) (xy 450.101488 -199.515991) (xy 450.155079 -199.521888) (xy 450.20724 -199.535524)
			(xy 450.25686 -199.556611) (xy 450.302881 -199.584697) (xy 450.344323 -199.619185) (xy 450.380301 -199.659339)
			(xy 450.410049 -199.704303) (xy 450.432934 -199.75312) (xy 450.448466 -199.804749) (xy 450.456316 -199.858089)
			(xy 450.456808 -199.885046) (xy 450.456316 -199.912003) (xy 450.448466 -199.965343) (xy 450.432934 -200.016972)
			(xy 450.410049 -200.065789) (xy 450.380301 -200.110753) (xy 450.344323 -200.150907) (xy 450.302881 -200.185395)
			(xy 450.25686 -200.213481) (xy 450.20724 -200.234568) (xy 450.155079 -200.248204) (xy 450.101488 -200.254101)
			(xy 450.047609 -200.252132) (xy 449.994591 -200.242339) (xy 449.943564 -200.224931) (xy 449.895616 -200.200279)
			(xy 449.851768 -200.168909) (xy 449.812955 -200.131488) (xy 449.780003 -200.088815) (xy 449.753617 -200.041798)
			(xy 449.734357 -199.991441) (xy 449.722634 -199.938817) (xy 449.718699 -199.885046) (xy 442.913008 -199.885046)
			(xy 442.912516 -199.912003) (xy 442.904666 -199.965343) (xy 442.889134 -200.016972) (xy 442.866249 -200.065789)
			(xy 442.836501 -200.110753) (xy 442.800523 -200.150907) (xy 442.759081 -200.185395) (xy 442.71306 -200.213481)
			(xy 442.66344 -200.234568) (xy 442.611279 -200.248204) (xy 442.557688 -200.254101) (xy 442.503809 -200.252132)
			(xy 442.450791 -200.242339) (xy 442.399764 -200.224931) (xy 442.351816 -200.200279) (xy 442.307968 -200.168909)
			(xy 442.269155 -200.131488) (xy 442.236203 -200.088815) (xy 442.209817 -200.041798) (xy 442.190557 -199.991441)
			(xy 442.178834 -199.938817) (xy 442.174899 -199.885046) (xy 435.368954 -199.885046) (xy 435.368462 -199.912003)
			(xy 435.360612 -199.965343) (xy 435.34508 -200.016972) (xy 435.322195 -200.065789) (xy 435.292447 -200.110753)
			(xy 435.256469 -200.150907) (xy 435.215027 -200.185395) (xy 435.169006 -200.213481) (xy 435.119386 -200.234568)
			(xy 435.067225 -200.248204) (xy 435.013634 -200.254101) (xy 434.959755 -200.252132) (xy 434.906737 -200.242339)
			(xy 434.85571 -200.224931) (xy 434.807762 -200.200279) (xy 434.763914 -200.168909) (xy 434.725101 -200.131488)
			(xy 434.692149 -200.088815) (xy 434.665763 -200.041798) (xy 434.646503 -199.991441) (xy 434.63478 -199.938817)
			(xy 434.630845 -199.885046) (xy 427.8249 -199.885046) (xy 427.824408 -199.912003) (xy 427.816558 -199.965343)
			(xy 427.801026 -200.016972) (xy 427.778141 -200.065789) (xy 427.748393 -200.110753) (xy 427.712415 -200.150907)
			(xy 427.670973 -200.185395) (xy 427.624952 -200.213481) (xy 427.575332 -200.234568) (xy 427.523171 -200.248204)
			(xy 427.46958 -200.254101) (xy 427.415701 -200.252132) (xy 427.362683 -200.242339) (xy 427.311656 -200.224931)
			(xy 427.263708 -200.200279) (xy 427.21986 -200.168909) (xy 427.181047 -200.131488) (xy 427.148095 -200.088815)
			(xy 427.121709 -200.041798) (xy 427.102449 -199.991441) (xy 427.090726 -199.938817) (xy 427.086791 -199.885046)
			(xy 425.985178 -199.885046) (xy 425.985178 -200.735184) (xy 431.186859 -200.735184) (xy 431.190794 -200.681413)
			(xy 431.202517 -200.628789) (xy 431.221777 -200.578432) (xy 431.248163 -200.531415) (xy 431.281115 -200.488742)
			(xy 431.319928 -200.451321) (xy 431.363776 -200.419951) (xy 431.411724 -200.395299) (xy 431.462751 -200.377891)
			(xy 431.515769 -200.368098) (xy 431.569648 -200.366129) (xy 431.623239 -200.372026) (xy 431.6754 -200.385662)
			(xy 431.72502 -200.406749) (xy 431.771041 -200.434835) (xy 431.812483 -200.469323) (xy 431.848461 -200.509477)
			(xy 431.878209 -200.554441) (xy 431.901094 -200.603258) (xy 431.916626 -200.654887) (xy 431.924476 -200.708227)
			(xy 431.924968 -200.735184) (xy 438.730913 -200.735184) (xy 438.734848 -200.681413) (xy 438.746571 -200.628789)
			(xy 438.765831 -200.578432) (xy 438.792217 -200.531415) (xy 438.825169 -200.488742) (xy 438.863982 -200.451321)
			(xy 438.90783 -200.419951) (xy 438.955778 -200.395299) (xy 439.006805 -200.377891) (xy 439.059823 -200.368098)
			(xy 439.113702 -200.366129) (xy 439.167293 -200.372026) (xy 439.219454 -200.385662) (xy 439.269074 -200.406749)
			(xy 439.315095 -200.434835) (xy 439.356537 -200.469323) (xy 439.392515 -200.509477) (xy 439.422263 -200.554441)
			(xy 439.445148 -200.603258) (xy 439.46068 -200.654887) (xy 439.46853 -200.708227) (xy 439.469022 -200.735184)
			(xy 446.274967 -200.735184) (xy 446.278902 -200.681413) (xy 446.290625 -200.628789) (xy 446.309885 -200.578432)
			(xy 446.336271 -200.531415) (xy 446.369223 -200.488742) (xy 446.408036 -200.451321) (xy 446.451884 -200.419951)
			(xy 446.499832 -200.395299) (xy 446.550859 -200.377891) (xy 446.603877 -200.368098) (xy 446.657756 -200.366129)
			(xy 446.711347 -200.372026) (xy 446.763508 -200.385662) (xy 446.813128 -200.406749) (xy 446.859149 -200.434835)
			(xy 446.900591 -200.469323) (xy 446.936569 -200.509477) (xy 446.966317 -200.554441) (xy 446.989202 -200.603258)
			(xy 447.004734 -200.654887) (xy 447.012584 -200.708227) (xy 447.013076 -200.735184) (xy 453.818767 -200.735184)
			(xy 453.822702 -200.681413) (xy 453.834425 -200.628789) (xy 453.853685 -200.578432) (xy 453.880071 -200.531415)
			(xy 453.913023 -200.488742) (xy 453.951836 -200.451321) (xy 453.995684 -200.419951) (xy 454.043632 -200.395299)
			(xy 454.094659 -200.377891) (xy 454.147677 -200.368098) (xy 454.201556 -200.366129) (xy 454.255147 -200.372026)
			(xy 454.307308 -200.385662) (xy 454.356928 -200.406749) (xy 454.402949 -200.434835) (xy 454.444391 -200.469323)
			(xy 454.480369 -200.509477) (xy 454.510117 -200.554441) (xy 454.533002 -200.603258) (xy 454.548534 -200.654887)
			(xy 454.556384 -200.708227) (xy 454.556876 -200.735184) (xy 454.556384 -200.762141) (xy 454.548534 -200.815481)
			(xy 454.533002 -200.86711) (xy 454.510117 -200.915927) (xy 454.480369 -200.960891) (xy 454.444391 -201.001045)
			(xy 454.402949 -201.035533) (xy 454.356928 -201.063619) (xy 454.307308 -201.084706) (xy 454.255147 -201.098342)
			(xy 454.201556 -201.104239) (xy 454.147677 -201.10227) (xy 454.094659 -201.092477) (xy 454.043632 -201.075069)
			(xy 453.995684 -201.050417) (xy 453.951836 -201.019047) (xy 453.913023 -200.981626) (xy 453.880071 -200.938953)
			(xy 453.853685 -200.891936) (xy 453.834425 -200.841579) (xy 453.822702 -200.788955) (xy 453.818767 -200.735184)
			(xy 447.013076 -200.735184) (xy 447.012584 -200.762141) (xy 447.004734 -200.815481) (xy 446.989202 -200.86711)
			(xy 446.966317 -200.915927) (xy 446.936569 -200.960891) (xy 446.900591 -201.001045) (xy 446.859149 -201.035533)
			(xy 446.813128 -201.063619) (xy 446.763508 -201.084706) (xy 446.711347 -201.098342) (xy 446.657756 -201.104239)
			(xy 446.603877 -201.10227) (xy 446.550859 -201.092477) (xy 446.499832 -201.075069) (xy 446.451884 -201.050417)
			(xy 446.408036 -201.019047) (xy 446.369223 -200.981626) (xy 446.336271 -200.938953) (xy 446.309885 -200.891936)
			(xy 446.290625 -200.841579) (xy 446.278902 -200.788955) (xy 446.274967 -200.735184) (xy 439.469022 -200.735184)
			(xy 439.46853 -200.762141) (xy 439.46068 -200.815481) (xy 439.445148 -200.86711) (xy 439.422263 -200.915927)
			(xy 439.392515 -200.960891) (xy 439.356537 -201.001045) (xy 439.315095 -201.035533) (xy 439.269074 -201.063619)
			(xy 439.219454 -201.084706) (xy 439.167293 -201.098342) (xy 439.113702 -201.104239) (xy 439.059823 -201.10227)
			(xy 439.006805 -201.092477) (xy 438.955778 -201.075069) (xy 438.90783 -201.050417) (xy 438.863982 -201.019047)
			(xy 438.825169 -200.981626) (xy 438.792217 -200.938953) (xy 438.765831 -200.891936) (xy 438.746571 -200.841579)
			(xy 438.734848 -200.788955) (xy 438.730913 -200.735184) (xy 431.924968 -200.735184) (xy 431.924476 -200.762141)
			(xy 431.916626 -200.815481) (xy 431.901094 -200.86711) (xy 431.878209 -200.915927) (xy 431.848461 -200.960891)
			(xy 431.812483 -201.001045) (xy 431.771041 -201.035533) (xy 431.72502 -201.063619) (xy 431.6754 -201.084706)
			(xy 431.623239 -201.098342) (xy 431.569648 -201.104239) (xy 431.515769 -201.10227) (xy 431.462751 -201.092477)
			(xy 431.411724 -201.075069) (xy 431.363776 -201.050417) (xy 431.319928 -201.019047) (xy 431.281115 -200.981626)
			(xy 431.248163 -200.938953) (xy 431.221777 -200.891936) (xy 431.202517 -200.841579) (xy 431.190794 -200.788955)
			(xy 431.186859 -200.735184) (xy 425.985178 -200.735184) (xy 425.985178 -201.585068) (xy 427.086791 -201.585068)
			(xy 427.090726 -201.531297) (xy 427.102449 -201.478673) (xy 427.121709 -201.428316) (xy 427.148095 -201.381299)
			(xy 427.181047 -201.338626) (xy 427.21986 -201.301205) (xy 427.263708 -201.269835) (xy 427.311656 -201.245183)
			(xy 427.362683 -201.227775) (xy 427.415701 -201.217982) (xy 427.46958 -201.216013) (xy 427.523171 -201.22191)
			(xy 427.575332 -201.235546) (xy 427.624952 -201.256633) (xy 427.670973 -201.284719) (xy 427.712415 -201.319207)
			(xy 427.748393 -201.359361) (xy 427.778141 -201.404325) (xy 427.801026 -201.453142) (xy 427.816558 -201.504771)
			(xy 427.824408 -201.558111) (xy 427.8249 -201.585068) (xy 431.186859 -201.585068) (xy 431.190794 -201.531297)
			(xy 431.202517 -201.478673) (xy 431.221777 -201.428316) (xy 431.248163 -201.381299) (xy 431.281115 -201.338626)
			(xy 431.319928 -201.301205) (xy 431.363776 -201.269835) (xy 431.411724 -201.245183) (xy 431.462751 -201.227775)
			(xy 431.515769 -201.217982) (xy 431.569648 -201.216013) (xy 431.623239 -201.22191) (xy 431.6754 -201.235546)
			(xy 431.72502 -201.256633) (xy 431.771041 -201.284719) (xy 431.812483 -201.319207) (xy 431.848461 -201.359361)
			(xy 431.878209 -201.404325) (xy 431.901094 -201.453142) (xy 431.916626 -201.504771) (xy 431.924476 -201.558111)
			(xy 431.924968 -201.585068) (xy 434.630845 -201.585068) (xy 434.63478 -201.531297) (xy 434.646503 -201.478673)
			(xy 434.665763 -201.428316) (xy 434.692149 -201.381299) (xy 434.725101 -201.338626) (xy 434.763914 -201.301205)
			(xy 434.807762 -201.269835) (xy 434.85571 -201.245183) (xy 434.906737 -201.227775) (xy 434.959755 -201.217982)
			(xy 435.013634 -201.216013) (xy 435.067225 -201.22191) (xy 435.119386 -201.235546) (xy 435.169006 -201.256633)
			(xy 435.215027 -201.284719) (xy 435.256469 -201.319207) (xy 435.292447 -201.359361) (xy 435.322195 -201.404325)
			(xy 435.34508 -201.453142) (xy 435.360612 -201.504771) (xy 435.368462 -201.558111) (xy 435.368954 -201.585068)
			(xy 438.730913 -201.585068) (xy 438.734848 -201.531297) (xy 438.746571 -201.478673) (xy 438.765831 -201.428316)
			(xy 438.792217 -201.381299) (xy 438.825169 -201.338626) (xy 438.863982 -201.301205) (xy 438.90783 -201.269835)
			(xy 438.955778 -201.245183) (xy 439.006805 -201.227775) (xy 439.059823 -201.217982) (xy 439.113702 -201.216013)
			(xy 439.167293 -201.22191) (xy 439.219454 -201.235546) (xy 439.269074 -201.256633) (xy 439.315095 -201.284719)
			(xy 439.356537 -201.319207) (xy 439.392515 -201.359361) (xy 439.422263 -201.404325) (xy 439.445148 -201.453142)
			(xy 439.46068 -201.504771) (xy 439.46853 -201.558111) (xy 439.469022 -201.585068) (xy 442.174899 -201.585068)
			(xy 442.178834 -201.531297) (xy 442.190557 -201.478673) (xy 442.209817 -201.428316) (xy 442.236203 -201.381299)
			(xy 442.269155 -201.338626) (xy 442.307968 -201.301205) (xy 442.351816 -201.269835) (xy 442.399764 -201.245183)
			(xy 442.450791 -201.227775) (xy 442.503809 -201.217982) (xy 442.557688 -201.216013) (xy 442.611279 -201.22191)
			(xy 442.66344 -201.235546) (xy 442.71306 -201.256633) (xy 442.759081 -201.284719) (xy 442.800523 -201.319207)
			(xy 442.836501 -201.359361) (xy 442.866249 -201.404325) (xy 442.889134 -201.453142) (xy 442.904666 -201.504771)
			(xy 442.912516 -201.558111) (xy 442.913008 -201.585068) (xy 446.274967 -201.585068) (xy 446.278902 -201.531297)
			(xy 446.290625 -201.478673) (xy 446.309885 -201.428316) (xy 446.336271 -201.381299) (xy 446.369223 -201.338626)
			(xy 446.408036 -201.301205) (xy 446.451884 -201.269835) (xy 446.499832 -201.245183) (xy 446.550859 -201.227775)
			(xy 446.603877 -201.217982) (xy 446.657756 -201.216013) (xy 446.711347 -201.22191) (xy 446.763508 -201.235546)
			(xy 446.813128 -201.256633) (xy 446.859149 -201.284719) (xy 446.900591 -201.319207) (xy 446.936569 -201.359361)
			(xy 446.966317 -201.404325) (xy 446.989202 -201.453142) (xy 447.004734 -201.504771) (xy 447.012584 -201.558111)
			(xy 447.013076 -201.585068) (xy 449.718699 -201.585068) (xy 449.722634 -201.531297) (xy 449.734357 -201.478673)
			(xy 449.753617 -201.428316) (xy 449.780003 -201.381299) (xy 449.812955 -201.338626) (xy 449.851768 -201.301205)
			(xy 449.895616 -201.269835) (xy 449.943564 -201.245183) (xy 449.994591 -201.227775) (xy 450.047609 -201.217982)
			(xy 450.101488 -201.216013) (xy 450.155079 -201.22191) (xy 450.20724 -201.235546) (xy 450.25686 -201.256633)
			(xy 450.302881 -201.284719) (xy 450.344323 -201.319207) (xy 450.380301 -201.359361) (xy 450.410049 -201.404325)
			(xy 450.432934 -201.453142) (xy 450.448466 -201.504771) (xy 450.456316 -201.558111) (xy 450.456808 -201.585068)
			(xy 453.818767 -201.585068) (xy 453.822702 -201.531297) (xy 453.834425 -201.478673) (xy 453.853685 -201.428316)
			(xy 453.880071 -201.381299) (xy 453.913023 -201.338626) (xy 453.951836 -201.301205) (xy 453.995684 -201.269835)
			(xy 454.043632 -201.245183) (xy 454.094659 -201.227775) (xy 454.147677 -201.217982) (xy 454.201556 -201.216013)
			(xy 454.255147 -201.22191) (xy 454.307308 -201.235546) (xy 454.356928 -201.256633) (xy 454.402949 -201.284719)
			(xy 454.444391 -201.319207) (xy 454.480369 -201.359361) (xy 454.510117 -201.404325) (xy 454.533002 -201.453142)
			(xy 454.548534 -201.504771) (xy 454.556384 -201.558111) (xy 454.556876 -201.585068) (xy 454.556384 -201.612025)
			(xy 454.548534 -201.665365) (xy 454.533002 -201.716994) (xy 454.510117 -201.765811) (xy 454.480369 -201.810775)
			(xy 454.444391 -201.850929) (xy 454.402949 -201.885417) (xy 454.356928 -201.913503) (xy 454.307308 -201.93459)
			(xy 454.255147 -201.948226) (xy 454.201556 -201.954123) (xy 454.147677 -201.952154) (xy 454.094659 -201.942361)
			(xy 454.043632 -201.924953) (xy 453.995684 -201.900301) (xy 453.951836 -201.868931) (xy 453.913023 -201.83151)
			(xy 453.880071 -201.788837) (xy 453.853685 -201.74182) (xy 453.834425 -201.691463) (xy 453.822702 -201.638839)
			(xy 453.818767 -201.585068) (xy 450.456808 -201.585068) (xy 450.456316 -201.612025) (xy 450.448466 -201.665365)
			(xy 450.432934 -201.716994) (xy 450.410049 -201.765811) (xy 450.380301 -201.810775) (xy 450.344323 -201.850929)
			(xy 450.302881 -201.885417) (xy 450.25686 -201.913503) (xy 450.20724 -201.93459) (xy 450.155079 -201.948226)
			(xy 450.101488 -201.954123) (xy 450.047609 -201.952154) (xy 449.994591 -201.942361) (xy 449.943564 -201.924953)
			(xy 449.895616 -201.900301) (xy 449.851768 -201.868931) (xy 449.812955 -201.83151) (xy 449.780003 -201.788837)
			(xy 449.753617 -201.74182) (xy 449.734357 -201.691463) (xy 449.722634 -201.638839) (xy 449.718699 -201.585068)
			(xy 447.013076 -201.585068) (xy 447.012584 -201.612025) (xy 447.004734 -201.665365) (xy 446.989202 -201.716994)
			(xy 446.966317 -201.765811) (xy 446.936569 -201.810775) (xy 446.900591 -201.850929) (xy 446.859149 -201.885417)
			(xy 446.813128 -201.913503) (xy 446.763508 -201.93459) (xy 446.711347 -201.948226) (xy 446.657756 -201.954123)
			(xy 446.603877 -201.952154) (xy 446.550859 -201.942361) (xy 446.499832 -201.924953) (xy 446.451884 -201.900301)
			(xy 446.408036 -201.868931) (xy 446.369223 -201.83151) (xy 446.336271 -201.788837) (xy 446.309885 -201.74182)
			(xy 446.290625 -201.691463) (xy 446.278902 -201.638839) (xy 446.274967 -201.585068) (xy 442.913008 -201.585068)
			(xy 442.912516 -201.612025) (xy 442.904666 -201.665365) (xy 442.889134 -201.716994) (xy 442.866249 -201.765811)
			(xy 442.836501 -201.810775) (xy 442.800523 -201.850929) (xy 442.759081 -201.885417) (xy 442.71306 -201.913503)
			(xy 442.66344 -201.93459) (xy 442.611279 -201.948226) (xy 442.557688 -201.954123) (xy 442.503809 -201.952154)
			(xy 442.450791 -201.942361) (xy 442.399764 -201.924953) (xy 442.351816 -201.900301) (xy 442.307968 -201.868931)
			(xy 442.269155 -201.83151) (xy 442.236203 -201.788837) (xy 442.209817 -201.74182) (xy 442.190557 -201.691463)
			(xy 442.178834 -201.638839) (xy 442.174899 -201.585068) (xy 439.469022 -201.585068) (xy 439.46853 -201.612025)
			(xy 439.46068 -201.665365) (xy 439.445148 -201.716994) (xy 439.422263 -201.765811) (xy 439.392515 -201.810775)
			(xy 439.356537 -201.850929) (xy 439.315095 -201.885417) (xy 439.269074 -201.913503) (xy 439.219454 -201.93459)
			(xy 439.167293 -201.948226) (xy 439.113702 -201.954123) (xy 439.059823 -201.952154) (xy 439.006805 -201.942361)
			(xy 438.955778 -201.924953) (xy 438.90783 -201.900301) (xy 438.863982 -201.868931) (xy 438.825169 -201.83151)
			(xy 438.792217 -201.788837) (xy 438.765831 -201.74182) (xy 438.746571 -201.691463) (xy 438.734848 -201.638839)
			(xy 438.730913 -201.585068) (xy 435.368954 -201.585068) (xy 435.368462 -201.612025) (xy 435.360612 -201.665365)
			(xy 435.34508 -201.716994) (xy 435.322195 -201.765811) (xy 435.292447 -201.810775) (xy 435.256469 -201.850929)
			(xy 435.215027 -201.885417) (xy 435.169006 -201.913503) (xy 435.119386 -201.93459) (xy 435.067225 -201.948226)
			(xy 435.013634 -201.954123) (xy 434.959755 -201.952154) (xy 434.906737 -201.942361) (xy 434.85571 -201.924953)
			(xy 434.807762 -201.900301) (xy 434.763914 -201.868931) (xy 434.725101 -201.83151) (xy 434.692149 -201.788837)
			(xy 434.665763 -201.74182) (xy 434.646503 -201.691463) (xy 434.63478 -201.638839) (xy 434.630845 -201.585068)
			(xy 431.924968 -201.585068) (xy 431.924476 -201.612025) (xy 431.916626 -201.665365) (xy 431.901094 -201.716994)
			(xy 431.878209 -201.765811) (xy 431.848461 -201.810775) (xy 431.812483 -201.850929) (xy 431.771041 -201.885417)
			(xy 431.72502 -201.913503) (xy 431.6754 -201.93459) (xy 431.623239 -201.948226) (xy 431.569648 -201.954123)
			(xy 431.515769 -201.952154) (xy 431.462751 -201.942361) (xy 431.411724 -201.924953) (xy 431.363776 -201.900301)
			(xy 431.319928 -201.868931) (xy 431.281115 -201.83151) (xy 431.248163 -201.788837) (xy 431.221777 -201.74182)
			(xy 431.202517 -201.691463) (xy 431.190794 -201.638839) (xy 431.186859 -201.585068) (xy 427.8249 -201.585068)
			(xy 427.824408 -201.612025) (xy 427.816558 -201.665365) (xy 427.801026 -201.716994) (xy 427.778141 -201.765811)
			(xy 427.748393 -201.810775) (xy 427.712415 -201.850929) (xy 427.670973 -201.885417) (xy 427.624952 -201.913503)
			(xy 427.575332 -201.93459) (xy 427.523171 -201.948226) (xy 427.46958 -201.954123) (xy 427.415701 -201.952154)
			(xy 427.362683 -201.942361) (xy 427.311656 -201.924953) (xy 427.263708 -201.900301) (xy 427.21986 -201.868931)
			(xy 427.181047 -201.83151) (xy 427.148095 -201.788837) (xy 427.121709 -201.74182) (xy 427.102449 -201.691463)
			(xy 427.090726 -201.638839) (xy 427.086791 -201.585068) (xy 425.985178 -201.585068) (xy 425.985178 -202.434952)
			(xy 427.086791 -202.434952) (xy 427.090726 -202.381181) (xy 427.102449 -202.328557) (xy 427.121709 -202.2782)
			(xy 427.148095 -202.231183) (xy 427.181047 -202.18851) (xy 427.21986 -202.151089) (xy 427.263708 -202.119719)
			(xy 427.311656 -202.095067) (xy 427.362683 -202.077659) (xy 427.415701 -202.067866) (xy 427.46958 -202.065897)
			(xy 427.523171 -202.071794) (xy 427.575332 -202.08543) (xy 427.624952 -202.106517) (xy 427.670973 -202.134603)
			(xy 427.712415 -202.169091) (xy 427.748393 -202.209245) (xy 427.778141 -202.254209) (xy 427.801026 -202.303026)
			(xy 427.816558 -202.354655) (xy 427.824408 -202.407995) (xy 427.8249 -202.434952) (xy 434.630845 -202.434952)
			(xy 434.63478 -202.381181) (xy 434.646503 -202.328557) (xy 434.665763 -202.2782) (xy 434.692149 -202.231183)
			(xy 434.725101 -202.18851) (xy 434.763914 -202.151089) (xy 434.807762 -202.119719) (xy 434.85571 -202.095067)
			(xy 434.906737 -202.077659) (xy 434.959755 -202.067866) (xy 435.013634 -202.065897) (xy 435.067225 -202.071794)
			(xy 435.119386 -202.08543) (xy 435.169006 -202.106517) (xy 435.215027 -202.134603) (xy 435.256469 -202.169091)
			(xy 435.292447 -202.209245) (xy 435.322195 -202.254209) (xy 435.34508 -202.303026) (xy 435.360612 -202.354655)
			(xy 435.368462 -202.407995) (xy 435.368954 -202.434952) (xy 442.174899 -202.434952) (xy 442.178834 -202.381181)
			(xy 442.190557 -202.328557) (xy 442.209817 -202.2782) (xy 442.236203 -202.231183) (xy 442.269155 -202.18851)
			(xy 442.307968 -202.151089) (xy 442.351816 -202.119719) (xy 442.399764 -202.095067) (xy 442.450791 -202.077659)
			(xy 442.503809 -202.067866) (xy 442.557688 -202.065897) (xy 442.611279 -202.071794) (xy 442.66344 -202.08543)
			(xy 442.71306 -202.106517) (xy 442.759081 -202.134603) (xy 442.800523 -202.169091) (xy 442.836501 -202.209245)
			(xy 442.866249 -202.254209) (xy 442.889134 -202.303026) (xy 442.904666 -202.354655) (xy 442.912516 -202.407995)
			(xy 442.913008 -202.434952) (xy 449.718699 -202.434952) (xy 449.722634 -202.381181) (xy 449.734357 -202.328557)
			(xy 449.753617 -202.2782) (xy 449.780003 -202.231183) (xy 449.812955 -202.18851) (xy 449.851768 -202.151089)
			(xy 449.895616 -202.119719) (xy 449.943564 -202.095067) (xy 449.994591 -202.077659) (xy 450.047609 -202.067866)
			(xy 450.101488 -202.065897) (xy 450.155079 -202.071794) (xy 450.20724 -202.08543) (xy 450.25686 -202.106517)
			(xy 450.302881 -202.134603) (xy 450.344323 -202.169091) (xy 450.380301 -202.209245) (xy 450.410049 -202.254209)
			(xy 450.432934 -202.303026) (xy 450.448466 -202.354655) (xy 450.456316 -202.407995) (xy 450.456808 -202.434952)
			(xy 450.456316 -202.461909) (xy 450.448466 -202.515249) (xy 450.432934 -202.566878) (xy 450.410049 -202.615695)
			(xy 450.380301 -202.660659) (xy 450.344323 -202.700813) (xy 450.302881 -202.735301) (xy 450.25686 -202.763387)
			(xy 450.20724 -202.784474) (xy 450.155079 -202.79811) (xy 450.101488 -202.804007) (xy 450.047609 -202.802038)
			(xy 449.994591 -202.792245) (xy 449.943564 -202.774837) (xy 449.895616 -202.750185) (xy 449.851768 -202.718815)
			(xy 449.812955 -202.681394) (xy 449.780003 -202.638721) (xy 449.753617 -202.591704) (xy 449.734357 -202.541347)
			(xy 449.722634 -202.488723) (xy 449.718699 -202.434952) (xy 442.913008 -202.434952) (xy 442.912516 -202.461909)
			(xy 442.904666 -202.515249) (xy 442.889134 -202.566878) (xy 442.866249 -202.615695) (xy 442.836501 -202.660659)
			(xy 442.800523 -202.700813) (xy 442.759081 -202.735301) (xy 442.71306 -202.763387) (xy 442.66344 -202.784474)
			(xy 442.611279 -202.79811) (xy 442.557688 -202.804007) (xy 442.503809 -202.802038) (xy 442.450791 -202.792245)
			(xy 442.399764 -202.774837) (xy 442.351816 -202.750185) (xy 442.307968 -202.718815) (xy 442.269155 -202.681394)
			(xy 442.236203 -202.638721) (xy 442.209817 -202.591704) (xy 442.190557 -202.541347) (xy 442.178834 -202.488723)
			(xy 442.174899 -202.434952) (xy 435.368954 -202.434952) (xy 435.368462 -202.461909) (xy 435.360612 -202.515249)
			(xy 435.34508 -202.566878) (xy 435.322195 -202.615695) (xy 435.292447 -202.660659) (xy 435.256469 -202.700813)
			(xy 435.215027 -202.735301) (xy 435.169006 -202.763387) (xy 435.119386 -202.784474) (xy 435.067225 -202.79811)
			(xy 435.013634 -202.804007) (xy 434.959755 -202.802038) (xy 434.906737 -202.792245) (xy 434.85571 -202.774837)
			(xy 434.807762 -202.750185) (xy 434.763914 -202.718815) (xy 434.725101 -202.681394) (xy 434.692149 -202.638721)
			(xy 434.665763 -202.591704) (xy 434.646503 -202.541347) (xy 434.63478 -202.488723) (xy 434.630845 -202.434952)
			(xy 427.8249 -202.434952) (xy 427.824408 -202.461909) (xy 427.816558 -202.515249) (xy 427.801026 -202.566878)
			(xy 427.778141 -202.615695) (xy 427.748393 -202.660659) (xy 427.712415 -202.700813) (xy 427.670973 -202.735301)
			(xy 427.624952 -202.763387) (xy 427.575332 -202.784474) (xy 427.523171 -202.79811) (xy 427.46958 -202.804007)
			(xy 427.415701 -202.802038) (xy 427.362683 -202.792245) (xy 427.311656 -202.774837) (xy 427.263708 -202.750185)
			(xy 427.21986 -202.718815) (xy 427.181047 -202.681394) (xy 427.148095 -202.638721) (xy 427.121709 -202.591704)
			(xy 427.102449 -202.541347) (xy 427.090726 -202.488723) (xy 427.086791 -202.434952) (xy 425.985178 -202.434952)
			(xy 425.985178 -203.28509) (xy 431.186859 -203.28509) (xy 431.190794 -203.231319) (xy 431.202517 -203.178695)
			(xy 431.221777 -203.128338) (xy 431.248163 -203.081321) (xy 431.281115 -203.038648) (xy 431.319928 -203.001227)
			(xy 431.363776 -202.969857) (xy 431.411724 -202.945205) (xy 431.462751 -202.927797) (xy 431.515769 -202.918004)
			(xy 431.569648 -202.916035) (xy 431.623239 -202.921932) (xy 431.6754 -202.935568) (xy 431.72502 -202.956655)
			(xy 431.771041 -202.984741) (xy 431.812483 -203.019229) (xy 431.848461 -203.059383) (xy 431.878209 -203.104347)
			(xy 431.901094 -203.153164) (xy 431.916626 -203.204793) (xy 431.924476 -203.258133) (xy 431.924968 -203.28509)
			(xy 438.730913 -203.28509) (xy 438.734848 -203.231319) (xy 438.746571 -203.178695) (xy 438.765831 -203.128338)
			(xy 438.792217 -203.081321) (xy 438.825169 -203.038648) (xy 438.863982 -203.001227) (xy 438.90783 -202.969857)
			(xy 438.955778 -202.945205) (xy 439.006805 -202.927797) (xy 439.059823 -202.918004) (xy 439.113702 -202.916035)
			(xy 439.167293 -202.921932) (xy 439.219454 -202.935568) (xy 439.269074 -202.956655) (xy 439.315095 -202.984741)
			(xy 439.356537 -203.019229) (xy 439.392515 -203.059383) (xy 439.422263 -203.104347) (xy 439.445148 -203.153164)
			(xy 439.46068 -203.204793) (xy 439.46853 -203.258133) (xy 439.469022 -203.28509) (xy 446.274967 -203.28509)
			(xy 446.278902 -203.231319) (xy 446.290625 -203.178695) (xy 446.309885 -203.128338) (xy 446.336271 -203.081321)
			(xy 446.369223 -203.038648) (xy 446.408036 -203.001227) (xy 446.451884 -202.969857) (xy 446.499832 -202.945205)
			(xy 446.550859 -202.927797) (xy 446.603877 -202.918004) (xy 446.657756 -202.916035) (xy 446.711347 -202.921932)
			(xy 446.763508 -202.935568) (xy 446.813128 -202.956655) (xy 446.859149 -202.984741) (xy 446.900591 -203.019229)
			(xy 446.936569 -203.059383) (xy 446.966317 -203.104347) (xy 446.989202 -203.153164) (xy 447.004734 -203.204793)
			(xy 447.012584 -203.258133) (xy 447.013076 -203.28509) (xy 453.818767 -203.28509) (xy 453.822702 -203.231319)
			(xy 453.834425 -203.178695) (xy 453.853685 -203.128338) (xy 453.880071 -203.081321) (xy 453.913023 -203.038648)
			(xy 453.951836 -203.001227) (xy 453.995684 -202.969857) (xy 454.043632 -202.945205) (xy 454.094659 -202.927797)
			(xy 454.147677 -202.918004) (xy 454.201556 -202.916035) (xy 454.255147 -202.921932) (xy 454.307308 -202.935568)
			(xy 454.356928 -202.956655) (xy 454.402949 -202.984741) (xy 454.444391 -203.019229) (xy 454.480369 -203.059383)
			(xy 454.510117 -203.104347) (xy 454.533002 -203.153164) (xy 454.548534 -203.204793) (xy 454.556384 -203.258133)
			(xy 454.556876 -203.28509) (xy 454.556384 -203.312047) (xy 454.548534 -203.365387) (xy 454.533002 -203.417016)
			(xy 454.510117 -203.465833) (xy 454.480369 -203.510797) (xy 454.444391 -203.550951) (xy 454.402949 -203.585439)
			(xy 454.356928 -203.613525) (xy 454.307308 -203.634612) (xy 454.255147 -203.648248) (xy 454.201556 -203.654145)
			(xy 454.147677 -203.652176) (xy 454.094659 -203.642383) (xy 454.043632 -203.624975) (xy 453.995684 -203.600323)
			(xy 453.951836 -203.568953) (xy 453.913023 -203.531532) (xy 453.880071 -203.488859) (xy 453.853685 -203.441842)
			(xy 453.834425 -203.391485) (xy 453.822702 -203.338861) (xy 453.818767 -203.28509) (xy 447.013076 -203.28509)
			(xy 447.012584 -203.312047) (xy 447.004734 -203.365387) (xy 446.989202 -203.417016) (xy 446.966317 -203.465833)
			(xy 446.936569 -203.510797) (xy 446.900591 -203.550951) (xy 446.859149 -203.585439) (xy 446.813128 -203.613525)
			(xy 446.763508 -203.634612) (xy 446.711347 -203.648248) (xy 446.657756 -203.654145) (xy 446.603877 -203.652176)
			(xy 446.550859 -203.642383) (xy 446.499832 -203.624975) (xy 446.451884 -203.600323) (xy 446.408036 -203.568953)
			(xy 446.369223 -203.531532) (xy 446.336271 -203.488859) (xy 446.309885 -203.441842) (xy 446.290625 -203.391485)
			(xy 446.278902 -203.338861) (xy 446.274967 -203.28509) (xy 439.469022 -203.28509) (xy 439.46853 -203.312047)
			(xy 439.46068 -203.365387) (xy 439.445148 -203.417016) (xy 439.422263 -203.465833) (xy 439.392515 -203.510797)
			(xy 439.356537 -203.550951) (xy 439.315095 -203.585439) (xy 439.269074 -203.613525) (xy 439.219454 -203.634612)
			(xy 439.167293 -203.648248) (xy 439.113702 -203.654145) (xy 439.059823 -203.652176) (xy 439.006805 -203.642383)
			(xy 438.955778 -203.624975) (xy 438.90783 -203.600323) (xy 438.863982 -203.568953) (xy 438.825169 -203.531532)
			(xy 438.792217 -203.488859) (xy 438.765831 -203.441842) (xy 438.746571 -203.391485) (xy 438.734848 -203.338861)
			(xy 438.730913 -203.28509) (xy 431.924968 -203.28509) (xy 431.924476 -203.312047) (xy 431.916626 -203.365387)
			(xy 431.901094 -203.417016) (xy 431.878209 -203.465833) (xy 431.848461 -203.510797) (xy 431.812483 -203.550951)
			(xy 431.771041 -203.585439) (xy 431.72502 -203.613525) (xy 431.6754 -203.634612) (xy 431.623239 -203.648248)
			(xy 431.569648 -203.654145) (xy 431.515769 -203.652176) (xy 431.462751 -203.642383) (xy 431.411724 -203.624975)
			(xy 431.363776 -203.600323) (xy 431.319928 -203.568953) (xy 431.281115 -203.531532) (xy 431.248163 -203.488859)
			(xy 431.221777 -203.441842) (xy 431.202517 -203.391485) (xy 431.190794 -203.338861) (xy 431.186859 -203.28509)
			(xy 425.985178 -203.28509) (xy 425.985178 -204.134974) (xy 427.086791 -204.134974) (xy 427.090726 -204.081203)
			(xy 427.102449 -204.028579) (xy 427.121709 -203.978222) (xy 427.148095 -203.931205) (xy 427.181047 -203.888532)
			(xy 427.21986 -203.851111) (xy 427.263708 -203.819741) (xy 427.311656 -203.795089) (xy 427.362683 -203.777681)
			(xy 427.415701 -203.767888) (xy 427.46958 -203.765919) (xy 427.523171 -203.771816) (xy 427.575332 -203.785452)
			(xy 427.624952 -203.806539) (xy 427.670973 -203.834625) (xy 427.712415 -203.869113) (xy 427.748393 -203.909267)
			(xy 427.778141 -203.954231) (xy 427.801026 -204.003048) (xy 427.816558 -204.054677) (xy 427.824408 -204.108017)
			(xy 427.8249 -204.134974) (xy 434.630845 -204.134974) (xy 434.63478 -204.081203) (xy 434.646503 -204.028579)
			(xy 434.665763 -203.978222) (xy 434.692149 -203.931205) (xy 434.725101 -203.888532) (xy 434.763914 -203.851111)
			(xy 434.807762 -203.819741) (xy 434.85571 -203.795089) (xy 434.906737 -203.777681) (xy 434.959755 -203.767888)
			(xy 435.013634 -203.765919) (xy 435.067225 -203.771816) (xy 435.119386 -203.785452) (xy 435.169006 -203.806539)
			(xy 435.215027 -203.834625) (xy 435.256469 -203.869113) (xy 435.292447 -203.909267) (xy 435.322195 -203.954231)
			(xy 435.34508 -204.003048) (xy 435.360612 -204.054677) (xy 435.368462 -204.108017) (xy 435.368954 -204.134974)
			(xy 442.174899 -204.134974) (xy 442.178834 -204.081203) (xy 442.190557 -204.028579) (xy 442.209817 -203.978222)
			(xy 442.236203 -203.931205) (xy 442.269155 -203.888532) (xy 442.307968 -203.851111) (xy 442.351816 -203.819741)
			(xy 442.399764 -203.795089) (xy 442.450791 -203.777681) (xy 442.503809 -203.767888) (xy 442.557688 -203.765919)
			(xy 442.611279 -203.771816) (xy 442.66344 -203.785452) (xy 442.71306 -203.806539) (xy 442.759081 -203.834625)
			(xy 442.800523 -203.869113) (xy 442.836501 -203.909267) (xy 442.866249 -203.954231) (xy 442.889134 -204.003048)
			(xy 442.904666 -204.054677) (xy 442.912516 -204.108017) (xy 442.913008 -204.134974) (xy 449.718699 -204.134974)
			(xy 449.722634 -204.081203) (xy 449.734357 -204.028579) (xy 449.753617 -203.978222) (xy 449.780003 -203.931205)
			(xy 449.812955 -203.888532) (xy 449.851768 -203.851111) (xy 449.895616 -203.819741) (xy 449.943564 -203.795089)
			(xy 449.994591 -203.777681) (xy 450.047609 -203.767888) (xy 450.101488 -203.765919) (xy 450.155079 -203.771816)
			(xy 450.20724 -203.785452) (xy 450.25686 -203.806539) (xy 450.302881 -203.834625) (xy 450.344323 -203.869113)
			(xy 450.380301 -203.909267) (xy 450.410049 -203.954231) (xy 450.432934 -204.003048) (xy 450.448466 -204.054677)
			(xy 450.456316 -204.108017) (xy 450.456808 -204.134974) (xy 450.456316 -204.161931) (xy 450.448466 -204.215271)
			(xy 450.432934 -204.2669) (xy 450.410049 -204.315717) (xy 450.380301 -204.360681) (xy 450.344323 -204.400835)
			(xy 450.302881 -204.435323) (xy 450.25686 -204.463409) (xy 450.20724 -204.484496) (xy 450.155079 -204.498132)
			(xy 450.101488 -204.504029) (xy 450.047609 -204.50206) (xy 449.994591 -204.492267) (xy 449.943564 -204.474859)
			(xy 449.895616 -204.450207) (xy 449.851768 -204.418837) (xy 449.812955 -204.381416) (xy 449.780003 -204.338743)
			(xy 449.753617 -204.291726) (xy 449.734357 -204.241369) (xy 449.722634 -204.188745) (xy 449.718699 -204.134974)
			(xy 442.913008 -204.134974) (xy 442.912516 -204.161931) (xy 442.904666 -204.215271) (xy 442.889134 -204.2669)
			(xy 442.866249 -204.315717) (xy 442.836501 -204.360681) (xy 442.800523 -204.400835) (xy 442.759081 -204.435323)
			(xy 442.71306 -204.463409) (xy 442.66344 -204.484496) (xy 442.611279 -204.498132) (xy 442.557688 -204.504029)
			(xy 442.503809 -204.50206) (xy 442.450791 -204.492267) (xy 442.399764 -204.474859) (xy 442.351816 -204.450207)
			(xy 442.307968 -204.418837) (xy 442.269155 -204.381416) (xy 442.236203 -204.338743) (xy 442.209817 -204.291726)
			(xy 442.190557 -204.241369) (xy 442.178834 -204.188745) (xy 442.174899 -204.134974) (xy 435.368954 -204.134974)
			(xy 435.368462 -204.161931) (xy 435.360612 -204.215271) (xy 435.34508 -204.2669) (xy 435.322195 -204.315717)
			(xy 435.292447 -204.360681) (xy 435.256469 -204.400835) (xy 435.215027 -204.435323) (xy 435.169006 -204.463409)
			(xy 435.119386 -204.484496) (xy 435.067225 -204.498132) (xy 435.013634 -204.504029) (xy 434.959755 -204.50206)
			(xy 434.906737 -204.492267) (xy 434.85571 -204.474859) (xy 434.807762 -204.450207) (xy 434.763914 -204.418837)
			(xy 434.725101 -204.381416) (xy 434.692149 -204.338743) (xy 434.665763 -204.291726) (xy 434.646503 -204.241369)
			(xy 434.63478 -204.188745) (xy 434.630845 -204.134974) (xy 427.8249 -204.134974) (xy 427.824408 -204.161931)
			(xy 427.816558 -204.215271) (xy 427.801026 -204.2669) (xy 427.778141 -204.315717) (xy 427.748393 -204.360681)
			(xy 427.712415 -204.400835) (xy 427.670973 -204.435323) (xy 427.624952 -204.463409) (xy 427.575332 -204.484496)
			(xy 427.523171 -204.498132) (xy 427.46958 -204.504029) (xy 427.415701 -204.50206) (xy 427.362683 -204.492267)
			(xy 427.311656 -204.474859) (xy 427.263708 -204.450207) (xy 427.21986 -204.418837) (xy 427.181047 -204.381416)
			(xy 427.148095 -204.338743) (xy 427.121709 -204.291726) (xy 427.102449 -204.241369) (xy 427.090726 -204.188745)
			(xy 427.086791 -204.134974) (xy 425.985178 -204.134974) (xy 425.985178 -204.985112) (xy 431.186859 -204.985112)
			(xy 431.190794 -204.931341) (xy 431.202517 -204.878717) (xy 431.221777 -204.82836) (xy 431.248163 -204.781343)
			(xy 431.281115 -204.73867) (xy 431.319928 -204.701249) (xy 431.363776 -204.669879) (xy 431.411724 -204.645227)
			(xy 431.462751 -204.627819) (xy 431.515769 -204.618026) (xy 431.569648 -204.616057) (xy 431.623239 -204.621954)
			(xy 431.6754 -204.63559) (xy 431.72502 -204.656677) (xy 431.771041 -204.684763) (xy 431.812483 -204.719251)
			(xy 431.848461 -204.759405) (xy 431.878209 -204.804369) (xy 431.901094 -204.853186) (xy 431.916626 -204.904815)
			(xy 431.924476 -204.958155) (xy 431.924968 -204.985112) (xy 438.730913 -204.985112) (xy 438.734848 -204.931341)
			(xy 438.746571 -204.878717) (xy 438.765831 -204.82836) (xy 438.792217 -204.781343) (xy 438.825169 -204.73867)
			(xy 438.863982 -204.701249) (xy 438.90783 -204.669879) (xy 438.955778 -204.645227) (xy 439.006805 -204.627819)
			(xy 439.059823 -204.618026) (xy 439.113702 -204.616057) (xy 439.167293 -204.621954) (xy 439.219454 -204.63559)
			(xy 439.269074 -204.656677) (xy 439.315095 -204.684763) (xy 439.356537 -204.719251) (xy 439.392515 -204.759405)
			(xy 439.422263 -204.804369) (xy 439.445148 -204.853186) (xy 439.46068 -204.904815) (xy 439.46853 -204.958155)
			(xy 439.469022 -204.985112) (xy 446.274967 -204.985112) (xy 446.278902 -204.931341) (xy 446.290625 -204.878717)
			(xy 446.309885 -204.82836) (xy 446.336271 -204.781343) (xy 446.369223 -204.73867) (xy 446.408036 -204.701249)
			(xy 446.451884 -204.669879) (xy 446.499832 -204.645227) (xy 446.550859 -204.627819) (xy 446.603877 -204.618026)
			(xy 446.657756 -204.616057) (xy 446.711347 -204.621954) (xy 446.763508 -204.63559) (xy 446.813128 -204.656677)
			(xy 446.859149 -204.684763) (xy 446.900591 -204.719251) (xy 446.936569 -204.759405) (xy 446.966317 -204.804369)
			(xy 446.989202 -204.853186) (xy 447.004734 -204.904815) (xy 447.012584 -204.958155) (xy 447.013076 -204.985112)
			(xy 453.818767 -204.985112) (xy 453.822702 -204.931341) (xy 453.834425 -204.878717) (xy 453.853685 -204.82836)
			(xy 453.880071 -204.781343) (xy 453.913023 -204.73867) (xy 453.951836 -204.701249) (xy 453.995684 -204.669879)
			(xy 454.043632 -204.645227) (xy 454.094659 -204.627819) (xy 454.147677 -204.618026) (xy 454.201556 -204.616057)
			(xy 454.255147 -204.621954) (xy 454.307308 -204.63559) (xy 454.356928 -204.656677) (xy 454.402949 -204.684763)
			(xy 454.444391 -204.719251) (xy 454.480369 -204.759405) (xy 454.510117 -204.804369) (xy 454.533002 -204.853186)
			(xy 454.548534 -204.904815) (xy 454.556384 -204.958155) (xy 454.556876 -204.985112) (xy 454.556384 -205.012069)
			(xy 454.548534 -205.065409) (xy 454.533002 -205.117038) (xy 454.510117 -205.165855) (xy 454.480369 -205.210819)
			(xy 454.444391 -205.250973) (xy 454.402949 -205.285461) (xy 454.356928 -205.313547) (xy 454.307308 -205.334634)
			(xy 454.255147 -205.34827) (xy 454.201556 -205.354167) (xy 454.147677 -205.352198) (xy 454.094659 -205.342405)
			(xy 454.043632 -205.324997) (xy 453.995684 -205.300345) (xy 453.951836 -205.268975) (xy 453.913023 -205.231554)
			(xy 453.880071 -205.188881) (xy 453.853685 -205.141864) (xy 453.834425 -205.091507) (xy 453.822702 -205.038883)
			(xy 453.818767 -204.985112) (xy 447.013076 -204.985112) (xy 447.012584 -205.012069) (xy 447.004734 -205.065409)
			(xy 446.989202 -205.117038) (xy 446.966317 -205.165855) (xy 446.936569 -205.210819) (xy 446.900591 -205.250973)
			(xy 446.859149 -205.285461) (xy 446.813128 -205.313547) (xy 446.763508 -205.334634) (xy 446.711347 -205.34827)
			(xy 446.657756 -205.354167) (xy 446.603877 -205.352198) (xy 446.550859 -205.342405) (xy 446.499832 -205.324997)
			(xy 446.451884 -205.300345) (xy 446.408036 -205.268975) (xy 446.369223 -205.231554) (xy 446.336271 -205.188881)
			(xy 446.309885 -205.141864) (xy 446.290625 -205.091507) (xy 446.278902 -205.038883) (xy 446.274967 -204.985112)
			(xy 439.469022 -204.985112) (xy 439.46853 -205.012069) (xy 439.46068 -205.065409) (xy 439.445148 -205.117038)
			(xy 439.422263 -205.165855) (xy 439.392515 -205.210819) (xy 439.356537 -205.250973) (xy 439.315095 -205.285461)
			(xy 439.269074 -205.313547) (xy 439.219454 -205.334634) (xy 439.167293 -205.34827) (xy 439.113702 -205.354167)
			(xy 439.059823 -205.352198) (xy 439.006805 -205.342405) (xy 438.955778 -205.324997) (xy 438.90783 -205.300345)
			(xy 438.863982 -205.268975) (xy 438.825169 -205.231554) (xy 438.792217 -205.188881) (xy 438.765831 -205.141864)
			(xy 438.746571 -205.091507) (xy 438.734848 -205.038883) (xy 438.730913 -204.985112) (xy 431.924968 -204.985112)
			(xy 431.924476 -205.012069) (xy 431.916626 -205.065409) (xy 431.901094 -205.117038) (xy 431.878209 -205.165855)
			(xy 431.848461 -205.210819) (xy 431.812483 -205.250973) (xy 431.771041 -205.285461) (xy 431.72502 -205.313547)
			(xy 431.6754 -205.334634) (xy 431.623239 -205.34827) (xy 431.569648 -205.354167) (xy 431.515769 -205.352198)
			(xy 431.462751 -205.342405) (xy 431.411724 -205.324997) (xy 431.363776 -205.300345) (xy 431.319928 -205.268975)
			(xy 431.281115 -205.231554) (xy 431.248163 -205.188881) (xy 431.221777 -205.141864) (xy 431.202517 -205.091507)
			(xy 431.190794 -205.038883) (xy 431.186859 -204.985112) (xy 425.985178 -204.985112) (xy 425.985178 -205.834996)
			(xy 427.086791 -205.834996) (xy 427.090726 -205.781225) (xy 427.102449 -205.728601) (xy 427.121709 -205.678244)
			(xy 427.148095 -205.631227) (xy 427.181047 -205.588554) (xy 427.21986 -205.551133) (xy 427.263708 -205.519763)
			(xy 427.311656 -205.495111) (xy 427.362683 -205.477703) (xy 427.415701 -205.46791) (xy 427.46958 -205.465941)
			(xy 427.523171 -205.471838) (xy 427.575332 -205.485474) (xy 427.624952 -205.506561) (xy 427.670973 -205.534647)
			(xy 427.712415 -205.569135) (xy 427.748393 -205.609289) (xy 427.778141 -205.654253) (xy 427.801026 -205.70307)
			(xy 427.816558 -205.754699) (xy 427.824408 -205.808039) (xy 427.8249 -205.834996) (xy 434.630845 -205.834996)
			(xy 434.63478 -205.781225) (xy 434.646503 -205.728601) (xy 434.665763 -205.678244) (xy 434.692149 -205.631227)
			(xy 434.725101 -205.588554) (xy 434.763914 -205.551133) (xy 434.807762 -205.519763) (xy 434.85571 -205.495111)
			(xy 434.906737 -205.477703) (xy 434.959755 -205.46791) (xy 435.013634 -205.465941) (xy 435.067225 -205.471838)
			(xy 435.119386 -205.485474) (xy 435.169006 -205.506561) (xy 435.215027 -205.534647) (xy 435.256469 -205.569135)
			(xy 435.292447 -205.609289) (xy 435.322195 -205.654253) (xy 435.34508 -205.70307) (xy 435.360612 -205.754699)
			(xy 435.368462 -205.808039) (xy 435.368954 -205.834996) (xy 442.174899 -205.834996) (xy 442.178834 -205.781225)
			(xy 442.190557 -205.728601) (xy 442.209817 -205.678244) (xy 442.236203 -205.631227) (xy 442.269155 -205.588554)
			(xy 442.307968 -205.551133) (xy 442.351816 -205.519763) (xy 442.399764 -205.495111) (xy 442.450791 -205.477703)
			(xy 442.503809 -205.46791) (xy 442.557688 -205.465941) (xy 442.611279 -205.471838) (xy 442.66344 -205.485474)
			(xy 442.71306 -205.506561) (xy 442.759081 -205.534647) (xy 442.800523 -205.569135) (xy 442.836501 -205.609289)
			(xy 442.866249 -205.654253) (xy 442.889134 -205.70307) (xy 442.904666 -205.754699) (xy 442.912516 -205.808039)
			(xy 442.913008 -205.834996) (xy 449.718699 -205.834996) (xy 449.722634 -205.781225) (xy 449.734357 -205.728601)
			(xy 449.753617 -205.678244) (xy 449.780003 -205.631227) (xy 449.812955 -205.588554) (xy 449.851768 -205.551133)
			(xy 449.895616 -205.519763) (xy 449.943564 -205.495111) (xy 449.994591 -205.477703) (xy 450.047609 -205.46791)
			(xy 450.101488 -205.465941) (xy 450.155079 -205.471838) (xy 450.20724 -205.485474) (xy 450.25686 -205.506561)
			(xy 450.302881 -205.534647) (xy 450.344323 -205.569135) (xy 450.380301 -205.609289) (xy 450.410049 -205.654253)
			(xy 450.432934 -205.70307) (xy 450.448466 -205.754699) (xy 450.456316 -205.808039) (xy 450.456808 -205.834996)
			(xy 450.456316 -205.861953) (xy 450.448466 -205.915293) (xy 450.432934 -205.966922) (xy 450.410049 -206.015739)
			(xy 450.380301 -206.060703) (xy 450.344323 -206.100857) (xy 450.302881 -206.135345) (xy 450.25686 -206.163431)
			(xy 450.20724 -206.184518) (xy 450.155079 -206.198154) (xy 450.101488 -206.204051) (xy 450.047609 -206.202082)
			(xy 449.994591 -206.192289) (xy 449.943564 -206.174881) (xy 449.895616 -206.150229) (xy 449.851768 -206.118859)
			(xy 449.812955 -206.081438) (xy 449.780003 -206.038765) (xy 449.753617 -205.991748) (xy 449.734357 -205.941391)
			(xy 449.722634 -205.888767) (xy 449.718699 -205.834996) (xy 442.913008 -205.834996) (xy 442.912516 -205.861953)
			(xy 442.904666 -205.915293) (xy 442.889134 -205.966922) (xy 442.866249 -206.015739) (xy 442.836501 -206.060703)
			(xy 442.800523 -206.100857) (xy 442.759081 -206.135345) (xy 442.71306 -206.163431) (xy 442.66344 -206.184518)
			(xy 442.611279 -206.198154) (xy 442.557688 -206.204051) (xy 442.503809 -206.202082) (xy 442.450791 -206.192289)
			(xy 442.399764 -206.174881) (xy 442.351816 -206.150229) (xy 442.307968 -206.118859) (xy 442.269155 -206.081438)
			(xy 442.236203 -206.038765) (xy 442.209817 -205.991748) (xy 442.190557 -205.941391) (xy 442.178834 -205.888767)
			(xy 442.174899 -205.834996) (xy 435.368954 -205.834996) (xy 435.368462 -205.861953) (xy 435.360612 -205.915293)
			(xy 435.34508 -205.966922) (xy 435.322195 -206.015739) (xy 435.292447 -206.060703) (xy 435.256469 -206.100857)
			(xy 435.215027 -206.135345) (xy 435.169006 -206.163431) (xy 435.119386 -206.184518) (xy 435.067225 -206.198154)
			(xy 435.013634 -206.204051) (xy 434.959755 -206.202082) (xy 434.906737 -206.192289) (xy 434.85571 -206.174881)
			(xy 434.807762 -206.150229) (xy 434.763914 -206.118859) (xy 434.725101 -206.081438) (xy 434.692149 -206.038765)
			(xy 434.665763 -205.991748) (xy 434.646503 -205.941391) (xy 434.63478 -205.888767) (xy 434.630845 -205.834996)
			(xy 427.8249 -205.834996) (xy 427.824408 -205.861953) (xy 427.816558 -205.915293) (xy 427.801026 -205.966922)
			(xy 427.778141 -206.015739) (xy 427.748393 -206.060703) (xy 427.712415 -206.100857) (xy 427.670973 -206.135345)
			(xy 427.624952 -206.163431) (xy 427.575332 -206.184518) (xy 427.523171 -206.198154) (xy 427.46958 -206.204051)
			(xy 427.415701 -206.202082) (xy 427.362683 -206.192289) (xy 427.311656 -206.174881) (xy 427.263708 -206.150229)
			(xy 427.21986 -206.118859) (xy 427.181047 -206.081438) (xy 427.148095 -206.038765) (xy 427.121709 -205.991748)
			(xy 427.102449 -205.941391) (xy 427.090726 -205.888767) (xy 427.086791 -205.834996) (xy 425.985178 -205.834996)
			(xy 425.985178 -206.685134) (xy 431.186859 -206.685134) (xy 431.190794 -206.631363) (xy 431.202517 -206.578739)
			(xy 431.221777 -206.528382) (xy 431.248163 -206.481365) (xy 431.281115 -206.438692) (xy 431.319928 -206.401271)
			(xy 431.363776 -206.369901) (xy 431.411724 -206.345249) (xy 431.462751 -206.327841) (xy 431.515769 -206.318048)
			(xy 431.569648 -206.316079) (xy 431.623239 -206.321976) (xy 431.6754 -206.335612) (xy 431.72502 -206.356699)
			(xy 431.771041 -206.384785) (xy 431.812483 -206.419273) (xy 431.848461 -206.459427) (xy 431.878209 -206.504391)
			(xy 431.901094 -206.553208) (xy 431.916626 -206.604837) (xy 431.924476 -206.658177) (xy 431.924968 -206.685134)
			(xy 438.730913 -206.685134) (xy 438.734848 -206.631363) (xy 438.746571 -206.578739) (xy 438.765831 -206.528382)
			(xy 438.792217 -206.481365) (xy 438.825169 -206.438692) (xy 438.863982 -206.401271) (xy 438.90783 -206.369901)
			(xy 438.955778 -206.345249) (xy 439.006805 -206.327841) (xy 439.059823 -206.318048) (xy 439.113702 -206.316079)
			(xy 439.167293 -206.321976) (xy 439.219454 -206.335612) (xy 439.269074 -206.356699) (xy 439.315095 -206.384785)
			(xy 439.356537 -206.419273) (xy 439.392515 -206.459427) (xy 439.422263 -206.504391) (xy 439.445148 -206.553208)
			(xy 439.46068 -206.604837) (xy 439.46853 -206.658177) (xy 439.469022 -206.685134) (xy 446.274967 -206.685134)
			(xy 446.278902 -206.631363) (xy 446.290625 -206.578739) (xy 446.309885 -206.528382) (xy 446.336271 -206.481365)
			(xy 446.369223 -206.438692) (xy 446.408036 -206.401271) (xy 446.451884 -206.369901) (xy 446.499832 -206.345249)
			(xy 446.550859 -206.327841) (xy 446.603877 -206.318048) (xy 446.657756 -206.316079) (xy 446.711347 -206.321976)
			(xy 446.763508 -206.335612) (xy 446.813128 -206.356699) (xy 446.859149 -206.384785) (xy 446.900591 -206.419273)
			(xy 446.936569 -206.459427) (xy 446.966317 -206.504391) (xy 446.989202 -206.553208) (xy 447.004734 -206.604837)
			(xy 447.012584 -206.658177) (xy 447.013076 -206.685134) (xy 453.818767 -206.685134) (xy 453.822702 -206.631363)
			(xy 453.834425 -206.578739) (xy 453.853685 -206.528382) (xy 453.880071 -206.481365) (xy 453.913023 -206.438692)
			(xy 453.951836 -206.401271) (xy 453.995684 -206.369901) (xy 454.043632 -206.345249) (xy 454.094659 -206.327841)
			(xy 454.147677 -206.318048) (xy 454.201556 -206.316079) (xy 454.255147 -206.321976) (xy 454.307308 -206.335612)
			(xy 454.356928 -206.356699) (xy 454.402949 -206.384785) (xy 454.444391 -206.419273) (xy 454.480369 -206.459427)
			(xy 454.510117 -206.504391) (xy 454.533002 -206.553208) (xy 454.548534 -206.604837) (xy 454.556384 -206.658177)
			(xy 454.556876 -206.685134) (xy 454.556384 -206.712091) (xy 454.548534 -206.765431) (xy 454.533002 -206.81706)
			(xy 454.510117 -206.865877) (xy 454.480369 -206.910841) (xy 454.444391 -206.950995) (xy 454.402949 -206.985483)
			(xy 454.356928 -207.013569) (xy 454.307308 -207.034656) (xy 454.255147 -207.048292) (xy 454.201556 -207.054189)
			(xy 454.147677 -207.05222) (xy 454.094659 -207.042427) (xy 454.043632 -207.025019) (xy 453.995684 -207.000367)
			(xy 453.951836 -206.968997) (xy 453.913023 -206.931576) (xy 453.880071 -206.888903) (xy 453.853685 -206.841886)
			(xy 453.834425 -206.791529) (xy 453.822702 -206.738905) (xy 453.818767 -206.685134) (xy 447.013076 -206.685134)
			(xy 447.012584 -206.712091) (xy 447.004734 -206.765431) (xy 446.989202 -206.81706) (xy 446.966317 -206.865877)
			(xy 446.936569 -206.910841) (xy 446.900591 -206.950995) (xy 446.859149 -206.985483) (xy 446.813128 -207.013569)
			(xy 446.763508 -207.034656) (xy 446.711347 -207.048292) (xy 446.657756 -207.054189) (xy 446.603877 -207.05222)
			(xy 446.550859 -207.042427) (xy 446.499832 -207.025019) (xy 446.451884 -207.000367) (xy 446.408036 -206.968997)
			(xy 446.369223 -206.931576) (xy 446.336271 -206.888903) (xy 446.309885 -206.841886) (xy 446.290625 -206.791529)
			(xy 446.278902 -206.738905) (xy 446.274967 -206.685134) (xy 439.469022 -206.685134) (xy 439.46853 -206.712091)
			(xy 439.46068 -206.765431) (xy 439.445148 -206.81706) (xy 439.422263 -206.865877) (xy 439.392515 -206.910841)
			(xy 439.356537 -206.950995) (xy 439.315095 -206.985483) (xy 439.269074 -207.013569) (xy 439.219454 -207.034656)
			(xy 439.167293 -207.048292) (xy 439.113702 -207.054189) (xy 439.059823 -207.05222) (xy 439.006805 -207.042427)
			(xy 438.955778 -207.025019) (xy 438.90783 -207.000367) (xy 438.863982 -206.968997) (xy 438.825169 -206.931576)
			(xy 438.792217 -206.888903) (xy 438.765831 -206.841886) (xy 438.746571 -206.791529) (xy 438.734848 -206.738905)
			(xy 438.730913 -206.685134) (xy 431.924968 -206.685134) (xy 431.924476 -206.712091) (xy 431.916626 -206.765431)
			(xy 431.901094 -206.81706) (xy 431.878209 -206.865877) (xy 431.848461 -206.910841) (xy 431.812483 -206.950995)
			(xy 431.771041 -206.985483) (xy 431.72502 -207.013569) (xy 431.6754 -207.034656) (xy 431.623239 -207.048292)
			(xy 431.569648 -207.054189) (xy 431.515769 -207.05222) (xy 431.462751 -207.042427) (xy 431.411724 -207.025019)
			(xy 431.363776 -207.000367) (xy 431.319928 -206.968997) (xy 431.281115 -206.931576) (xy 431.248163 -206.888903)
			(xy 431.221777 -206.841886) (xy 431.202517 -206.791529) (xy 431.190794 -206.738905) (xy 431.186859 -206.685134)
			(xy 425.985178 -206.685134) (xy 425.985178 -207.535018) (xy 427.086791 -207.535018) (xy 427.090726 -207.481247)
			(xy 427.102449 -207.428623) (xy 427.121709 -207.378266) (xy 427.148095 -207.331249) (xy 427.181047 -207.288576)
			(xy 427.21986 -207.251155) (xy 427.263708 -207.219785) (xy 427.311656 -207.195133) (xy 427.362683 -207.177725)
			(xy 427.415701 -207.167932) (xy 427.46958 -207.165963) (xy 427.523171 -207.17186) (xy 427.575332 -207.185496)
			(xy 427.624952 -207.206583) (xy 427.670973 -207.234669) (xy 427.712415 -207.269157) (xy 427.748393 -207.309311)
			(xy 427.778141 -207.354275) (xy 427.801026 -207.403092) (xy 427.816558 -207.454721) (xy 427.824408 -207.508061)
			(xy 427.8249 -207.535018) (xy 434.630845 -207.535018) (xy 434.63478 -207.481247) (xy 434.646503 -207.428623)
			(xy 434.665763 -207.378266) (xy 434.692149 -207.331249) (xy 434.725101 -207.288576) (xy 434.763914 -207.251155)
			(xy 434.807762 -207.219785) (xy 434.85571 -207.195133) (xy 434.906737 -207.177725) (xy 434.959755 -207.167932)
			(xy 435.013634 -207.165963) (xy 435.067225 -207.17186) (xy 435.119386 -207.185496) (xy 435.169006 -207.206583)
			(xy 435.215027 -207.234669) (xy 435.256469 -207.269157) (xy 435.292447 -207.309311) (xy 435.322195 -207.354275)
			(xy 435.34508 -207.403092) (xy 435.360612 -207.454721) (xy 435.368462 -207.508061) (xy 435.368954 -207.535018)
			(xy 442.174899 -207.535018) (xy 442.178834 -207.481247) (xy 442.190557 -207.428623) (xy 442.209817 -207.378266)
			(xy 442.236203 -207.331249) (xy 442.269155 -207.288576) (xy 442.307968 -207.251155) (xy 442.351816 -207.219785)
			(xy 442.399764 -207.195133) (xy 442.450791 -207.177725) (xy 442.503809 -207.167932) (xy 442.557688 -207.165963)
			(xy 442.611279 -207.17186) (xy 442.66344 -207.185496) (xy 442.71306 -207.206583) (xy 442.759081 -207.234669)
			(xy 442.800523 -207.269157) (xy 442.836501 -207.309311) (xy 442.866249 -207.354275) (xy 442.889134 -207.403092)
			(xy 442.904666 -207.454721) (xy 442.912516 -207.508061) (xy 442.913008 -207.535018) (xy 449.718699 -207.535018)
			(xy 449.722634 -207.481247) (xy 449.734357 -207.428623) (xy 449.753617 -207.378266) (xy 449.780003 -207.331249)
			(xy 449.812955 -207.288576) (xy 449.851768 -207.251155) (xy 449.895616 -207.219785) (xy 449.943564 -207.195133)
			(xy 449.994591 -207.177725) (xy 450.047609 -207.167932) (xy 450.101488 -207.165963) (xy 450.155079 -207.17186)
			(xy 450.20724 -207.185496) (xy 450.25686 -207.206583) (xy 450.302881 -207.234669) (xy 450.344323 -207.269157)
			(xy 450.380301 -207.309311) (xy 450.410049 -207.354275) (xy 450.432934 -207.403092) (xy 450.448466 -207.454721)
			(xy 450.456316 -207.508061) (xy 450.456808 -207.535018) (xy 450.456316 -207.561975) (xy 450.448466 -207.615315)
			(xy 450.432934 -207.666944) (xy 450.410049 -207.715761) (xy 450.380301 -207.760725) (xy 450.344323 -207.800879)
			(xy 450.302881 -207.835367) (xy 450.25686 -207.863453) (xy 450.20724 -207.88454) (xy 450.155079 -207.898176)
			(xy 450.101488 -207.904073) (xy 450.047609 -207.902104) (xy 449.994591 -207.892311) (xy 449.943564 -207.874903)
			(xy 449.895616 -207.850251) (xy 449.851768 -207.818881) (xy 449.812955 -207.78146) (xy 449.780003 -207.738787)
			(xy 449.753617 -207.69177) (xy 449.734357 -207.641413) (xy 449.722634 -207.588789) (xy 449.718699 -207.535018)
			(xy 442.913008 -207.535018) (xy 442.912516 -207.561975) (xy 442.904666 -207.615315) (xy 442.889134 -207.666944)
			(xy 442.866249 -207.715761) (xy 442.836501 -207.760725) (xy 442.800523 -207.800879) (xy 442.759081 -207.835367)
			(xy 442.71306 -207.863453) (xy 442.66344 -207.88454) (xy 442.611279 -207.898176) (xy 442.557688 -207.904073)
			(xy 442.503809 -207.902104) (xy 442.450791 -207.892311) (xy 442.399764 -207.874903) (xy 442.351816 -207.850251)
			(xy 442.307968 -207.818881) (xy 442.269155 -207.78146) (xy 442.236203 -207.738787) (xy 442.209817 -207.69177)
			(xy 442.190557 -207.641413) (xy 442.178834 -207.588789) (xy 442.174899 -207.535018) (xy 435.368954 -207.535018)
			(xy 435.368462 -207.561975) (xy 435.360612 -207.615315) (xy 435.34508 -207.666944) (xy 435.322195 -207.715761)
			(xy 435.292447 -207.760725) (xy 435.256469 -207.800879) (xy 435.215027 -207.835367) (xy 435.169006 -207.863453)
			(xy 435.119386 -207.88454) (xy 435.067225 -207.898176) (xy 435.013634 -207.904073) (xy 434.959755 -207.902104)
			(xy 434.906737 -207.892311) (xy 434.85571 -207.874903) (xy 434.807762 -207.850251) (xy 434.763914 -207.818881)
			(xy 434.725101 -207.78146) (xy 434.692149 -207.738787) (xy 434.665763 -207.69177) (xy 434.646503 -207.641413)
			(xy 434.63478 -207.588789) (xy 434.630845 -207.535018) (xy 427.8249 -207.535018) (xy 427.824408 -207.561975)
			(xy 427.816558 -207.615315) (xy 427.801026 -207.666944) (xy 427.778141 -207.715761) (xy 427.748393 -207.760725)
			(xy 427.712415 -207.800879) (xy 427.670973 -207.835367) (xy 427.624952 -207.863453) (xy 427.575332 -207.88454)
			(xy 427.523171 -207.898176) (xy 427.46958 -207.904073) (xy 427.415701 -207.902104) (xy 427.362683 -207.892311)
			(xy 427.311656 -207.874903) (xy 427.263708 -207.850251) (xy 427.21986 -207.818881) (xy 427.181047 -207.78146)
			(xy 427.148095 -207.738787) (xy 427.121709 -207.69177) (xy 427.102449 -207.641413) (xy 427.090726 -207.588789)
			(xy 427.086791 -207.535018) (xy 425.985178 -207.535018) (xy 425.985178 -208.385156) (xy 431.186859 -208.385156)
			(xy 431.190794 -208.331385) (xy 431.202517 -208.278761) (xy 431.221777 -208.228404) (xy 431.248163 -208.181387)
			(xy 431.281115 -208.138714) (xy 431.319928 -208.101293) (xy 431.363776 -208.069923) (xy 431.411724 -208.045271)
			(xy 431.462751 -208.027863) (xy 431.515769 -208.01807) (xy 431.569648 -208.016101) (xy 431.623239 -208.021998)
			(xy 431.6754 -208.035634) (xy 431.72502 -208.056721) (xy 431.771041 -208.084807) (xy 431.812483 -208.119295)
			(xy 431.848461 -208.159449) (xy 431.878209 -208.204413) (xy 431.901094 -208.25323) (xy 431.916626 -208.304859)
			(xy 431.924476 -208.358199) (xy 431.924968 -208.385156) (xy 438.730913 -208.385156) (xy 438.734848 -208.331385)
			(xy 438.746571 -208.278761) (xy 438.765831 -208.228404) (xy 438.792217 -208.181387) (xy 438.825169 -208.138714)
			(xy 438.863982 -208.101293) (xy 438.90783 -208.069923) (xy 438.955778 -208.045271) (xy 439.006805 -208.027863)
			(xy 439.059823 -208.01807) (xy 439.113702 -208.016101) (xy 439.167293 -208.021998) (xy 439.219454 -208.035634)
			(xy 439.269074 -208.056721) (xy 439.315095 -208.084807) (xy 439.356537 -208.119295) (xy 439.392515 -208.159449)
			(xy 439.422263 -208.204413) (xy 439.445148 -208.25323) (xy 439.46068 -208.304859) (xy 439.46853 -208.358199)
			(xy 439.469022 -208.385156) (xy 446.274967 -208.385156) (xy 446.278902 -208.331385) (xy 446.290625 -208.278761)
			(xy 446.309885 -208.228404) (xy 446.336271 -208.181387) (xy 446.369223 -208.138714) (xy 446.408036 -208.101293)
			(xy 446.451884 -208.069923) (xy 446.499832 -208.045271) (xy 446.550859 -208.027863) (xy 446.603877 -208.01807)
			(xy 446.657756 -208.016101) (xy 446.711347 -208.021998) (xy 446.763508 -208.035634) (xy 446.813128 -208.056721)
			(xy 446.859149 -208.084807) (xy 446.900591 -208.119295) (xy 446.936569 -208.159449) (xy 446.966317 -208.204413)
			(xy 446.989202 -208.25323) (xy 447.004734 -208.304859) (xy 447.012584 -208.358199) (xy 447.013076 -208.385156)
			(xy 453.818767 -208.385156) (xy 453.822702 -208.331385) (xy 453.834425 -208.278761) (xy 453.853685 -208.228404)
			(xy 453.880071 -208.181387) (xy 453.913023 -208.138714) (xy 453.951836 -208.101293) (xy 453.995684 -208.069923)
			(xy 454.043632 -208.045271) (xy 454.094659 -208.027863) (xy 454.147677 -208.01807) (xy 454.201556 -208.016101)
			(xy 454.255147 -208.021998) (xy 454.307308 -208.035634) (xy 454.356928 -208.056721) (xy 454.402949 -208.084807)
			(xy 454.444391 -208.119295) (xy 454.480369 -208.159449) (xy 454.510117 -208.204413) (xy 454.533002 -208.25323)
			(xy 454.548534 -208.304859) (xy 454.556384 -208.358199) (xy 454.556876 -208.385156) (xy 454.556384 -208.412113)
			(xy 454.548534 -208.465453) (xy 454.533002 -208.517082) (xy 454.510117 -208.565899) (xy 454.480369 -208.610863)
			(xy 454.444391 -208.651017) (xy 454.402949 -208.685505) (xy 454.356928 -208.713591) (xy 454.307308 -208.734678)
			(xy 454.255147 -208.748314) (xy 454.201556 -208.754211) (xy 454.147677 -208.752242) (xy 454.094659 -208.742449)
			(xy 454.043632 -208.725041) (xy 453.995684 -208.700389) (xy 453.951836 -208.669019) (xy 453.913023 -208.631598)
			(xy 453.880071 -208.588925) (xy 453.853685 -208.541908) (xy 453.834425 -208.491551) (xy 453.822702 -208.438927)
			(xy 453.818767 -208.385156) (xy 447.013076 -208.385156) (xy 447.012584 -208.412113) (xy 447.004734 -208.465453)
			(xy 446.989202 -208.517082) (xy 446.966317 -208.565899) (xy 446.936569 -208.610863) (xy 446.900591 -208.651017)
			(xy 446.859149 -208.685505) (xy 446.813128 -208.713591) (xy 446.763508 -208.734678) (xy 446.711347 -208.748314)
			(xy 446.657756 -208.754211) (xy 446.603877 -208.752242) (xy 446.550859 -208.742449) (xy 446.499832 -208.725041)
			(xy 446.451884 -208.700389) (xy 446.408036 -208.669019) (xy 446.369223 -208.631598) (xy 446.336271 -208.588925)
			(xy 446.309885 -208.541908) (xy 446.290625 -208.491551) (xy 446.278902 -208.438927) (xy 446.274967 -208.385156)
			(xy 439.469022 -208.385156) (xy 439.46853 -208.412113) (xy 439.46068 -208.465453) (xy 439.445148 -208.517082)
			(xy 439.422263 -208.565899) (xy 439.392515 -208.610863) (xy 439.356537 -208.651017) (xy 439.315095 -208.685505)
			(xy 439.269074 -208.713591) (xy 439.219454 -208.734678) (xy 439.167293 -208.748314) (xy 439.113702 -208.754211)
			(xy 439.059823 -208.752242) (xy 439.006805 -208.742449) (xy 438.955778 -208.725041) (xy 438.90783 -208.700389)
			(xy 438.863982 -208.669019) (xy 438.825169 -208.631598) (xy 438.792217 -208.588925) (xy 438.765831 -208.541908)
			(xy 438.746571 -208.491551) (xy 438.734848 -208.438927) (xy 438.730913 -208.385156) (xy 431.924968 -208.385156)
			(xy 431.924476 -208.412113) (xy 431.916626 -208.465453) (xy 431.901094 -208.517082) (xy 431.878209 -208.565899)
			(xy 431.848461 -208.610863) (xy 431.812483 -208.651017) (xy 431.771041 -208.685505) (xy 431.72502 -208.713591)
			(xy 431.6754 -208.734678) (xy 431.623239 -208.748314) (xy 431.569648 -208.754211) (xy 431.515769 -208.752242)
			(xy 431.462751 -208.742449) (xy 431.411724 -208.725041) (xy 431.363776 -208.700389) (xy 431.319928 -208.669019)
			(xy 431.281115 -208.631598) (xy 431.248163 -208.588925) (xy 431.221777 -208.541908) (xy 431.202517 -208.491551)
			(xy 431.190794 -208.438927) (xy 431.186859 -208.385156) (xy 425.985178 -208.385156) (xy 425.985178 -209.23504)
			(xy 427.086791 -209.23504) (xy 427.090726 -209.181269) (xy 427.102449 -209.128645) (xy 427.121709 -209.078288)
			(xy 427.148095 -209.031271) (xy 427.181047 -208.988598) (xy 427.21986 -208.951177) (xy 427.263708 -208.919807)
			(xy 427.311656 -208.895155) (xy 427.362683 -208.877747) (xy 427.415701 -208.867954) (xy 427.46958 -208.865985)
			(xy 427.523171 -208.871882) (xy 427.575332 -208.885518) (xy 427.624952 -208.906605) (xy 427.670973 -208.934691)
			(xy 427.712415 -208.969179) (xy 427.748393 -209.009333) (xy 427.778141 -209.054297) (xy 427.801026 -209.103114)
			(xy 427.816558 -209.154743) (xy 427.824408 -209.208083) (xy 427.8249 -209.23504) (xy 434.630845 -209.23504)
			(xy 434.63478 -209.181269) (xy 434.646503 -209.128645) (xy 434.665763 -209.078288) (xy 434.692149 -209.031271)
			(xy 434.725101 -208.988598) (xy 434.763914 -208.951177) (xy 434.807762 -208.919807) (xy 434.85571 -208.895155)
			(xy 434.906737 -208.877747) (xy 434.959755 -208.867954) (xy 435.013634 -208.865985) (xy 435.067225 -208.871882)
			(xy 435.119386 -208.885518) (xy 435.169006 -208.906605) (xy 435.215027 -208.934691) (xy 435.256469 -208.969179)
			(xy 435.292447 -209.009333) (xy 435.322195 -209.054297) (xy 435.34508 -209.103114) (xy 435.360612 -209.154743)
			(xy 435.368462 -209.208083) (xy 435.368954 -209.23504) (xy 442.174899 -209.23504) (xy 442.178834 -209.181269)
			(xy 442.190557 -209.128645) (xy 442.209817 -209.078288) (xy 442.236203 -209.031271) (xy 442.269155 -208.988598)
			(xy 442.307968 -208.951177) (xy 442.351816 -208.919807) (xy 442.399764 -208.895155) (xy 442.450791 -208.877747)
			(xy 442.503809 -208.867954) (xy 442.557688 -208.865985) (xy 442.611279 -208.871882) (xy 442.66344 -208.885518)
			(xy 442.71306 -208.906605) (xy 442.759081 -208.934691) (xy 442.800523 -208.969179) (xy 442.836501 -209.009333)
			(xy 442.866249 -209.054297) (xy 442.889134 -209.103114) (xy 442.904666 -209.154743) (xy 442.912516 -209.208083)
			(xy 442.913008 -209.23504) (xy 449.718699 -209.23504) (xy 449.722634 -209.181269) (xy 449.734357 -209.128645)
			(xy 449.753617 -209.078288) (xy 449.780003 -209.031271) (xy 449.812955 -208.988598) (xy 449.851768 -208.951177)
			(xy 449.895616 -208.919807) (xy 449.943564 -208.895155) (xy 449.994591 -208.877747) (xy 450.047609 -208.867954)
			(xy 450.101488 -208.865985) (xy 450.155079 -208.871882) (xy 450.20724 -208.885518) (xy 450.25686 -208.906605)
			(xy 450.302881 -208.934691) (xy 450.344323 -208.969179) (xy 450.380301 -209.009333) (xy 450.410049 -209.054297)
			(xy 450.432934 -209.103114) (xy 450.448466 -209.154743) (xy 450.456316 -209.208083) (xy 450.456808 -209.23504)
			(xy 450.456316 -209.261997) (xy 450.448466 -209.315337) (xy 450.432934 -209.366966) (xy 450.410049 -209.415783)
			(xy 450.380301 -209.460747) (xy 450.344323 -209.500901) (xy 450.302881 -209.535389) (xy 450.25686 -209.563475)
			(xy 450.20724 -209.584562) (xy 450.155079 -209.598198) (xy 450.101488 -209.604095) (xy 450.047609 -209.602126)
			(xy 449.994591 -209.592333) (xy 449.943564 -209.574925) (xy 449.895616 -209.550273) (xy 449.851768 -209.518903)
			(xy 449.812955 -209.481482) (xy 449.780003 -209.438809) (xy 449.753617 -209.391792) (xy 449.734357 -209.341435)
			(xy 449.722634 -209.288811) (xy 449.718699 -209.23504) (xy 442.913008 -209.23504) (xy 442.912516 -209.261997)
			(xy 442.904666 -209.315337) (xy 442.889134 -209.366966) (xy 442.866249 -209.415783) (xy 442.836501 -209.460747)
			(xy 442.800523 -209.500901) (xy 442.759081 -209.535389) (xy 442.71306 -209.563475) (xy 442.66344 -209.584562)
			(xy 442.611279 -209.598198) (xy 442.557688 -209.604095) (xy 442.503809 -209.602126) (xy 442.450791 -209.592333)
			(xy 442.399764 -209.574925) (xy 442.351816 -209.550273) (xy 442.307968 -209.518903) (xy 442.269155 -209.481482)
			(xy 442.236203 -209.438809) (xy 442.209817 -209.391792) (xy 442.190557 -209.341435) (xy 442.178834 -209.288811)
			(xy 442.174899 -209.23504) (xy 435.368954 -209.23504) (xy 435.368462 -209.261997) (xy 435.360612 -209.315337)
			(xy 435.34508 -209.366966) (xy 435.322195 -209.415783) (xy 435.292447 -209.460747) (xy 435.256469 -209.500901)
			(xy 435.215027 -209.535389) (xy 435.169006 -209.563475) (xy 435.119386 -209.584562) (xy 435.067225 -209.598198)
			(xy 435.013634 -209.604095) (xy 434.959755 -209.602126) (xy 434.906737 -209.592333) (xy 434.85571 -209.574925)
			(xy 434.807762 -209.550273) (xy 434.763914 -209.518903) (xy 434.725101 -209.481482) (xy 434.692149 -209.438809)
			(xy 434.665763 -209.391792) (xy 434.646503 -209.341435) (xy 434.63478 -209.288811) (xy 434.630845 -209.23504)
			(xy 427.8249 -209.23504) (xy 427.824408 -209.261997) (xy 427.816558 -209.315337) (xy 427.801026 -209.366966)
			(xy 427.778141 -209.415783) (xy 427.748393 -209.460747) (xy 427.712415 -209.500901) (xy 427.670973 -209.535389)
			(xy 427.624952 -209.563475) (xy 427.575332 -209.584562) (xy 427.523171 -209.598198) (xy 427.46958 -209.604095)
			(xy 427.415701 -209.602126) (xy 427.362683 -209.592333) (xy 427.311656 -209.574925) (xy 427.263708 -209.550273)
			(xy 427.21986 -209.518903) (xy 427.181047 -209.481482) (xy 427.148095 -209.438809) (xy 427.121709 -209.391792)
			(xy 427.102449 -209.341435) (xy 427.090726 -209.288811) (xy 427.086791 -209.23504) (xy 425.985178 -209.23504)
			(xy 425.985178 -210.085178) (xy 431.186859 -210.085178) (xy 431.190794 -210.031407) (xy 431.202517 -209.978783)
			(xy 431.221777 -209.928426) (xy 431.248163 -209.881409) (xy 431.281115 -209.838736) (xy 431.319928 -209.801315)
			(xy 431.363776 -209.769945) (xy 431.411724 -209.745293) (xy 431.462751 -209.727885) (xy 431.515769 -209.718092)
			(xy 431.569648 -209.716123) (xy 431.623239 -209.72202) (xy 431.6754 -209.735656) (xy 431.72502 -209.756743)
			(xy 431.771041 -209.784829) (xy 431.812483 -209.819317) (xy 431.848461 -209.859471) (xy 431.878209 -209.904435)
			(xy 431.901094 -209.953252) (xy 431.916626 -210.004881) (xy 431.924476 -210.058221) (xy 431.924968 -210.085178)
			(xy 438.730913 -210.085178) (xy 438.734848 -210.031407) (xy 438.746571 -209.978783) (xy 438.765831 -209.928426)
			(xy 438.792217 -209.881409) (xy 438.825169 -209.838736) (xy 438.863982 -209.801315) (xy 438.90783 -209.769945)
			(xy 438.955778 -209.745293) (xy 439.006805 -209.727885) (xy 439.059823 -209.718092) (xy 439.113702 -209.716123)
			(xy 439.167293 -209.72202) (xy 439.219454 -209.735656) (xy 439.269074 -209.756743) (xy 439.315095 -209.784829)
			(xy 439.356537 -209.819317) (xy 439.392515 -209.859471) (xy 439.422263 -209.904435) (xy 439.445148 -209.953252)
			(xy 439.46068 -210.004881) (xy 439.46853 -210.058221) (xy 439.469022 -210.085178) (xy 446.274967 -210.085178)
			(xy 446.278902 -210.031407) (xy 446.290625 -209.978783) (xy 446.309885 -209.928426) (xy 446.336271 -209.881409)
			(xy 446.369223 -209.838736) (xy 446.408036 -209.801315) (xy 446.451884 -209.769945) (xy 446.499832 -209.745293)
			(xy 446.550859 -209.727885) (xy 446.603877 -209.718092) (xy 446.657756 -209.716123) (xy 446.711347 -209.72202)
			(xy 446.763508 -209.735656) (xy 446.813128 -209.756743) (xy 446.859149 -209.784829) (xy 446.900591 -209.819317)
			(xy 446.936569 -209.859471) (xy 446.966317 -209.904435) (xy 446.989202 -209.953252) (xy 447.004734 -210.004881)
			(xy 447.012584 -210.058221) (xy 447.013076 -210.085178) (xy 453.818767 -210.085178) (xy 453.822702 -210.031407)
			(xy 453.834425 -209.978783) (xy 453.853685 -209.928426) (xy 453.880071 -209.881409) (xy 453.913023 -209.838736)
			(xy 453.951836 -209.801315) (xy 453.995684 -209.769945) (xy 454.043632 -209.745293) (xy 454.094659 -209.727885)
			(xy 454.147677 -209.718092) (xy 454.201556 -209.716123) (xy 454.255147 -209.72202) (xy 454.307308 -209.735656)
			(xy 454.356928 -209.756743) (xy 454.402949 -209.784829) (xy 454.444391 -209.819317) (xy 454.480369 -209.859471)
			(xy 454.510117 -209.904435) (xy 454.533002 -209.953252) (xy 454.548534 -210.004881) (xy 454.556384 -210.058221)
			(xy 454.556876 -210.085178) (xy 454.556384 -210.112135) (xy 454.548534 -210.165475) (xy 454.533002 -210.217104)
			(xy 454.510117 -210.265921) (xy 454.480369 -210.310885) (xy 454.444391 -210.351039) (xy 454.402949 -210.385527)
			(xy 454.356928 -210.413613) (xy 454.307308 -210.4347) (xy 454.255147 -210.448336) (xy 454.201556 -210.454233)
			(xy 454.147677 -210.452264) (xy 454.094659 -210.442471) (xy 454.043632 -210.425063) (xy 453.995684 -210.400411)
			(xy 453.951836 -210.369041) (xy 453.913023 -210.33162) (xy 453.880071 -210.288947) (xy 453.853685 -210.24193)
			(xy 453.834425 -210.191573) (xy 453.822702 -210.138949) (xy 453.818767 -210.085178) (xy 447.013076 -210.085178)
			(xy 447.012584 -210.112135) (xy 447.004734 -210.165475) (xy 446.989202 -210.217104) (xy 446.966317 -210.265921)
			(xy 446.936569 -210.310885) (xy 446.900591 -210.351039) (xy 446.859149 -210.385527) (xy 446.813128 -210.413613)
			(xy 446.763508 -210.4347) (xy 446.711347 -210.448336) (xy 446.657756 -210.454233) (xy 446.603877 -210.452264)
			(xy 446.550859 -210.442471) (xy 446.499832 -210.425063) (xy 446.451884 -210.400411) (xy 446.408036 -210.369041)
			(xy 446.369223 -210.33162) (xy 446.336271 -210.288947) (xy 446.309885 -210.24193) (xy 446.290625 -210.191573)
			(xy 446.278902 -210.138949) (xy 446.274967 -210.085178) (xy 439.469022 -210.085178) (xy 439.46853 -210.112135)
			(xy 439.46068 -210.165475) (xy 439.445148 -210.217104) (xy 439.422263 -210.265921) (xy 439.392515 -210.310885)
			(xy 439.356537 -210.351039) (xy 439.315095 -210.385527) (xy 439.269074 -210.413613) (xy 439.219454 -210.4347)
			(xy 439.167293 -210.448336) (xy 439.113702 -210.454233) (xy 439.059823 -210.452264) (xy 439.006805 -210.442471)
			(xy 438.955778 -210.425063) (xy 438.90783 -210.400411) (xy 438.863982 -210.369041) (xy 438.825169 -210.33162)
			(xy 438.792217 -210.288947) (xy 438.765831 -210.24193) (xy 438.746571 -210.191573) (xy 438.734848 -210.138949)
			(xy 438.730913 -210.085178) (xy 431.924968 -210.085178) (xy 431.924476 -210.112135) (xy 431.916626 -210.165475)
			(xy 431.901094 -210.217104) (xy 431.878209 -210.265921) (xy 431.848461 -210.310885) (xy 431.812483 -210.351039)
			(xy 431.771041 -210.385527) (xy 431.72502 -210.413613) (xy 431.6754 -210.4347) (xy 431.623239 -210.448336)
			(xy 431.569648 -210.454233) (xy 431.515769 -210.452264) (xy 431.462751 -210.442471) (xy 431.411724 -210.425063)
			(xy 431.363776 -210.400411) (xy 431.319928 -210.369041) (xy 431.281115 -210.33162) (xy 431.248163 -210.288947)
			(xy 431.221777 -210.24193) (xy 431.202517 -210.191573) (xy 431.190794 -210.138949) (xy 431.186859 -210.085178)
			(xy 425.985178 -210.085178) (xy 425.985178 -210.935062) (xy 427.086791 -210.935062) (xy 427.090726 -210.881291)
			(xy 427.102449 -210.828667) (xy 427.121709 -210.77831) (xy 427.148095 -210.731293) (xy 427.181047 -210.68862)
			(xy 427.21986 -210.651199) (xy 427.263708 -210.619829) (xy 427.311656 -210.595177) (xy 427.362683 -210.577769)
			(xy 427.415701 -210.567976) (xy 427.46958 -210.566007) (xy 427.523171 -210.571904) (xy 427.575332 -210.58554)
			(xy 427.624952 -210.606627) (xy 427.670973 -210.634713) (xy 427.712415 -210.669201) (xy 427.748393 -210.709355)
			(xy 427.778141 -210.754319) (xy 427.801026 -210.803136) (xy 427.816558 -210.854765) (xy 427.824408 -210.908105)
			(xy 427.8249 -210.935062) (xy 431.186859 -210.935062) (xy 431.190794 -210.881291) (xy 431.202517 -210.828667)
			(xy 431.221777 -210.77831) (xy 431.248163 -210.731293) (xy 431.281115 -210.68862) (xy 431.319928 -210.651199)
			(xy 431.363776 -210.619829) (xy 431.411724 -210.595177) (xy 431.462751 -210.577769) (xy 431.515769 -210.567976)
			(xy 431.569648 -210.566007) (xy 431.623239 -210.571904) (xy 431.6754 -210.58554) (xy 431.72502 -210.606627)
			(xy 431.771041 -210.634713) (xy 431.812483 -210.669201) (xy 431.848461 -210.709355) (xy 431.878209 -210.754319)
			(xy 431.901094 -210.803136) (xy 431.916626 -210.854765) (xy 431.924476 -210.908105) (xy 431.924968 -210.935062)
			(xy 434.630845 -210.935062) (xy 434.63478 -210.881291) (xy 434.646503 -210.828667) (xy 434.665763 -210.77831)
			(xy 434.692149 -210.731293) (xy 434.725101 -210.68862) (xy 434.763914 -210.651199) (xy 434.807762 -210.619829)
			(xy 434.85571 -210.595177) (xy 434.906737 -210.577769) (xy 434.959755 -210.567976) (xy 435.013634 -210.566007)
			(xy 435.067225 -210.571904) (xy 435.119386 -210.58554) (xy 435.169006 -210.606627) (xy 435.215027 -210.634713)
			(xy 435.256469 -210.669201) (xy 435.292447 -210.709355) (xy 435.322195 -210.754319) (xy 435.34508 -210.803136)
			(xy 435.360612 -210.854765) (xy 435.368462 -210.908105) (xy 435.368954 -210.935062) (xy 438.730913 -210.935062)
			(xy 438.734848 -210.881291) (xy 438.746571 -210.828667) (xy 438.765831 -210.77831) (xy 438.792217 -210.731293)
			(xy 438.825169 -210.68862) (xy 438.863982 -210.651199) (xy 438.90783 -210.619829) (xy 438.955778 -210.595177)
			(xy 439.006805 -210.577769) (xy 439.059823 -210.567976) (xy 439.113702 -210.566007) (xy 439.167293 -210.571904)
			(xy 439.219454 -210.58554) (xy 439.269074 -210.606627) (xy 439.315095 -210.634713) (xy 439.356537 -210.669201)
			(xy 439.392515 -210.709355) (xy 439.422263 -210.754319) (xy 439.445148 -210.803136) (xy 439.46068 -210.854765)
			(xy 439.46853 -210.908105) (xy 439.469022 -210.935062) (xy 442.174899 -210.935062) (xy 442.178834 -210.881291)
			(xy 442.190557 -210.828667) (xy 442.209817 -210.77831) (xy 442.236203 -210.731293) (xy 442.269155 -210.68862)
			(xy 442.307968 -210.651199) (xy 442.351816 -210.619829) (xy 442.399764 -210.595177) (xy 442.450791 -210.577769)
			(xy 442.503809 -210.567976) (xy 442.557688 -210.566007) (xy 442.611279 -210.571904) (xy 442.66344 -210.58554)
			(xy 442.71306 -210.606627) (xy 442.759081 -210.634713) (xy 442.800523 -210.669201) (xy 442.836501 -210.709355)
			(xy 442.866249 -210.754319) (xy 442.889134 -210.803136) (xy 442.904666 -210.854765) (xy 442.912516 -210.908105)
			(xy 442.913008 -210.935062) (xy 446.274967 -210.935062) (xy 446.278902 -210.881291) (xy 446.290625 -210.828667)
			(xy 446.309885 -210.77831) (xy 446.336271 -210.731293) (xy 446.369223 -210.68862) (xy 446.408036 -210.651199)
			(xy 446.451884 -210.619829) (xy 446.499832 -210.595177) (xy 446.550859 -210.577769) (xy 446.603877 -210.567976)
			(xy 446.657756 -210.566007) (xy 446.711347 -210.571904) (xy 446.763508 -210.58554) (xy 446.813128 -210.606627)
			(xy 446.859149 -210.634713) (xy 446.900591 -210.669201) (xy 446.936569 -210.709355) (xy 446.966317 -210.754319)
			(xy 446.989202 -210.803136) (xy 447.004734 -210.854765) (xy 447.012584 -210.908105) (xy 447.013076 -210.935062)
			(xy 449.718699 -210.935062) (xy 449.722634 -210.881291) (xy 449.734357 -210.828667) (xy 449.753617 -210.77831)
			(xy 449.780003 -210.731293) (xy 449.812955 -210.68862) (xy 449.851768 -210.651199) (xy 449.895616 -210.619829)
			(xy 449.943564 -210.595177) (xy 449.994591 -210.577769) (xy 450.047609 -210.567976) (xy 450.101488 -210.566007)
			(xy 450.155079 -210.571904) (xy 450.20724 -210.58554) (xy 450.25686 -210.606627) (xy 450.302881 -210.634713)
			(xy 450.344323 -210.669201) (xy 450.380301 -210.709355) (xy 450.410049 -210.754319) (xy 450.432934 -210.803136)
			(xy 450.448466 -210.854765) (xy 450.456316 -210.908105) (xy 450.456808 -210.935062) (xy 453.818767 -210.935062)
			(xy 453.822702 -210.881291) (xy 453.834425 -210.828667) (xy 453.853685 -210.77831) (xy 453.880071 -210.731293)
			(xy 453.913023 -210.68862) (xy 453.951836 -210.651199) (xy 453.995684 -210.619829) (xy 454.043632 -210.595177)
			(xy 454.094659 -210.577769) (xy 454.147677 -210.567976) (xy 454.201556 -210.566007) (xy 454.255147 -210.571904)
			(xy 454.307308 -210.58554) (xy 454.356928 -210.606627) (xy 454.402949 -210.634713) (xy 454.444391 -210.669201)
			(xy 454.480369 -210.709355) (xy 454.510117 -210.754319) (xy 454.533002 -210.803136) (xy 454.548534 -210.854765)
			(xy 454.556384 -210.908105) (xy 454.556876 -210.935062) (xy 454.556384 -210.962019) (xy 454.548534 -211.015359)
			(xy 454.533002 -211.066988) (xy 454.510117 -211.115805) (xy 454.480369 -211.160769) (xy 454.444391 -211.200923)
			(xy 454.402949 -211.235411) (xy 454.356928 -211.263497) (xy 454.307308 -211.284584) (xy 454.255147 -211.29822)
			(xy 454.201556 -211.304117) (xy 454.147677 -211.302148) (xy 454.094659 -211.292355) (xy 454.043632 -211.274947)
			(xy 453.995684 -211.250295) (xy 453.951836 -211.218925) (xy 453.913023 -211.181504) (xy 453.880071 -211.138831)
			(xy 453.853685 -211.091814) (xy 453.834425 -211.041457) (xy 453.822702 -210.988833) (xy 453.818767 -210.935062)
			(xy 450.456808 -210.935062) (xy 450.456316 -210.962019) (xy 450.448466 -211.015359) (xy 450.432934 -211.066988)
			(xy 450.410049 -211.115805) (xy 450.380301 -211.160769) (xy 450.344323 -211.200923) (xy 450.302881 -211.235411)
			(xy 450.25686 -211.263497) (xy 450.20724 -211.284584) (xy 450.155079 -211.29822) (xy 450.101488 -211.304117)
			(xy 450.047609 -211.302148) (xy 449.994591 -211.292355) (xy 449.943564 -211.274947) (xy 449.895616 -211.250295)
			(xy 449.851768 -211.218925) (xy 449.812955 -211.181504) (xy 449.780003 -211.138831) (xy 449.753617 -211.091814)
			(xy 449.734357 -211.041457) (xy 449.722634 -210.988833) (xy 449.718699 -210.935062) (xy 447.013076 -210.935062)
			(xy 447.012584 -210.962019) (xy 447.004734 -211.015359) (xy 446.989202 -211.066988) (xy 446.966317 -211.115805)
			(xy 446.936569 -211.160769) (xy 446.900591 -211.200923) (xy 446.859149 -211.235411) (xy 446.813128 -211.263497)
			(xy 446.763508 -211.284584) (xy 446.711347 -211.29822) (xy 446.657756 -211.304117) (xy 446.603877 -211.302148)
			(xy 446.550859 -211.292355) (xy 446.499832 -211.274947) (xy 446.451884 -211.250295) (xy 446.408036 -211.218925)
			(xy 446.369223 -211.181504) (xy 446.336271 -211.138831) (xy 446.309885 -211.091814) (xy 446.290625 -211.041457)
			(xy 446.278902 -210.988833) (xy 446.274967 -210.935062) (xy 442.913008 -210.935062) (xy 442.912516 -210.962019)
			(xy 442.904666 -211.015359) (xy 442.889134 -211.066988) (xy 442.866249 -211.115805) (xy 442.836501 -211.160769)
			(xy 442.800523 -211.200923) (xy 442.759081 -211.235411) (xy 442.71306 -211.263497) (xy 442.66344 -211.284584)
			(xy 442.611279 -211.29822) (xy 442.557688 -211.304117) (xy 442.503809 -211.302148) (xy 442.450791 -211.292355)
			(xy 442.399764 -211.274947) (xy 442.351816 -211.250295) (xy 442.307968 -211.218925) (xy 442.269155 -211.181504)
			(xy 442.236203 -211.138831) (xy 442.209817 -211.091814) (xy 442.190557 -211.041457) (xy 442.178834 -210.988833)
			(xy 442.174899 -210.935062) (xy 439.469022 -210.935062) (xy 439.46853 -210.962019) (xy 439.46068 -211.015359)
			(xy 439.445148 -211.066988) (xy 439.422263 -211.115805) (xy 439.392515 -211.160769) (xy 439.356537 -211.200923)
			(xy 439.315095 -211.235411) (xy 439.269074 -211.263497) (xy 439.219454 -211.284584) (xy 439.167293 -211.29822)
			(xy 439.113702 -211.304117) (xy 439.059823 -211.302148) (xy 439.006805 -211.292355) (xy 438.955778 -211.274947)
			(xy 438.90783 -211.250295) (xy 438.863982 -211.218925) (xy 438.825169 -211.181504) (xy 438.792217 -211.138831)
			(xy 438.765831 -211.091814) (xy 438.746571 -211.041457) (xy 438.734848 -210.988833) (xy 438.730913 -210.935062)
			(xy 435.368954 -210.935062) (xy 435.368462 -210.962019) (xy 435.360612 -211.015359) (xy 435.34508 -211.066988)
			(xy 435.322195 -211.115805) (xy 435.292447 -211.160769) (xy 435.256469 -211.200923) (xy 435.215027 -211.235411)
			(xy 435.169006 -211.263497) (xy 435.119386 -211.284584) (xy 435.067225 -211.29822) (xy 435.013634 -211.304117)
			(xy 434.959755 -211.302148) (xy 434.906737 -211.292355) (xy 434.85571 -211.274947) (xy 434.807762 -211.250295)
			(xy 434.763914 -211.218925) (xy 434.725101 -211.181504) (xy 434.692149 -211.138831) (xy 434.665763 -211.091814)
			(xy 434.646503 -211.041457) (xy 434.63478 -210.988833) (xy 434.630845 -210.935062) (xy 431.924968 -210.935062)
			(xy 431.924476 -210.962019) (xy 431.916626 -211.015359) (xy 431.901094 -211.066988) (xy 431.878209 -211.115805)
			(xy 431.848461 -211.160769) (xy 431.812483 -211.200923) (xy 431.771041 -211.235411) (xy 431.72502 -211.263497)
			(xy 431.6754 -211.284584) (xy 431.623239 -211.29822) (xy 431.569648 -211.304117) (xy 431.515769 -211.302148)
			(xy 431.462751 -211.292355) (xy 431.411724 -211.274947) (xy 431.363776 -211.250295) (xy 431.319928 -211.218925)
			(xy 431.281115 -211.181504) (xy 431.248163 -211.138831) (xy 431.221777 -211.091814) (xy 431.202517 -211.041457)
			(xy 431.190794 -210.988833) (xy 431.186859 -210.935062) (xy 427.8249 -210.935062) (xy 427.824408 -210.962019)
			(xy 427.816558 -211.015359) (xy 427.801026 -211.066988) (xy 427.778141 -211.115805) (xy 427.748393 -211.160769)
			(xy 427.712415 -211.200923) (xy 427.670973 -211.235411) (xy 427.624952 -211.263497) (xy 427.575332 -211.284584)
			(xy 427.523171 -211.29822) (xy 427.46958 -211.304117) (xy 427.415701 -211.302148) (xy 427.362683 -211.292355)
			(xy 427.311656 -211.274947) (xy 427.263708 -211.250295) (xy 427.21986 -211.218925) (xy 427.181047 -211.181504)
			(xy 427.148095 -211.138831) (xy 427.121709 -211.091814) (xy 427.102449 -211.041457) (xy 427.090726 -210.988833)
			(xy 427.086791 -210.935062) (xy 425.985178 -210.935062) (xy 425.985178 -211.784946) (xy 427.086791 -211.784946)
			(xy 427.090726 -211.731175) (xy 427.102449 -211.678551) (xy 427.121709 -211.628194) (xy 427.148095 -211.581177)
			(xy 427.181047 -211.538504) (xy 427.21986 -211.501083) (xy 427.263708 -211.469713) (xy 427.311656 -211.445061)
			(xy 427.362683 -211.427653) (xy 427.415701 -211.41786) (xy 427.46958 -211.415891) (xy 427.523171 -211.421788)
			(xy 427.575332 -211.435424) (xy 427.624952 -211.456511) (xy 427.670973 -211.484597) (xy 427.712415 -211.519085)
			(xy 427.748393 -211.559239) (xy 427.778141 -211.604203) (xy 427.801026 -211.65302) (xy 427.816558 -211.704649)
			(xy 427.824408 -211.757989) (xy 427.8249 -211.784946) (xy 434.630845 -211.784946) (xy 434.63478 -211.731175)
			(xy 434.646503 -211.678551) (xy 434.665763 -211.628194) (xy 434.692149 -211.581177) (xy 434.725101 -211.538504)
			(xy 434.763914 -211.501083) (xy 434.807762 -211.469713) (xy 434.85571 -211.445061) (xy 434.906737 -211.427653)
			(xy 434.959755 -211.41786) (xy 435.013634 -211.415891) (xy 435.067225 -211.421788) (xy 435.119386 -211.435424)
			(xy 435.169006 -211.456511) (xy 435.215027 -211.484597) (xy 435.256469 -211.519085) (xy 435.292447 -211.559239)
			(xy 435.322195 -211.604203) (xy 435.34508 -211.65302) (xy 435.360612 -211.704649) (xy 435.368462 -211.757989)
			(xy 435.368954 -211.784946) (xy 442.174899 -211.784946) (xy 442.178834 -211.731175) (xy 442.190557 -211.678551)
			(xy 442.209817 -211.628194) (xy 442.236203 -211.581177) (xy 442.269155 -211.538504) (xy 442.307968 -211.501083)
			(xy 442.351816 -211.469713) (xy 442.399764 -211.445061) (xy 442.450791 -211.427653) (xy 442.503809 -211.41786)
			(xy 442.557688 -211.415891) (xy 442.611279 -211.421788) (xy 442.66344 -211.435424) (xy 442.71306 -211.456511)
			(xy 442.759081 -211.484597) (xy 442.800523 -211.519085) (xy 442.836501 -211.559239) (xy 442.866249 -211.604203)
			(xy 442.889134 -211.65302) (xy 442.904666 -211.704649) (xy 442.912516 -211.757989) (xy 442.913008 -211.784946)
			(xy 449.718699 -211.784946) (xy 449.722634 -211.731175) (xy 449.734357 -211.678551) (xy 449.753617 -211.628194)
			(xy 449.780003 -211.581177) (xy 449.812955 -211.538504) (xy 449.851768 -211.501083) (xy 449.895616 -211.469713)
			(xy 449.943564 -211.445061) (xy 449.994591 -211.427653) (xy 450.047609 -211.41786) (xy 450.101488 -211.415891)
			(xy 450.155079 -211.421788) (xy 450.20724 -211.435424) (xy 450.25686 -211.456511) (xy 450.302881 -211.484597)
			(xy 450.344323 -211.519085) (xy 450.380301 -211.559239) (xy 450.410049 -211.604203) (xy 450.432934 -211.65302)
			(xy 450.448466 -211.704649) (xy 450.456316 -211.757989) (xy 450.456808 -211.784946) (xy 450.456316 -211.811903)
			(xy 450.448466 -211.865243) (xy 450.432934 -211.916872) (xy 450.410049 -211.965689) (xy 450.380301 -212.010653)
			(xy 450.344323 -212.050807) (xy 450.302881 -212.085295) (xy 450.25686 -212.113381) (xy 450.20724 -212.134468)
			(xy 450.155079 -212.148104) (xy 450.101488 -212.154001) (xy 450.047609 -212.152032) (xy 449.994591 -212.142239)
			(xy 449.943564 -212.124831) (xy 449.895616 -212.100179) (xy 449.851768 -212.068809) (xy 449.812955 -212.031388)
			(xy 449.780003 -211.988715) (xy 449.753617 -211.941698) (xy 449.734357 -211.891341) (xy 449.722634 -211.838717)
			(xy 449.718699 -211.784946) (xy 442.913008 -211.784946) (xy 442.912516 -211.811903) (xy 442.904666 -211.865243)
			(xy 442.889134 -211.916872) (xy 442.866249 -211.965689) (xy 442.836501 -212.010653) (xy 442.800523 -212.050807)
			(xy 442.759081 -212.085295) (xy 442.71306 -212.113381) (xy 442.66344 -212.134468) (xy 442.611279 -212.148104)
			(xy 442.557688 -212.154001) (xy 442.503809 -212.152032) (xy 442.450791 -212.142239) (xy 442.399764 -212.124831)
			(xy 442.351816 -212.100179) (xy 442.307968 -212.068809) (xy 442.269155 -212.031388) (xy 442.236203 -211.988715)
			(xy 442.209817 -211.941698) (xy 442.190557 -211.891341) (xy 442.178834 -211.838717) (xy 442.174899 -211.784946)
			(xy 435.368954 -211.784946) (xy 435.368462 -211.811903) (xy 435.360612 -211.865243) (xy 435.34508 -211.916872)
			(xy 435.322195 -211.965689) (xy 435.292447 -212.010653) (xy 435.256469 -212.050807) (xy 435.215027 -212.085295)
			(xy 435.169006 -212.113381) (xy 435.119386 -212.134468) (xy 435.067225 -212.148104) (xy 435.013634 -212.154001)
			(xy 434.959755 -212.152032) (xy 434.906737 -212.142239) (xy 434.85571 -212.124831) (xy 434.807762 -212.100179)
			(xy 434.763914 -212.068809) (xy 434.725101 -212.031388) (xy 434.692149 -211.988715) (xy 434.665763 -211.941698)
			(xy 434.646503 -211.891341) (xy 434.63478 -211.838717) (xy 434.630845 -211.784946) (xy 427.8249 -211.784946)
			(xy 427.824408 -211.811903) (xy 427.816558 -211.865243) (xy 427.801026 -211.916872) (xy 427.778141 -211.965689)
			(xy 427.748393 -212.010653) (xy 427.712415 -212.050807) (xy 427.670973 -212.085295) (xy 427.624952 -212.113381)
			(xy 427.575332 -212.134468) (xy 427.523171 -212.148104) (xy 427.46958 -212.154001) (xy 427.415701 -212.152032)
			(xy 427.362683 -212.142239) (xy 427.311656 -212.124831) (xy 427.263708 -212.100179) (xy 427.21986 -212.068809)
			(xy 427.181047 -212.031388) (xy 427.148095 -211.988715) (xy 427.121709 -211.941698) (xy 427.102449 -211.891341)
			(xy 427.090726 -211.838717) (xy 427.086791 -211.784946) (xy 425.985178 -211.784946) (xy 425.985178 -212.635084)
			(xy 431.186859 -212.635084) (xy 431.190794 -212.581313) (xy 431.202517 -212.528689) (xy 431.221777 -212.478332)
			(xy 431.248163 -212.431315) (xy 431.281115 -212.388642) (xy 431.319928 -212.351221) (xy 431.363776 -212.319851)
			(xy 431.411724 -212.295199) (xy 431.462751 -212.277791) (xy 431.515769 -212.267998) (xy 431.569648 -212.266029)
			(xy 431.623239 -212.271926) (xy 431.6754 -212.285562) (xy 431.72502 -212.306649) (xy 431.771041 -212.334735)
			(xy 431.812483 -212.369223) (xy 431.848461 -212.409377) (xy 431.878209 -212.454341) (xy 431.901094 -212.503158)
			(xy 431.916626 -212.554787) (xy 431.924476 -212.608127) (xy 431.924968 -212.635084) (xy 438.730913 -212.635084)
			(xy 438.734848 -212.581313) (xy 438.746571 -212.528689) (xy 438.765831 -212.478332) (xy 438.792217 -212.431315)
			(xy 438.825169 -212.388642) (xy 438.863982 -212.351221) (xy 438.90783 -212.319851) (xy 438.955778 -212.295199)
			(xy 439.006805 -212.277791) (xy 439.059823 -212.267998) (xy 439.113702 -212.266029) (xy 439.167293 -212.271926)
			(xy 439.219454 -212.285562) (xy 439.269074 -212.306649) (xy 439.315095 -212.334735) (xy 439.356537 -212.369223)
			(xy 439.392515 -212.409377) (xy 439.422263 -212.454341) (xy 439.445148 -212.503158) (xy 439.46068 -212.554787)
			(xy 439.46853 -212.608127) (xy 439.469022 -212.635084) (xy 446.274967 -212.635084) (xy 446.278902 -212.581313)
			(xy 446.290625 -212.528689) (xy 446.309885 -212.478332) (xy 446.336271 -212.431315) (xy 446.369223 -212.388642)
			(xy 446.408036 -212.351221) (xy 446.451884 -212.319851) (xy 446.499832 -212.295199) (xy 446.550859 -212.277791)
			(xy 446.603877 -212.267998) (xy 446.657756 -212.266029) (xy 446.711347 -212.271926) (xy 446.763508 -212.285562)
			(xy 446.813128 -212.306649) (xy 446.859149 -212.334735) (xy 446.900591 -212.369223) (xy 446.936569 -212.409377)
			(xy 446.966317 -212.454341) (xy 446.989202 -212.503158) (xy 447.004734 -212.554787) (xy 447.012584 -212.608127)
			(xy 447.013076 -212.635084) (xy 453.818767 -212.635084) (xy 453.822702 -212.581313) (xy 453.834425 -212.528689)
			(xy 453.853685 -212.478332) (xy 453.880071 -212.431315) (xy 453.913023 -212.388642) (xy 453.951836 -212.351221)
			(xy 453.995684 -212.319851) (xy 454.043632 -212.295199) (xy 454.094659 -212.277791) (xy 454.147677 -212.267998)
			(xy 454.201556 -212.266029) (xy 454.255147 -212.271926) (xy 454.307308 -212.285562) (xy 454.356928 -212.306649)
			(xy 454.402949 -212.334735) (xy 454.444391 -212.369223) (xy 454.480369 -212.409377) (xy 454.510117 -212.454341)
			(xy 454.533002 -212.503158) (xy 454.548534 -212.554787) (xy 454.556384 -212.608127) (xy 454.556876 -212.635084)
			(xy 454.556384 -212.662041) (xy 454.548534 -212.715381) (xy 454.533002 -212.76701) (xy 454.510117 -212.815827)
			(xy 454.480369 -212.860791) (xy 454.444391 -212.900945) (xy 454.402949 -212.935433) (xy 454.356928 -212.963519)
			(xy 454.307308 -212.984606) (xy 454.255147 -212.998242) (xy 454.201556 -213.004139) (xy 454.147677 -213.00217)
			(xy 454.094659 -212.992377) (xy 454.043632 -212.974969) (xy 453.995684 -212.950317) (xy 453.951836 -212.918947)
			(xy 453.913023 -212.881526) (xy 453.880071 -212.838853) (xy 453.853685 -212.791836) (xy 453.834425 -212.741479)
			(xy 453.822702 -212.688855) (xy 453.818767 -212.635084) (xy 447.013076 -212.635084) (xy 447.012584 -212.662041)
			(xy 447.004734 -212.715381) (xy 446.989202 -212.76701) (xy 446.966317 -212.815827) (xy 446.936569 -212.860791)
			(xy 446.900591 -212.900945) (xy 446.859149 -212.935433) (xy 446.813128 -212.963519) (xy 446.763508 -212.984606)
			(xy 446.711347 -212.998242) (xy 446.657756 -213.004139) (xy 446.603877 -213.00217) (xy 446.550859 -212.992377)
			(xy 446.499832 -212.974969) (xy 446.451884 -212.950317) (xy 446.408036 -212.918947) (xy 446.369223 -212.881526)
			(xy 446.336271 -212.838853) (xy 446.309885 -212.791836) (xy 446.290625 -212.741479) (xy 446.278902 -212.688855)
			(xy 446.274967 -212.635084) (xy 439.469022 -212.635084) (xy 439.46853 -212.662041) (xy 439.46068 -212.715381)
			(xy 439.445148 -212.76701) (xy 439.422263 -212.815827) (xy 439.392515 -212.860791) (xy 439.356537 -212.900945)
			(xy 439.315095 -212.935433) (xy 439.269074 -212.963519) (xy 439.219454 -212.984606) (xy 439.167293 -212.998242)
			(xy 439.113702 -213.004139) (xy 439.059823 -213.00217) (xy 439.006805 -212.992377) (xy 438.955778 -212.974969)
			(xy 438.90783 -212.950317) (xy 438.863982 -212.918947) (xy 438.825169 -212.881526) (xy 438.792217 -212.838853)
			(xy 438.765831 -212.791836) (xy 438.746571 -212.741479) (xy 438.734848 -212.688855) (xy 438.730913 -212.635084)
			(xy 431.924968 -212.635084) (xy 431.924476 -212.662041) (xy 431.916626 -212.715381) (xy 431.901094 -212.76701)
			(xy 431.878209 -212.815827) (xy 431.848461 -212.860791) (xy 431.812483 -212.900945) (xy 431.771041 -212.935433)
			(xy 431.72502 -212.963519) (xy 431.6754 -212.984606) (xy 431.623239 -212.998242) (xy 431.569648 -213.004139)
			(xy 431.515769 -213.00217) (xy 431.462751 -212.992377) (xy 431.411724 -212.974969) (xy 431.363776 -212.950317)
			(xy 431.319928 -212.918947) (xy 431.281115 -212.881526) (xy 431.248163 -212.838853) (xy 431.221777 -212.791836)
			(xy 431.202517 -212.741479) (xy 431.190794 -212.688855) (xy 431.186859 -212.635084) (xy 425.985178 -212.635084)
			(xy 425.985178 -213.484968) (xy 427.086791 -213.484968) (xy 427.090726 -213.431197) (xy 427.102449 -213.378573)
			(xy 427.121709 -213.328216) (xy 427.148095 -213.281199) (xy 427.181047 -213.238526) (xy 427.21986 -213.201105)
			(xy 427.263708 -213.169735) (xy 427.311656 -213.145083) (xy 427.362683 -213.127675) (xy 427.415701 -213.117882)
			(xy 427.46958 -213.115913) (xy 427.523171 -213.12181) (xy 427.575332 -213.135446) (xy 427.624952 -213.156533)
			(xy 427.670973 -213.184619) (xy 427.712415 -213.219107) (xy 427.748393 -213.259261) (xy 427.778141 -213.304225)
			(xy 427.801026 -213.353042) (xy 427.816558 -213.404671) (xy 427.824408 -213.458011) (xy 427.8249 -213.484968)
			(xy 434.630845 -213.484968) (xy 434.63478 -213.431197) (xy 434.646503 -213.378573) (xy 434.665763 -213.328216)
			(xy 434.692149 -213.281199) (xy 434.725101 -213.238526) (xy 434.763914 -213.201105) (xy 434.807762 -213.169735)
			(xy 434.85571 -213.145083) (xy 434.906737 -213.127675) (xy 434.959755 -213.117882) (xy 435.013634 -213.115913)
			(xy 435.067225 -213.12181) (xy 435.119386 -213.135446) (xy 435.169006 -213.156533) (xy 435.215027 -213.184619)
			(xy 435.256469 -213.219107) (xy 435.292447 -213.259261) (xy 435.322195 -213.304225) (xy 435.34508 -213.353042)
			(xy 435.360612 -213.404671) (xy 435.368462 -213.458011) (xy 435.368954 -213.484968) (xy 442.174899 -213.484968)
			(xy 442.178834 -213.431197) (xy 442.190557 -213.378573) (xy 442.209817 -213.328216) (xy 442.236203 -213.281199)
			(xy 442.269155 -213.238526) (xy 442.307968 -213.201105) (xy 442.351816 -213.169735) (xy 442.399764 -213.145083)
			(xy 442.450791 -213.127675) (xy 442.503809 -213.117882) (xy 442.557688 -213.115913) (xy 442.611279 -213.12181)
			(xy 442.66344 -213.135446) (xy 442.71306 -213.156533) (xy 442.759081 -213.184619) (xy 442.800523 -213.219107)
			(xy 442.836501 -213.259261) (xy 442.866249 -213.304225) (xy 442.889134 -213.353042) (xy 442.904666 -213.404671)
			(xy 442.912516 -213.458011) (xy 442.913008 -213.484968) (xy 449.718699 -213.484968) (xy 449.722634 -213.431197)
			(xy 449.734357 -213.378573) (xy 449.753617 -213.328216) (xy 449.780003 -213.281199) (xy 449.812955 -213.238526)
			(xy 449.851768 -213.201105) (xy 449.895616 -213.169735) (xy 449.943564 -213.145083) (xy 449.994591 -213.127675)
			(xy 450.047609 -213.117882) (xy 450.101488 -213.115913) (xy 450.155079 -213.12181) (xy 450.20724 -213.135446)
			(xy 450.25686 -213.156533) (xy 450.302881 -213.184619) (xy 450.344323 -213.219107) (xy 450.380301 -213.259261)
			(xy 450.410049 -213.304225) (xy 450.432934 -213.353042) (xy 450.448466 -213.404671) (xy 450.456316 -213.458011)
			(xy 450.456808 -213.484968) (xy 450.456316 -213.511925) (xy 450.448466 -213.565265) (xy 450.432934 -213.616894)
			(xy 450.410049 -213.665711) (xy 450.380301 -213.710675) (xy 450.344323 -213.750829) (xy 450.302881 -213.785317)
			(xy 450.25686 -213.813403) (xy 450.20724 -213.83449) (xy 450.155079 -213.848126) (xy 450.101488 -213.854023)
			(xy 450.047609 -213.852054) (xy 449.994591 -213.842261) (xy 449.943564 -213.824853) (xy 449.895616 -213.800201)
			(xy 449.851768 -213.768831) (xy 449.812955 -213.73141) (xy 449.780003 -213.688737) (xy 449.753617 -213.64172)
			(xy 449.734357 -213.591363) (xy 449.722634 -213.538739) (xy 449.718699 -213.484968) (xy 442.913008 -213.484968)
			(xy 442.912516 -213.511925) (xy 442.904666 -213.565265) (xy 442.889134 -213.616894) (xy 442.866249 -213.665711)
			(xy 442.836501 -213.710675) (xy 442.800523 -213.750829) (xy 442.759081 -213.785317) (xy 442.71306 -213.813403)
			(xy 442.66344 -213.83449) (xy 442.611279 -213.848126) (xy 442.557688 -213.854023) (xy 442.503809 -213.852054)
			(xy 442.450791 -213.842261) (xy 442.399764 -213.824853) (xy 442.351816 -213.800201) (xy 442.307968 -213.768831)
			(xy 442.269155 -213.73141) (xy 442.236203 -213.688737) (xy 442.209817 -213.64172) (xy 442.190557 -213.591363)
			(xy 442.178834 -213.538739) (xy 442.174899 -213.484968) (xy 435.368954 -213.484968) (xy 435.368462 -213.511925)
			(xy 435.360612 -213.565265) (xy 435.34508 -213.616894) (xy 435.322195 -213.665711) (xy 435.292447 -213.710675)
			(xy 435.256469 -213.750829) (xy 435.215027 -213.785317) (xy 435.169006 -213.813403) (xy 435.119386 -213.83449)
			(xy 435.067225 -213.848126) (xy 435.013634 -213.854023) (xy 434.959755 -213.852054) (xy 434.906737 -213.842261)
			(xy 434.85571 -213.824853) (xy 434.807762 -213.800201) (xy 434.763914 -213.768831) (xy 434.725101 -213.73141)
			(xy 434.692149 -213.688737) (xy 434.665763 -213.64172) (xy 434.646503 -213.591363) (xy 434.63478 -213.538739)
			(xy 434.630845 -213.484968) (xy 427.8249 -213.484968) (xy 427.824408 -213.511925) (xy 427.816558 -213.565265)
			(xy 427.801026 -213.616894) (xy 427.778141 -213.665711) (xy 427.748393 -213.710675) (xy 427.712415 -213.750829)
			(xy 427.670973 -213.785317) (xy 427.624952 -213.813403) (xy 427.575332 -213.83449) (xy 427.523171 -213.848126)
			(xy 427.46958 -213.854023) (xy 427.415701 -213.852054) (xy 427.362683 -213.842261) (xy 427.311656 -213.824853)
			(xy 427.263708 -213.800201) (xy 427.21986 -213.768831) (xy 427.181047 -213.73141) (xy 427.148095 -213.688737)
			(xy 427.121709 -213.64172) (xy 427.102449 -213.591363) (xy 427.090726 -213.538739) (xy 427.086791 -213.484968)
			(xy 425.985178 -213.484968) (xy 425.985178 -214.335106) (xy 431.186859 -214.335106) (xy 431.190794 -214.281335)
			(xy 431.202517 -214.228711) (xy 431.221777 -214.178354) (xy 431.248163 -214.131337) (xy 431.281115 -214.088664)
			(xy 431.319928 -214.051243) (xy 431.363776 -214.019873) (xy 431.411724 -213.995221) (xy 431.462751 -213.977813)
			(xy 431.515769 -213.96802) (xy 431.569648 -213.966051) (xy 431.623239 -213.971948) (xy 431.6754 -213.985584)
			(xy 431.72502 -214.006671) (xy 431.771041 -214.034757) (xy 431.812483 -214.069245) (xy 431.848461 -214.109399)
			(xy 431.878209 -214.154363) (xy 431.901094 -214.20318) (xy 431.916626 -214.254809) (xy 431.924476 -214.308149)
			(xy 431.924968 -214.335106) (xy 438.730913 -214.335106) (xy 438.734848 -214.281335) (xy 438.746571 -214.228711)
			(xy 438.765831 -214.178354) (xy 438.792217 -214.131337) (xy 438.825169 -214.088664) (xy 438.863982 -214.051243)
			(xy 438.90783 -214.019873) (xy 438.955778 -213.995221) (xy 439.006805 -213.977813) (xy 439.059823 -213.96802)
			(xy 439.113702 -213.966051) (xy 439.167293 -213.971948) (xy 439.219454 -213.985584) (xy 439.269074 -214.006671)
			(xy 439.315095 -214.034757) (xy 439.356537 -214.069245) (xy 439.392515 -214.109399) (xy 439.422263 -214.154363)
			(xy 439.445148 -214.20318) (xy 439.46068 -214.254809) (xy 439.46853 -214.308149) (xy 439.469022 -214.335106)
			(xy 446.274967 -214.335106) (xy 446.278902 -214.281335) (xy 446.290625 -214.228711) (xy 446.309885 -214.178354)
			(xy 446.336271 -214.131337) (xy 446.369223 -214.088664) (xy 446.408036 -214.051243) (xy 446.451884 -214.019873)
			(xy 446.499832 -213.995221) (xy 446.550859 -213.977813) (xy 446.603877 -213.96802) (xy 446.657756 -213.966051)
			(xy 446.711347 -213.971948) (xy 446.763508 -213.985584) (xy 446.813128 -214.006671) (xy 446.859149 -214.034757)
			(xy 446.900591 -214.069245) (xy 446.936569 -214.109399) (xy 446.966317 -214.154363) (xy 446.989202 -214.20318)
			(xy 447.004734 -214.254809) (xy 447.012584 -214.308149) (xy 447.013076 -214.335106) (xy 453.818767 -214.335106)
			(xy 453.822702 -214.281335) (xy 453.834425 -214.228711) (xy 453.853685 -214.178354) (xy 453.880071 -214.131337)
			(xy 453.913023 -214.088664) (xy 453.951836 -214.051243) (xy 453.995684 -214.019873) (xy 454.043632 -213.995221)
			(xy 454.094659 -213.977813) (xy 454.147677 -213.96802) (xy 454.201556 -213.966051) (xy 454.255147 -213.971948)
			(xy 454.307308 -213.985584) (xy 454.356928 -214.006671) (xy 454.402949 -214.034757) (xy 454.444391 -214.069245)
			(xy 454.480369 -214.109399) (xy 454.510117 -214.154363) (xy 454.533002 -214.20318) (xy 454.548534 -214.254809)
			(xy 454.556384 -214.308149) (xy 454.556876 -214.335106) (xy 454.556384 -214.362063) (xy 454.548534 -214.415403)
			(xy 454.533002 -214.467032) (xy 454.510117 -214.515849) (xy 454.480369 -214.560813) (xy 454.444391 -214.600967)
			(xy 454.402949 -214.635455) (xy 454.356928 -214.663541) (xy 454.307308 -214.684628) (xy 454.255147 -214.698264)
			(xy 454.201556 -214.704161) (xy 454.147677 -214.702192) (xy 454.094659 -214.692399) (xy 454.043632 -214.674991)
			(xy 453.995684 -214.650339) (xy 453.951836 -214.618969) (xy 453.913023 -214.581548) (xy 453.880071 -214.538875)
			(xy 453.853685 -214.491858) (xy 453.834425 -214.441501) (xy 453.822702 -214.388877) (xy 453.818767 -214.335106)
			(xy 447.013076 -214.335106) (xy 447.012584 -214.362063) (xy 447.004734 -214.415403) (xy 446.989202 -214.467032)
			(xy 446.966317 -214.515849) (xy 446.936569 -214.560813) (xy 446.900591 -214.600967) (xy 446.859149 -214.635455)
			(xy 446.813128 -214.663541) (xy 446.763508 -214.684628) (xy 446.711347 -214.698264) (xy 446.657756 -214.704161)
			(xy 446.603877 -214.702192) (xy 446.550859 -214.692399) (xy 446.499832 -214.674991) (xy 446.451884 -214.650339)
			(xy 446.408036 -214.618969) (xy 446.369223 -214.581548) (xy 446.336271 -214.538875) (xy 446.309885 -214.491858)
			(xy 446.290625 -214.441501) (xy 446.278902 -214.388877) (xy 446.274967 -214.335106) (xy 439.469022 -214.335106)
			(xy 439.46853 -214.362063) (xy 439.46068 -214.415403) (xy 439.445148 -214.467032) (xy 439.422263 -214.515849)
			(xy 439.392515 -214.560813) (xy 439.356537 -214.600967) (xy 439.315095 -214.635455) (xy 439.269074 -214.663541)
			(xy 439.219454 -214.684628) (xy 439.167293 -214.698264) (xy 439.113702 -214.704161) (xy 439.059823 -214.702192)
			(xy 439.006805 -214.692399) (xy 438.955778 -214.674991) (xy 438.90783 -214.650339) (xy 438.863982 -214.618969)
			(xy 438.825169 -214.581548) (xy 438.792217 -214.538875) (xy 438.765831 -214.491858) (xy 438.746571 -214.441501)
			(xy 438.734848 -214.388877) (xy 438.730913 -214.335106) (xy 431.924968 -214.335106) (xy 431.924476 -214.362063)
			(xy 431.916626 -214.415403) (xy 431.901094 -214.467032) (xy 431.878209 -214.515849) (xy 431.848461 -214.560813)
			(xy 431.812483 -214.600967) (xy 431.771041 -214.635455) (xy 431.72502 -214.663541) (xy 431.6754 -214.684628)
			(xy 431.623239 -214.698264) (xy 431.569648 -214.704161) (xy 431.515769 -214.702192) (xy 431.462751 -214.692399)
			(xy 431.411724 -214.674991) (xy 431.363776 -214.650339) (xy 431.319928 -214.618969) (xy 431.281115 -214.581548)
			(xy 431.248163 -214.538875) (xy 431.221777 -214.491858) (xy 431.202517 -214.441501) (xy 431.190794 -214.388877)
			(xy 431.186859 -214.335106) (xy 425.985178 -214.335106) (xy 425.985178 -215.18499) (xy 427.086791 -215.18499)
			(xy 427.090726 -215.131219) (xy 427.102449 -215.078595) (xy 427.121709 -215.028238) (xy 427.148095 -214.981221)
			(xy 427.181047 -214.938548) (xy 427.21986 -214.901127) (xy 427.263708 -214.869757) (xy 427.311656 -214.845105)
			(xy 427.362683 -214.827697) (xy 427.415701 -214.817904) (xy 427.46958 -214.815935) (xy 427.523171 -214.821832)
			(xy 427.575332 -214.835468) (xy 427.624952 -214.856555) (xy 427.670973 -214.884641) (xy 427.712415 -214.919129)
			(xy 427.748393 -214.959283) (xy 427.778141 -215.004247) (xy 427.801026 -215.053064) (xy 427.816558 -215.104693)
			(xy 427.824408 -215.158033) (xy 427.8249 -215.18499) (xy 434.630845 -215.18499) (xy 434.63478 -215.131219)
			(xy 434.646503 -215.078595) (xy 434.665763 -215.028238) (xy 434.692149 -214.981221) (xy 434.725101 -214.938548)
			(xy 434.763914 -214.901127) (xy 434.807762 -214.869757) (xy 434.85571 -214.845105) (xy 434.906737 -214.827697)
			(xy 434.959755 -214.817904) (xy 435.013634 -214.815935) (xy 435.067225 -214.821832) (xy 435.119386 -214.835468)
			(xy 435.169006 -214.856555) (xy 435.215027 -214.884641) (xy 435.256469 -214.919129) (xy 435.292447 -214.959283)
			(xy 435.322195 -215.004247) (xy 435.34508 -215.053064) (xy 435.360612 -215.104693) (xy 435.368462 -215.158033)
			(xy 435.368954 -215.18499) (xy 442.174899 -215.18499) (xy 442.178834 -215.131219) (xy 442.190557 -215.078595)
			(xy 442.209817 -215.028238) (xy 442.236203 -214.981221) (xy 442.269155 -214.938548) (xy 442.307968 -214.901127)
			(xy 442.351816 -214.869757) (xy 442.399764 -214.845105) (xy 442.450791 -214.827697) (xy 442.503809 -214.817904)
			(xy 442.557688 -214.815935) (xy 442.611279 -214.821832) (xy 442.66344 -214.835468) (xy 442.71306 -214.856555)
			(xy 442.759081 -214.884641) (xy 442.800523 -214.919129) (xy 442.836501 -214.959283) (xy 442.866249 -215.004247)
			(xy 442.889134 -215.053064) (xy 442.904666 -215.104693) (xy 442.912516 -215.158033) (xy 442.913008 -215.18499)
			(xy 449.718699 -215.18499) (xy 449.722634 -215.131219) (xy 449.734357 -215.078595) (xy 449.753617 -215.028238)
			(xy 449.780003 -214.981221) (xy 449.812955 -214.938548) (xy 449.851768 -214.901127) (xy 449.895616 -214.869757)
			(xy 449.943564 -214.845105) (xy 449.994591 -214.827697) (xy 450.047609 -214.817904) (xy 450.101488 -214.815935)
			(xy 450.155079 -214.821832) (xy 450.20724 -214.835468) (xy 450.25686 -214.856555) (xy 450.302881 -214.884641)
			(xy 450.344323 -214.919129) (xy 450.380301 -214.959283) (xy 450.410049 -215.004247) (xy 450.432934 -215.053064)
			(xy 450.448466 -215.104693) (xy 450.456316 -215.158033) (xy 450.456808 -215.18499) (xy 450.456316 -215.211947)
			(xy 450.448466 -215.265287) (xy 450.432934 -215.316916) (xy 450.410049 -215.365733) (xy 450.380301 -215.410697)
			(xy 450.344323 -215.450851) (xy 450.302881 -215.485339) (xy 450.25686 -215.513425) (xy 450.20724 -215.534512)
			(xy 450.155079 -215.548148) (xy 450.101488 -215.554045) (xy 450.047609 -215.552076) (xy 449.994591 -215.542283)
			(xy 449.943564 -215.524875) (xy 449.895616 -215.500223) (xy 449.851768 -215.468853) (xy 449.812955 -215.431432)
			(xy 449.780003 -215.388759) (xy 449.753617 -215.341742) (xy 449.734357 -215.291385) (xy 449.722634 -215.238761)
			(xy 449.718699 -215.18499) (xy 442.913008 -215.18499) (xy 442.912516 -215.211947) (xy 442.904666 -215.265287)
			(xy 442.889134 -215.316916) (xy 442.866249 -215.365733) (xy 442.836501 -215.410697) (xy 442.800523 -215.450851)
			(xy 442.759081 -215.485339) (xy 442.71306 -215.513425) (xy 442.66344 -215.534512) (xy 442.611279 -215.548148)
			(xy 442.557688 -215.554045) (xy 442.503809 -215.552076) (xy 442.450791 -215.542283) (xy 442.399764 -215.524875)
			(xy 442.351816 -215.500223) (xy 442.307968 -215.468853) (xy 442.269155 -215.431432) (xy 442.236203 -215.388759)
			(xy 442.209817 -215.341742) (xy 442.190557 -215.291385) (xy 442.178834 -215.238761) (xy 442.174899 -215.18499)
			(xy 435.368954 -215.18499) (xy 435.368462 -215.211947) (xy 435.360612 -215.265287) (xy 435.34508 -215.316916)
			(xy 435.322195 -215.365733) (xy 435.292447 -215.410697) (xy 435.256469 -215.450851) (xy 435.215027 -215.485339)
			(xy 435.169006 -215.513425) (xy 435.119386 -215.534512) (xy 435.067225 -215.548148) (xy 435.013634 -215.554045)
			(xy 434.959755 -215.552076) (xy 434.906737 -215.542283) (xy 434.85571 -215.524875) (xy 434.807762 -215.500223)
			(xy 434.763914 -215.468853) (xy 434.725101 -215.431432) (xy 434.692149 -215.388759) (xy 434.665763 -215.341742)
			(xy 434.646503 -215.291385) (xy 434.63478 -215.238761) (xy 434.630845 -215.18499) (xy 427.8249 -215.18499)
			(xy 427.824408 -215.211947) (xy 427.816558 -215.265287) (xy 427.801026 -215.316916) (xy 427.778141 -215.365733)
			(xy 427.748393 -215.410697) (xy 427.712415 -215.450851) (xy 427.670973 -215.485339) (xy 427.624952 -215.513425)
			(xy 427.575332 -215.534512) (xy 427.523171 -215.548148) (xy 427.46958 -215.554045) (xy 427.415701 -215.552076)
			(xy 427.362683 -215.542283) (xy 427.311656 -215.524875) (xy 427.263708 -215.500223) (xy 427.21986 -215.468853)
			(xy 427.181047 -215.431432) (xy 427.148095 -215.388759) (xy 427.121709 -215.341742) (xy 427.102449 -215.291385)
			(xy 427.090726 -215.238761) (xy 427.086791 -215.18499) (xy 425.985178 -215.18499) (xy 425.985178 -216.035128)
			(xy 431.186859 -216.035128) (xy 431.190794 -215.981357) (xy 431.202517 -215.928733) (xy 431.221777 -215.878376)
			(xy 431.248163 -215.831359) (xy 431.281115 -215.788686) (xy 431.319928 -215.751265) (xy 431.363776 -215.719895)
			(xy 431.411724 -215.695243) (xy 431.462751 -215.677835) (xy 431.515769 -215.668042) (xy 431.569648 -215.666073)
			(xy 431.623239 -215.67197) (xy 431.6754 -215.685606) (xy 431.72502 -215.706693) (xy 431.771041 -215.734779)
			(xy 431.812483 -215.769267) (xy 431.848461 -215.809421) (xy 431.878209 -215.854385) (xy 431.901094 -215.903202)
			(xy 431.916626 -215.954831) (xy 431.924476 -216.008171) (xy 431.924968 -216.035128) (xy 438.730913 -216.035128)
			(xy 438.734848 -215.981357) (xy 438.746571 -215.928733) (xy 438.765831 -215.878376) (xy 438.792217 -215.831359)
			(xy 438.825169 -215.788686) (xy 438.863982 -215.751265) (xy 438.90783 -215.719895) (xy 438.955778 -215.695243)
			(xy 439.006805 -215.677835) (xy 439.059823 -215.668042) (xy 439.113702 -215.666073) (xy 439.167293 -215.67197)
			(xy 439.219454 -215.685606) (xy 439.269074 -215.706693) (xy 439.315095 -215.734779) (xy 439.356537 -215.769267)
			(xy 439.392515 -215.809421) (xy 439.422263 -215.854385) (xy 439.445148 -215.903202) (xy 439.46068 -215.954831)
			(xy 439.46853 -216.008171) (xy 439.469022 -216.035128) (xy 446.274967 -216.035128) (xy 446.278902 -215.981357)
			(xy 446.290625 -215.928733) (xy 446.309885 -215.878376) (xy 446.336271 -215.831359) (xy 446.369223 -215.788686)
			(xy 446.408036 -215.751265) (xy 446.451884 -215.719895) (xy 446.499832 -215.695243) (xy 446.550859 -215.677835)
			(xy 446.603877 -215.668042) (xy 446.657756 -215.666073) (xy 446.711347 -215.67197) (xy 446.763508 -215.685606)
			(xy 446.813128 -215.706693) (xy 446.859149 -215.734779) (xy 446.900591 -215.769267) (xy 446.936569 -215.809421)
			(xy 446.966317 -215.854385) (xy 446.989202 -215.903202) (xy 447.004734 -215.954831) (xy 447.012584 -216.008171)
			(xy 447.013076 -216.035128) (xy 453.818767 -216.035128) (xy 453.822702 -215.981357) (xy 453.834425 -215.928733)
			(xy 453.853685 -215.878376) (xy 453.880071 -215.831359) (xy 453.913023 -215.788686) (xy 453.951836 -215.751265)
			(xy 453.995684 -215.719895) (xy 454.043632 -215.695243) (xy 454.094659 -215.677835) (xy 454.147677 -215.668042)
			(xy 454.201556 -215.666073) (xy 454.255147 -215.67197) (xy 454.307308 -215.685606) (xy 454.356928 -215.706693)
			(xy 454.402949 -215.734779) (xy 454.444391 -215.769267) (xy 454.480369 -215.809421) (xy 454.510117 -215.854385)
			(xy 454.533002 -215.903202) (xy 454.548534 -215.954831) (xy 454.556384 -216.008171) (xy 454.556876 -216.035128)
			(xy 454.556384 -216.062085) (xy 454.548534 -216.115425) (xy 454.533002 -216.167054) (xy 454.510117 -216.215871)
			(xy 454.480369 -216.260835) (xy 454.444391 -216.300989) (xy 454.402949 -216.335477) (xy 454.356928 -216.363563)
			(xy 454.307308 -216.38465) (xy 454.255147 -216.398286) (xy 454.201556 -216.404183) (xy 454.147677 -216.402214)
			(xy 454.094659 -216.392421) (xy 454.043632 -216.375013) (xy 453.995684 -216.350361) (xy 453.951836 -216.318991)
			(xy 453.913023 -216.28157) (xy 453.880071 -216.238897) (xy 453.853685 -216.19188) (xy 453.834425 -216.141523)
			(xy 453.822702 -216.088899) (xy 453.818767 -216.035128) (xy 447.013076 -216.035128) (xy 447.012584 -216.062085)
			(xy 447.004734 -216.115425) (xy 446.989202 -216.167054) (xy 446.966317 -216.215871) (xy 446.936569 -216.260835)
			(xy 446.900591 -216.300989) (xy 446.859149 -216.335477) (xy 446.813128 -216.363563) (xy 446.763508 -216.38465)
			(xy 446.711347 -216.398286) (xy 446.657756 -216.404183) (xy 446.603877 -216.402214) (xy 446.550859 -216.392421)
			(xy 446.499832 -216.375013) (xy 446.451884 -216.350361) (xy 446.408036 -216.318991) (xy 446.369223 -216.28157)
			(xy 446.336271 -216.238897) (xy 446.309885 -216.19188) (xy 446.290625 -216.141523) (xy 446.278902 -216.088899)
			(xy 446.274967 -216.035128) (xy 439.469022 -216.035128) (xy 439.46853 -216.062085) (xy 439.46068 -216.115425)
			(xy 439.445148 -216.167054) (xy 439.422263 -216.215871) (xy 439.392515 -216.260835) (xy 439.356537 -216.300989)
			(xy 439.315095 -216.335477) (xy 439.269074 -216.363563) (xy 439.219454 -216.38465) (xy 439.167293 -216.398286)
			(xy 439.113702 -216.404183) (xy 439.059823 -216.402214) (xy 439.006805 -216.392421) (xy 438.955778 -216.375013)
			(xy 438.90783 -216.350361) (xy 438.863982 -216.318991) (xy 438.825169 -216.28157) (xy 438.792217 -216.238897)
			(xy 438.765831 -216.19188) (xy 438.746571 -216.141523) (xy 438.734848 -216.088899) (xy 438.730913 -216.035128)
			(xy 431.924968 -216.035128) (xy 431.924476 -216.062085) (xy 431.916626 -216.115425) (xy 431.901094 -216.167054)
			(xy 431.878209 -216.215871) (xy 431.848461 -216.260835) (xy 431.812483 -216.300989) (xy 431.771041 -216.335477)
			(xy 431.72502 -216.363563) (xy 431.6754 -216.38465) (xy 431.623239 -216.398286) (xy 431.569648 -216.404183)
			(xy 431.515769 -216.402214) (xy 431.462751 -216.392421) (xy 431.411724 -216.375013) (xy 431.363776 -216.350361)
			(xy 431.319928 -216.318991) (xy 431.281115 -216.28157) (xy 431.248163 -216.238897) (xy 431.221777 -216.19188)
			(xy 431.202517 -216.141523) (xy 431.190794 -216.088899) (xy 431.186859 -216.035128) (xy 425.985178 -216.035128)
			(xy 425.985178 -216.885012) (xy 427.086791 -216.885012) (xy 427.090726 -216.831241) (xy 427.102449 -216.778617)
			(xy 427.121709 -216.72826) (xy 427.148095 -216.681243) (xy 427.181047 -216.63857) (xy 427.21986 -216.601149)
			(xy 427.263708 -216.569779) (xy 427.311656 -216.545127) (xy 427.362683 -216.527719) (xy 427.415701 -216.517926)
			(xy 427.46958 -216.515957) (xy 427.523171 -216.521854) (xy 427.575332 -216.53549) (xy 427.624952 -216.556577)
			(xy 427.670973 -216.584663) (xy 427.712415 -216.619151) (xy 427.748393 -216.659305) (xy 427.778141 -216.704269)
			(xy 427.801026 -216.753086) (xy 427.816558 -216.804715) (xy 427.824408 -216.858055) (xy 427.8249 -216.885012)
			(xy 434.630845 -216.885012) (xy 434.63478 -216.831241) (xy 434.646503 -216.778617) (xy 434.665763 -216.72826)
			(xy 434.692149 -216.681243) (xy 434.725101 -216.63857) (xy 434.763914 -216.601149) (xy 434.807762 -216.569779)
			(xy 434.85571 -216.545127) (xy 434.906737 -216.527719) (xy 434.959755 -216.517926) (xy 435.013634 -216.515957)
			(xy 435.067225 -216.521854) (xy 435.119386 -216.53549) (xy 435.169006 -216.556577) (xy 435.215027 -216.584663)
			(xy 435.256469 -216.619151) (xy 435.292447 -216.659305) (xy 435.322195 -216.704269) (xy 435.34508 -216.753086)
			(xy 435.360612 -216.804715) (xy 435.368462 -216.858055) (xy 435.368954 -216.885012) (xy 442.174899 -216.885012)
			(xy 442.178834 -216.831241) (xy 442.190557 -216.778617) (xy 442.209817 -216.72826) (xy 442.236203 -216.681243)
			(xy 442.269155 -216.63857) (xy 442.307968 -216.601149) (xy 442.351816 -216.569779) (xy 442.399764 -216.545127)
			(xy 442.450791 -216.527719) (xy 442.503809 -216.517926) (xy 442.557688 -216.515957) (xy 442.611279 -216.521854)
			(xy 442.66344 -216.53549) (xy 442.71306 -216.556577) (xy 442.759081 -216.584663) (xy 442.800523 -216.619151)
			(xy 442.836501 -216.659305) (xy 442.866249 -216.704269) (xy 442.889134 -216.753086) (xy 442.904666 -216.804715)
			(xy 442.912516 -216.858055) (xy 442.913008 -216.885012) (xy 449.718699 -216.885012) (xy 449.722634 -216.831241)
			(xy 449.734357 -216.778617) (xy 449.753617 -216.72826) (xy 449.780003 -216.681243) (xy 449.812955 -216.63857)
			(xy 449.851768 -216.601149) (xy 449.895616 -216.569779) (xy 449.943564 -216.545127) (xy 449.994591 -216.527719)
			(xy 450.047609 -216.517926) (xy 450.101488 -216.515957) (xy 450.155079 -216.521854) (xy 450.20724 -216.53549)
			(xy 450.25686 -216.556577) (xy 450.302881 -216.584663) (xy 450.344323 -216.619151) (xy 450.380301 -216.659305)
			(xy 450.410049 -216.704269) (xy 450.432934 -216.753086) (xy 450.448466 -216.804715) (xy 450.456316 -216.858055)
			(xy 450.456808 -216.885012) (xy 450.456316 -216.911969) (xy 450.448466 -216.965309) (xy 450.432934 -217.016938)
			(xy 450.410049 -217.065755) (xy 450.380301 -217.110719) (xy 450.344323 -217.150873) (xy 450.302881 -217.185361)
			(xy 450.25686 -217.213447) (xy 450.20724 -217.234534) (xy 450.155079 -217.24817) (xy 450.101488 -217.254067)
			(xy 450.047609 -217.252098) (xy 449.994591 -217.242305) (xy 449.943564 -217.224897) (xy 449.895616 -217.200245)
			(xy 449.851768 -217.168875) (xy 449.812955 -217.131454) (xy 449.780003 -217.088781) (xy 449.753617 -217.041764)
			(xy 449.734357 -216.991407) (xy 449.722634 -216.938783) (xy 449.718699 -216.885012) (xy 442.913008 -216.885012)
			(xy 442.912516 -216.911969) (xy 442.904666 -216.965309) (xy 442.889134 -217.016938) (xy 442.866249 -217.065755)
			(xy 442.836501 -217.110719) (xy 442.800523 -217.150873) (xy 442.759081 -217.185361) (xy 442.71306 -217.213447)
			(xy 442.66344 -217.234534) (xy 442.611279 -217.24817) (xy 442.557688 -217.254067) (xy 442.503809 -217.252098)
			(xy 442.450791 -217.242305) (xy 442.399764 -217.224897) (xy 442.351816 -217.200245) (xy 442.307968 -217.168875)
			(xy 442.269155 -217.131454) (xy 442.236203 -217.088781) (xy 442.209817 -217.041764) (xy 442.190557 -216.991407)
			(xy 442.178834 -216.938783) (xy 442.174899 -216.885012) (xy 435.368954 -216.885012) (xy 435.368462 -216.911969)
			(xy 435.360612 -216.965309) (xy 435.34508 -217.016938) (xy 435.322195 -217.065755) (xy 435.292447 -217.110719)
			(xy 435.256469 -217.150873) (xy 435.215027 -217.185361) (xy 435.169006 -217.213447) (xy 435.119386 -217.234534)
			(xy 435.067225 -217.24817) (xy 435.013634 -217.254067) (xy 434.959755 -217.252098) (xy 434.906737 -217.242305)
			(xy 434.85571 -217.224897) (xy 434.807762 -217.200245) (xy 434.763914 -217.168875) (xy 434.725101 -217.131454)
			(xy 434.692149 -217.088781) (xy 434.665763 -217.041764) (xy 434.646503 -216.991407) (xy 434.63478 -216.938783)
			(xy 434.630845 -216.885012) (xy 427.8249 -216.885012) (xy 427.824408 -216.911969) (xy 427.816558 -216.965309)
			(xy 427.801026 -217.016938) (xy 427.778141 -217.065755) (xy 427.748393 -217.110719) (xy 427.712415 -217.150873)
			(xy 427.670973 -217.185361) (xy 427.624952 -217.213447) (xy 427.575332 -217.234534) (xy 427.523171 -217.24817)
			(xy 427.46958 -217.254067) (xy 427.415701 -217.252098) (xy 427.362683 -217.242305) (xy 427.311656 -217.224897)
			(xy 427.263708 -217.200245) (xy 427.21986 -217.168875) (xy 427.181047 -217.131454) (xy 427.148095 -217.088781)
			(xy 427.121709 -217.041764) (xy 427.102449 -216.991407) (xy 427.090726 -216.938783) (xy 427.086791 -216.885012)
			(xy 425.985178 -216.885012) (xy 425.985178 -217.73515) (xy 431.186859 -217.73515) (xy 431.190794 -217.681379)
			(xy 431.202517 -217.628755) (xy 431.221777 -217.578398) (xy 431.248163 -217.531381) (xy 431.281115 -217.488708)
			(xy 431.319928 -217.451287) (xy 431.363776 -217.419917) (xy 431.411724 -217.395265) (xy 431.462751 -217.377857)
			(xy 431.515769 -217.368064) (xy 431.569648 -217.366095) (xy 431.623239 -217.371992) (xy 431.6754 -217.385628)
			(xy 431.72502 -217.406715) (xy 431.771041 -217.434801) (xy 431.812483 -217.469289) (xy 431.848461 -217.509443)
			(xy 431.878209 -217.554407) (xy 431.901094 -217.603224) (xy 431.916626 -217.654853) (xy 431.924476 -217.708193)
			(xy 431.924968 -217.73515) (xy 438.730913 -217.73515) (xy 438.734848 -217.681379) (xy 438.746571 -217.628755)
			(xy 438.765831 -217.578398) (xy 438.792217 -217.531381) (xy 438.825169 -217.488708) (xy 438.863982 -217.451287)
			(xy 438.90783 -217.419917) (xy 438.955778 -217.395265) (xy 439.006805 -217.377857) (xy 439.059823 -217.368064)
			(xy 439.113702 -217.366095) (xy 439.167293 -217.371992) (xy 439.219454 -217.385628) (xy 439.269074 -217.406715)
			(xy 439.315095 -217.434801) (xy 439.356537 -217.469289) (xy 439.392515 -217.509443) (xy 439.422263 -217.554407)
			(xy 439.445148 -217.603224) (xy 439.46068 -217.654853) (xy 439.46853 -217.708193) (xy 439.469022 -217.73515)
			(xy 446.274967 -217.73515) (xy 446.278902 -217.681379) (xy 446.290625 -217.628755) (xy 446.309885 -217.578398)
			(xy 446.336271 -217.531381) (xy 446.369223 -217.488708) (xy 446.408036 -217.451287) (xy 446.451884 -217.419917)
			(xy 446.499832 -217.395265) (xy 446.550859 -217.377857) (xy 446.603877 -217.368064) (xy 446.657756 -217.366095)
			(xy 446.711347 -217.371992) (xy 446.763508 -217.385628) (xy 446.813128 -217.406715) (xy 446.859149 -217.434801)
			(xy 446.900591 -217.469289) (xy 446.936569 -217.509443) (xy 446.966317 -217.554407) (xy 446.989202 -217.603224)
			(xy 447.004734 -217.654853) (xy 447.012584 -217.708193) (xy 447.013076 -217.73515) (xy 453.818767 -217.73515)
			(xy 453.822702 -217.681379) (xy 453.834425 -217.628755) (xy 453.853685 -217.578398) (xy 453.880071 -217.531381)
			(xy 453.913023 -217.488708) (xy 453.951836 -217.451287) (xy 453.995684 -217.419917) (xy 454.043632 -217.395265)
			(xy 454.094659 -217.377857) (xy 454.147677 -217.368064) (xy 454.201556 -217.366095) (xy 454.255147 -217.371992)
			(xy 454.307308 -217.385628) (xy 454.356928 -217.406715) (xy 454.402949 -217.434801) (xy 454.444391 -217.469289)
			(xy 454.480369 -217.509443) (xy 454.510117 -217.554407) (xy 454.533002 -217.603224) (xy 454.548534 -217.654853)
			(xy 454.556384 -217.708193) (xy 454.556876 -217.73515) (xy 454.556384 -217.762107) (xy 454.548534 -217.815447)
			(xy 454.533002 -217.867076) (xy 454.510117 -217.915893) (xy 454.480369 -217.960857) (xy 454.444391 -218.001011)
			(xy 454.402949 -218.035499) (xy 454.356928 -218.063585) (xy 454.307308 -218.084672) (xy 454.255147 -218.098308)
			(xy 454.201556 -218.104205) (xy 454.147677 -218.102236) (xy 454.094659 -218.092443) (xy 454.043632 -218.075035)
			(xy 453.995684 -218.050383) (xy 453.951836 -218.019013) (xy 453.913023 -217.981592) (xy 453.880071 -217.938919)
			(xy 453.853685 -217.891902) (xy 453.834425 -217.841545) (xy 453.822702 -217.788921) (xy 453.818767 -217.73515)
			(xy 447.013076 -217.73515) (xy 447.012584 -217.762107) (xy 447.004734 -217.815447) (xy 446.989202 -217.867076)
			(xy 446.966317 -217.915893) (xy 446.936569 -217.960857) (xy 446.900591 -218.001011) (xy 446.859149 -218.035499)
			(xy 446.813128 -218.063585) (xy 446.763508 -218.084672) (xy 446.711347 -218.098308) (xy 446.657756 -218.104205)
			(xy 446.603877 -218.102236) (xy 446.550859 -218.092443) (xy 446.499832 -218.075035) (xy 446.451884 -218.050383)
			(xy 446.408036 -218.019013) (xy 446.369223 -217.981592) (xy 446.336271 -217.938919) (xy 446.309885 -217.891902)
			(xy 446.290625 -217.841545) (xy 446.278902 -217.788921) (xy 446.274967 -217.73515) (xy 439.469022 -217.73515)
			(xy 439.46853 -217.762107) (xy 439.46068 -217.815447) (xy 439.445148 -217.867076) (xy 439.422263 -217.915893)
			(xy 439.392515 -217.960857) (xy 439.356537 -218.001011) (xy 439.315095 -218.035499) (xy 439.269074 -218.063585)
			(xy 439.219454 -218.084672) (xy 439.167293 -218.098308) (xy 439.113702 -218.104205) (xy 439.059823 -218.102236)
			(xy 439.006805 -218.092443) (xy 438.955778 -218.075035) (xy 438.90783 -218.050383) (xy 438.863982 -218.019013)
			(xy 438.825169 -217.981592) (xy 438.792217 -217.938919) (xy 438.765831 -217.891902) (xy 438.746571 -217.841545)
			(xy 438.734848 -217.788921) (xy 438.730913 -217.73515) (xy 431.924968 -217.73515) (xy 431.924476 -217.762107)
			(xy 431.916626 -217.815447) (xy 431.901094 -217.867076) (xy 431.878209 -217.915893) (xy 431.848461 -217.960857)
			(xy 431.812483 -218.001011) (xy 431.771041 -218.035499) (xy 431.72502 -218.063585) (xy 431.6754 -218.084672)
			(xy 431.623239 -218.098308) (xy 431.569648 -218.104205) (xy 431.515769 -218.102236) (xy 431.462751 -218.092443)
			(xy 431.411724 -218.075035) (xy 431.363776 -218.050383) (xy 431.319928 -218.019013) (xy 431.281115 -217.981592)
			(xy 431.248163 -217.938919) (xy 431.221777 -217.891902) (xy 431.202517 -217.841545) (xy 431.190794 -217.788921)
			(xy 431.186859 -217.73515) (xy 425.985178 -217.73515) (xy 425.985178 -218.585034) (xy 427.086791 -218.585034)
			(xy 427.090726 -218.531263) (xy 427.102449 -218.478639) (xy 427.121709 -218.428282) (xy 427.148095 -218.381265)
			(xy 427.181047 -218.338592) (xy 427.21986 -218.301171) (xy 427.263708 -218.269801) (xy 427.311656 -218.245149)
			(xy 427.362683 -218.227741) (xy 427.415701 -218.217948) (xy 427.46958 -218.215979) (xy 427.523171 -218.221876)
			(xy 427.575332 -218.235512) (xy 427.624952 -218.256599) (xy 427.670973 -218.284685) (xy 427.712415 -218.319173)
			(xy 427.748393 -218.359327) (xy 427.778141 -218.404291) (xy 427.801026 -218.453108) (xy 427.816558 -218.504737)
			(xy 427.824408 -218.558077) (xy 427.8249 -218.585034) (xy 434.630845 -218.585034) (xy 434.63478 -218.531263)
			(xy 434.646503 -218.478639) (xy 434.665763 -218.428282) (xy 434.692149 -218.381265) (xy 434.725101 -218.338592)
			(xy 434.763914 -218.301171) (xy 434.807762 -218.269801) (xy 434.85571 -218.245149) (xy 434.906737 -218.227741)
			(xy 434.959755 -218.217948) (xy 435.013634 -218.215979) (xy 435.067225 -218.221876) (xy 435.119386 -218.235512)
			(xy 435.169006 -218.256599) (xy 435.215027 -218.284685) (xy 435.256469 -218.319173) (xy 435.292447 -218.359327)
			(xy 435.322195 -218.404291) (xy 435.34508 -218.453108) (xy 435.360612 -218.504737) (xy 435.368462 -218.558077)
			(xy 435.368954 -218.585034) (xy 442.174899 -218.585034) (xy 442.178834 -218.531263) (xy 442.190557 -218.478639)
			(xy 442.209817 -218.428282) (xy 442.236203 -218.381265) (xy 442.269155 -218.338592) (xy 442.307968 -218.301171)
			(xy 442.351816 -218.269801) (xy 442.399764 -218.245149) (xy 442.450791 -218.227741) (xy 442.503809 -218.217948)
			(xy 442.557688 -218.215979) (xy 442.611279 -218.221876) (xy 442.66344 -218.235512) (xy 442.71306 -218.256599)
			(xy 442.759081 -218.284685) (xy 442.800523 -218.319173) (xy 442.836501 -218.359327) (xy 442.866249 -218.404291)
			(xy 442.889134 -218.453108) (xy 442.904666 -218.504737) (xy 442.912516 -218.558077) (xy 442.913008 -218.585034)
			(xy 449.718699 -218.585034) (xy 449.722634 -218.531263) (xy 449.734357 -218.478639) (xy 449.753617 -218.428282)
			(xy 449.780003 -218.381265) (xy 449.812955 -218.338592) (xy 449.851768 -218.301171) (xy 449.895616 -218.269801)
			(xy 449.943564 -218.245149) (xy 449.994591 -218.227741) (xy 450.047609 -218.217948) (xy 450.101488 -218.215979)
			(xy 450.155079 -218.221876) (xy 450.20724 -218.235512) (xy 450.25686 -218.256599) (xy 450.302881 -218.284685)
			(xy 450.344323 -218.319173) (xy 450.380301 -218.359327) (xy 450.410049 -218.404291) (xy 450.432934 -218.453108)
			(xy 450.448466 -218.504737) (xy 450.456316 -218.558077) (xy 450.456808 -218.585034) (xy 450.456316 -218.611991)
			(xy 450.448466 -218.665331) (xy 450.432934 -218.71696) (xy 450.410049 -218.765777) (xy 450.380301 -218.810741)
			(xy 450.344323 -218.850895) (xy 450.302881 -218.885383) (xy 450.25686 -218.913469) (xy 450.20724 -218.934556)
			(xy 450.155079 -218.948192) (xy 450.101488 -218.954089) (xy 450.047609 -218.95212) (xy 449.994591 -218.942327)
			(xy 449.943564 -218.924919) (xy 449.895616 -218.900267) (xy 449.851768 -218.868897) (xy 449.812955 -218.831476)
			(xy 449.780003 -218.788803) (xy 449.753617 -218.741786) (xy 449.734357 -218.691429) (xy 449.722634 -218.638805)
			(xy 449.718699 -218.585034) (xy 442.913008 -218.585034) (xy 442.912516 -218.611991) (xy 442.904666 -218.665331)
			(xy 442.889134 -218.71696) (xy 442.866249 -218.765777) (xy 442.836501 -218.810741) (xy 442.800523 -218.850895)
			(xy 442.759081 -218.885383) (xy 442.71306 -218.913469) (xy 442.66344 -218.934556) (xy 442.611279 -218.948192)
			(xy 442.557688 -218.954089) (xy 442.503809 -218.95212) (xy 442.450791 -218.942327) (xy 442.399764 -218.924919)
			(xy 442.351816 -218.900267) (xy 442.307968 -218.868897) (xy 442.269155 -218.831476) (xy 442.236203 -218.788803)
			(xy 442.209817 -218.741786) (xy 442.190557 -218.691429) (xy 442.178834 -218.638805) (xy 442.174899 -218.585034)
			(xy 435.368954 -218.585034) (xy 435.368462 -218.611991) (xy 435.360612 -218.665331) (xy 435.34508 -218.71696)
			(xy 435.322195 -218.765777) (xy 435.292447 -218.810741) (xy 435.256469 -218.850895) (xy 435.215027 -218.885383)
			(xy 435.169006 -218.913469) (xy 435.119386 -218.934556) (xy 435.067225 -218.948192) (xy 435.013634 -218.954089)
			(xy 434.959755 -218.95212) (xy 434.906737 -218.942327) (xy 434.85571 -218.924919) (xy 434.807762 -218.900267)
			(xy 434.763914 -218.868897) (xy 434.725101 -218.831476) (xy 434.692149 -218.788803) (xy 434.665763 -218.741786)
			(xy 434.646503 -218.691429) (xy 434.63478 -218.638805) (xy 434.630845 -218.585034) (xy 427.8249 -218.585034)
			(xy 427.824408 -218.611991) (xy 427.816558 -218.665331) (xy 427.801026 -218.71696) (xy 427.778141 -218.765777)
			(xy 427.748393 -218.810741) (xy 427.712415 -218.850895) (xy 427.670973 -218.885383) (xy 427.624952 -218.913469)
			(xy 427.575332 -218.934556) (xy 427.523171 -218.948192) (xy 427.46958 -218.954089) (xy 427.415701 -218.95212)
			(xy 427.362683 -218.942327) (xy 427.311656 -218.924919) (xy 427.263708 -218.900267) (xy 427.21986 -218.868897)
			(xy 427.181047 -218.831476) (xy 427.148095 -218.788803) (xy 427.121709 -218.741786) (xy 427.102449 -218.691429)
			(xy 427.090726 -218.638805) (xy 427.086791 -218.585034) (xy 425.985178 -218.585034) (xy 425.985178 -219.435172)
			(xy 431.186859 -219.435172) (xy 431.190794 -219.381401) (xy 431.202517 -219.328777) (xy 431.221777 -219.27842)
			(xy 431.248163 -219.231403) (xy 431.281115 -219.18873) (xy 431.319928 -219.151309) (xy 431.363776 -219.119939)
			(xy 431.411724 -219.095287) (xy 431.462751 -219.077879) (xy 431.515769 -219.068086) (xy 431.569648 -219.066117)
			(xy 431.623239 -219.072014) (xy 431.6754 -219.08565) (xy 431.72502 -219.106737) (xy 431.771041 -219.134823)
			(xy 431.812483 -219.169311) (xy 431.848461 -219.209465) (xy 431.878209 -219.254429) (xy 431.901094 -219.303246)
			(xy 431.916626 -219.354875) (xy 431.924476 -219.408215) (xy 431.924968 -219.435172) (xy 438.730913 -219.435172)
			(xy 438.734848 -219.381401) (xy 438.746571 -219.328777) (xy 438.765831 -219.27842) (xy 438.792217 -219.231403)
			(xy 438.825169 -219.18873) (xy 438.863982 -219.151309) (xy 438.90783 -219.119939) (xy 438.955778 -219.095287)
			(xy 439.006805 -219.077879) (xy 439.059823 -219.068086) (xy 439.113702 -219.066117) (xy 439.167293 -219.072014)
			(xy 439.219454 -219.08565) (xy 439.269074 -219.106737) (xy 439.315095 -219.134823) (xy 439.356537 -219.169311)
			(xy 439.392515 -219.209465) (xy 439.422263 -219.254429) (xy 439.445148 -219.303246) (xy 439.46068 -219.354875)
			(xy 439.46853 -219.408215) (xy 439.469022 -219.435172) (xy 446.274967 -219.435172) (xy 446.278902 -219.381401)
			(xy 446.290625 -219.328777) (xy 446.309885 -219.27842) (xy 446.336271 -219.231403) (xy 446.369223 -219.18873)
			(xy 446.408036 -219.151309) (xy 446.451884 -219.119939) (xy 446.499832 -219.095287) (xy 446.550859 -219.077879)
			(xy 446.603877 -219.068086) (xy 446.657756 -219.066117) (xy 446.711347 -219.072014) (xy 446.763508 -219.08565)
			(xy 446.813128 -219.106737) (xy 446.859149 -219.134823) (xy 446.900591 -219.169311) (xy 446.936569 -219.209465)
			(xy 446.966317 -219.254429) (xy 446.989202 -219.303246) (xy 447.004734 -219.354875) (xy 447.012584 -219.408215)
			(xy 447.013076 -219.435172) (xy 453.818767 -219.435172) (xy 453.822702 -219.381401) (xy 453.834425 -219.328777)
			(xy 453.853685 -219.27842) (xy 453.880071 -219.231403) (xy 453.913023 -219.18873) (xy 453.951836 -219.151309)
			(xy 453.995684 -219.119939) (xy 454.043632 -219.095287) (xy 454.094659 -219.077879) (xy 454.147677 -219.068086)
			(xy 454.201556 -219.066117) (xy 454.255147 -219.072014) (xy 454.307308 -219.08565) (xy 454.356928 -219.106737)
			(xy 454.402949 -219.134823) (xy 454.444391 -219.169311) (xy 454.480369 -219.209465) (xy 454.510117 -219.254429)
			(xy 454.533002 -219.303246) (xy 454.548534 -219.354875) (xy 454.556384 -219.408215) (xy 454.556876 -219.435172)
			(xy 454.556384 -219.462129) (xy 454.548534 -219.515469) (xy 454.533002 -219.567098) (xy 454.510117 -219.615915)
			(xy 454.480369 -219.660879) (xy 454.444391 -219.701033) (xy 454.402949 -219.735521) (xy 454.356928 -219.763607)
			(xy 454.307308 -219.784694) (xy 454.255147 -219.79833) (xy 454.201556 -219.804227) (xy 454.147677 -219.802258)
			(xy 454.094659 -219.792465) (xy 454.043632 -219.775057) (xy 453.995684 -219.750405) (xy 453.951836 -219.719035)
			(xy 453.913023 -219.681614) (xy 453.880071 -219.638941) (xy 453.853685 -219.591924) (xy 453.834425 -219.541567)
			(xy 453.822702 -219.488943) (xy 453.818767 -219.435172) (xy 447.013076 -219.435172) (xy 447.012584 -219.462129)
			(xy 447.004734 -219.515469) (xy 446.989202 -219.567098) (xy 446.966317 -219.615915) (xy 446.936569 -219.660879)
			(xy 446.900591 -219.701033) (xy 446.859149 -219.735521) (xy 446.813128 -219.763607) (xy 446.763508 -219.784694)
			(xy 446.711347 -219.79833) (xy 446.657756 -219.804227) (xy 446.603877 -219.802258) (xy 446.550859 -219.792465)
			(xy 446.499832 -219.775057) (xy 446.451884 -219.750405) (xy 446.408036 -219.719035) (xy 446.369223 -219.681614)
			(xy 446.336271 -219.638941) (xy 446.309885 -219.591924) (xy 446.290625 -219.541567) (xy 446.278902 -219.488943)
			(xy 446.274967 -219.435172) (xy 439.469022 -219.435172) (xy 439.46853 -219.462129) (xy 439.46068 -219.515469)
			(xy 439.445148 -219.567098) (xy 439.422263 -219.615915) (xy 439.392515 -219.660879) (xy 439.356537 -219.701033)
			(xy 439.315095 -219.735521) (xy 439.269074 -219.763607) (xy 439.219454 -219.784694) (xy 439.167293 -219.79833)
			(xy 439.113702 -219.804227) (xy 439.059823 -219.802258) (xy 439.006805 -219.792465) (xy 438.955778 -219.775057)
			(xy 438.90783 -219.750405) (xy 438.863982 -219.719035) (xy 438.825169 -219.681614) (xy 438.792217 -219.638941)
			(xy 438.765831 -219.591924) (xy 438.746571 -219.541567) (xy 438.734848 -219.488943) (xy 438.730913 -219.435172)
			(xy 431.924968 -219.435172) (xy 431.924476 -219.462129) (xy 431.916626 -219.515469) (xy 431.901094 -219.567098)
			(xy 431.878209 -219.615915) (xy 431.848461 -219.660879) (xy 431.812483 -219.701033) (xy 431.771041 -219.735521)
			(xy 431.72502 -219.763607) (xy 431.6754 -219.784694) (xy 431.623239 -219.79833) (xy 431.569648 -219.804227)
			(xy 431.515769 -219.802258) (xy 431.462751 -219.792465) (xy 431.411724 -219.775057) (xy 431.363776 -219.750405)
			(xy 431.319928 -219.719035) (xy 431.281115 -219.681614) (xy 431.248163 -219.638941) (xy 431.221777 -219.591924)
			(xy 431.202517 -219.541567) (xy 431.190794 -219.488943) (xy 431.186859 -219.435172) (xy 425.985178 -219.435172)
			(xy 425.985178 -220.285056) (xy 427.086791 -220.285056) (xy 427.090726 -220.231285) (xy 427.102449 -220.178661)
			(xy 427.121709 -220.128304) (xy 427.148095 -220.081287) (xy 427.181047 -220.038614) (xy 427.21986 -220.001193)
			(xy 427.263708 -219.969823) (xy 427.311656 -219.945171) (xy 427.362683 -219.927763) (xy 427.415701 -219.91797)
			(xy 427.46958 -219.916001) (xy 427.523171 -219.921898) (xy 427.575332 -219.935534) (xy 427.624952 -219.956621)
			(xy 427.670973 -219.984707) (xy 427.712415 -220.019195) (xy 427.748393 -220.059349) (xy 427.778141 -220.104313)
			(xy 427.801026 -220.15313) (xy 427.816558 -220.204759) (xy 427.824408 -220.258099) (xy 427.8249 -220.285056)
			(xy 431.186859 -220.285056) (xy 431.190794 -220.231285) (xy 431.202517 -220.178661) (xy 431.221777 -220.128304)
			(xy 431.248163 -220.081287) (xy 431.281115 -220.038614) (xy 431.319928 -220.001193) (xy 431.363776 -219.969823)
			(xy 431.411724 -219.945171) (xy 431.462751 -219.927763) (xy 431.515769 -219.91797) (xy 431.569648 -219.916001)
			(xy 431.623239 -219.921898) (xy 431.6754 -219.935534) (xy 431.72502 -219.956621) (xy 431.771041 -219.984707)
			(xy 431.812483 -220.019195) (xy 431.848461 -220.059349) (xy 431.878209 -220.104313) (xy 431.901094 -220.15313)
			(xy 431.916626 -220.204759) (xy 431.924476 -220.258099) (xy 431.924968 -220.285056) (xy 434.630845 -220.285056)
			(xy 434.63478 -220.231285) (xy 434.646503 -220.178661) (xy 434.665763 -220.128304) (xy 434.692149 -220.081287)
			(xy 434.725101 -220.038614) (xy 434.763914 -220.001193) (xy 434.807762 -219.969823) (xy 434.85571 -219.945171)
			(xy 434.906737 -219.927763) (xy 434.959755 -219.91797) (xy 435.013634 -219.916001) (xy 435.067225 -219.921898)
			(xy 435.119386 -219.935534) (xy 435.169006 -219.956621) (xy 435.215027 -219.984707) (xy 435.256469 -220.019195)
			(xy 435.292447 -220.059349) (xy 435.322195 -220.104313) (xy 435.34508 -220.15313) (xy 435.360612 -220.204759)
			(xy 435.368462 -220.258099) (xy 435.368954 -220.285056) (xy 438.730913 -220.285056) (xy 438.734848 -220.231285)
			(xy 438.746571 -220.178661) (xy 438.765831 -220.128304) (xy 438.792217 -220.081287) (xy 438.825169 -220.038614)
			(xy 438.863982 -220.001193) (xy 438.90783 -219.969823) (xy 438.955778 -219.945171) (xy 439.006805 -219.927763)
			(xy 439.059823 -219.91797) (xy 439.113702 -219.916001) (xy 439.167293 -219.921898) (xy 439.219454 -219.935534)
			(xy 439.269074 -219.956621) (xy 439.315095 -219.984707) (xy 439.356537 -220.019195) (xy 439.392515 -220.059349)
			(xy 439.422263 -220.104313) (xy 439.445148 -220.15313) (xy 439.46068 -220.204759) (xy 439.46853 -220.258099)
			(xy 439.469022 -220.285056) (xy 442.174899 -220.285056) (xy 442.178834 -220.231285) (xy 442.190557 -220.178661)
			(xy 442.209817 -220.128304) (xy 442.236203 -220.081287) (xy 442.269155 -220.038614) (xy 442.307968 -220.001193)
			(xy 442.351816 -219.969823) (xy 442.399764 -219.945171) (xy 442.450791 -219.927763) (xy 442.503809 -219.91797)
			(xy 442.557688 -219.916001) (xy 442.611279 -219.921898) (xy 442.66344 -219.935534) (xy 442.71306 -219.956621)
			(xy 442.759081 -219.984707) (xy 442.800523 -220.019195) (xy 442.836501 -220.059349) (xy 442.866249 -220.104313)
			(xy 442.889134 -220.15313) (xy 442.904666 -220.204759) (xy 442.912516 -220.258099) (xy 442.913008 -220.285056)
			(xy 446.274967 -220.285056) (xy 446.278902 -220.231285) (xy 446.290625 -220.178661) (xy 446.309885 -220.128304)
			(xy 446.336271 -220.081287) (xy 446.369223 -220.038614) (xy 446.408036 -220.001193) (xy 446.451884 -219.969823)
			(xy 446.499832 -219.945171) (xy 446.550859 -219.927763) (xy 446.603877 -219.91797) (xy 446.657756 -219.916001)
			(xy 446.711347 -219.921898) (xy 446.763508 -219.935534) (xy 446.813128 -219.956621) (xy 446.859149 -219.984707)
			(xy 446.900591 -220.019195) (xy 446.936569 -220.059349) (xy 446.966317 -220.104313) (xy 446.989202 -220.15313)
			(xy 447.004734 -220.204759) (xy 447.012584 -220.258099) (xy 447.013076 -220.285056) (xy 449.718699 -220.285056)
			(xy 449.722634 -220.231285) (xy 449.734357 -220.178661) (xy 449.753617 -220.128304) (xy 449.780003 -220.081287)
			(xy 449.812955 -220.038614) (xy 449.851768 -220.001193) (xy 449.895616 -219.969823) (xy 449.943564 -219.945171)
			(xy 449.994591 -219.927763) (xy 450.047609 -219.91797) (xy 450.101488 -219.916001) (xy 450.155079 -219.921898)
			(xy 450.20724 -219.935534) (xy 450.25686 -219.956621) (xy 450.302881 -219.984707) (xy 450.344323 -220.019195)
			(xy 450.380301 -220.059349) (xy 450.410049 -220.104313) (xy 450.432934 -220.15313) (xy 450.448466 -220.204759)
			(xy 450.456316 -220.258099) (xy 450.456808 -220.285056) (xy 453.818767 -220.285056) (xy 453.822702 -220.231285)
			(xy 453.834425 -220.178661) (xy 453.853685 -220.128304) (xy 453.880071 -220.081287) (xy 453.913023 -220.038614)
			(xy 453.951836 -220.001193) (xy 453.995684 -219.969823) (xy 454.043632 -219.945171) (xy 454.094659 -219.927763)
			(xy 454.147677 -219.91797) (xy 454.201556 -219.916001) (xy 454.255147 -219.921898) (xy 454.307308 -219.935534)
			(xy 454.356928 -219.956621) (xy 454.402949 -219.984707) (xy 454.444391 -220.019195) (xy 454.480369 -220.059349)
			(xy 454.510117 -220.104313) (xy 454.533002 -220.15313) (xy 454.548534 -220.204759) (xy 454.556384 -220.258099)
			(xy 454.556876 -220.285056) (xy 454.556384 -220.312013) (xy 454.548534 -220.365353) (xy 454.533002 -220.416982)
			(xy 454.510117 -220.465799) (xy 454.480369 -220.510763) (xy 454.444391 -220.550917) (xy 454.402949 -220.585405)
			(xy 454.356928 -220.613491) (xy 454.307308 -220.634578) (xy 454.255147 -220.648214) (xy 454.201556 -220.654111)
			(xy 454.147677 -220.652142) (xy 454.094659 -220.642349) (xy 454.043632 -220.624941) (xy 453.995684 -220.600289)
			(xy 453.951836 -220.568919) (xy 453.913023 -220.531498) (xy 453.880071 -220.488825) (xy 453.853685 -220.441808)
			(xy 453.834425 -220.391451) (xy 453.822702 -220.338827) (xy 453.818767 -220.285056) (xy 450.456808 -220.285056)
			(xy 450.456316 -220.312013) (xy 450.448466 -220.365353) (xy 450.432934 -220.416982) (xy 450.410049 -220.465799)
			(xy 450.380301 -220.510763) (xy 450.344323 -220.550917) (xy 450.302881 -220.585405) (xy 450.25686 -220.613491)
			(xy 450.20724 -220.634578) (xy 450.155079 -220.648214) (xy 450.101488 -220.654111) (xy 450.047609 -220.652142)
			(xy 449.994591 -220.642349) (xy 449.943564 -220.624941) (xy 449.895616 -220.600289) (xy 449.851768 -220.568919)
			(xy 449.812955 -220.531498) (xy 449.780003 -220.488825) (xy 449.753617 -220.441808) (xy 449.734357 -220.391451)
			(xy 449.722634 -220.338827) (xy 449.718699 -220.285056) (xy 447.013076 -220.285056) (xy 447.012584 -220.312013)
			(xy 447.004734 -220.365353) (xy 446.989202 -220.416982) (xy 446.966317 -220.465799) (xy 446.936569 -220.510763)
			(xy 446.900591 -220.550917) (xy 446.859149 -220.585405) (xy 446.813128 -220.613491) (xy 446.763508 -220.634578)
			(xy 446.711347 -220.648214) (xy 446.657756 -220.654111) (xy 446.603877 -220.652142) (xy 446.550859 -220.642349)
			(xy 446.499832 -220.624941) (xy 446.451884 -220.600289) (xy 446.408036 -220.568919) (xy 446.369223 -220.531498)
			(xy 446.336271 -220.488825) (xy 446.309885 -220.441808) (xy 446.290625 -220.391451) (xy 446.278902 -220.338827)
			(xy 446.274967 -220.285056) (xy 442.913008 -220.285056) (xy 442.912516 -220.312013) (xy 442.904666 -220.365353)
			(xy 442.889134 -220.416982) (xy 442.866249 -220.465799) (xy 442.836501 -220.510763) (xy 442.800523 -220.550917)
			(xy 442.759081 -220.585405) (xy 442.71306 -220.613491) (xy 442.66344 -220.634578) (xy 442.611279 -220.648214)
			(xy 442.557688 -220.654111) (xy 442.503809 -220.652142) (xy 442.450791 -220.642349) (xy 442.399764 -220.624941)
			(xy 442.351816 -220.600289) (xy 442.307968 -220.568919) (xy 442.269155 -220.531498) (xy 442.236203 -220.488825)
			(xy 442.209817 -220.441808) (xy 442.190557 -220.391451) (xy 442.178834 -220.338827) (xy 442.174899 -220.285056)
			(xy 439.469022 -220.285056) (xy 439.46853 -220.312013) (xy 439.46068 -220.365353) (xy 439.445148 -220.416982)
			(xy 439.422263 -220.465799) (xy 439.392515 -220.510763) (xy 439.356537 -220.550917) (xy 439.315095 -220.585405)
			(xy 439.269074 -220.613491) (xy 439.219454 -220.634578) (xy 439.167293 -220.648214) (xy 439.113702 -220.654111)
			(xy 439.059823 -220.652142) (xy 439.006805 -220.642349) (xy 438.955778 -220.624941) (xy 438.90783 -220.600289)
			(xy 438.863982 -220.568919) (xy 438.825169 -220.531498) (xy 438.792217 -220.488825) (xy 438.765831 -220.441808)
			(xy 438.746571 -220.391451) (xy 438.734848 -220.338827) (xy 438.730913 -220.285056) (xy 435.368954 -220.285056)
			(xy 435.368462 -220.312013) (xy 435.360612 -220.365353) (xy 435.34508 -220.416982) (xy 435.322195 -220.465799)
			(xy 435.292447 -220.510763) (xy 435.256469 -220.550917) (xy 435.215027 -220.585405) (xy 435.169006 -220.613491)
			(xy 435.119386 -220.634578) (xy 435.067225 -220.648214) (xy 435.013634 -220.654111) (xy 434.959755 -220.652142)
			(xy 434.906737 -220.642349) (xy 434.85571 -220.624941) (xy 434.807762 -220.600289) (xy 434.763914 -220.568919)
			(xy 434.725101 -220.531498) (xy 434.692149 -220.488825) (xy 434.665763 -220.441808) (xy 434.646503 -220.391451)
			(xy 434.63478 -220.338827) (xy 434.630845 -220.285056) (xy 431.924968 -220.285056) (xy 431.924476 -220.312013)
			(xy 431.916626 -220.365353) (xy 431.901094 -220.416982) (xy 431.878209 -220.465799) (xy 431.848461 -220.510763)
			(xy 431.812483 -220.550917) (xy 431.771041 -220.585405) (xy 431.72502 -220.613491) (xy 431.6754 -220.634578)
			(xy 431.623239 -220.648214) (xy 431.569648 -220.654111) (xy 431.515769 -220.652142) (xy 431.462751 -220.642349)
			(xy 431.411724 -220.624941) (xy 431.363776 -220.600289) (xy 431.319928 -220.568919) (xy 431.281115 -220.531498)
			(xy 431.248163 -220.488825) (xy 431.221777 -220.441808) (xy 431.202517 -220.391451) (xy 431.190794 -220.338827)
			(xy 431.186859 -220.285056) (xy 427.8249 -220.285056) (xy 427.824408 -220.312013) (xy 427.816558 -220.365353)
			(xy 427.801026 -220.416982) (xy 427.778141 -220.465799) (xy 427.748393 -220.510763) (xy 427.712415 -220.550917)
			(xy 427.670973 -220.585405) (xy 427.624952 -220.613491) (xy 427.575332 -220.634578) (xy 427.523171 -220.648214)
			(xy 427.46958 -220.654111) (xy 427.415701 -220.652142) (xy 427.362683 -220.642349) (xy 427.311656 -220.624941)
			(xy 427.263708 -220.600289) (xy 427.21986 -220.568919) (xy 427.181047 -220.531498) (xy 427.148095 -220.488825)
			(xy 427.121709 -220.441808) (xy 427.102449 -220.391451) (xy 427.090726 -220.338827) (xy 427.086791 -220.285056)
			(xy 425.985178 -220.285056) (xy 425.985178 -221.13494) (xy 427.086791 -221.13494) (xy 427.090726 -221.081169)
			(xy 427.102449 -221.028545) (xy 427.121709 -220.978188) (xy 427.148095 -220.931171) (xy 427.181047 -220.888498)
			(xy 427.21986 -220.851077) (xy 427.263708 -220.819707) (xy 427.311656 -220.795055) (xy 427.362683 -220.777647)
			(xy 427.415701 -220.767854) (xy 427.46958 -220.765885) (xy 427.523171 -220.771782) (xy 427.575332 -220.785418)
			(xy 427.624952 -220.806505) (xy 427.670973 -220.834591) (xy 427.712415 -220.869079) (xy 427.748393 -220.909233)
			(xy 427.778141 -220.954197) (xy 427.801026 -221.003014) (xy 427.816558 -221.054643) (xy 427.824408 -221.107983)
			(xy 427.8249 -221.13494) (xy 434.630845 -221.13494) (xy 434.63478 -221.081169) (xy 434.646503 -221.028545)
			(xy 434.665763 -220.978188) (xy 434.692149 -220.931171) (xy 434.725101 -220.888498) (xy 434.763914 -220.851077)
			(xy 434.807762 -220.819707) (xy 434.85571 -220.795055) (xy 434.906737 -220.777647) (xy 434.959755 -220.767854)
			(xy 435.013634 -220.765885) (xy 435.067225 -220.771782) (xy 435.119386 -220.785418) (xy 435.169006 -220.806505)
			(xy 435.215027 -220.834591) (xy 435.256469 -220.869079) (xy 435.292447 -220.909233) (xy 435.322195 -220.954197)
			(xy 435.34508 -221.003014) (xy 435.360612 -221.054643) (xy 435.368462 -221.107983) (xy 435.368954 -221.13494)
			(xy 442.174899 -221.13494) (xy 442.178834 -221.081169) (xy 442.190557 -221.028545) (xy 442.209817 -220.978188)
			(xy 442.236203 -220.931171) (xy 442.269155 -220.888498) (xy 442.307968 -220.851077) (xy 442.351816 -220.819707)
			(xy 442.399764 -220.795055) (xy 442.450791 -220.777647) (xy 442.503809 -220.767854) (xy 442.557688 -220.765885)
			(xy 442.611279 -220.771782) (xy 442.66344 -220.785418) (xy 442.71306 -220.806505) (xy 442.759081 -220.834591)
			(xy 442.800523 -220.869079) (xy 442.836501 -220.909233) (xy 442.866249 -220.954197) (xy 442.889134 -221.003014)
			(xy 442.904666 -221.054643) (xy 442.912516 -221.107983) (xy 442.913008 -221.13494) (xy 449.718699 -221.13494)
			(xy 449.722634 -221.081169) (xy 449.734357 -221.028545) (xy 449.753617 -220.978188) (xy 449.780003 -220.931171)
			(xy 449.812955 -220.888498) (xy 449.851768 -220.851077) (xy 449.895616 -220.819707) (xy 449.943564 -220.795055)
			(xy 449.994591 -220.777647) (xy 450.047609 -220.767854) (xy 450.101488 -220.765885) (xy 450.155079 -220.771782)
			(xy 450.20724 -220.785418) (xy 450.25686 -220.806505) (xy 450.302881 -220.834591) (xy 450.344323 -220.869079)
			(xy 450.380301 -220.909233) (xy 450.410049 -220.954197) (xy 450.432934 -221.003014) (xy 450.448466 -221.054643)
			(xy 450.456316 -221.107983) (xy 450.456808 -221.13494) (xy 450.456316 -221.161897) (xy 450.448466 -221.215237)
			(xy 450.432934 -221.266866) (xy 450.410049 -221.315683) (xy 450.380301 -221.360647) (xy 450.344323 -221.400801)
			(xy 450.302881 -221.435289) (xy 450.25686 -221.463375) (xy 450.20724 -221.484462) (xy 450.155079 -221.498098)
			(xy 450.101488 -221.503995) (xy 450.047609 -221.502026) (xy 449.994591 -221.492233) (xy 449.943564 -221.474825)
			(xy 449.895616 -221.450173) (xy 449.851768 -221.418803) (xy 449.812955 -221.381382) (xy 449.780003 -221.338709)
			(xy 449.753617 -221.291692) (xy 449.734357 -221.241335) (xy 449.722634 -221.188711) (xy 449.718699 -221.13494)
			(xy 442.913008 -221.13494) (xy 442.912516 -221.161897) (xy 442.904666 -221.215237) (xy 442.889134 -221.266866)
			(xy 442.866249 -221.315683) (xy 442.836501 -221.360647) (xy 442.800523 -221.400801) (xy 442.759081 -221.435289)
			(xy 442.71306 -221.463375) (xy 442.66344 -221.484462) (xy 442.611279 -221.498098) (xy 442.557688 -221.503995)
			(xy 442.503809 -221.502026) (xy 442.450791 -221.492233) (xy 442.399764 -221.474825) (xy 442.351816 -221.450173)
			(xy 442.307968 -221.418803) (xy 442.269155 -221.381382) (xy 442.236203 -221.338709) (xy 442.209817 -221.291692)
			(xy 442.190557 -221.241335) (xy 442.178834 -221.188711) (xy 442.174899 -221.13494) (xy 435.368954 -221.13494)
			(xy 435.368462 -221.161897) (xy 435.360612 -221.215237) (xy 435.34508 -221.266866) (xy 435.322195 -221.315683)
			(xy 435.292447 -221.360647) (xy 435.256469 -221.400801) (xy 435.215027 -221.435289) (xy 435.169006 -221.463375)
			(xy 435.119386 -221.484462) (xy 435.067225 -221.498098) (xy 435.013634 -221.503995) (xy 434.959755 -221.502026)
			(xy 434.906737 -221.492233) (xy 434.85571 -221.474825) (xy 434.807762 -221.450173) (xy 434.763914 -221.418803)
			(xy 434.725101 -221.381382) (xy 434.692149 -221.338709) (xy 434.665763 -221.291692) (xy 434.646503 -221.241335)
			(xy 434.63478 -221.188711) (xy 434.630845 -221.13494) (xy 427.8249 -221.13494) (xy 427.824408 -221.161897)
			(xy 427.816558 -221.215237) (xy 427.801026 -221.266866) (xy 427.778141 -221.315683) (xy 427.748393 -221.360647)
			(xy 427.712415 -221.400801) (xy 427.670973 -221.435289) (xy 427.624952 -221.463375) (xy 427.575332 -221.484462)
			(xy 427.523171 -221.498098) (xy 427.46958 -221.503995) (xy 427.415701 -221.502026) (xy 427.362683 -221.492233)
			(xy 427.311656 -221.474825) (xy 427.263708 -221.450173) (xy 427.21986 -221.418803) (xy 427.181047 -221.381382)
			(xy 427.148095 -221.338709) (xy 427.121709 -221.291692) (xy 427.102449 -221.241335) (xy 427.090726 -221.188711)
			(xy 427.086791 -221.13494) (xy 425.985178 -221.13494) (xy 425.985178 -221.985078) (xy 431.186859 -221.985078)
			(xy 431.190794 -221.931307) (xy 431.202517 -221.878683) (xy 431.221777 -221.828326) (xy 431.248163 -221.781309)
			(xy 431.281115 -221.738636) (xy 431.319928 -221.701215) (xy 431.363776 -221.669845) (xy 431.411724 -221.645193)
			(xy 431.462751 -221.627785) (xy 431.515769 -221.617992) (xy 431.569648 -221.616023) (xy 431.623239 -221.62192)
			(xy 431.6754 -221.635556) (xy 431.72502 -221.656643) (xy 431.771041 -221.684729) (xy 431.812483 -221.719217)
			(xy 431.848461 -221.759371) (xy 431.878209 -221.804335) (xy 431.901094 -221.853152) (xy 431.916626 -221.904781)
			(xy 431.924476 -221.958121) (xy 431.924968 -221.985078) (xy 438.730913 -221.985078) (xy 438.734848 -221.931307)
			(xy 438.746571 -221.878683) (xy 438.765831 -221.828326) (xy 438.792217 -221.781309) (xy 438.825169 -221.738636)
			(xy 438.863982 -221.701215) (xy 438.90783 -221.669845) (xy 438.955778 -221.645193) (xy 439.006805 -221.627785)
			(xy 439.059823 -221.617992) (xy 439.113702 -221.616023) (xy 439.167293 -221.62192) (xy 439.219454 -221.635556)
			(xy 439.269074 -221.656643) (xy 439.315095 -221.684729) (xy 439.356537 -221.719217) (xy 439.392515 -221.759371)
			(xy 439.422263 -221.804335) (xy 439.445148 -221.853152) (xy 439.46068 -221.904781) (xy 439.46853 -221.958121)
			(xy 439.469022 -221.985078) (xy 446.274967 -221.985078) (xy 446.278902 -221.931307) (xy 446.290625 -221.878683)
			(xy 446.309885 -221.828326) (xy 446.336271 -221.781309) (xy 446.369223 -221.738636) (xy 446.408036 -221.701215)
			(xy 446.451884 -221.669845) (xy 446.499832 -221.645193) (xy 446.550859 -221.627785) (xy 446.603877 -221.617992)
			(xy 446.657756 -221.616023) (xy 446.711347 -221.62192) (xy 446.763508 -221.635556) (xy 446.813128 -221.656643)
			(xy 446.859149 -221.684729) (xy 446.900591 -221.719217) (xy 446.936569 -221.759371) (xy 446.966317 -221.804335)
			(xy 446.989202 -221.853152) (xy 447.004734 -221.904781) (xy 447.012584 -221.958121) (xy 447.013076 -221.985078)
			(xy 453.818767 -221.985078) (xy 453.822702 -221.931307) (xy 453.834425 -221.878683) (xy 453.853685 -221.828326)
			(xy 453.880071 -221.781309) (xy 453.913023 -221.738636) (xy 453.951836 -221.701215) (xy 453.995684 -221.669845)
			(xy 454.043632 -221.645193) (xy 454.094659 -221.627785) (xy 454.147677 -221.617992) (xy 454.201556 -221.616023)
			(xy 454.255147 -221.62192) (xy 454.307308 -221.635556) (xy 454.356928 -221.656643) (xy 454.402949 -221.684729)
			(xy 454.444391 -221.719217) (xy 454.480369 -221.759371) (xy 454.510117 -221.804335) (xy 454.533002 -221.853152)
			(xy 454.548534 -221.904781) (xy 454.556384 -221.958121) (xy 454.556876 -221.985078) (xy 454.556384 -222.012035)
			(xy 454.548534 -222.065375) (xy 454.533002 -222.117004) (xy 454.510117 -222.165821) (xy 454.480369 -222.210785)
			(xy 454.444391 -222.250939) (xy 454.402949 -222.285427) (xy 454.356928 -222.313513) (xy 454.307308 -222.3346)
			(xy 454.255147 -222.348236) (xy 454.201556 -222.354133) (xy 454.147677 -222.352164) (xy 454.094659 -222.342371)
			(xy 454.043632 -222.324963) (xy 453.995684 -222.300311) (xy 453.951836 -222.268941) (xy 453.913023 -222.23152)
			(xy 453.880071 -222.188847) (xy 453.853685 -222.14183) (xy 453.834425 -222.091473) (xy 453.822702 -222.038849)
			(xy 453.818767 -221.985078) (xy 447.013076 -221.985078) (xy 447.012584 -222.012035) (xy 447.004734 -222.065375)
			(xy 446.989202 -222.117004) (xy 446.966317 -222.165821) (xy 446.936569 -222.210785) (xy 446.900591 -222.250939)
			(xy 446.859149 -222.285427) (xy 446.813128 -222.313513) (xy 446.763508 -222.3346) (xy 446.711347 -222.348236)
			(xy 446.657756 -222.354133) (xy 446.603877 -222.352164) (xy 446.550859 -222.342371) (xy 446.499832 -222.324963)
			(xy 446.451884 -222.300311) (xy 446.408036 -222.268941) (xy 446.369223 -222.23152) (xy 446.336271 -222.188847)
			(xy 446.309885 -222.14183) (xy 446.290625 -222.091473) (xy 446.278902 -222.038849) (xy 446.274967 -221.985078)
			(xy 439.469022 -221.985078) (xy 439.46853 -222.012035) (xy 439.46068 -222.065375) (xy 439.445148 -222.117004)
			(xy 439.422263 -222.165821) (xy 439.392515 -222.210785) (xy 439.356537 -222.250939) (xy 439.315095 -222.285427)
			(xy 439.269074 -222.313513) (xy 439.219454 -222.3346) (xy 439.167293 -222.348236) (xy 439.113702 -222.354133)
			(xy 439.059823 -222.352164) (xy 439.006805 -222.342371) (xy 438.955778 -222.324963) (xy 438.90783 -222.300311)
			(xy 438.863982 -222.268941) (xy 438.825169 -222.23152) (xy 438.792217 -222.188847) (xy 438.765831 -222.14183)
			(xy 438.746571 -222.091473) (xy 438.734848 -222.038849) (xy 438.730913 -221.985078) (xy 431.924968 -221.985078)
			(xy 431.924476 -222.012035) (xy 431.916626 -222.065375) (xy 431.901094 -222.117004) (xy 431.878209 -222.165821)
			(xy 431.848461 -222.210785) (xy 431.812483 -222.250939) (xy 431.771041 -222.285427) (xy 431.72502 -222.313513)
			(xy 431.6754 -222.3346) (xy 431.623239 -222.348236) (xy 431.569648 -222.354133) (xy 431.515769 -222.352164)
			(xy 431.462751 -222.342371) (xy 431.411724 -222.324963) (xy 431.363776 -222.300311) (xy 431.319928 -222.268941)
			(xy 431.281115 -222.23152) (xy 431.248163 -222.188847) (xy 431.221777 -222.14183) (xy 431.202517 -222.091473)
			(xy 431.190794 -222.038849) (xy 431.186859 -221.985078) (xy 425.985178 -221.985078) (xy 425.985178 -222.834962)
			(xy 427.086791 -222.834962) (xy 427.090726 -222.781191) (xy 427.102449 -222.728567) (xy 427.121709 -222.67821)
			(xy 427.148095 -222.631193) (xy 427.181047 -222.58852) (xy 427.21986 -222.551099) (xy 427.263708 -222.519729)
			(xy 427.311656 -222.495077) (xy 427.362683 -222.477669) (xy 427.415701 -222.467876) (xy 427.46958 -222.465907)
			(xy 427.523171 -222.471804) (xy 427.575332 -222.48544) (xy 427.624952 -222.506527) (xy 427.670973 -222.534613)
			(xy 427.712415 -222.569101) (xy 427.748393 -222.609255) (xy 427.778141 -222.654219) (xy 427.801026 -222.703036)
			(xy 427.816558 -222.754665) (xy 427.824408 -222.808005) (xy 427.8249 -222.834962) (xy 434.630845 -222.834962)
			(xy 434.63478 -222.781191) (xy 434.646503 -222.728567) (xy 434.665763 -222.67821) (xy 434.692149 -222.631193)
			(xy 434.725101 -222.58852) (xy 434.763914 -222.551099) (xy 434.807762 -222.519729) (xy 434.85571 -222.495077)
			(xy 434.906737 -222.477669) (xy 434.959755 -222.467876) (xy 435.013634 -222.465907) (xy 435.067225 -222.471804)
			(xy 435.119386 -222.48544) (xy 435.169006 -222.506527) (xy 435.215027 -222.534613) (xy 435.256469 -222.569101)
			(xy 435.292447 -222.609255) (xy 435.322195 -222.654219) (xy 435.34508 -222.703036) (xy 435.360612 -222.754665)
			(xy 435.368462 -222.808005) (xy 435.368954 -222.834962) (xy 442.174899 -222.834962) (xy 442.178834 -222.781191)
			(xy 442.190557 -222.728567) (xy 442.209817 -222.67821) (xy 442.236203 -222.631193) (xy 442.269155 -222.58852)
			(xy 442.307968 -222.551099) (xy 442.351816 -222.519729) (xy 442.399764 -222.495077) (xy 442.450791 -222.477669)
			(xy 442.503809 -222.467876) (xy 442.557688 -222.465907) (xy 442.611279 -222.471804) (xy 442.66344 -222.48544)
			(xy 442.71306 -222.506527) (xy 442.759081 -222.534613) (xy 442.800523 -222.569101) (xy 442.836501 -222.609255)
			(xy 442.866249 -222.654219) (xy 442.889134 -222.703036) (xy 442.904666 -222.754665) (xy 442.912516 -222.808005)
			(xy 442.913008 -222.834962) (xy 449.718699 -222.834962) (xy 449.722634 -222.781191) (xy 449.734357 -222.728567)
			(xy 449.753617 -222.67821) (xy 449.780003 -222.631193) (xy 449.812955 -222.58852) (xy 449.851768 -222.551099)
			(xy 449.895616 -222.519729) (xy 449.943564 -222.495077) (xy 449.994591 -222.477669) (xy 450.047609 -222.467876)
			(xy 450.101488 -222.465907) (xy 450.155079 -222.471804) (xy 450.20724 -222.48544) (xy 450.25686 -222.506527)
			(xy 450.302881 -222.534613) (xy 450.344323 -222.569101) (xy 450.380301 -222.609255) (xy 450.410049 -222.654219)
			(xy 450.432934 -222.703036) (xy 450.448466 -222.754665) (xy 450.456316 -222.808005) (xy 450.456808 -222.834962)
			(xy 450.456316 -222.861919) (xy 450.448466 -222.915259) (xy 450.432934 -222.966888) (xy 450.410049 -223.015705)
			(xy 450.380301 -223.060669) (xy 450.344323 -223.100823) (xy 450.302881 -223.135311) (xy 450.25686 -223.163397)
			(xy 450.20724 -223.184484) (xy 450.155079 -223.19812) (xy 450.101488 -223.204017) (xy 450.047609 -223.202048)
			(xy 449.994591 -223.192255) (xy 449.943564 -223.174847) (xy 449.895616 -223.150195) (xy 449.851768 -223.118825)
			(xy 449.812955 -223.081404) (xy 449.780003 -223.038731) (xy 449.753617 -222.991714) (xy 449.734357 -222.941357)
			(xy 449.722634 -222.888733) (xy 449.718699 -222.834962) (xy 442.913008 -222.834962) (xy 442.912516 -222.861919)
			(xy 442.904666 -222.915259) (xy 442.889134 -222.966888) (xy 442.866249 -223.015705) (xy 442.836501 -223.060669)
			(xy 442.800523 -223.100823) (xy 442.759081 -223.135311) (xy 442.71306 -223.163397) (xy 442.66344 -223.184484)
			(xy 442.611279 -223.19812) (xy 442.557688 -223.204017) (xy 442.503809 -223.202048) (xy 442.450791 -223.192255)
			(xy 442.399764 -223.174847) (xy 442.351816 -223.150195) (xy 442.307968 -223.118825) (xy 442.269155 -223.081404)
			(xy 442.236203 -223.038731) (xy 442.209817 -222.991714) (xy 442.190557 -222.941357) (xy 442.178834 -222.888733)
			(xy 442.174899 -222.834962) (xy 435.368954 -222.834962) (xy 435.368462 -222.861919) (xy 435.360612 -222.915259)
			(xy 435.34508 -222.966888) (xy 435.322195 -223.015705) (xy 435.292447 -223.060669) (xy 435.256469 -223.100823)
			(xy 435.215027 -223.135311) (xy 435.169006 -223.163397) (xy 435.119386 -223.184484) (xy 435.067225 -223.19812)
			(xy 435.013634 -223.204017) (xy 434.959755 -223.202048) (xy 434.906737 -223.192255) (xy 434.85571 -223.174847)
			(xy 434.807762 -223.150195) (xy 434.763914 -223.118825) (xy 434.725101 -223.081404) (xy 434.692149 -223.038731)
			(xy 434.665763 -222.991714) (xy 434.646503 -222.941357) (xy 434.63478 -222.888733) (xy 434.630845 -222.834962)
			(xy 427.8249 -222.834962) (xy 427.824408 -222.861919) (xy 427.816558 -222.915259) (xy 427.801026 -222.966888)
			(xy 427.778141 -223.015705) (xy 427.748393 -223.060669) (xy 427.712415 -223.100823) (xy 427.670973 -223.135311)
			(xy 427.624952 -223.163397) (xy 427.575332 -223.184484) (xy 427.523171 -223.19812) (xy 427.46958 -223.204017)
			(xy 427.415701 -223.202048) (xy 427.362683 -223.192255) (xy 427.311656 -223.174847) (xy 427.263708 -223.150195)
			(xy 427.21986 -223.118825) (xy 427.181047 -223.081404) (xy 427.148095 -223.038731) (xy 427.121709 -222.991714)
			(xy 427.102449 -222.941357) (xy 427.090726 -222.888733) (xy 427.086791 -222.834962) (xy 425.985178 -222.834962)
			(xy 425.985178 -223.6851) (xy 431.186859 -223.6851) (xy 431.190794 -223.631329) (xy 431.202517 -223.578705)
			(xy 431.221777 -223.528348) (xy 431.248163 -223.481331) (xy 431.281115 -223.438658) (xy 431.319928 -223.401237)
			(xy 431.363776 -223.369867) (xy 431.411724 -223.345215) (xy 431.462751 -223.327807) (xy 431.515769 -223.318014)
			(xy 431.569648 -223.316045) (xy 431.623239 -223.321942) (xy 431.6754 -223.335578) (xy 431.72502 -223.356665)
			(xy 431.771041 -223.384751) (xy 431.812483 -223.419239) (xy 431.848461 -223.459393) (xy 431.878209 -223.504357)
			(xy 431.901094 -223.553174) (xy 431.916626 -223.604803) (xy 431.924476 -223.658143) (xy 431.924968 -223.6851)
			(xy 438.730913 -223.6851) (xy 438.734848 -223.631329) (xy 438.746571 -223.578705) (xy 438.765831 -223.528348)
			(xy 438.792217 -223.481331) (xy 438.825169 -223.438658) (xy 438.863982 -223.401237) (xy 438.90783 -223.369867)
			(xy 438.955778 -223.345215) (xy 439.006805 -223.327807) (xy 439.059823 -223.318014) (xy 439.113702 -223.316045)
			(xy 439.167293 -223.321942) (xy 439.219454 -223.335578) (xy 439.269074 -223.356665) (xy 439.315095 -223.384751)
			(xy 439.356537 -223.419239) (xy 439.392515 -223.459393) (xy 439.422263 -223.504357) (xy 439.445148 -223.553174)
			(xy 439.46068 -223.604803) (xy 439.46853 -223.658143) (xy 439.469022 -223.6851) (xy 446.274967 -223.6851)
			(xy 446.278902 -223.631329) (xy 446.290625 -223.578705) (xy 446.309885 -223.528348) (xy 446.336271 -223.481331)
			(xy 446.369223 -223.438658) (xy 446.408036 -223.401237) (xy 446.451884 -223.369867) (xy 446.499832 -223.345215)
			(xy 446.550859 -223.327807) (xy 446.603877 -223.318014) (xy 446.657756 -223.316045) (xy 446.711347 -223.321942)
			(xy 446.763508 -223.335578) (xy 446.813128 -223.356665) (xy 446.859149 -223.384751) (xy 446.900591 -223.419239)
			(xy 446.936569 -223.459393) (xy 446.966317 -223.504357) (xy 446.989202 -223.553174) (xy 447.004734 -223.604803)
			(xy 447.012584 -223.658143) (xy 447.013076 -223.6851) (xy 453.818767 -223.6851) (xy 453.822702 -223.631329)
			(xy 453.834425 -223.578705) (xy 453.853685 -223.528348) (xy 453.880071 -223.481331) (xy 453.913023 -223.438658)
			(xy 453.951836 -223.401237) (xy 453.995684 -223.369867) (xy 454.043632 -223.345215) (xy 454.094659 -223.327807)
			(xy 454.147677 -223.318014) (xy 454.201556 -223.316045) (xy 454.255147 -223.321942) (xy 454.307308 -223.335578)
			(xy 454.356928 -223.356665) (xy 454.402949 -223.384751) (xy 454.444391 -223.419239) (xy 454.480369 -223.459393)
			(xy 454.510117 -223.504357) (xy 454.533002 -223.553174) (xy 454.548534 -223.604803) (xy 454.556384 -223.658143)
			(xy 454.556876 -223.6851) (xy 454.556384 -223.712057) (xy 454.548534 -223.765397) (xy 454.533002 -223.817026)
			(xy 454.510117 -223.865843) (xy 454.480369 -223.910807) (xy 454.444391 -223.950961) (xy 454.402949 -223.985449)
			(xy 454.356928 -224.013535) (xy 454.307308 -224.034622) (xy 454.255147 -224.048258) (xy 454.201556 -224.054155)
			(xy 454.147677 -224.052186) (xy 454.094659 -224.042393) (xy 454.043632 -224.024985) (xy 453.995684 -224.000333)
			(xy 453.951836 -223.968963) (xy 453.913023 -223.931542) (xy 453.880071 -223.888869) (xy 453.853685 -223.841852)
			(xy 453.834425 -223.791495) (xy 453.822702 -223.738871) (xy 453.818767 -223.6851) (xy 447.013076 -223.6851)
			(xy 447.012584 -223.712057) (xy 447.004734 -223.765397) (xy 446.989202 -223.817026) (xy 446.966317 -223.865843)
			(xy 446.936569 -223.910807) (xy 446.900591 -223.950961) (xy 446.859149 -223.985449) (xy 446.813128 -224.013535)
			(xy 446.763508 -224.034622) (xy 446.711347 -224.048258) (xy 446.657756 -224.054155) (xy 446.603877 -224.052186)
			(xy 446.550859 -224.042393) (xy 446.499832 -224.024985) (xy 446.451884 -224.000333) (xy 446.408036 -223.968963)
			(xy 446.369223 -223.931542) (xy 446.336271 -223.888869) (xy 446.309885 -223.841852) (xy 446.290625 -223.791495)
			(xy 446.278902 -223.738871) (xy 446.274967 -223.6851) (xy 439.469022 -223.6851) (xy 439.46853 -223.712057)
			(xy 439.46068 -223.765397) (xy 439.445148 -223.817026) (xy 439.422263 -223.865843) (xy 439.392515 -223.910807)
			(xy 439.356537 -223.950961) (xy 439.315095 -223.985449) (xy 439.269074 -224.013535) (xy 439.219454 -224.034622)
			(xy 439.167293 -224.048258) (xy 439.113702 -224.054155) (xy 439.059823 -224.052186) (xy 439.006805 -224.042393)
			(xy 438.955778 -224.024985) (xy 438.90783 -224.000333) (xy 438.863982 -223.968963) (xy 438.825169 -223.931542)
			(xy 438.792217 -223.888869) (xy 438.765831 -223.841852) (xy 438.746571 -223.791495) (xy 438.734848 -223.738871)
			(xy 438.730913 -223.6851) (xy 431.924968 -223.6851) (xy 431.924476 -223.712057) (xy 431.916626 -223.765397)
			(xy 431.901094 -223.817026) (xy 431.878209 -223.865843) (xy 431.848461 -223.910807) (xy 431.812483 -223.950961)
			(xy 431.771041 -223.985449) (xy 431.72502 -224.013535) (xy 431.6754 -224.034622) (xy 431.623239 -224.048258)
			(xy 431.569648 -224.054155) (xy 431.515769 -224.052186) (xy 431.462751 -224.042393) (xy 431.411724 -224.024985)
			(xy 431.363776 -224.000333) (xy 431.319928 -223.968963) (xy 431.281115 -223.931542) (xy 431.248163 -223.888869)
			(xy 431.221777 -223.841852) (xy 431.202517 -223.791495) (xy 431.190794 -223.738871) (xy 431.186859 -223.6851)
			(xy 425.985178 -223.6851) (xy 425.985178 -224.534984) (xy 427.086791 -224.534984) (xy 427.090726 -224.481213)
			(xy 427.102449 -224.428589) (xy 427.121709 -224.378232) (xy 427.148095 -224.331215) (xy 427.181047 -224.288542)
			(xy 427.21986 -224.251121) (xy 427.263708 -224.219751) (xy 427.311656 -224.195099) (xy 427.362683 -224.177691)
			(xy 427.415701 -224.167898) (xy 427.46958 -224.165929) (xy 427.523171 -224.171826) (xy 427.575332 -224.185462)
			(xy 427.624952 -224.206549) (xy 427.670973 -224.234635) (xy 427.712415 -224.269123) (xy 427.748393 -224.309277)
			(xy 427.778141 -224.354241) (xy 427.801026 -224.403058) (xy 427.816558 -224.454687) (xy 427.824408 -224.508027)
			(xy 427.8249 -224.534984) (xy 434.630845 -224.534984) (xy 434.63478 -224.481213) (xy 434.646503 -224.428589)
			(xy 434.665763 -224.378232) (xy 434.692149 -224.331215) (xy 434.725101 -224.288542) (xy 434.763914 -224.251121)
			(xy 434.807762 -224.219751) (xy 434.85571 -224.195099) (xy 434.906737 -224.177691) (xy 434.959755 -224.167898)
			(xy 435.013634 -224.165929) (xy 435.067225 -224.171826) (xy 435.119386 -224.185462) (xy 435.169006 -224.206549)
			(xy 435.215027 -224.234635) (xy 435.256469 -224.269123) (xy 435.292447 -224.309277) (xy 435.322195 -224.354241)
			(xy 435.34508 -224.403058) (xy 435.360612 -224.454687) (xy 435.368462 -224.508027) (xy 435.368954 -224.534984)
			(xy 442.174899 -224.534984) (xy 442.178834 -224.481213) (xy 442.190557 -224.428589) (xy 442.209817 -224.378232)
			(xy 442.236203 -224.331215) (xy 442.269155 -224.288542) (xy 442.307968 -224.251121) (xy 442.351816 -224.219751)
			(xy 442.399764 -224.195099) (xy 442.450791 -224.177691) (xy 442.503809 -224.167898) (xy 442.557688 -224.165929)
			(xy 442.611279 -224.171826) (xy 442.66344 -224.185462) (xy 442.71306 -224.206549) (xy 442.759081 -224.234635)
			(xy 442.800523 -224.269123) (xy 442.836501 -224.309277) (xy 442.866249 -224.354241) (xy 442.889134 -224.403058)
			(xy 442.904666 -224.454687) (xy 442.912516 -224.508027) (xy 442.913008 -224.534984) (xy 449.718699 -224.534984)
			(xy 449.722634 -224.481213) (xy 449.734357 -224.428589) (xy 449.753617 -224.378232) (xy 449.780003 -224.331215)
			(xy 449.812955 -224.288542) (xy 449.851768 -224.251121) (xy 449.895616 -224.219751) (xy 449.943564 -224.195099)
			(xy 449.994591 -224.177691) (xy 450.047609 -224.167898) (xy 450.101488 -224.165929) (xy 450.155079 -224.171826)
			(xy 450.20724 -224.185462) (xy 450.25686 -224.206549) (xy 450.302881 -224.234635) (xy 450.344323 -224.269123)
			(xy 450.380301 -224.309277) (xy 450.410049 -224.354241) (xy 450.432934 -224.403058) (xy 450.448466 -224.454687)
			(xy 450.456316 -224.508027) (xy 450.456808 -224.534984) (xy 450.456316 -224.561941) (xy 450.448466 -224.615281)
			(xy 450.432934 -224.66691) (xy 450.410049 -224.715727) (xy 450.380301 -224.760691) (xy 450.344323 -224.800845)
			(xy 450.302881 -224.835333) (xy 450.25686 -224.863419) (xy 450.20724 -224.884506) (xy 450.155079 -224.898142)
			(xy 450.101488 -224.904039) (xy 450.047609 -224.90207) (xy 449.994591 -224.892277) (xy 449.943564 -224.874869)
			(xy 449.895616 -224.850217) (xy 449.851768 -224.818847) (xy 449.812955 -224.781426) (xy 449.780003 -224.738753)
			(xy 449.753617 -224.691736) (xy 449.734357 -224.641379) (xy 449.722634 -224.588755) (xy 449.718699 -224.534984)
			(xy 442.913008 -224.534984) (xy 442.912516 -224.561941) (xy 442.904666 -224.615281) (xy 442.889134 -224.66691)
			(xy 442.866249 -224.715727) (xy 442.836501 -224.760691) (xy 442.800523 -224.800845) (xy 442.759081 -224.835333)
			(xy 442.71306 -224.863419) (xy 442.66344 -224.884506) (xy 442.611279 -224.898142) (xy 442.557688 -224.904039)
			(xy 442.503809 -224.90207) (xy 442.450791 -224.892277) (xy 442.399764 -224.874869) (xy 442.351816 -224.850217)
			(xy 442.307968 -224.818847) (xy 442.269155 -224.781426) (xy 442.236203 -224.738753) (xy 442.209817 -224.691736)
			(xy 442.190557 -224.641379) (xy 442.178834 -224.588755) (xy 442.174899 -224.534984) (xy 435.368954 -224.534984)
			(xy 435.368462 -224.561941) (xy 435.360612 -224.615281) (xy 435.34508 -224.66691) (xy 435.322195 -224.715727)
			(xy 435.292447 -224.760691) (xy 435.256469 -224.800845) (xy 435.215027 -224.835333) (xy 435.169006 -224.863419)
			(xy 435.119386 -224.884506) (xy 435.067225 -224.898142) (xy 435.013634 -224.904039) (xy 434.959755 -224.90207)
			(xy 434.906737 -224.892277) (xy 434.85571 -224.874869) (xy 434.807762 -224.850217) (xy 434.763914 -224.818847)
			(xy 434.725101 -224.781426) (xy 434.692149 -224.738753) (xy 434.665763 -224.691736) (xy 434.646503 -224.641379)
			(xy 434.63478 -224.588755) (xy 434.630845 -224.534984) (xy 427.8249 -224.534984) (xy 427.824408 -224.561941)
			(xy 427.816558 -224.615281) (xy 427.801026 -224.66691) (xy 427.778141 -224.715727) (xy 427.748393 -224.760691)
			(xy 427.712415 -224.800845) (xy 427.670973 -224.835333) (xy 427.624952 -224.863419) (xy 427.575332 -224.884506)
			(xy 427.523171 -224.898142) (xy 427.46958 -224.904039) (xy 427.415701 -224.90207) (xy 427.362683 -224.892277)
			(xy 427.311656 -224.874869) (xy 427.263708 -224.850217) (xy 427.21986 -224.818847) (xy 427.181047 -224.781426)
			(xy 427.148095 -224.738753) (xy 427.121709 -224.691736) (xy 427.102449 -224.641379) (xy 427.090726 -224.588755)
			(xy 427.086791 -224.534984) (xy 425.985178 -224.534984) (xy 425.985178 -225.385122) (xy 431.186859 -225.385122)
			(xy 431.190794 -225.331351) (xy 431.202517 -225.278727) (xy 431.221777 -225.22837) (xy 431.248163 -225.181353)
			(xy 431.281115 -225.13868) (xy 431.319928 -225.101259) (xy 431.363776 -225.069889) (xy 431.411724 -225.045237)
			(xy 431.462751 -225.027829) (xy 431.515769 -225.018036) (xy 431.569648 -225.016067) (xy 431.623239 -225.021964)
			(xy 431.6754 -225.0356) (xy 431.72502 -225.056687) (xy 431.771041 -225.084773) (xy 431.812483 -225.119261)
			(xy 431.848461 -225.159415) (xy 431.878209 -225.204379) (xy 431.901094 -225.253196) (xy 431.916626 -225.304825)
			(xy 431.924476 -225.358165) (xy 431.924968 -225.385122) (xy 438.730913 -225.385122) (xy 438.734848 -225.331351)
			(xy 438.746571 -225.278727) (xy 438.765831 -225.22837) (xy 438.792217 -225.181353) (xy 438.825169 -225.13868)
			(xy 438.863982 -225.101259) (xy 438.90783 -225.069889) (xy 438.955778 -225.045237) (xy 439.006805 -225.027829)
			(xy 439.059823 -225.018036) (xy 439.113702 -225.016067) (xy 439.167293 -225.021964) (xy 439.219454 -225.0356)
			(xy 439.269074 -225.056687) (xy 439.315095 -225.084773) (xy 439.356537 -225.119261) (xy 439.392515 -225.159415)
			(xy 439.422263 -225.204379) (xy 439.445148 -225.253196) (xy 439.46068 -225.304825) (xy 439.46853 -225.358165)
			(xy 439.469022 -225.385122) (xy 446.274967 -225.385122) (xy 446.278902 -225.331351) (xy 446.290625 -225.278727)
			(xy 446.309885 -225.22837) (xy 446.336271 -225.181353) (xy 446.369223 -225.13868) (xy 446.408036 -225.101259)
			(xy 446.451884 -225.069889) (xy 446.499832 -225.045237) (xy 446.550859 -225.027829) (xy 446.603877 -225.018036)
			(xy 446.657756 -225.016067) (xy 446.711347 -225.021964) (xy 446.763508 -225.0356) (xy 446.813128 -225.056687)
			(xy 446.859149 -225.084773) (xy 446.900591 -225.119261) (xy 446.936569 -225.159415) (xy 446.966317 -225.204379)
			(xy 446.989202 -225.253196) (xy 447.004734 -225.304825) (xy 447.012584 -225.358165) (xy 447.013076 -225.385122)
			(xy 453.818767 -225.385122) (xy 453.822702 -225.331351) (xy 453.834425 -225.278727) (xy 453.853685 -225.22837)
			(xy 453.880071 -225.181353) (xy 453.913023 -225.13868) (xy 453.951836 -225.101259) (xy 453.995684 -225.069889)
			(xy 454.043632 -225.045237) (xy 454.094659 -225.027829) (xy 454.147677 -225.018036) (xy 454.201556 -225.016067)
			(xy 454.255147 -225.021964) (xy 454.307308 -225.0356) (xy 454.356928 -225.056687) (xy 454.402949 -225.084773)
			(xy 454.444391 -225.119261) (xy 454.480369 -225.159415) (xy 454.510117 -225.204379) (xy 454.533002 -225.253196)
			(xy 454.548534 -225.304825) (xy 454.556384 -225.358165) (xy 454.556876 -225.385122) (xy 454.556384 -225.412079)
			(xy 454.548534 -225.465419) (xy 454.533002 -225.517048) (xy 454.510117 -225.565865) (xy 454.480369 -225.610829)
			(xy 454.444391 -225.650983) (xy 454.402949 -225.685471) (xy 454.356928 -225.713557) (xy 454.307308 -225.734644)
			(xy 454.255147 -225.74828) (xy 454.201556 -225.754177) (xy 454.147677 -225.752208) (xy 454.094659 -225.742415)
			(xy 454.043632 -225.725007) (xy 453.995684 -225.700355) (xy 453.951836 -225.668985) (xy 453.913023 -225.631564)
			(xy 453.880071 -225.588891) (xy 453.853685 -225.541874) (xy 453.834425 -225.491517) (xy 453.822702 -225.438893)
			(xy 453.818767 -225.385122) (xy 447.013076 -225.385122) (xy 447.012584 -225.412079) (xy 447.004734 -225.465419)
			(xy 446.989202 -225.517048) (xy 446.966317 -225.565865) (xy 446.936569 -225.610829) (xy 446.900591 -225.650983)
			(xy 446.859149 -225.685471) (xy 446.813128 -225.713557) (xy 446.763508 -225.734644) (xy 446.711347 -225.74828)
			(xy 446.657756 -225.754177) (xy 446.603877 -225.752208) (xy 446.550859 -225.742415) (xy 446.499832 -225.725007)
			(xy 446.451884 -225.700355) (xy 446.408036 -225.668985) (xy 446.369223 -225.631564) (xy 446.336271 -225.588891)
			(xy 446.309885 -225.541874) (xy 446.290625 -225.491517) (xy 446.278902 -225.438893) (xy 446.274967 -225.385122)
			(xy 439.469022 -225.385122) (xy 439.46853 -225.412079) (xy 439.46068 -225.465419) (xy 439.445148 -225.517048)
			(xy 439.422263 -225.565865) (xy 439.392515 -225.610829) (xy 439.356537 -225.650983) (xy 439.315095 -225.685471)
			(xy 439.269074 -225.713557) (xy 439.219454 -225.734644) (xy 439.167293 -225.74828) (xy 439.113702 -225.754177)
			(xy 439.059823 -225.752208) (xy 439.006805 -225.742415) (xy 438.955778 -225.725007) (xy 438.90783 -225.700355)
			(xy 438.863982 -225.668985) (xy 438.825169 -225.631564) (xy 438.792217 -225.588891) (xy 438.765831 -225.541874)
			(xy 438.746571 -225.491517) (xy 438.734848 -225.438893) (xy 438.730913 -225.385122) (xy 431.924968 -225.385122)
			(xy 431.924476 -225.412079) (xy 431.916626 -225.465419) (xy 431.901094 -225.517048) (xy 431.878209 -225.565865)
			(xy 431.848461 -225.610829) (xy 431.812483 -225.650983) (xy 431.771041 -225.685471) (xy 431.72502 -225.713557)
			(xy 431.6754 -225.734644) (xy 431.623239 -225.74828) (xy 431.569648 -225.754177) (xy 431.515769 -225.752208)
			(xy 431.462751 -225.742415) (xy 431.411724 -225.725007) (xy 431.363776 -225.700355) (xy 431.319928 -225.668985)
			(xy 431.281115 -225.631564) (xy 431.248163 -225.588891) (xy 431.221777 -225.541874) (xy 431.202517 -225.491517)
			(xy 431.190794 -225.438893) (xy 431.186859 -225.385122) (xy 425.985178 -225.385122) (xy 425.985178 -226.235006)
			(xy 427.086791 -226.235006) (xy 427.090726 -226.181235) (xy 427.102449 -226.128611) (xy 427.121709 -226.078254)
			(xy 427.148095 -226.031237) (xy 427.181047 -225.988564) (xy 427.21986 -225.951143) (xy 427.263708 -225.919773)
			(xy 427.311656 -225.895121) (xy 427.362683 -225.877713) (xy 427.415701 -225.86792) (xy 427.46958 -225.865951)
			(xy 427.523171 -225.871848) (xy 427.575332 -225.885484) (xy 427.624952 -225.906571) (xy 427.670973 -225.934657)
			(xy 427.712415 -225.969145) (xy 427.748393 -226.009299) (xy 427.778141 -226.054263) (xy 427.801026 -226.10308)
			(xy 427.816558 -226.154709) (xy 427.824408 -226.208049) (xy 427.8249 -226.235006) (xy 434.630845 -226.235006)
			(xy 434.63478 -226.181235) (xy 434.646503 -226.128611) (xy 434.665763 -226.078254) (xy 434.692149 -226.031237)
			(xy 434.725101 -225.988564) (xy 434.763914 -225.951143) (xy 434.807762 -225.919773) (xy 434.85571 -225.895121)
			(xy 434.906737 -225.877713) (xy 434.959755 -225.86792) (xy 435.013634 -225.865951) (xy 435.067225 -225.871848)
			(xy 435.119386 -225.885484) (xy 435.169006 -225.906571) (xy 435.215027 -225.934657) (xy 435.256469 -225.969145)
			(xy 435.292447 -226.009299) (xy 435.322195 -226.054263) (xy 435.34508 -226.10308) (xy 435.360612 -226.154709)
			(xy 435.368462 -226.208049) (xy 435.368954 -226.235006) (xy 442.174899 -226.235006) (xy 442.178834 -226.181235)
			(xy 442.190557 -226.128611) (xy 442.209817 -226.078254) (xy 442.236203 -226.031237) (xy 442.269155 -225.988564)
			(xy 442.307968 -225.951143) (xy 442.351816 -225.919773) (xy 442.399764 -225.895121) (xy 442.450791 -225.877713)
			(xy 442.503809 -225.86792) (xy 442.557688 -225.865951) (xy 442.611279 -225.871848) (xy 442.66344 -225.885484)
			(xy 442.71306 -225.906571) (xy 442.759081 -225.934657) (xy 442.800523 -225.969145) (xy 442.836501 -226.009299)
			(xy 442.866249 -226.054263) (xy 442.889134 -226.10308) (xy 442.904666 -226.154709) (xy 442.912516 -226.208049)
			(xy 442.913008 -226.235006) (xy 449.718699 -226.235006) (xy 449.722634 -226.181235) (xy 449.734357 -226.128611)
			(xy 449.753617 -226.078254) (xy 449.780003 -226.031237) (xy 449.812955 -225.988564) (xy 449.851768 -225.951143)
			(xy 449.895616 -225.919773) (xy 449.943564 -225.895121) (xy 449.994591 -225.877713) (xy 450.047609 -225.86792)
			(xy 450.101488 -225.865951) (xy 450.155079 -225.871848) (xy 450.20724 -225.885484) (xy 450.25686 -225.906571)
			(xy 450.302881 -225.934657) (xy 450.344323 -225.969145) (xy 450.380301 -226.009299) (xy 450.410049 -226.054263)
			(xy 450.432934 -226.10308) (xy 450.448466 -226.154709) (xy 450.456316 -226.208049) (xy 450.456808 -226.235006)
			(xy 450.456316 -226.261963) (xy 450.448466 -226.315303) (xy 450.432934 -226.366932) (xy 450.410049 -226.415749)
			(xy 450.380301 -226.460713) (xy 450.344323 -226.500867) (xy 450.302881 -226.535355) (xy 450.25686 -226.563441)
			(xy 450.20724 -226.584528) (xy 450.155079 -226.598164) (xy 450.101488 -226.604061) (xy 450.047609 -226.602092)
			(xy 449.994591 -226.592299) (xy 449.943564 -226.574891) (xy 449.895616 -226.550239) (xy 449.851768 -226.518869)
			(xy 449.812955 -226.481448) (xy 449.780003 -226.438775) (xy 449.753617 -226.391758) (xy 449.734357 -226.341401)
			(xy 449.722634 -226.288777) (xy 449.718699 -226.235006) (xy 442.913008 -226.235006) (xy 442.912516 -226.261963)
			(xy 442.904666 -226.315303) (xy 442.889134 -226.366932) (xy 442.866249 -226.415749) (xy 442.836501 -226.460713)
			(xy 442.800523 -226.500867) (xy 442.759081 -226.535355) (xy 442.71306 -226.563441) (xy 442.66344 -226.584528)
			(xy 442.611279 -226.598164) (xy 442.557688 -226.604061) (xy 442.503809 -226.602092) (xy 442.450791 -226.592299)
			(xy 442.399764 -226.574891) (xy 442.351816 -226.550239) (xy 442.307968 -226.518869) (xy 442.269155 -226.481448)
			(xy 442.236203 -226.438775) (xy 442.209817 -226.391758) (xy 442.190557 -226.341401) (xy 442.178834 -226.288777)
			(xy 442.174899 -226.235006) (xy 435.368954 -226.235006) (xy 435.368462 -226.261963) (xy 435.360612 -226.315303)
			(xy 435.34508 -226.366932) (xy 435.322195 -226.415749) (xy 435.292447 -226.460713) (xy 435.256469 -226.500867)
			(xy 435.215027 -226.535355) (xy 435.169006 -226.563441) (xy 435.119386 -226.584528) (xy 435.067225 -226.598164)
			(xy 435.013634 -226.604061) (xy 434.959755 -226.602092) (xy 434.906737 -226.592299) (xy 434.85571 -226.574891)
			(xy 434.807762 -226.550239) (xy 434.763914 -226.518869) (xy 434.725101 -226.481448) (xy 434.692149 -226.438775)
			(xy 434.665763 -226.391758) (xy 434.646503 -226.341401) (xy 434.63478 -226.288777) (xy 434.630845 -226.235006)
			(xy 427.8249 -226.235006) (xy 427.824408 -226.261963) (xy 427.816558 -226.315303) (xy 427.801026 -226.366932)
			(xy 427.778141 -226.415749) (xy 427.748393 -226.460713) (xy 427.712415 -226.500867) (xy 427.670973 -226.535355)
			(xy 427.624952 -226.563441) (xy 427.575332 -226.584528) (xy 427.523171 -226.598164) (xy 427.46958 -226.604061)
			(xy 427.415701 -226.602092) (xy 427.362683 -226.592299) (xy 427.311656 -226.574891) (xy 427.263708 -226.550239)
			(xy 427.21986 -226.518869) (xy 427.181047 -226.481448) (xy 427.148095 -226.438775) (xy 427.121709 -226.391758)
			(xy 427.102449 -226.341401) (xy 427.090726 -226.288777) (xy 427.086791 -226.235006) (xy 425.985178 -226.235006)
			(xy 425.985178 -227.085144) (xy 431.186859 -227.085144) (xy 431.190794 -227.031373) (xy 431.202517 -226.978749)
			(xy 431.221777 -226.928392) (xy 431.248163 -226.881375) (xy 431.281115 -226.838702) (xy 431.319928 -226.801281)
			(xy 431.363776 -226.769911) (xy 431.411724 -226.745259) (xy 431.462751 -226.727851) (xy 431.515769 -226.718058)
			(xy 431.569648 -226.716089) (xy 431.623239 -226.721986) (xy 431.6754 -226.735622) (xy 431.72502 -226.756709)
			(xy 431.771041 -226.784795) (xy 431.812483 -226.819283) (xy 431.848461 -226.859437) (xy 431.878209 -226.904401)
			(xy 431.901094 -226.953218) (xy 431.916626 -227.004847) (xy 431.924476 -227.058187) (xy 431.924968 -227.085144)
			(xy 438.730913 -227.085144) (xy 438.734848 -227.031373) (xy 438.746571 -226.978749) (xy 438.765831 -226.928392)
			(xy 438.792217 -226.881375) (xy 438.825169 -226.838702) (xy 438.863982 -226.801281) (xy 438.90783 -226.769911)
			(xy 438.955778 -226.745259) (xy 439.006805 -226.727851) (xy 439.059823 -226.718058) (xy 439.113702 -226.716089)
			(xy 439.167293 -226.721986) (xy 439.219454 -226.735622) (xy 439.269074 -226.756709) (xy 439.315095 -226.784795)
			(xy 439.356537 -226.819283) (xy 439.392515 -226.859437) (xy 439.422263 -226.904401) (xy 439.445148 -226.953218)
			(xy 439.46068 -227.004847) (xy 439.46853 -227.058187) (xy 439.469022 -227.085144) (xy 446.274967 -227.085144)
			(xy 446.278902 -227.031373) (xy 446.290625 -226.978749) (xy 446.309885 -226.928392) (xy 446.336271 -226.881375)
			(xy 446.369223 -226.838702) (xy 446.408036 -226.801281) (xy 446.451884 -226.769911) (xy 446.499832 -226.745259)
			(xy 446.550859 -226.727851) (xy 446.603877 -226.718058) (xy 446.657756 -226.716089) (xy 446.711347 -226.721986)
			(xy 446.763508 -226.735622) (xy 446.813128 -226.756709) (xy 446.859149 -226.784795) (xy 446.900591 -226.819283)
			(xy 446.936569 -226.859437) (xy 446.966317 -226.904401) (xy 446.989202 -226.953218) (xy 447.004734 -227.004847)
			(xy 447.012584 -227.058187) (xy 447.013076 -227.085144) (xy 453.818767 -227.085144) (xy 453.822702 -227.031373)
			(xy 453.834425 -226.978749) (xy 453.853685 -226.928392) (xy 453.880071 -226.881375) (xy 453.913023 -226.838702)
			(xy 453.951836 -226.801281) (xy 453.995684 -226.769911) (xy 454.043632 -226.745259) (xy 454.094659 -226.727851)
			(xy 454.147677 -226.718058) (xy 454.201556 -226.716089) (xy 454.255147 -226.721986) (xy 454.307308 -226.735622)
			(xy 454.356928 -226.756709) (xy 454.402949 -226.784795) (xy 454.444391 -226.819283) (xy 454.480369 -226.859437)
			(xy 454.510117 -226.904401) (xy 454.533002 -226.953218) (xy 454.548534 -227.004847) (xy 454.556384 -227.058187)
			(xy 454.556876 -227.085144) (xy 454.556384 -227.112101) (xy 454.548534 -227.165441) (xy 454.533002 -227.21707)
			(xy 454.510117 -227.265887) (xy 454.480369 -227.310851) (xy 454.444391 -227.351005) (xy 454.402949 -227.385493)
			(xy 454.356928 -227.413579) (xy 454.307308 -227.434666) (xy 454.255147 -227.448302) (xy 454.201556 -227.454199)
			(xy 454.147677 -227.45223) (xy 454.094659 -227.442437) (xy 454.043632 -227.425029) (xy 453.995684 -227.400377)
			(xy 453.951836 -227.369007) (xy 453.913023 -227.331586) (xy 453.880071 -227.288913) (xy 453.853685 -227.241896)
			(xy 453.834425 -227.191539) (xy 453.822702 -227.138915) (xy 453.818767 -227.085144) (xy 447.013076 -227.085144)
			(xy 447.012584 -227.112101) (xy 447.004734 -227.165441) (xy 446.989202 -227.21707) (xy 446.966317 -227.265887)
			(xy 446.936569 -227.310851) (xy 446.900591 -227.351005) (xy 446.859149 -227.385493) (xy 446.813128 -227.413579)
			(xy 446.763508 -227.434666) (xy 446.711347 -227.448302) (xy 446.657756 -227.454199) (xy 446.603877 -227.45223)
			(xy 446.550859 -227.442437) (xy 446.499832 -227.425029) (xy 446.451884 -227.400377) (xy 446.408036 -227.369007)
			(xy 446.369223 -227.331586) (xy 446.336271 -227.288913) (xy 446.309885 -227.241896) (xy 446.290625 -227.191539)
			(xy 446.278902 -227.138915) (xy 446.274967 -227.085144) (xy 439.469022 -227.085144) (xy 439.46853 -227.112101)
			(xy 439.46068 -227.165441) (xy 439.445148 -227.21707) (xy 439.422263 -227.265887) (xy 439.392515 -227.310851)
			(xy 439.356537 -227.351005) (xy 439.315095 -227.385493) (xy 439.269074 -227.413579) (xy 439.219454 -227.434666)
			(xy 439.167293 -227.448302) (xy 439.113702 -227.454199) (xy 439.059823 -227.45223) (xy 439.006805 -227.442437)
			(xy 438.955778 -227.425029) (xy 438.90783 -227.400377) (xy 438.863982 -227.369007) (xy 438.825169 -227.331586)
			(xy 438.792217 -227.288913) (xy 438.765831 -227.241896) (xy 438.746571 -227.191539) (xy 438.734848 -227.138915)
			(xy 438.730913 -227.085144) (xy 431.924968 -227.085144) (xy 431.924476 -227.112101) (xy 431.916626 -227.165441)
			(xy 431.901094 -227.21707) (xy 431.878209 -227.265887) (xy 431.848461 -227.310851) (xy 431.812483 -227.351005)
			(xy 431.771041 -227.385493) (xy 431.72502 -227.413579) (xy 431.6754 -227.434666) (xy 431.623239 -227.448302)
			(xy 431.569648 -227.454199) (xy 431.515769 -227.45223) (xy 431.462751 -227.442437) (xy 431.411724 -227.425029)
			(xy 431.363776 -227.400377) (xy 431.319928 -227.369007) (xy 431.281115 -227.331586) (xy 431.248163 -227.288913)
			(xy 431.221777 -227.241896) (xy 431.202517 -227.191539) (xy 431.190794 -227.138915) (xy 431.186859 -227.085144)
			(xy 425.985178 -227.085144) (xy 425.985178 -227.935028) (xy 427.086791 -227.935028) (xy 427.090726 -227.881257)
			(xy 427.102449 -227.828633) (xy 427.121709 -227.778276) (xy 427.148095 -227.731259) (xy 427.181047 -227.688586)
			(xy 427.21986 -227.651165) (xy 427.263708 -227.619795) (xy 427.311656 -227.595143) (xy 427.362683 -227.577735)
			(xy 427.415701 -227.567942) (xy 427.46958 -227.565973) (xy 427.523171 -227.57187) (xy 427.575332 -227.585506)
			(xy 427.624952 -227.606593) (xy 427.670973 -227.634679) (xy 427.712415 -227.669167) (xy 427.748393 -227.709321)
			(xy 427.778141 -227.754285) (xy 427.801026 -227.803102) (xy 427.816558 -227.854731) (xy 427.824408 -227.908071)
			(xy 427.8249 -227.935028) (xy 434.630845 -227.935028) (xy 434.63478 -227.881257) (xy 434.646503 -227.828633)
			(xy 434.665763 -227.778276) (xy 434.692149 -227.731259) (xy 434.725101 -227.688586) (xy 434.763914 -227.651165)
			(xy 434.807762 -227.619795) (xy 434.85571 -227.595143) (xy 434.906737 -227.577735) (xy 434.959755 -227.567942)
			(xy 435.013634 -227.565973) (xy 435.067225 -227.57187) (xy 435.119386 -227.585506) (xy 435.169006 -227.606593)
			(xy 435.215027 -227.634679) (xy 435.256469 -227.669167) (xy 435.292447 -227.709321) (xy 435.322195 -227.754285)
			(xy 435.34508 -227.803102) (xy 435.360612 -227.854731) (xy 435.368462 -227.908071) (xy 435.368954 -227.935028)
			(xy 442.174899 -227.935028) (xy 442.178834 -227.881257) (xy 442.190557 -227.828633) (xy 442.209817 -227.778276)
			(xy 442.236203 -227.731259) (xy 442.269155 -227.688586) (xy 442.307968 -227.651165) (xy 442.351816 -227.619795)
			(xy 442.399764 -227.595143) (xy 442.450791 -227.577735) (xy 442.503809 -227.567942) (xy 442.557688 -227.565973)
			(xy 442.611279 -227.57187) (xy 442.66344 -227.585506) (xy 442.71306 -227.606593) (xy 442.759081 -227.634679)
			(xy 442.800523 -227.669167) (xy 442.836501 -227.709321) (xy 442.866249 -227.754285) (xy 442.889134 -227.803102)
			(xy 442.904666 -227.854731) (xy 442.912516 -227.908071) (xy 442.913008 -227.935028) (xy 449.718699 -227.935028)
			(xy 449.722634 -227.881257) (xy 449.734357 -227.828633) (xy 449.753617 -227.778276) (xy 449.780003 -227.731259)
			(xy 449.812955 -227.688586) (xy 449.851768 -227.651165) (xy 449.895616 -227.619795) (xy 449.943564 -227.595143)
			(xy 449.994591 -227.577735) (xy 450.047609 -227.567942) (xy 450.101488 -227.565973) (xy 450.155079 -227.57187)
			(xy 450.20724 -227.585506) (xy 450.25686 -227.606593) (xy 450.302881 -227.634679) (xy 450.344323 -227.669167)
			(xy 450.380301 -227.709321) (xy 450.410049 -227.754285) (xy 450.432934 -227.803102) (xy 450.448466 -227.854731)
			(xy 450.456316 -227.908071) (xy 450.456808 -227.935028) (xy 450.456316 -227.961985) (xy 450.448466 -228.015325)
			(xy 450.432934 -228.066954) (xy 450.410049 -228.115771) (xy 450.380301 -228.160735) (xy 450.344323 -228.200889)
			(xy 450.302881 -228.235377) (xy 450.25686 -228.263463) (xy 450.20724 -228.28455) (xy 450.155079 -228.298186)
			(xy 450.101488 -228.304083) (xy 450.047609 -228.302114) (xy 449.994591 -228.292321) (xy 449.943564 -228.274913)
			(xy 449.895616 -228.250261) (xy 449.851768 -228.218891) (xy 449.812955 -228.18147) (xy 449.780003 -228.138797)
			(xy 449.753617 -228.09178) (xy 449.734357 -228.041423) (xy 449.722634 -227.988799) (xy 449.718699 -227.935028)
			(xy 442.913008 -227.935028) (xy 442.912516 -227.961985) (xy 442.904666 -228.015325) (xy 442.889134 -228.066954)
			(xy 442.866249 -228.115771) (xy 442.836501 -228.160735) (xy 442.800523 -228.200889) (xy 442.759081 -228.235377)
			(xy 442.71306 -228.263463) (xy 442.66344 -228.28455) (xy 442.611279 -228.298186) (xy 442.557688 -228.304083)
			(xy 442.503809 -228.302114) (xy 442.450791 -228.292321) (xy 442.399764 -228.274913) (xy 442.351816 -228.250261)
			(xy 442.307968 -228.218891) (xy 442.269155 -228.18147) (xy 442.236203 -228.138797) (xy 442.209817 -228.09178)
			(xy 442.190557 -228.041423) (xy 442.178834 -227.988799) (xy 442.174899 -227.935028) (xy 435.368954 -227.935028)
			(xy 435.368462 -227.961985) (xy 435.360612 -228.015325) (xy 435.34508 -228.066954) (xy 435.322195 -228.115771)
			(xy 435.292447 -228.160735) (xy 435.256469 -228.200889) (xy 435.215027 -228.235377) (xy 435.169006 -228.263463)
			(xy 435.119386 -228.28455) (xy 435.067225 -228.298186) (xy 435.013634 -228.304083) (xy 434.959755 -228.302114)
			(xy 434.906737 -228.292321) (xy 434.85571 -228.274913) (xy 434.807762 -228.250261) (xy 434.763914 -228.218891)
			(xy 434.725101 -228.18147) (xy 434.692149 -228.138797) (xy 434.665763 -228.09178) (xy 434.646503 -228.041423)
			(xy 434.63478 -227.988799) (xy 434.630845 -227.935028) (xy 427.8249 -227.935028) (xy 427.824408 -227.961985)
			(xy 427.816558 -228.015325) (xy 427.801026 -228.066954) (xy 427.778141 -228.115771) (xy 427.748393 -228.160735)
			(xy 427.712415 -228.200889) (xy 427.670973 -228.235377) (xy 427.624952 -228.263463) (xy 427.575332 -228.28455)
			(xy 427.523171 -228.298186) (xy 427.46958 -228.304083) (xy 427.415701 -228.302114) (xy 427.362683 -228.292321)
			(xy 427.311656 -228.274913) (xy 427.263708 -228.250261) (xy 427.21986 -228.218891) (xy 427.181047 -228.18147)
			(xy 427.148095 -228.138797) (xy 427.121709 -228.09178) (xy 427.102449 -228.041423) (xy 427.090726 -227.988799)
			(xy 427.086791 -227.935028) (xy 425.985178 -227.935028) (xy 425.985178 -228.785166) (xy 431.186859 -228.785166)
			(xy 431.190794 -228.731395) (xy 431.202517 -228.678771) (xy 431.221777 -228.628414) (xy 431.248163 -228.581397)
			(xy 431.281115 -228.538724) (xy 431.319928 -228.501303) (xy 431.363776 -228.469933) (xy 431.411724 -228.445281)
			(xy 431.462751 -228.427873) (xy 431.515769 -228.41808) (xy 431.569648 -228.416111) (xy 431.623239 -228.422008)
			(xy 431.6754 -228.435644) (xy 431.72502 -228.456731) (xy 431.771041 -228.484817) (xy 431.812483 -228.519305)
			(xy 431.848461 -228.559459) (xy 431.878209 -228.604423) (xy 431.901094 -228.65324) (xy 431.916626 -228.704869)
			(xy 431.924476 -228.758209) (xy 431.924968 -228.785166) (xy 438.730913 -228.785166) (xy 438.734848 -228.731395)
			(xy 438.746571 -228.678771) (xy 438.765831 -228.628414) (xy 438.792217 -228.581397) (xy 438.825169 -228.538724)
			(xy 438.863982 -228.501303) (xy 438.90783 -228.469933) (xy 438.955778 -228.445281) (xy 439.006805 -228.427873)
			(xy 439.059823 -228.41808) (xy 439.113702 -228.416111) (xy 439.167293 -228.422008) (xy 439.219454 -228.435644)
			(xy 439.269074 -228.456731) (xy 439.315095 -228.484817) (xy 439.356537 -228.519305) (xy 439.392515 -228.559459)
			(xy 439.422263 -228.604423) (xy 439.445148 -228.65324) (xy 439.46068 -228.704869) (xy 439.46853 -228.758209)
			(xy 439.469022 -228.785166) (xy 446.274967 -228.785166) (xy 446.278902 -228.731395) (xy 446.290625 -228.678771)
			(xy 446.309885 -228.628414) (xy 446.336271 -228.581397) (xy 446.369223 -228.538724) (xy 446.408036 -228.501303)
			(xy 446.451884 -228.469933) (xy 446.499832 -228.445281) (xy 446.550859 -228.427873) (xy 446.603877 -228.41808)
			(xy 446.657756 -228.416111) (xy 446.711347 -228.422008) (xy 446.763508 -228.435644) (xy 446.813128 -228.456731)
			(xy 446.859149 -228.484817) (xy 446.900591 -228.519305) (xy 446.936569 -228.559459) (xy 446.966317 -228.604423)
			(xy 446.989202 -228.65324) (xy 447.004734 -228.704869) (xy 447.012584 -228.758209) (xy 447.013076 -228.785166)
			(xy 453.818767 -228.785166) (xy 453.822702 -228.731395) (xy 453.834425 -228.678771) (xy 453.853685 -228.628414)
			(xy 453.880071 -228.581397) (xy 453.913023 -228.538724) (xy 453.951836 -228.501303) (xy 453.995684 -228.469933)
			(xy 454.043632 -228.445281) (xy 454.094659 -228.427873) (xy 454.147677 -228.41808) (xy 454.201556 -228.416111)
			(xy 454.255147 -228.422008) (xy 454.307308 -228.435644) (xy 454.356928 -228.456731) (xy 454.402949 -228.484817)
			(xy 454.444391 -228.519305) (xy 454.480369 -228.559459) (xy 454.510117 -228.604423) (xy 454.533002 -228.65324)
			(xy 454.548534 -228.704869) (xy 454.556384 -228.758209) (xy 454.556876 -228.785166) (xy 454.556384 -228.812123)
			(xy 454.548534 -228.865463) (xy 454.533002 -228.917092) (xy 454.510117 -228.965909) (xy 454.480369 -229.010873)
			(xy 454.444391 -229.051027) (xy 454.402949 -229.085515) (xy 454.356928 -229.113601) (xy 454.307308 -229.134688)
			(xy 454.255147 -229.148324) (xy 454.201556 -229.154221) (xy 454.147677 -229.152252) (xy 454.094659 -229.142459)
			(xy 454.043632 -229.125051) (xy 453.995684 -229.100399) (xy 453.951836 -229.069029) (xy 453.913023 -229.031608)
			(xy 453.880071 -228.988935) (xy 453.853685 -228.941918) (xy 453.834425 -228.891561) (xy 453.822702 -228.838937)
			(xy 453.818767 -228.785166) (xy 447.013076 -228.785166) (xy 447.012584 -228.812123) (xy 447.004734 -228.865463)
			(xy 446.989202 -228.917092) (xy 446.966317 -228.965909) (xy 446.936569 -229.010873) (xy 446.900591 -229.051027)
			(xy 446.859149 -229.085515) (xy 446.813128 -229.113601) (xy 446.763508 -229.134688) (xy 446.711347 -229.148324)
			(xy 446.657756 -229.154221) (xy 446.603877 -229.152252) (xy 446.550859 -229.142459) (xy 446.499832 -229.125051)
			(xy 446.451884 -229.100399) (xy 446.408036 -229.069029) (xy 446.369223 -229.031608) (xy 446.336271 -228.988935)
			(xy 446.309885 -228.941918) (xy 446.290625 -228.891561) (xy 446.278902 -228.838937) (xy 446.274967 -228.785166)
			(xy 439.469022 -228.785166) (xy 439.46853 -228.812123) (xy 439.46068 -228.865463) (xy 439.445148 -228.917092)
			(xy 439.422263 -228.965909) (xy 439.392515 -229.010873) (xy 439.356537 -229.051027) (xy 439.315095 -229.085515)
			(xy 439.269074 -229.113601) (xy 439.219454 -229.134688) (xy 439.167293 -229.148324) (xy 439.113702 -229.154221)
			(xy 439.059823 -229.152252) (xy 439.006805 -229.142459) (xy 438.955778 -229.125051) (xy 438.90783 -229.100399)
			(xy 438.863982 -229.069029) (xy 438.825169 -229.031608) (xy 438.792217 -228.988935) (xy 438.765831 -228.941918)
			(xy 438.746571 -228.891561) (xy 438.734848 -228.838937) (xy 438.730913 -228.785166) (xy 431.924968 -228.785166)
			(xy 431.924476 -228.812123) (xy 431.916626 -228.865463) (xy 431.901094 -228.917092) (xy 431.878209 -228.965909)
			(xy 431.848461 -229.010873) (xy 431.812483 -229.051027) (xy 431.771041 -229.085515) (xy 431.72502 -229.113601)
			(xy 431.6754 -229.134688) (xy 431.623239 -229.148324) (xy 431.569648 -229.154221) (xy 431.515769 -229.152252)
			(xy 431.462751 -229.142459) (xy 431.411724 -229.125051) (xy 431.363776 -229.100399) (xy 431.319928 -229.069029)
			(xy 431.281115 -229.031608) (xy 431.248163 -228.988935) (xy 431.221777 -228.941918) (xy 431.202517 -228.891561)
			(xy 431.190794 -228.838937) (xy 431.186859 -228.785166) (xy 425.985178 -228.785166) (xy 425.985178 -229.63505)
			(xy 427.086791 -229.63505) (xy 427.090726 -229.581279) (xy 427.102449 -229.528655) (xy 427.121709 -229.478298)
			(xy 427.148095 -229.431281) (xy 427.181047 -229.388608) (xy 427.21986 -229.351187) (xy 427.263708 -229.319817)
			(xy 427.311656 -229.295165) (xy 427.362683 -229.277757) (xy 427.415701 -229.267964) (xy 427.46958 -229.265995)
			(xy 427.523171 -229.271892) (xy 427.575332 -229.285528) (xy 427.624952 -229.306615) (xy 427.670973 -229.334701)
			(xy 427.712415 -229.369189) (xy 427.748393 -229.409343) (xy 427.778141 -229.454307) (xy 427.801026 -229.503124)
			(xy 427.816558 -229.554753) (xy 427.824408 -229.608093) (xy 427.8249 -229.63505) (xy 431.186859 -229.63505)
			(xy 431.190794 -229.581279) (xy 431.202517 -229.528655) (xy 431.221777 -229.478298) (xy 431.248163 -229.431281)
			(xy 431.281115 -229.388608) (xy 431.319928 -229.351187) (xy 431.363776 -229.319817) (xy 431.411724 -229.295165)
			(xy 431.462751 -229.277757) (xy 431.515769 -229.267964) (xy 431.569648 -229.265995) (xy 431.623239 -229.271892)
			(xy 431.6754 -229.285528) (xy 431.72502 -229.306615) (xy 431.771041 -229.334701) (xy 431.812483 -229.369189)
			(xy 431.848461 -229.409343) (xy 431.878209 -229.454307) (xy 431.901094 -229.503124) (xy 431.916626 -229.554753)
			(xy 431.924476 -229.608093) (xy 431.924968 -229.63505) (xy 434.630845 -229.63505) (xy 434.63478 -229.581279)
			(xy 434.646503 -229.528655) (xy 434.665763 -229.478298) (xy 434.692149 -229.431281) (xy 434.725101 -229.388608)
			(xy 434.763914 -229.351187) (xy 434.807762 -229.319817) (xy 434.85571 -229.295165) (xy 434.906737 -229.277757)
			(xy 434.959755 -229.267964) (xy 435.013634 -229.265995) (xy 435.067225 -229.271892) (xy 435.119386 -229.285528)
			(xy 435.169006 -229.306615) (xy 435.215027 -229.334701) (xy 435.256469 -229.369189) (xy 435.292447 -229.409343)
			(xy 435.322195 -229.454307) (xy 435.34508 -229.503124) (xy 435.360612 -229.554753) (xy 435.368462 -229.608093)
			(xy 435.368954 -229.63505) (xy 438.730913 -229.63505) (xy 438.734848 -229.581279) (xy 438.746571 -229.528655)
			(xy 438.765831 -229.478298) (xy 438.792217 -229.431281) (xy 438.825169 -229.388608) (xy 438.863982 -229.351187)
			(xy 438.90783 -229.319817) (xy 438.955778 -229.295165) (xy 439.006805 -229.277757) (xy 439.059823 -229.267964)
			(xy 439.113702 -229.265995) (xy 439.167293 -229.271892) (xy 439.219454 -229.285528) (xy 439.269074 -229.306615)
			(xy 439.315095 -229.334701) (xy 439.356537 -229.369189) (xy 439.392515 -229.409343) (xy 439.422263 -229.454307)
			(xy 439.445148 -229.503124) (xy 439.46068 -229.554753) (xy 439.46853 -229.608093) (xy 439.469022 -229.63505)
			(xy 442.174899 -229.63505) (xy 442.178834 -229.581279) (xy 442.190557 -229.528655) (xy 442.209817 -229.478298)
			(xy 442.236203 -229.431281) (xy 442.269155 -229.388608) (xy 442.307968 -229.351187) (xy 442.351816 -229.319817)
			(xy 442.399764 -229.295165) (xy 442.450791 -229.277757) (xy 442.503809 -229.267964) (xy 442.557688 -229.265995)
			(xy 442.611279 -229.271892) (xy 442.66344 -229.285528) (xy 442.71306 -229.306615) (xy 442.759081 -229.334701)
			(xy 442.800523 -229.369189) (xy 442.836501 -229.409343) (xy 442.866249 -229.454307) (xy 442.889134 -229.503124)
			(xy 442.904666 -229.554753) (xy 442.912516 -229.608093) (xy 442.913008 -229.63505) (xy 446.274967 -229.63505)
			(xy 446.278902 -229.581279) (xy 446.290625 -229.528655) (xy 446.309885 -229.478298) (xy 446.336271 -229.431281)
			(xy 446.369223 -229.388608) (xy 446.408036 -229.351187) (xy 446.451884 -229.319817) (xy 446.499832 -229.295165)
			(xy 446.550859 -229.277757) (xy 446.603877 -229.267964) (xy 446.657756 -229.265995) (xy 446.711347 -229.271892)
			(xy 446.763508 -229.285528) (xy 446.813128 -229.306615) (xy 446.859149 -229.334701) (xy 446.900591 -229.369189)
			(xy 446.936569 -229.409343) (xy 446.966317 -229.454307) (xy 446.989202 -229.503124) (xy 447.004734 -229.554753)
			(xy 447.012584 -229.608093) (xy 447.013076 -229.63505) (xy 449.718699 -229.63505) (xy 449.722634 -229.581279)
			(xy 449.734357 -229.528655) (xy 449.753617 -229.478298) (xy 449.780003 -229.431281) (xy 449.812955 -229.388608)
			(xy 449.851768 -229.351187) (xy 449.895616 -229.319817) (xy 449.943564 -229.295165) (xy 449.994591 -229.277757)
			(xy 450.047609 -229.267964) (xy 450.101488 -229.265995) (xy 450.155079 -229.271892) (xy 450.20724 -229.285528)
			(xy 450.25686 -229.306615) (xy 450.302881 -229.334701) (xy 450.344323 -229.369189) (xy 450.380301 -229.409343)
			(xy 450.410049 -229.454307) (xy 450.432934 -229.503124) (xy 450.448466 -229.554753) (xy 450.456316 -229.608093)
			(xy 450.456808 -229.63505) (xy 453.818767 -229.63505) (xy 453.822702 -229.581279) (xy 453.834425 -229.528655)
			(xy 453.853685 -229.478298) (xy 453.880071 -229.431281) (xy 453.913023 -229.388608) (xy 453.951836 -229.351187)
			(xy 453.995684 -229.319817) (xy 454.043632 -229.295165) (xy 454.094659 -229.277757) (xy 454.147677 -229.267964)
			(xy 454.201556 -229.265995) (xy 454.255147 -229.271892) (xy 454.307308 -229.285528) (xy 454.356928 -229.306615)
			(xy 454.402949 -229.334701) (xy 454.444391 -229.369189) (xy 454.480369 -229.409343) (xy 454.510117 -229.454307)
			(xy 454.533002 -229.503124) (xy 454.548534 -229.554753) (xy 454.556384 -229.608093) (xy 454.556876 -229.63505)
			(xy 454.556384 -229.662007) (xy 454.548534 -229.715347) (xy 454.533002 -229.766976) (xy 454.510117 -229.815793)
			(xy 454.480369 -229.860757) (xy 454.444391 -229.900911) (xy 454.402949 -229.935399) (xy 454.356928 -229.963485)
			(xy 454.307308 -229.984572) (xy 454.255147 -229.998208) (xy 454.201556 -230.004105) (xy 454.147677 -230.002136)
			(xy 454.094659 -229.992343) (xy 454.043632 -229.974935) (xy 453.995684 -229.950283) (xy 453.951836 -229.918913)
			(xy 453.913023 -229.881492) (xy 453.880071 -229.838819) (xy 453.853685 -229.791802) (xy 453.834425 -229.741445)
			(xy 453.822702 -229.688821) (xy 453.818767 -229.63505) (xy 450.456808 -229.63505) (xy 450.456316 -229.662007)
			(xy 450.448466 -229.715347) (xy 450.432934 -229.766976) (xy 450.410049 -229.815793) (xy 450.380301 -229.860757)
			(xy 450.344323 -229.900911) (xy 450.302881 -229.935399) (xy 450.25686 -229.963485) (xy 450.20724 -229.984572)
			(xy 450.155079 -229.998208) (xy 450.101488 -230.004105) (xy 450.047609 -230.002136) (xy 449.994591 -229.992343)
			(xy 449.943564 -229.974935) (xy 449.895616 -229.950283) (xy 449.851768 -229.918913) (xy 449.812955 -229.881492)
			(xy 449.780003 -229.838819) (xy 449.753617 -229.791802) (xy 449.734357 -229.741445) (xy 449.722634 -229.688821)
			(xy 449.718699 -229.63505) (xy 447.013076 -229.63505) (xy 447.012584 -229.662007) (xy 447.004734 -229.715347)
			(xy 446.989202 -229.766976) (xy 446.966317 -229.815793) (xy 446.936569 -229.860757) (xy 446.900591 -229.900911)
			(xy 446.859149 -229.935399) (xy 446.813128 -229.963485) (xy 446.763508 -229.984572) (xy 446.711347 -229.998208)
			(xy 446.657756 -230.004105) (xy 446.603877 -230.002136) (xy 446.550859 -229.992343) (xy 446.499832 -229.974935)
			(xy 446.451884 -229.950283) (xy 446.408036 -229.918913) (xy 446.369223 -229.881492) (xy 446.336271 -229.838819)
			(xy 446.309885 -229.791802) (xy 446.290625 -229.741445) (xy 446.278902 -229.688821) (xy 446.274967 -229.63505)
			(xy 442.913008 -229.63505) (xy 442.912516 -229.662007) (xy 442.904666 -229.715347) (xy 442.889134 -229.766976)
			(xy 442.866249 -229.815793) (xy 442.836501 -229.860757) (xy 442.800523 -229.900911) (xy 442.759081 -229.935399)
			(xy 442.71306 -229.963485) (xy 442.66344 -229.984572) (xy 442.611279 -229.998208) (xy 442.557688 -230.004105)
			(xy 442.503809 -230.002136) (xy 442.450791 -229.992343) (xy 442.399764 -229.974935) (xy 442.351816 -229.950283)
			(xy 442.307968 -229.918913) (xy 442.269155 -229.881492) (xy 442.236203 -229.838819) (xy 442.209817 -229.791802)
			(xy 442.190557 -229.741445) (xy 442.178834 -229.688821) (xy 442.174899 -229.63505) (xy 439.469022 -229.63505)
			(xy 439.46853 -229.662007) (xy 439.46068 -229.715347) (xy 439.445148 -229.766976) (xy 439.422263 -229.815793)
			(xy 439.392515 -229.860757) (xy 439.356537 -229.900911) (xy 439.315095 -229.935399) (xy 439.269074 -229.963485)
			(xy 439.219454 -229.984572) (xy 439.167293 -229.998208) (xy 439.113702 -230.004105) (xy 439.059823 -230.002136)
			(xy 439.006805 -229.992343) (xy 438.955778 -229.974935) (xy 438.90783 -229.950283) (xy 438.863982 -229.918913)
			(xy 438.825169 -229.881492) (xy 438.792217 -229.838819) (xy 438.765831 -229.791802) (xy 438.746571 -229.741445)
			(xy 438.734848 -229.688821) (xy 438.730913 -229.63505) (xy 435.368954 -229.63505) (xy 435.368462 -229.662007)
			(xy 435.360612 -229.715347) (xy 435.34508 -229.766976) (xy 435.322195 -229.815793) (xy 435.292447 -229.860757)
			(xy 435.256469 -229.900911) (xy 435.215027 -229.935399) (xy 435.169006 -229.963485) (xy 435.119386 -229.984572)
			(xy 435.067225 -229.998208) (xy 435.013634 -230.004105) (xy 434.959755 -230.002136) (xy 434.906737 -229.992343)
			(xy 434.85571 -229.974935) (xy 434.807762 -229.950283) (xy 434.763914 -229.918913) (xy 434.725101 -229.881492)
			(xy 434.692149 -229.838819) (xy 434.665763 -229.791802) (xy 434.646503 -229.741445) (xy 434.63478 -229.688821)
			(xy 434.630845 -229.63505) (xy 431.924968 -229.63505) (xy 431.924476 -229.662007) (xy 431.916626 -229.715347)
			(xy 431.901094 -229.766976) (xy 431.878209 -229.815793) (xy 431.848461 -229.860757) (xy 431.812483 -229.900911)
			(xy 431.771041 -229.935399) (xy 431.72502 -229.963485) (xy 431.6754 -229.984572) (xy 431.623239 -229.998208)
			(xy 431.569648 -230.004105) (xy 431.515769 -230.002136) (xy 431.462751 -229.992343) (xy 431.411724 -229.974935)
			(xy 431.363776 -229.950283) (xy 431.319928 -229.918913) (xy 431.281115 -229.881492) (xy 431.248163 -229.838819)
			(xy 431.221777 -229.791802) (xy 431.202517 -229.741445) (xy 431.190794 -229.688821) (xy 431.186859 -229.63505)
			(xy 427.8249 -229.63505) (xy 427.824408 -229.662007) (xy 427.816558 -229.715347) (xy 427.801026 -229.766976)
			(xy 427.778141 -229.815793) (xy 427.748393 -229.860757) (xy 427.712415 -229.900911) (xy 427.670973 -229.935399)
			(xy 427.624952 -229.963485) (xy 427.575332 -229.984572) (xy 427.523171 -229.998208) (xy 427.46958 -230.004105)
			(xy 427.415701 -230.002136) (xy 427.362683 -229.992343) (xy 427.311656 -229.974935) (xy 427.263708 -229.950283)
			(xy 427.21986 -229.918913) (xy 427.181047 -229.881492) (xy 427.148095 -229.838819) (xy 427.121709 -229.791802)
			(xy 427.102449 -229.741445) (xy 427.090726 -229.688821) (xy 427.086791 -229.63505) (xy 425.985178 -229.63505)
			(xy 425.985178 -230.485188) (xy 427.086791 -230.485188) (xy 427.090726 -230.431417) (xy 427.102449 -230.378793)
			(xy 427.121709 -230.328436) (xy 427.148095 -230.281419) (xy 427.181047 -230.238746) (xy 427.21986 -230.201325)
			(xy 427.263708 -230.169955) (xy 427.311656 -230.145303) (xy 427.362683 -230.127895) (xy 427.415701 -230.118102)
			(xy 427.46958 -230.116133) (xy 427.523171 -230.12203) (xy 427.575332 -230.135666) (xy 427.624952 -230.156753)
			(xy 427.670973 -230.184839) (xy 427.712415 -230.219327) (xy 427.748393 -230.259481) (xy 427.778141 -230.304445)
			(xy 427.801026 -230.353262) (xy 427.816558 -230.404891) (xy 427.824408 -230.458231) (xy 427.8249 -230.485188)
			(xy 434.630845 -230.485188) (xy 434.63478 -230.431417) (xy 434.646503 -230.378793) (xy 434.665763 -230.328436)
			(xy 434.692149 -230.281419) (xy 434.725101 -230.238746) (xy 434.763914 -230.201325) (xy 434.807762 -230.169955)
			(xy 434.85571 -230.145303) (xy 434.906737 -230.127895) (xy 434.959755 -230.118102) (xy 435.013634 -230.116133)
			(xy 435.067225 -230.12203) (xy 435.119386 -230.135666) (xy 435.169006 -230.156753) (xy 435.215027 -230.184839)
			(xy 435.256469 -230.219327) (xy 435.292447 -230.259481) (xy 435.322195 -230.304445) (xy 435.34508 -230.353262)
			(xy 435.360612 -230.404891) (xy 435.368462 -230.458231) (xy 435.368954 -230.485188) (xy 442.174899 -230.485188)
			(xy 442.178834 -230.431417) (xy 442.190557 -230.378793) (xy 442.209817 -230.328436) (xy 442.236203 -230.281419)
			(xy 442.269155 -230.238746) (xy 442.307968 -230.201325) (xy 442.351816 -230.169955) (xy 442.399764 -230.145303)
			(xy 442.450791 -230.127895) (xy 442.503809 -230.118102) (xy 442.557688 -230.116133) (xy 442.611279 -230.12203)
			(xy 442.66344 -230.135666) (xy 442.71306 -230.156753) (xy 442.759081 -230.184839) (xy 442.800523 -230.219327)
			(xy 442.836501 -230.259481) (xy 442.866249 -230.304445) (xy 442.889134 -230.353262) (xy 442.904666 -230.404891)
			(xy 442.912516 -230.458231) (xy 442.913008 -230.485188) (xy 449.718699 -230.485188) (xy 449.722634 -230.431417)
			(xy 449.734357 -230.378793) (xy 449.753617 -230.328436) (xy 449.780003 -230.281419) (xy 449.812955 -230.238746)
			(xy 449.851768 -230.201325) (xy 449.895616 -230.169955) (xy 449.943564 -230.145303) (xy 449.994591 -230.127895)
			(xy 450.047609 -230.118102) (xy 450.101488 -230.116133) (xy 450.155079 -230.12203) (xy 450.20724 -230.135666)
			(xy 450.25686 -230.156753) (xy 450.302881 -230.184839) (xy 450.344323 -230.219327) (xy 450.380301 -230.259481)
			(xy 450.410049 -230.304445) (xy 450.432934 -230.353262) (xy 450.448466 -230.404891) (xy 450.456316 -230.458231)
			(xy 450.456808 -230.485188) (xy 450.456316 -230.512145) (xy 450.448466 -230.565485) (xy 450.432934 -230.617114)
			(xy 450.410049 -230.665931) (xy 450.380301 -230.710895) (xy 450.344323 -230.751049) (xy 450.302881 -230.785537)
			(xy 450.25686 -230.813623) (xy 450.20724 -230.83471) (xy 450.155079 -230.848346) (xy 450.101488 -230.854243)
			(xy 450.047609 -230.852274) (xy 449.994591 -230.842481) (xy 449.943564 -230.825073) (xy 449.895616 -230.800421)
			(xy 449.851768 -230.769051) (xy 449.812955 -230.73163) (xy 449.780003 -230.688957) (xy 449.753617 -230.64194)
			(xy 449.734357 -230.591583) (xy 449.722634 -230.538959) (xy 449.718699 -230.485188) (xy 442.913008 -230.485188)
			(xy 442.912516 -230.512145) (xy 442.904666 -230.565485) (xy 442.889134 -230.617114) (xy 442.866249 -230.665931)
			(xy 442.836501 -230.710895) (xy 442.800523 -230.751049) (xy 442.759081 -230.785537) (xy 442.71306 -230.813623)
			(xy 442.66344 -230.83471) (xy 442.611279 -230.848346) (xy 442.557688 -230.854243) (xy 442.503809 -230.852274)
			(xy 442.450791 -230.842481) (xy 442.399764 -230.825073) (xy 442.351816 -230.800421) (xy 442.307968 -230.769051)
			(xy 442.269155 -230.73163) (xy 442.236203 -230.688957) (xy 442.209817 -230.64194) (xy 442.190557 -230.591583)
			(xy 442.178834 -230.538959) (xy 442.174899 -230.485188) (xy 435.368954 -230.485188) (xy 435.368462 -230.512145)
			(xy 435.360612 -230.565485) (xy 435.34508 -230.617114) (xy 435.322195 -230.665931) (xy 435.292447 -230.710895)
			(xy 435.256469 -230.751049) (xy 435.215027 -230.785537) (xy 435.169006 -230.813623) (xy 435.119386 -230.83471)
			(xy 435.067225 -230.848346) (xy 435.013634 -230.854243) (xy 434.959755 -230.852274) (xy 434.906737 -230.842481)
			(xy 434.85571 -230.825073) (xy 434.807762 -230.800421) (xy 434.763914 -230.769051) (xy 434.725101 -230.73163)
			(xy 434.692149 -230.688957) (xy 434.665763 -230.64194) (xy 434.646503 -230.591583) (xy 434.63478 -230.538959)
			(xy 434.630845 -230.485188) (xy 427.8249 -230.485188) (xy 427.824408 -230.512145) (xy 427.816558 -230.565485)
			(xy 427.801026 -230.617114) (xy 427.778141 -230.665931) (xy 427.748393 -230.710895) (xy 427.712415 -230.751049)
			(xy 427.670973 -230.785537) (xy 427.624952 -230.813623) (xy 427.575332 -230.83471) (xy 427.523171 -230.848346)
			(xy 427.46958 -230.854243) (xy 427.415701 -230.852274) (xy 427.362683 -230.842481) (xy 427.311656 -230.825073)
			(xy 427.263708 -230.800421) (xy 427.21986 -230.769051) (xy 427.181047 -230.73163) (xy 427.148095 -230.688957)
			(xy 427.121709 -230.64194) (xy 427.102449 -230.591583) (xy 427.090726 -230.538959) (xy 427.086791 -230.485188)
			(xy 425.985178 -230.485188) (xy 425.985178 -231.335072) (xy 431.186859 -231.335072) (xy 431.190794 -231.281301)
			(xy 431.202517 -231.228677) (xy 431.221777 -231.17832) (xy 431.248163 -231.131303) (xy 431.281115 -231.08863)
			(xy 431.319928 -231.051209) (xy 431.363776 -231.019839) (xy 431.411724 -230.995187) (xy 431.462751 -230.977779)
			(xy 431.515769 -230.967986) (xy 431.569648 -230.966017) (xy 431.623239 -230.971914) (xy 431.6754 -230.98555)
			(xy 431.72502 -231.006637) (xy 431.771041 -231.034723) (xy 431.812483 -231.069211) (xy 431.848461 -231.109365)
			(xy 431.878209 -231.154329) (xy 431.901094 -231.203146) (xy 431.916626 -231.254775) (xy 431.924476 -231.308115)
			(xy 431.924968 -231.335072) (xy 438.730913 -231.335072) (xy 438.734848 -231.281301) (xy 438.746571 -231.228677)
			(xy 438.765831 -231.17832) (xy 438.792217 -231.131303) (xy 438.825169 -231.08863) (xy 438.863982 -231.051209)
			(xy 438.90783 -231.019839) (xy 438.955778 -230.995187) (xy 439.006805 -230.977779) (xy 439.059823 -230.967986)
			(xy 439.113702 -230.966017) (xy 439.167293 -230.971914) (xy 439.219454 -230.98555) (xy 439.269074 -231.006637)
			(xy 439.315095 -231.034723) (xy 439.356537 -231.069211) (xy 439.392515 -231.109365) (xy 439.422263 -231.154329)
			(xy 439.445148 -231.203146) (xy 439.46068 -231.254775) (xy 439.46853 -231.308115) (xy 439.469022 -231.335072)
			(xy 446.274967 -231.335072) (xy 446.278902 -231.281301) (xy 446.290625 -231.228677) (xy 446.309885 -231.17832)
			(xy 446.336271 -231.131303) (xy 446.369223 -231.08863) (xy 446.408036 -231.051209) (xy 446.451884 -231.019839)
			(xy 446.499832 -230.995187) (xy 446.550859 -230.977779) (xy 446.603877 -230.967986) (xy 446.657756 -230.966017)
			(xy 446.711347 -230.971914) (xy 446.763508 -230.98555) (xy 446.813128 -231.006637) (xy 446.859149 -231.034723)
			(xy 446.900591 -231.069211) (xy 446.936569 -231.109365) (xy 446.966317 -231.154329) (xy 446.989202 -231.203146)
			(xy 447.004734 -231.254775) (xy 447.012584 -231.308115) (xy 447.013076 -231.335072) (xy 453.818767 -231.335072)
			(xy 453.822702 -231.281301) (xy 453.834425 -231.228677) (xy 453.853685 -231.17832) (xy 453.880071 -231.131303)
			(xy 453.913023 -231.08863) (xy 453.951836 -231.051209) (xy 453.995684 -231.019839) (xy 454.043632 -230.995187)
			(xy 454.094659 -230.977779) (xy 454.147677 -230.967986) (xy 454.201556 -230.966017) (xy 454.255147 -230.971914)
			(xy 454.307308 -230.98555) (xy 454.356928 -231.006637) (xy 454.402949 -231.034723) (xy 454.444391 -231.069211)
			(xy 454.480369 -231.109365) (xy 454.510117 -231.154329) (xy 454.533002 -231.203146) (xy 454.548534 -231.254775)
			(xy 454.556384 -231.308115) (xy 454.556876 -231.335072) (xy 454.556384 -231.362029) (xy 454.548534 -231.415369)
			(xy 454.533002 -231.466998) (xy 454.510117 -231.515815) (xy 454.480369 -231.560779) (xy 454.444391 -231.600933)
			(xy 454.402949 -231.635421) (xy 454.356928 -231.663507) (xy 454.307308 -231.684594) (xy 454.255147 -231.69823)
			(xy 454.201556 -231.704127) (xy 454.147677 -231.702158) (xy 454.094659 -231.692365) (xy 454.043632 -231.674957)
			(xy 453.995684 -231.650305) (xy 453.951836 -231.618935) (xy 453.913023 -231.581514) (xy 453.880071 -231.538841)
			(xy 453.853685 -231.491824) (xy 453.834425 -231.441467) (xy 453.822702 -231.388843) (xy 453.818767 -231.335072)
			(xy 447.013076 -231.335072) (xy 447.012584 -231.362029) (xy 447.004734 -231.415369) (xy 446.989202 -231.466998)
			(xy 446.966317 -231.515815) (xy 446.936569 -231.560779) (xy 446.900591 -231.600933) (xy 446.859149 -231.635421)
			(xy 446.813128 -231.663507) (xy 446.763508 -231.684594) (xy 446.711347 -231.69823) (xy 446.657756 -231.704127)
			(xy 446.603877 -231.702158) (xy 446.550859 -231.692365) (xy 446.499832 -231.674957) (xy 446.451884 -231.650305)
			(xy 446.408036 -231.618935) (xy 446.369223 -231.581514) (xy 446.336271 -231.538841) (xy 446.309885 -231.491824)
			(xy 446.290625 -231.441467) (xy 446.278902 -231.388843) (xy 446.274967 -231.335072) (xy 439.469022 -231.335072)
			(xy 439.46853 -231.362029) (xy 439.46068 -231.415369) (xy 439.445148 -231.466998) (xy 439.422263 -231.515815)
			(xy 439.392515 -231.560779) (xy 439.356537 -231.600933) (xy 439.315095 -231.635421) (xy 439.269074 -231.663507)
			(xy 439.219454 -231.684594) (xy 439.167293 -231.69823) (xy 439.113702 -231.704127) (xy 439.059823 -231.702158)
			(xy 439.006805 -231.692365) (xy 438.955778 -231.674957) (xy 438.90783 -231.650305) (xy 438.863982 -231.618935)
			(xy 438.825169 -231.581514) (xy 438.792217 -231.538841) (xy 438.765831 -231.491824) (xy 438.746571 -231.441467)
			(xy 438.734848 -231.388843) (xy 438.730913 -231.335072) (xy 431.924968 -231.335072) (xy 431.924476 -231.362029)
			(xy 431.916626 -231.415369) (xy 431.901094 -231.466998) (xy 431.878209 -231.515815) (xy 431.848461 -231.560779)
			(xy 431.812483 -231.600933) (xy 431.771041 -231.635421) (xy 431.72502 -231.663507) (xy 431.6754 -231.684594)
			(xy 431.623239 -231.69823) (xy 431.569648 -231.704127) (xy 431.515769 -231.702158) (xy 431.462751 -231.692365)
			(xy 431.411724 -231.674957) (xy 431.363776 -231.650305) (xy 431.319928 -231.618935) (xy 431.281115 -231.581514)
			(xy 431.248163 -231.538841) (xy 431.221777 -231.491824) (xy 431.202517 -231.441467) (xy 431.190794 -231.388843)
			(xy 431.186859 -231.335072) (xy 425.985178 -231.335072) (xy 425.985178 -232.184956) (xy 427.086791 -232.184956)
			(xy 427.090726 -232.131185) (xy 427.102449 -232.078561) (xy 427.121709 -232.028204) (xy 427.148095 -231.981187)
			(xy 427.181047 -231.938514) (xy 427.21986 -231.901093) (xy 427.263708 -231.869723) (xy 427.311656 -231.845071)
			(xy 427.362683 -231.827663) (xy 427.415701 -231.81787) (xy 427.46958 -231.815901) (xy 427.523171 -231.821798)
			(xy 427.575332 -231.835434) (xy 427.624952 -231.856521) (xy 427.670973 -231.884607) (xy 427.712415 -231.919095)
			(xy 427.748393 -231.959249) (xy 427.778141 -232.004213) (xy 427.801026 -232.05303) (xy 427.816558 -232.104659)
			(xy 427.824408 -232.157999) (xy 427.8249 -232.184956) (xy 434.630845 -232.184956) (xy 434.63478 -232.131185)
			(xy 434.646503 -232.078561) (xy 434.665763 -232.028204) (xy 434.692149 -231.981187) (xy 434.725101 -231.938514)
			(xy 434.763914 -231.901093) (xy 434.807762 -231.869723) (xy 434.85571 -231.845071) (xy 434.906737 -231.827663)
			(xy 434.959755 -231.81787) (xy 435.013634 -231.815901) (xy 435.067225 -231.821798) (xy 435.119386 -231.835434)
			(xy 435.169006 -231.856521) (xy 435.215027 -231.884607) (xy 435.256469 -231.919095) (xy 435.292447 -231.959249)
			(xy 435.322195 -232.004213) (xy 435.34508 -232.05303) (xy 435.360612 -232.104659) (xy 435.368462 -232.157999)
			(xy 435.368954 -232.184956) (xy 442.174899 -232.184956) (xy 442.178834 -232.131185) (xy 442.190557 -232.078561)
			(xy 442.209817 -232.028204) (xy 442.236203 -231.981187) (xy 442.269155 -231.938514) (xy 442.307968 -231.901093)
			(xy 442.351816 -231.869723) (xy 442.399764 -231.845071) (xy 442.450791 -231.827663) (xy 442.503809 -231.81787)
			(xy 442.557688 -231.815901) (xy 442.611279 -231.821798) (xy 442.66344 -231.835434) (xy 442.71306 -231.856521)
			(xy 442.759081 -231.884607) (xy 442.800523 -231.919095) (xy 442.836501 -231.959249) (xy 442.866249 -232.004213)
			(xy 442.889134 -232.05303) (xy 442.904666 -232.104659) (xy 442.912516 -232.157999) (xy 442.913008 -232.184956)
			(xy 449.718699 -232.184956) (xy 449.722634 -232.131185) (xy 449.734357 -232.078561) (xy 449.753617 -232.028204)
			(xy 449.780003 -231.981187) (xy 449.812955 -231.938514) (xy 449.851768 -231.901093) (xy 449.895616 -231.869723)
			(xy 449.943564 -231.845071) (xy 449.994591 -231.827663) (xy 450.047609 -231.81787) (xy 450.101488 -231.815901)
			(xy 450.155079 -231.821798) (xy 450.20724 -231.835434) (xy 450.25686 -231.856521) (xy 450.302881 -231.884607)
			(xy 450.344323 -231.919095) (xy 450.380301 -231.959249) (xy 450.410049 -232.004213) (xy 450.432934 -232.05303)
			(xy 450.448466 -232.104659) (xy 450.456316 -232.157999) (xy 450.456808 -232.184956) (xy 450.456316 -232.211913)
			(xy 450.448466 -232.265253) (xy 450.432934 -232.316882) (xy 450.410049 -232.365699) (xy 450.380301 -232.410663)
			(xy 450.344323 -232.450817) (xy 450.302881 -232.485305) (xy 450.25686 -232.513391) (xy 450.20724 -232.534478)
			(xy 450.155079 -232.548114) (xy 450.101488 -232.554011) (xy 450.047609 -232.552042) (xy 449.994591 -232.542249)
			(xy 449.943564 -232.524841) (xy 449.895616 -232.500189) (xy 449.851768 -232.468819) (xy 449.812955 -232.431398)
			(xy 449.780003 -232.388725) (xy 449.753617 -232.341708) (xy 449.734357 -232.291351) (xy 449.722634 -232.238727)
			(xy 449.718699 -232.184956) (xy 442.913008 -232.184956) (xy 442.912516 -232.211913) (xy 442.904666 -232.265253)
			(xy 442.889134 -232.316882) (xy 442.866249 -232.365699) (xy 442.836501 -232.410663) (xy 442.800523 -232.450817)
			(xy 442.759081 -232.485305) (xy 442.71306 -232.513391) (xy 442.66344 -232.534478) (xy 442.611279 -232.548114)
			(xy 442.557688 -232.554011) (xy 442.503809 -232.552042) (xy 442.450791 -232.542249) (xy 442.399764 -232.524841)
			(xy 442.351816 -232.500189) (xy 442.307968 -232.468819) (xy 442.269155 -232.431398) (xy 442.236203 -232.388725)
			(xy 442.209817 -232.341708) (xy 442.190557 -232.291351) (xy 442.178834 -232.238727) (xy 442.174899 -232.184956)
			(xy 435.368954 -232.184956) (xy 435.368462 -232.211913) (xy 435.360612 -232.265253) (xy 435.34508 -232.316882)
			(xy 435.322195 -232.365699) (xy 435.292447 -232.410663) (xy 435.256469 -232.450817) (xy 435.215027 -232.485305)
			(xy 435.169006 -232.513391) (xy 435.119386 -232.534478) (xy 435.067225 -232.548114) (xy 435.013634 -232.554011)
			(xy 434.959755 -232.552042) (xy 434.906737 -232.542249) (xy 434.85571 -232.524841) (xy 434.807762 -232.500189)
			(xy 434.763914 -232.468819) (xy 434.725101 -232.431398) (xy 434.692149 -232.388725) (xy 434.665763 -232.341708)
			(xy 434.646503 -232.291351) (xy 434.63478 -232.238727) (xy 434.630845 -232.184956) (xy 427.8249 -232.184956)
			(xy 427.824408 -232.211913) (xy 427.816558 -232.265253) (xy 427.801026 -232.316882) (xy 427.778141 -232.365699)
			(xy 427.748393 -232.410663) (xy 427.712415 -232.450817) (xy 427.670973 -232.485305) (xy 427.624952 -232.513391)
			(xy 427.575332 -232.534478) (xy 427.523171 -232.548114) (xy 427.46958 -232.554011) (xy 427.415701 -232.552042)
			(xy 427.362683 -232.542249) (xy 427.311656 -232.524841) (xy 427.263708 -232.500189) (xy 427.21986 -232.468819)
			(xy 427.181047 -232.431398) (xy 427.148095 -232.388725) (xy 427.121709 -232.341708) (xy 427.102449 -232.291351)
			(xy 427.090726 -232.238727) (xy 427.086791 -232.184956) (xy 425.985178 -232.184956) (xy 425.985178 -233.035094)
			(xy 431.186859 -233.035094) (xy 431.190794 -232.981323) (xy 431.202517 -232.928699) (xy 431.221777 -232.878342)
			(xy 431.248163 -232.831325) (xy 431.281115 -232.788652) (xy 431.319928 -232.751231) (xy 431.363776 -232.719861)
			(xy 431.411724 -232.695209) (xy 431.462751 -232.677801) (xy 431.515769 -232.668008) (xy 431.569648 -232.666039)
			(xy 431.623239 -232.671936) (xy 431.6754 -232.685572) (xy 431.72502 -232.706659) (xy 431.771041 -232.734745)
			(xy 431.812483 -232.769233) (xy 431.848461 -232.809387) (xy 431.878209 -232.854351) (xy 431.901094 -232.903168)
			(xy 431.916626 -232.954797) (xy 431.924476 -233.008137) (xy 431.924968 -233.035094) (xy 438.730913 -233.035094)
			(xy 438.734848 -232.981323) (xy 438.746571 -232.928699) (xy 438.765831 -232.878342) (xy 438.792217 -232.831325)
			(xy 438.825169 -232.788652) (xy 438.863982 -232.751231) (xy 438.90783 -232.719861) (xy 438.955778 -232.695209)
			(xy 439.006805 -232.677801) (xy 439.059823 -232.668008) (xy 439.113702 -232.666039) (xy 439.167293 -232.671936)
			(xy 439.219454 -232.685572) (xy 439.269074 -232.706659) (xy 439.315095 -232.734745) (xy 439.356537 -232.769233)
			(xy 439.392515 -232.809387) (xy 439.422263 -232.854351) (xy 439.445148 -232.903168) (xy 439.46068 -232.954797)
			(xy 439.46853 -233.008137) (xy 439.469022 -233.035094) (xy 446.274967 -233.035094) (xy 446.278902 -232.981323)
			(xy 446.290625 -232.928699) (xy 446.309885 -232.878342) (xy 446.336271 -232.831325) (xy 446.369223 -232.788652)
			(xy 446.408036 -232.751231) (xy 446.451884 -232.719861) (xy 446.499832 -232.695209) (xy 446.550859 -232.677801)
			(xy 446.603877 -232.668008) (xy 446.657756 -232.666039) (xy 446.711347 -232.671936) (xy 446.763508 -232.685572)
			(xy 446.813128 -232.706659) (xy 446.859149 -232.734745) (xy 446.900591 -232.769233) (xy 446.936569 -232.809387)
			(xy 446.966317 -232.854351) (xy 446.989202 -232.903168) (xy 447.004734 -232.954797) (xy 447.012584 -233.008137)
			(xy 447.013076 -233.035094) (xy 453.818767 -233.035094) (xy 453.822702 -232.981323) (xy 453.834425 -232.928699)
			(xy 453.853685 -232.878342) (xy 453.880071 -232.831325) (xy 453.913023 -232.788652) (xy 453.951836 -232.751231)
			(xy 453.995684 -232.719861) (xy 454.043632 -232.695209) (xy 454.094659 -232.677801) (xy 454.147677 -232.668008)
			(xy 454.201556 -232.666039) (xy 454.255147 -232.671936) (xy 454.307308 -232.685572) (xy 454.356928 -232.706659)
			(xy 454.402949 -232.734745) (xy 454.444391 -232.769233) (xy 454.480369 -232.809387) (xy 454.510117 -232.854351)
			(xy 454.533002 -232.903168) (xy 454.548534 -232.954797) (xy 454.556384 -233.008137) (xy 454.556876 -233.035094)
			(xy 454.556384 -233.062051) (xy 454.548534 -233.115391) (xy 454.533002 -233.16702) (xy 454.510117 -233.215837)
			(xy 454.480369 -233.260801) (xy 454.444391 -233.300955) (xy 454.402949 -233.335443) (xy 454.356928 -233.363529)
			(xy 454.307308 -233.384616) (xy 454.255147 -233.398252) (xy 454.201556 -233.404149) (xy 454.147677 -233.40218)
			(xy 454.094659 -233.392387) (xy 454.043632 -233.374979) (xy 453.995684 -233.350327) (xy 453.951836 -233.318957)
			(xy 453.913023 -233.281536) (xy 453.880071 -233.238863) (xy 453.853685 -233.191846) (xy 453.834425 -233.141489)
			(xy 453.822702 -233.088865) (xy 453.818767 -233.035094) (xy 447.013076 -233.035094) (xy 447.012584 -233.062051)
			(xy 447.004734 -233.115391) (xy 446.989202 -233.16702) (xy 446.966317 -233.215837) (xy 446.936569 -233.260801)
			(xy 446.900591 -233.300955) (xy 446.859149 -233.335443) (xy 446.813128 -233.363529) (xy 446.763508 -233.384616)
			(xy 446.711347 -233.398252) (xy 446.657756 -233.404149) (xy 446.603877 -233.40218) (xy 446.550859 -233.392387)
			(xy 446.499832 -233.374979) (xy 446.451884 -233.350327) (xy 446.408036 -233.318957) (xy 446.369223 -233.281536)
			(xy 446.336271 -233.238863) (xy 446.309885 -233.191846) (xy 446.290625 -233.141489) (xy 446.278902 -233.088865)
			(xy 446.274967 -233.035094) (xy 439.469022 -233.035094) (xy 439.46853 -233.062051) (xy 439.46068 -233.115391)
			(xy 439.445148 -233.16702) (xy 439.422263 -233.215837) (xy 439.392515 -233.260801) (xy 439.356537 -233.300955)
			(xy 439.315095 -233.335443) (xy 439.269074 -233.363529) (xy 439.219454 -233.384616) (xy 439.167293 -233.398252)
			(xy 439.113702 -233.404149) (xy 439.059823 -233.40218) (xy 439.006805 -233.392387) (xy 438.955778 -233.374979)
			(xy 438.90783 -233.350327) (xy 438.863982 -233.318957) (xy 438.825169 -233.281536) (xy 438.792217 -233.238863)
			(xy 438.765831 -233.191846) (xy 438.746571 -233.141489) (xy 438.734848 -233.088865) (xy 438.730913 -233.035094)
			(xy 431.924968 -233.035094) (xy 431.924476 -233.062051) (xy 431.916626 -233.115391) (xy 431.901094 -233.16702)
			(xy 431.878209 -233.215837) (xy 431.848461 -233.260801) (xy 431.812483 -233.300955) (xy 431.771041 -233.335443)
			(xy 431.72502 -233.363529) (xy 431.6754 -233.384616) (xy 431.623239 -233.398252) (xy 431.569648 -233.404149)
			(xy 431.515769 -233.40218) (xy 431.462751 -233.392387) (xy 431.411724 -233.374979) (xy 431.363776 -233.350327)
			(xy 431.319928 -233.318957) (xy 431.281115 -233.281536) (xy 431.248163 -233.238863) (xy 431.221777 -233.191846)
			(xy 431.202517 -233.141489) (xy 431.190794 -233.088865) (xy 431.186859 -233.035094) (xy 425.985178 -233.035094)
			(xy 425.985178 -233.884978) (xy 427.086791 -233.884978) (xy 427.090726 -233.831207) (xy 427.102449 -233.778583)
			(xy 427.121709 -233.728226) (xy 427.148095 -233.681209) (xy 427.181047 -233.638536) (xy 427.21986 -233.601115)
			(xy 427.263708 -233.569745) (xy 427.311656 -233.545093) (xy 427.362683 -233.527685) (xy 427.415701 -233.517892)
			(xy 427.46958 -233.515923) (xy 427.523171 -233.52182) (xy 427.575332 -233.535456) (xy 427.624952 -233.556543)
			(xy 427.670973 -233.584629) (xy 427.712415 -233.619117) (xy 427.748393 -233.659271) (xy 427.778141 -233.704235)
			(xy 427.801026 -233.753052) (xy 427.816558 -233.804681) (xy 427.824408 -233.858021) (xy 427.8249 -233.884978)
			(xy 434.630845 -233.884978) (xy 434.63478 -233.831207) (xy 434.646503 -233.778583) (xy 434.665763 -233.728226)
			(xy 434.692149 -233.681209) (xy 434.725101 -233.638536) (xy 434.763914 -233.601115) (xy 434.807762 -233.569745)
			(xy 434.85571 -233.545093) (xy 434.906737 -233.527685) (xy 434.959755 -233.517892) (xy 435.013634 -233.515923)
			(xy 435.067225 -233.52182) (xy 435.119386 -233.535456) (xy 435.169006 -233.556543) (xy 435.215027 -233.584629)
			(xy 435.256469 -233.619117) (xy 435.292447 -233.659271) (xy 435.322195 -233.704235) (xy 435.34508 -233.753052)
			(xy 435.360612 -233.804681) (xy 435.368462 -233.858021) (xy 435.368954 -233.884978) (xy 442.174899 -233.884978)
			(xy 442.178834 -233.831207) (xy 442.190557 -233.778583) (xy 442.209817 -233.728226) (xy 442.236203 -233.681209)
			(xy 442.269155 -233.638536) (xy 442.307968 -233.601115) (xy 442.351816 -233.569745) (xy 442.399764 -233.545093)
			(xy 442.450791 -233.527685) (xy 442.503809 -233.517892) (xy 442.557688 -233.515923) (xy 442.611279 -233.52182)
			(xy 442.66344 -233.535456) (xy 442.71306 -233.556543) (xy 442.759081 -233.584629) (xy 442.800523 -233.619117)
			(xy 442.836501 -233.659271) (xy 442.866249 -233.704235) (xy 442.889134 -233.753052) (xy 442.904666 -233.804681)
			(xy 442.912516 -233.858021) (xy 442.913008 -233.884978) (xy 449.718699 -233.884978) (xy 449.722634 -233.831207)
			(xy 449.734357 -233.778583) (xy 449.753617 -233.728226) (xy 449.780003 -233.681209) (xy 449.812955 -233.638536)
			(xy 449.851768 -233.601115) (xy 449.895616 -233.569745) (xy 449.943564 -233.545093) (xy 449.994591 -233.527685)
			(xy 450.047609 -233.517892) (xy 450.101488 -233.515923) (xy 450.155079 -233.52182) (xy 450.20724 -233.535456)
			(xy 450.25686 -233.556543) (xy 450.302881 -233.584629) (xy 450.344323 -233.619117) (xy 450.380301 -233.659271)
			(xy 450.410049 -233.704235) (xy 450.432934 -233.753052) (xy 450.448466 -233.804681) (xy 450.456316 -233.858021)
			(xy 450.456808 -233.884978) (xy 450.456316 -233.911935) (xy 450.448466 -233.965275) (xy 450.432934 -234.016904)
			(xy 450.410049 -234.065721) (xy 450.380301 -234.110685) (xy 450.344323 -234.150839) (xy 450.302881 -234.185327)
			(xy 450.25686 -234.213413) (xy 450.20724 -234.2345) (xy 450.155079 -234.248136) (xy 450.101488 -234.254033)
			(xy 450.047609 -234.252064) (xy 449.994591 -234.242271) (xy 449.943564 -234.224863) (xy 449.895616 -234.200211)
			(xy 449.851768 -234.168841) (xy 449.812955 -234.13142) (xy 449.780003 -234.088747) (xy 449.753617 -234.04173)
			(xy 449.734357 -233.991373) (xy 449.722634 -233.938749) (xy 449.718699 -233.884978) (xy 442.913008 -233.884978)
			(xy 442.912516 -233.911935) (xy 442.904666 -233.965275) (xy 442.889134 -234.016904) (xy 442.866249 -234.065721)
			(xy 442.836501 -234.110685) (xy 442.800523 -234.150839) (xy 442.759081 -234.185327) (xy 442.71306 -234.213413)
			(xy 442.66344 -234.2345) (xy 442.611279 -234.248136) (xy 442.557688 -234.254033) (xy 442.503809 -234.252064)
			(xy 442.450791 -234.242271) (xy 442.399764 -234.224863) (xy 442.351816 -234.200211) (xy 442.307968 -234.168841)
			(xy 442.269155 -234.13142) (xy 442.236203 -234.088747) (xy 442.209817 -234.04173) (xy 442.190557 -233.991373)
			(xy 442.178834 -233.938749) (xy 442.174899 -233.884978) (xy 435.368954 -233.884978) (xy 435.368462 -233.911935)
			(xy 435.360612 -233.965275) (xy 435.34508 -234.016904) (xy 435.322195 -234.065721) (xy 435.292447 -234.110685)
			(xy 435.256469 -234.150839) (xy 435.215027 -234.185327) (xy 435.169006 -234.213413) (xy 435.119386 -234.2345)
			(xy 435.067225 -234.248136) (xy 435.013634 -234.254033) (xy 434.959755 -234.252064) (xy 434.906737 -234.242271)
			(xy 434.85571 -234.224863) (xy 434.807762 -234.200211) (xy 434.763914 -234.168841) (xy 434.725101 -234.13142)
			(xy 434.692149 -234.088747) (xy 434.665763 -234.04173) (xy 434.646503 -233.991373) (xy 434.63478 -233.938749)
			(xy 434.630845 -233.884978) (xy 427.8249 -233.884978) (xy 427.824408 -233.911935) (xy 427.816558 -233.965275)
			(xy 427.801026 -234.016904) (xy 427.778141 -234.065721) (xy 427.748393 -234.110685) (xy 427.712415 -234.150839)
			(xy 427.670973 -234.185327) (xy 427.624952 -234.213413) (xy 427.575332 -234.2345) (xy 427.523171 -234.248136)
			(xy 427.46958 -234.254033) (xy 427.415701 -234.252064) (xy 427.362683 -234.242271) (xy 427.311656 -234.224863)
			(xy 427.263708 -234.200211) (xy 427.21986 -234.168841) (xy 427.181047 -234.13142) (xy 427.148095 -234.088747)
			(xy 427.121709 -234.04173) (xy 427.102449 -233.991373) (xy 427.090726 -233.938749) (xy 427.086791 -233.884978)
			(xy 425.985178 -233.884978) (xy 425.985178 -234.735116) (xy 431.186859 -234.735116) (xy 431.190794 -234.681345)
			(xy 431.202517 -234.628721) (xy 431.221777 -234.578364) (xy 431.248163 -234.531347) (xy 431.281115 -234.488674)
			(xy 431.319928 -234.451253) (xy 431.363776 -234.419883) (xy 431.411724 -234.395231) (xy 431.462751 -234.377823)
			(xy 431.515769 -234.36803) (xy 431.569648 -234.366061) (xy 431.623239 -234.371958) (xy 431.6754 -234.385594)
			(xy 431.72502 -234.406681) (xy 431.771041 -234.434767) (xy 431.812483 -234.469255) (xy 431.848461 -234.509409)
			(xy 431.878209 -234.554373) (xy 431.901094 -234.60319) (xy 431.916626 -234.654819) (xy 431.924476 -234.708159)
			(xy 431.924968 -234.735116) (xy 438.730913 -234.735116) (xy 438.734848 -234.681345) (xy 438.746571 -234.628721)
			(xy 438.765831 -234.578364) (xy 438.792217 -234.531347) (xy 438.825169 -234.488674) (xy 438.863982 -234.451253)
			(xy 438.90783 -234.419883) (xy 438.955778 -234.395231) (xy 439.006805 -234.377823) (xy 439.059823 -234.36803)
			(xy 439.113702 -234.366061) (xy 439.167293 -234.371958) (xy 439.219454 -234.385594) (xy 439.269074 -234.406681)
			(xy 439.315095 -234.434767) (xy 439.356537 -234.469255) (xy 439.392515 -234.509409) (xy 439.422263 -234.554373)
			(xy 439.445148 -234.60319) (xy 439.46068 -234.654819) (xy 439.46853 -234.708159) (xy 439.469022 -234.735116)
			(xy 446.274967 -234.735116) (xy 446.278902 -234.681345) (xy 446.290625 -234.628721) (xy 446.309885 -234.578364)
			(xy 446.336271 -234.531347) (xy 446.369223 -234.488674) (xy 446.408036 -234.451253) (xy 446.451884 -234.419883)
			(xy 446.499832 -234.395231) (xy 446.550859 -234.377823) (xy 446.603877 -234.36803) (xy 446.657756 -234.366061)
			(xy 446.711347 -234.371958) (xy 446.763508 -234.385594) (xy 446.813128 -234.406681) (xy 446.859149 -234.434767)
			(xy 446.900591 -234.469255) (xy 446.936569 -234.509409) (xy 446.966317 -234.554373) (xy 446.989202 -234.60319)
			(xy 447.004734 -234.654819) (xy 447.012584 -234.708159) (xy 447.013076 -234.735116) (xy 453.818767 -234.735116)
			(xy 453.822702 -234.681345) (xy 453.834425 -234.628721) (xy 453.853685 -234.578364) (xy 453.880071 -234.531347)
			(xy 453.913023 -234.488674) (xy 453.951836 -234.451253) (xy 453.995684 -234.419883) (xy 454.043632 -234.395231)
			(xy 454.094659 -234.377823) (xy 454.147677 -234.36803) (xy 454.201556 -234.366061) (xy 454.255147 -234.371958)
			(xy 454.307308 -234.385594) (xy 454.356928 -234.406681) (xy 454.402949 -234.434767) (xy 454.444391 -234.469255)
			(xy 454.480369 -234.509409) (xy 454.510117 -234.554373) (xy 454.533002 -234.60319) (xy 454.548534 -234.654819)
			(xy 454.556384 -234.708159) (xy 454.556876 -234.735116) (xy 454.556384 -234.762073) (xy 454.548534 -234.815413)
			(xy 454.533002 -234.867042) (xy 454.510117 -234.915859) (xy 454.480369 -234.960823) (xy 454.444391 -235.000977)
			(xy 454.402949 -235.035465) (xy 454.356928 -235.063551) (xy 454.307308 -235.084638) (xy 454.255147 -235.098274)
			(xy 454.201556 -235.104171) (xy 454.147677 -235.102202) (xy 454.094659 -235.092409) (xy 454.043632 -235.075001)
			(xy 453.995684 -235.050349) (xy 453.951836 -235.018979) (xy 453.913023 -234.981558) (xy 453.880071 -234.938885)
			(xy 453.853685 -234.891868) (xy 453.834425 -234.841511) (xy 453.822702 -234.788887) (xy 453.818767 -234.735116)
			(xy 447.013076 -234.735116) (xy 447.012584 -234.762073) (xy 447.004734 -234.815413) (xy 446.989202 -234.867042)
			(xy 446.966317 -234.915859) (xy 446.936569 -234.960823) (xy 446.900591 -235.000977) (xy 446.859149 -235.035465)
			(xy 446.813128 -235.063551) (xy 446.763508 -235.084638) (xy 446.711347 -235.098274) (xy 446.657756 -235.104171)
			(xy 446.603877 -235.102202) (xy 446.550859 -235.092409) (xy 446.499832 -235.075001) (xy 446.451884 -235.050349)
			(xy 446.408036 -235.018979) (xy 446.369223 -234.981558) (xy 446.336271 -234.938885) (xy 446.309885 -234.891868)
			(xy 446.290625 -234.841511) (xy 446.278902 -234.788887) (xy 446.274967 -234.735116) (xy 439.469022 -234.735116)
			(xy 439.46853 -234.762073) (xy 439.46068 -234.815413) (xy 439.445148 -234.867042) (xy 439.422263 -234.915859)
			(xy 439.392515 -234.960823) (xy 439.356537 -235.000977) (xy 439.315095 -235.035465) (xy 439.269074 -235.063551)
			(xy 439.219454 -235.084638) (xy 439.167293 -235.098274) (xy 439.113702 -235.104171) (xy 439.059823 -235.102202)
			(xy 439.006805 -235.092409) (xy 438.955778 -235.075001) (xy 438.90783 -235.050349) (xy 438.863982 -235.018979)
			(xy 438.825169 -234.981558) (xy 438.792217 -234.938885) (xy 438.765831 -234.891868) (xy 438.746571 -234.841511)
			(xy 438.734848 -234.788887) (xy 438.730913 -234.735116) (xy 431.924968 -234.735116) (xy 431.924476 -234.762073)
			(xy 431.916626 -234.815413) (xy 431.901094 -234.867042) (xy 431.878209 -234.915859) (xy 431.848461 -234.960823)
			(xy 431.812483 -235.000977) (xy 431.771041 -235.035465) (xy 431.72502 -235.063551) (xy 431.6754 -235.084638)
			(xy 431.623239 -235.098274) (xy 431.569648 -235.104171) (xy 431.515769 -235.102202) (xy 431.462751 -235.092409)
			(xy 431.411724 -235.075001) (xy 431.363776 -235.050349) (xy 431.319928 -235.018979) (xy 431.281115 -234.981558)
			(xy 431.248163 -234.938885) (xy 431.221777 -234.891868) (xy 431.202517 -234.841511) (xy 431.190794 -234.788887)
			(xy 431.186859 -234.735116) (xy 425.985178 -234.735116) (xy 425.985178 -235.585) (xy 427.086791 -235.585)
			(xy 427.090726 -235.531229) (xy 427.102449 -235.478605) (xy 427.121709 -235.428248) (xy 427.148095 -235.381231)
			(xy 427.181047 -235.338558) (xy 427.21986 -235.301137) (xy 427.263708 -235.269767) (xy 427.311656 -235.245115)
			(xy 427.362683 -235.227707) (xy 427.415701 -235.217914) (xy 427.46958 -235.215945) (xy 427.523171 -235.221842)
			(xy 427.575332 -235.235478) (xy 427.624952 -235.256565) (xy 427.670973 -235.284651) (xy 427.712415 -235.319139)
			(xy 427.748393 -235.359293) (xy 427.778141 -235.404257) (xy 427.801026 -235.453074) (xy 427.816558 -235.504703)
			(xy 427.824408 -235.558043) (xy 427.8249 -235.585) (xy 434.630845 -235.585) (xy 434.63478 -235.531229)
			(xy 434.646503 -235.478605) (xy 434.665763 -235.428248) (xy 434.692149 -235.381231) (xy 434.725101 -235.338558)
			(xy 434.763914 -235.301137) (xy 434.807762 -235.269767) (xy 434.85571 -235.245115) (xy 434.906737 -235.227707)
			(xy 434.959755 -235.217914) (xy 435.013634 -235.215945) (xy 435.067225 -235.221842) (xy 435.119386 -235.235478)
			(xy 435.169006 -235.256565) (xy 435.215027 -235.284651) (xy 435.256469 -235.319139) (xy 435.292447 -235.359293)
			(xy 435.322195 -235.404257) (xy 435.34508 -235.453074) (xy 435.360612 -235.504703) (xy 435.368462 -235.558043)
			(xy 435.368954 -235.585) (xy 442.174899 -235.585) (xy 442.178834 -235.531229) (xy 442.190557 -235.478605)
			(xy 442.209817 -235.428248) (xy 442.236203 -235.381231) (xy 442.269155 -235.338558) (xy 442.307968 -235.301137)
			(xy 442.351816 -235.269767) (xy 442.399764 -235.245115) (xy 442.450791 -235.227707) (xy 442.503809 -235.217914)
			(xy 442.557688 -235.215945) (xy 442.611279 -235.221842) (xy 442.66344 -235.235478) (xy 442.71306 -235.256565)
			(xy 442.759081 -235.284651) (xy 442.800523 -235.319139) (xy 442.836501 -235.359293) (xy 442.866249 -235.404257)
			(xy 442.889134 -235.453074) (xy 442.904666 -235.504703) (xy 442.912516 -235.558043) (xy 442.913008 -235.585)
			(xy 449.718699 -235.585) (xy 449.722634 -235.531229) (xy 449.734357 -235.478605) (xy 449.753617 -235.428248)
			(xy 449.780003 -235.381231) (xy 449.812955 -235.338558) (xy 449.851768 -235.301137) (xy 449.895616 -235.269767)
			(xy 449.943564 -235.245115) (xy 449.994591 -235.227707) (xy 450.047609 -235.217914) (xy 450.101488 -235.215945)
			(xy 450.155079 -235.221842) (xy 450.20724 -235.235478) (xy 450.25686 -235.256565) (xy 450.302881 -235.284651)
			(xy 450.344323 -235.319139) (xy 450.380301 -235.359293) (xy 450.410049 -235.404257) (xy 450.432934 -235.453074)
			(xy 450.448466 -235.504703) (xy 450.456316 -235.558043) (xy 450.456808 -235.585) (xy 450.456316 -235.611957)
			(xy 450.448466 -235.665297) (xy 450.432934 -235.716926) (xy 450.410049 -235.765743) (xy 450.380301 -235.810707)
			(xy 450.344323 -235.850861) (xy 450.302881 -235.885349) (xy 450.25686 -235.913435) (xy 450.20724 -235.934522)
			(xy 450.155079 -235.948158) (xy 450.101488 -235.954055) (xy 450.047609 -235.952086) (xy 449.994591 -235.942293)
			(xy 449.943564 -235.924885) (xy 449.895616 -235.900233) (xy 449.851768 -235.868863) (xy 449.812955 -235.831442)
			(xy 449.780003 -235.788769) (xy 449.753617 -235.741752) (xy 449.734357 -235.691395) (xy 449.722634 -235.638771)
			(xy 449.718699 -235.585) (xy 442.913008 -235.585) (xy 442.912516 -235.611957) (xy 442.904666 -235.665297)
			(xy 442.889134 -235.716926) (xy 442.866249 -235.765743) (xy 442.836501 -235.810707) (xy 442.800523 -235.850861)
			(xy 442.759081 -235.885349) (xy 442.71306 -235.913435) (xy 442.66344 -235.934522) (xy 442.611279 -235.948158)
			(xy 442.557688 -235.954055) (xy 442.503809 -235.952086) (xy 442.450791 -235.942293) (xy 442.399764 -235.924885)
			(xy 442.351816 -235.900233) (xy 442.307968 -235.868863) (xy 442.269155 -235.831442) (xy 442.236203 -235.788769)
			(xy 442.209817 -235.741752) (xy 442.190557 -235.691395) (xy 442.178834 -235.638771) (xy 442.174899 -235.585)
			(xy 435.368954 -235.585) (xy 435.368462 -235.611957) (xy 435.360612 -235.665297) (xy 435.34508 -235.716926)
			(xy 435.322195 -235.765743) (xy 435.292447 -235.810707) (xy 435.256469 -235.850861) (xy 435.215027 -235.885349)
			(xy 435.169006 -235.913435) (xy 435.119386 -235.934522) (xy 435.067225 -235.948158) (xy 435.013634 -235.954055)
			(xy 434.959755 -235.952086) (xy 434.906737 -235.942293) (xy 434.85571 -235.924885) (xy 434.807762 -235.900233)
			(xy 434.763914 -235.868863) (xy 434.725101 -235.831442) (xy 434.692149 -235.788769) (xy 434.665763 -235.741752)
			(xy 434.646503 -235.691395) (xy 434.63478 -235.638771) (xy 434.630845 -235.585) (xy 427.8249 -235.585)
			(xy 427.824408 -235.611957) (xy 427.816558 -235.665297) (xy 427.801026 -235.716926) (xy 427.778141 -235.765743)
			(xy 427.748393 -235.810707) (xy 427.712415 -235.850861) (xy 427.670973 -235.885349) (xy 427.624952 -235.913435)
			(xy 427.575332 -235.934522) (xy 427.523171 -235.948158) (xy 427.46958 -235.954055) (xy 427.415701 -235.952086)
			(xy 427.362683 -235.942293) (xy 427.311656 -235.924885) (xy 427.263708 -235.900233) (xy 427.21986 -235.868863)
			(xy 427.181047 -235.831442) (xy 427.148095 -235.788769) (xy 427.121709 -235.741752) (xy 427.102449 -235.691395)
			(xy 427.090726 -235.638771) (xy 427.086791 -235.585) (xy 425.985178 -235.585) (xy 425.985178 -236.435138)
			(xy 431.186859 -236.435138) (xy 431.190794 -236.381367) (xy 431.202517 -236.328743) (xy 431.221777 -236.278386)
			(xy 431.248163 -236.231369) (xy 431.281115 -236.188696) (xy 431.319928 -236.151275) (xy 431.363776 -236.119905)
			(xy 431.411724 -236.095253) (xy 431.462751 -236.077845) (xy 431.515769 -236.068052) (xy 431.569648 -236.066083)
			(xy 431.623239 -236.07198) (xy 431.6754 -236.085616) (xy 431.72502 -236.106703) (xy 431.771041 -236.134789)
			(xy 431.812483 -236.169277) (xy 431.848461 -236.209431) (xy 431.878209 -236.254395) (xy 431.901094 -236.303212)
			(xy 431.916626 -236.354841) (xy 431.924476 -236.408181) (xy 431.924968 -236.435138) (xy 438.730913 -236.435138)
			(xy 438.734848 -236.381367) (xy 438.746571 -236.328743) (xy 438.765831 -236.278386) (xy 438.792217 -236.231369)
			(xy 438.825169 -236.188696) (xy 438.863982 -236.151275) (xy 438.90783 -236.119905) (xy 438.955778 -236.095253)
			(xy 439.006805 -236.077845) (xy 439.059823 -236.068052) (xy 439.113702 -236.066083) (xy 439.167293 -236.07198)
			(xy 439.219454 -236.085616) (xy 439.269074 -236.106703) (xy 439.315095 -236.134789) (xy 439.356537 -236.169277)
			(xy 439.392515 -236.209431) (xy 439.422263 -236.254395) (xy 439.445148 -236.303212) (xy 439.46068 -236.354841)
			(xy 439.46853 -236.408181) (xy 439.469022 -236.435138) (xy 446.274967 -236.435138) (xy 446.278902 -236.381367)
			(xy 446.290625 -236.328743) (xy 446.309885 -236.278386) (xy 446.336271 -236.231369) (xy 446.369223 -236.188696)
			(xy 446.408036 -236.151275) (xy 446.451884 -236.119905) (xy 446.499832 -236.095253) (xy 446.550859 -236.077845)
			(xy 446.603877 -236.068052) (xy 446.657756 -236.066083) (xy 446.711347 -236.07198) (xy 446.763508 -236.085616)
			(xy 446.813128 -236.106703) (xy 446.859149 -236.134789) (xy 446.900591 -236.169277) (xy 446.936569 -236.209431)
			(xy 446.966317 -236.254395) (xy 446.989202 -236.303212) (xy 447.004734 -236.354841) (xy 447.012584 -236.408181)
			(xy 447.013076 -236.435138) (xy 453.818767 -236.435138) (xy 453.822702 -236.381367) (xy 453.834425 -236.328743)
			(xy 453.853685 -236.278386) (xy 453.880071 -236.231369) (xy 453.913023 -236.188696) (xy 453.951836 -236.151275)
			(xy 453.995684 -236.119905) (xy 454.043632 -236.095253) (xy 454.094659 -236.077845) (xy 454.147677 -236.068052)
			(xy 454.201556 -236.066083) (xy 454.255147 -236.07198) (xy 454.307308 -236.085616) (xy 454.356928 -236.106703)
			(xy 454.402949 -236.134789) (xy 454.444391 -236.169277) (xy 454.480369 -236.209431) (xy 454.510117 -236.254395)
			(xy 454.533002 -236.303212) (xy 454.548534 -236.354841) (xy 454.556384 -236.408181) (xy 454.556876 -236.435138)
			(xy 454.556384 -236.462095) (xy 454.548534 -236.515435) (xy 454.533002 -236.567064) (xy 454.510117 -236.615881)
			(xy 454.480369 -236.660845) (xy 454.444391 -236.700999) (xy 454.402949 -236.735487) (xy 454.356928 -236.763573)
			(xy 454.307308 -236.78466) (xy 454.255147 -236.798296) (xy 454.201556 -236.804193) (xy 454.147677 -236.802224)
			(xy 454.094659 -236.792431) (xy 454.043632 -236.775023) (xy 453.995684 -236.750371) (xy 453.951836 -236.719001)
			(xy 453.913023 -236.68158) (xy 453.880071 -236.638907) (xy 453.853685 -236.59189) (xy 453.834425 -236.541533)
			(xy 453.822702 -236.488909) (xy 453.818767 -236.435138) (xy 447.013076 -236.435138) (xy 447.012584 -236.462095)
			(xy 447.004734 -236.515435) (xy 446.989202 -236.567064) (xy 446.966317 -236.615881) (xy 446.936569 -236.660845)
			(xy 446.900591 -236.700999) (xy 446.859149 -236.735487) (xy 446.813128 -236.763573) (xy 446.763508 -236.78466)
			(xy 446.711347 -236.798296) (xy 446.657756 -236.804193) (xy 446.603877 -236.802224) (xy 446.550859 -236.792431)
			(xy 446.499832 -236.775023) (xy 446.451884 -236.750371) (xy 446.408036 -236.719001) (xy 446.369223 -236.68158)
			(xy 446.336271 -236.638907) (xy 446.309885 -236.59189) (xy 446.290625 -236.541533) (xy 446.278902 -236.488909)
			(xy 446.274967 -236.435138) (xy 439.469022 -236.435138) (xy 439.46853 -236.462095) (xy 439.46068 -236.515435)
			(xy 439.445148 -236.567064) (xy 439.422263 -236.615881) (xy 439.392515 -236.660845) (xy 439.356537 -236.700999)
			(xy 439.315095 -236.735487) (xy 439.269074 -236.763573) (xy 439.219454 -236.78466) (xy 439.167293 -236.798296)
			(xy 439.113702 -236.804193) (xy 439.059823 -236.802224) (xy 439.006805 -236.792431) (xy 438.955778 -236.775023)
			(xy 438.90783 -236.750371) (xy 438.863982 -236.719001) (xy 438.825169 -236.68158) (xy 438.792217 -236.638907)
			(xy 438.765831 -236.59189) (xy 438.746571 -236.541533) (xy 438.734848 -236.488909) (xy 438.730913 -236.435138)
			(xy 431.924968 -236.435138) (xy 431.924476 -236.462095) (xy 431.916626 -236.515435) (xy 431.901094 -236.567064)
			(xy 431.878209 -236.615881) (xy 431.848461 -236.660845) (xy 431.812483 -236.700999) (xy 431.771041 -236.735487)
			(xy 431.72502 -236.763573) (xy 431.6754 -236.78466) (xy 431.623239 -236.798296) (xy 431.569648 -236.804193)
			(xy 431.515769 -236.802224) (xy 431.462751 -236.792431) (xy 431.411724 -236.775023) (xy 431.363776 -236.750371)
			(xy 431.319928 -236.719001) (xy 431.281115 -236.68158) (xy 431.248163 -236.638907) (xy 431.221777 -236.59189)
			(xy 431.202517 -236.541533) (xy 431.190794 -236.488909) (xy 431.186859 -236.435138) (xy 425.985178 -236.435138)
			(xy 425.985178 -237.285022) (xy 427.086791 -237.285022) (xy 427.090726 -237.231251) (xy 427.102449 -237.178627)
			(xy 427.121709 -237.12827) (xy 427.148095 -237.081253) (xy 427.181047 -237.03858) (xy 427.21986 -237.001159)
			(xy 427.263708 -236.969789) (xy 427.311656 -236.945137) (xy 427.362683 -236.927729) (xy 427.415701 -236.917936)
			(xy 427.46958 -236.915967) (xy 427.523171 -236.921864) (xy 427.575332 -236.9355) (xy 427.624952 -236.956587)
			(xy 427.670973 -236.984673) (xy 427.712415 -237.019161) (xy 427.748393 -237.059315) (xy 427.778141 -237.104279)
			(xy 427.801026 -237.153096) (xy 427.816558 -237.204725) (xy 427.824408 -237.258065) (xy 427.8249 -237.285022)
			(xy 434.630845 -237.285022) (xy 434.63478 -237.231251) (xy 434.646503 -237.178627) (xy 434.665763 -237.12827)
			(xy 434.692149 -237.081253) (xy 434.725101 -237.03858) (xy 434.763914 -237.001159) (xy 434.807762 -236.969789)
			(xy 434.85571 -236.945137) (xy 434.906737 -236.927729) (xy 434.959755 -236.917936) (xy 435.013634 -236.915967)
			(xy 435.067225 -236.921864) (xy 435.119386 -236.9355) (xy 435.169006 -236.956587) (xy 435.215027 -236.984673)
			(xy 435.256469 -237.019161) (xy 435.292447 -237.059315) (xy 435.322195 -237.104279) (xy 435.34508 -237.153096)
			(xy 435.360612 -237.204725) (xy 435.368462 -237.258065) (xy 435.368954 -237.285022) (xy 442.174899 -237.285022)
			(xy 442.178834 -237.231251) (xy 442.190557 -237.178627) (xy 442.209817 -237.12827) (xy 442.236203 -237.081253)
			(xy 442.269155 -237.03858) (xy 442.307968 -237.001159) (xy 442.351816 -236.969789) (xy 442.399764 -236.945137)
			(xy 442.450791 -236.927729) (xy 442.503809 -236.917936) (xy 442.557688 -236.915967) (xy 442.611279 -236.921864)
			(xy 442.66344 -236.9355) (xy 442.71306 -236.956587) (xy 442.759081 -236.984673) (xy 442.800523 -237.019161)
			(xy 442.836501 -237.059315) (xy 442.866249 -237.104279) (xy 442.889134 -237.153096) (xy 442.904666 -237.204725)
			(xy 442.912516 -237.258065) (xy 442.913008 -237.285022) (xy 449.718699 -237.285022) (xy 449.722634 -237.231251)
			(xy 449.734357 -237.178627) (xy 449.753617 -237.12827) (xy 449.780003 -237.081253) (xy 449.812955 -237.03858)
			(xy 449.851768 -237.001159) (xy 449.895616 -236.969789) (xy 449.943564 -236.945137) (xy 449.994591 -236.927729)
			(xy 450.047609 -236.917936) (xy 450.101488 -236.915967) (xy 450.155079 -236.921864) (xy 450.20724 -236.9355)
			(xy 450.25686 -236.956587) (xy 450.302881 -236.984673) (xy 450.344323 -237.019161) (xy 450.380301 -237.059315)
			(xy 450.410049 -237.104279) (xy 450.432934 -237.153096) (xy 450.448466 -237.204725) (xy 450.456316 -237.258065)
			(xy 450.456808 -237.285022) (xy 450.456316 -237.311979) (xy 450.448466 -237.365319) (xy 450.432934 -237.416948)
			(xy 450.410049 -237.465765) (xy 450.380301 -237.510729) (xy 450.344323 -237.550883) (xy 450.302881 -237.585371)
			(xy 450.25686 -237.613457) (xy 450.20724 -237.634544) (xy 450.155079 -237.64818) (xy 450.101488 -237.654077)
			(xy 450.047609 -237.652108) (xy 449.994591 -237.642315) (xy 449.943564 -237.624907) (xy 449.895616 -237.600255)
			(xy 449.851768 -237.568885) (xy 449.812955 -237.531464) (xy 449.780003 -237.488791) (xy 449.753617 -237.441774)
			(xy 449.734357 -237.391417) (xy 449.722634 -237.338793) (xy 449.718699 -237.285022) (xy 442.913008 -237.285022)
			(xy 442.912516 -237.311979) (xy 442.904666 -237.365319) (xy 442.889134 -237.416948) (xy 442.866249 -237.465765)
			(xy 442.836501 -237.510729) (xy 442.800523 -237.550883) (xy 442.759081 -237.585371) (xy 442.71306 -237.613457)
			(xy 442.66344 -237.634544) (xy 442.611279 -237.64818) (xy 442.557688 -237.654077) (xy 442.503809 -237.652108)
			(xy 442.450791 -237.642315) (xy 442.399764 -237.624907) (xy 442.351816 -237.600255) (xy 442.307968 -237.568885)
			(xy 442.269155 -237.531464) (xy 442.236203 -237.488791) (xy 442.209817 -237.441774) (xy 442.190557 -237.391417)
			(xy 442.178834 -237.338793) (xy 442.174899 -237.285022) (xy 435.368954 -237.285022) (xy 435.368462 -237.311979)
			(xy 435.360612 -237.365319) (xy 435.34508 -237.416948) (xy 435.322195 -237.465765) (xy 435.292447 -237.510729)
			(xy 435.256469 -237.550883) (xy 435.215027 -237.585371) (xy 435.169006 -237.613457) (xy 435.119386 -237.634544)
			(xy 435.067225 -237.64818) (xy 435.013634 -237.654077) (xy 434.959755 -237.652108) (xy 434.906737 -237.642315)
			(xy 434.85571 -237.624907) (xy 434.807762 -237.600255) (xy 434.763914 -237.568885) (xy 434.725101 -237.531464)
			(xy 434.692149 -237.488791) (xy 434.665763 -237.441774) (xy 434.646503 -237.391417) (xy 434.63478 -237.338793)
			(xy 434.630845 -237.285022) (xy 427.8249 -237.285022) (xy 427.824408 -237.311979) (xy 427.816558 -237.365319)
			(xy 427.801026 -237.416948) (xy 427.778141 -237.465765) (xy 427.748393 -237.510729) (xy 427.712415 -237.550883)
			(xy 427.670973 -237.585371) (xy 427.624952 -237.613457) (xy 427.575332 -237.634544) (xy 427.523171 -237.64818)
			(xy 427.46958 -237.654077) (xy 427.415701 -237.652108) (xy 427.362683 -237.642315) (xy 427.311656 -237.624907)
			(xy 427.263708 -237.600255) (xy 427.21986 -237.568885) (xy 427.181047 -237.531464) (xy 427.148095 -237.488791)
			(xy 427.121709 -237.441774) (xy 427.102449 -237.391417) (xy 427.090726 -237.338793) (xy 427.086791 -237.285022)
			(xy 425.985178 -237.285022) (xy 425.985178 -238.13516) (xy 431.186859 -238.13516) (xy 431.190794 -238.081389)
			(xy 431.202517 -238.028765) (xy 431.221777 -237.978408) (xy 431.248163 -237.931391) (xy 431.281115 -237.888718)
			(xy 431.319928 -237.851297) (xy 431.363776 -237.819927) (xy 431.411724 -237.795275) (xy 431.462751 -237.777867)
			(xy 431.515769 -237.768074) (xy 431.569648 -237.766105) (xy 431.623239 -237.772002) (xy 431.6754 -237.785638)
			(xy 431.72502 -237.806725) (xy 431.771041 -237.834811) (xy 431.812483 -237.869299) (xy 431.848461 -237.909453)
			(xy 431.878209 -237.954417) (xy 431.901094 -238.003234) (xy 431.916626 -238.054863) (xy 431.924476 -238.108203)
			(xy 431.924968 -238.13516) (xy 438.730913 -238.13516) (xy 438.734848 -238.081389) (xy 438.746571 -238.028765)
			(xy 438.765831 -237.978408) (xy 438.792217 -237.931391) (xy 438.825169 -237.888718) (xy 438.863982 -237.851297)
			(xy 438.90783 -237.819927) (xy 438.955778 -237.795275) (xy 439.006805 -237.777867) (xy 439.059823 -237.768074)
			(xy 439.113702 -237.766105) (xy 439.167293 -237.772002) (xy 439.219454 -237.785638) (xy 439.269074 -237.806725)
			(xy 439.315095 -237.834811) (xy 439.356537 -237.869299) (xy 439.392515 -237.909453) (xy 439.422263 -237.954417)
			(xy 439.445148 -238.003234) (xy 439.46068 -238.054863) (xy 439.46853 -238.108203) (xy 439.469022 -238.13516)
			(xy 446.274967 -238.13516) (xy 446.278902 -238.081389) (xy 446.290625 -238.028765) (xy 446.309885 -237.978408)
			(xy 446.336271 -237.931391) (xy 446.369223 -237.888718) (xy 446.408036 -237.851297) (xy 446.451884 -237.819927)
			(xy 446.499832 -237.795275) (xy 446.550859 -237.777867) (xy 446.603877 -237.768074) (xy 446.657756 -237.766105)
			(xy 446.711347 -237.772002) (xy 446.763508 -237.785638) (xy 446.813128 -237.806725) (xy 446.859149 -237.834811)
			(xy 446.900591 -237.869299) (xy 446.936569 -237.909453) (xy 446.966317 -237.954417) (xy 446.989202 -238.003234)
			(xy 447.004734 -238.054863) (xy 447.012584 -238.108203) (xy 447.013076 -238.13516) (xy 453.818767 -238.13516)
			(xy 453.822702 -238.081389) (xy 453.834425 -238.028765) (xy 453.853685 -237.978408) (xy 453.880071 -237.931391)
			(xy 453.913023 -237.888718) (xy 453.951836 -237.851297) (xy 453.995684 -237.819927) (xy 454.043632 -237.795275)
			(xy 454.094659 -237.777867) (xy 454.147677 -237.768074) (xy 454.201556 -237.766105) (xy 454.255147 -237.772002)
			(xy 454.307308 -237.785638) (xy 454.356928 -237.806725) (xy 454.402949 -237.834811) (xy 454.444391 -237.869299)
			(xy 454.480369 -237.909453) (xy 454.510117 -237.954417) (xy 454.533002 -238.003234) (xy 454.548534 -238.054863)
			(xy 454.556384 -238.108203) (xy 454.556876 -238.13516) (xy 454.556384 -238.162117) (xy 454.548534 -238.215457)
			(xy 454.533002 -238.267086) (xy 454.510117 -238.315903) (xy 454.480369 -238.360867) (xy 454.444391 -238.401021)
			(xy 454.402949 -238.435509) (xy 454.356928 -238.463595) (xy 454.307308 -238.484682) (xy 454.255147 -238.498318)
			(xy 454.201556 -238.504215) (xy 454.147677 -238.502246) (xy 454.094659 -238.492453) (xy 454.043632 -238.475045)
			(xy 453.995684 -238.450393) (xy 453.951836 -238.419023) (xy 453.913023 -238.381602) (xy 453.880071 -238.338929)
			(xy 453.853685 -238.291912) (xy 453.834425 -238.241555) (xy 453.822702 -238.188931) (xy 453.818767 -238.13516)
			(xy 447.013076 -238.13516) (xy 447.012584 -238.162117) (xy 447.004734 -238.215457) (xy 446.989202 -238.267086)
			(xy 446.966317 -238.315903) (xy 446.936569 -238.360867) (xy 446.900591 -238.401021) (xy 446.859149 -238.435509)
			(xy 446.813128 -238.463595) (xy 446.763508 -238.484682) (xy 446.711347 -238.498318) (xy 446.657756 -238.504215)
			(xy 446.603877 -238.502246) (xy 446.550859 -238.492453) (xy 446.499832 -238.475045) (xy 446.451884 -238.450393)
			(xy 446.408036 -238.419023) (xy 446.369223 -238.381602) (xy 446.336271 -238.338929) (xy 446.309885 -238.291912)
			(xy 446.290625 -238.241555) (xy 446.278902 -238.188931) (xy 446.274967 -238.13516) (xy 439.469022 -238.13516)
			(xy 439.46853 -238.162117) (xy 439.46068 -238.215457) (xy 439.445148 -238.267086) (xy 439.422263 -238.315903)
			(xy 439.392515 -238.360867) (xy 439.356537 -238.401021) (xy 439.315095 -238.435509) (xy 439.269074 -238.463595)
			(xy 439.219454 -238.484682) (xy 439.167293 -238.498318) (xy 439.113702 -238.504215) (xy 439.059823 -238.502246)
			(xy 439.006805 -238.492453) (xy 438.955778 -238.475045) (xy 438.90783 -238.450393) (xy 438.863982 -238.419023)
			(xy 438.825169 -238.381602) (xy 438.792217 -238.338929) (xy 438.765831 -238.291912) (xy 438.746571 -238.241555)
			(xy 438.734848 -238.188931) (xy 438.730913 -238.13516) (xy 431.924968 -238.13516) (xy 431.924476 -238.162117)
			(xy 431.916626 -238.215457) (xy 431.901094 -238.267086) (xy 431.878209 -238.315903) (xy 431.848461 -238.360867)
			(xy 431.812483 -238.401021) (xy 431.771041 -238.435509) (xy 431.72502 -238.463595) (xy 431.6754 -238.484682)
			(xy 431.623239 -238.498318) (xy 431.569648 -238.504215) (xy 431.515769 -238.502246) (xy 431.462751 -238.492453)
			(xy 431.411724 -238.475045) (xy 431.363776 -238.450393) (xy 431.319928 -238.419023) (xy 431.281115 -238.381602)
			(xy 431.248163 -238.338929) (xy 431.221777 -238.291912) (xy 431.202517 -238.241555) (xy 431.190794 -238.188931)
			(xy 431.186859 -238.13516) (xy 425.985178 -238.13516) (xy 425.985178 -238.985044) (xy 427.086791 -238.985044)
			(xy 427.090726 -238.931273) (xy 427.102449 -238.878649) (xy 427.121709 -238.828292) (xy 427.148095 -238.781275)
			(xy 427.181047 -238.738602) (xy 427.21986 -238.701181) (xy 427.263708 -238.669811) (xy 427.311656 -238.645159)
			(xy 427.362683 -238.627751) (xy 427.415701 -238.617958) (xy 427.46958 -238.615989) (xy 427.523171 -238.621886)
			(xy 427.575332 -238.635522) (xy 427.624952 -238.656609) (xy 427.670973 -238.684695) (xy 427.712415 -238.719183)
			(xy 427.748393 -238.759337) (xy 427.778141 -238.804301) (xy 427.801026 -238.853118) (xy 427.816558 -238.904747)
			(xy 427.824408 -238.958087) (xy 427.8249 -238.985044) (xy 431.186859 -238.985044) (xy 431.190794 -238.931273)
			(xy 431.202517 -238.878649) (xy 431.221777 -238.828292) (xy 431.248163 -238.781275) (xy 431.281115 -238.738602)
			(xy 431.319928 -238.701181) (xy 431.363776 -238.669811) (xy 431.411724 -238.645159) (xy 431.462751 -238.627751)
			(xy 431.515769 -238.617958) (xy 431.569648 -238.615989) (xy 431.623239 -238.621886) (xy 431.6754 -238.635522)
			(xy 431.72502 -238.656609) (xy 431.771041 -238.684695) (xy 431.812483 -238.719183) (xy 431.848461 -238.759337)
			(xy 431.878209 -238.804301) (xy 431.901094 -238.853118) (xy 431.916626 -238.904747) (xy 431.924476 -238.958087)
			(xy 431.924968 -238.985044) (xy 434.630845 -238.985044) (xy 434.63478 -238.931273) (xy 434.646503 -238.878649)
			(xy 434.665763 -238.828292) (xy 434.692149 -238.781275) (xy 434.725101 -238.738602) (xy 434.763914 -238.701181)
			(xy 434.807762 -238.669811) (xy 434.85571 -238.645159) (xy 434.906737 -238.627751) (xy 434.959755 -238.617958)
			(xy 435.013634 -238.615989) (xy 435.067225 -238.621886) (xy 435.119386 -238.635522) (xy 435.169006 -238.656609)
			(xy 435.215027 -238.684695) (xy 435.256469 -238.719183) (xy 435.292447 -238.759337) (xy 435.322195 -238.804301)
			(xy 435.34508 -238.853118) (xy 435.360612 -238.904747) (xy 435.368462 -238.958087) (xy 435.368954 -238.985044)
			(xy 438.730913 -238.985044) (xy 438.734848 -238.931273) (xy 438.746571 -238.878649) (xy 438.765831 -238.828292)
			(xy 438.792217 -238.781275) (xy 438.825169 -238.738602) (xy 438.863982 -238.701181) (xy 438.90783 -238.669811)
			(xy 438.955778 -238.645159) (xy 439.006805 -238.627751) (xy 439.059823 -238.617958) (xy 439.113702 -238.615989)
			(xy 439.167293 -238.621886) (xy 439.219454 -238.635522) (xy 439.269074 -238.656609) (xy 439.315095 -238.684695)
			(xy 439.356537 -238.719183) (xy 439.392515 -238.759337) (xy 439.422263 -238.804301) (xy 439.445148 -238.853118)
			(xy 439.46068 -238.904747) (xy 439.46853 -238.958087) (xy 439.469022 -238.985044) (xy 442.174899 -238.985044)
			(xy 442.178834 -238.931273) (xy 442.190557 -238.878649) (xy 442.209817 -238.828292) (xy 442.236203 -238.781275)
			(xy 442.269155 -238.738602) (xy 442.307968 -238.701181) (xy 442.351816 -238.669811) (xy 442.399764 -238.645159)
			(xy 442.450791 -238.627751) (xy 442.503809 -238.617958) (xy 442.557688 -238.615989) (xy 442.611279 -238.621886)
			(xy 442.66344 -238.635522) (xy 442.71306 -238.656609) (xy 442.759081 -238.684695) (xy 442.800523 -238.719183)
			(xy 442.836501 -238.759337) (xy 442.866249 -238.804301) (xy 442.889134 -238.853118) (xy 442.904666 -238.904747)
			(xy 442.912516 -238.958087) (xy 442.913008 -238.985044) (xy 446.274967 -238.985044) (xy 446.278902 -238.931273)
			(xy 446.290625 -238.878649) (xy 446.309885 -238.828292) (xy 446.336271 -238.781275) (xy 446.369223 -238.738602)
			(xy 446.408036 -238.701181) (xy 446.451884 -238.669811) (xy 446.499832 -238.645159) (xy 446.550859 -238.627751)
			(xy 446.603877 -238.617958) (xy 446.657756 -238.615989) (xy 446.711347 -238.621886) (xy 446.763508 -238.635522)
			(xy 446.813128 -238.656609) (xy 446.859149 -238.684695) (xy 446.900591 -238.719183) (xy 446.936569 -238.759337)
			(xy 446.966317 -238.804301) (xy 446.989202 -238.853118) (xy 447.004734 -238.904747) (xy 447.012584 -238.958087)
			(xy 447.013076 -238.985044) (xy 449.718699 -238.985044) (xy 449.722634 -238.931273) (xy 449.734357 -238.878649)
			(xy 449.753617 -238.828292) (xy 449.780003 -238.781275) (xy 449.812955 -238.738602) (xy 449.851768 -238.701181)
			(xy 449.895616 -238.669811) (xy 449.943564 -238.645159) (xy 449.994591 -238.627751) (xy 450.047609 -238.617958)
			(xy 450.101488 -238.615989) (xy 450.155079 -238.621886) (xy 450.20724 -238.635522) (xy 450.25686 -238.656609)
			(xy 450.302881 -238.684695) (xy 450.344323 -238.719183) (xy 450.380301 -238.759337) (xy 450.410049 -238.804301)
			(xy 450.432934 -238.853118) (xy 450.448466 -238.904747) (xy 450.456316 -238.958087) (xy 450.456808 -238.985044)
			(xy 453.818767 -238.985044) (xy 453.822702 -238.931273) (xy 453.834425 -238.878649) (xy 453.853685 -238.828292)
			(xy 453.880071 -238.781275) (xy 453.913023 -238.738602) (xy 453.951836 -238.701181) (xy 453.995684 -238.669811)
			(xy 454.043632 -238.645159) (xy 454.094659 -238.627751) (xy 454.147677 -238.617958) (xy 454.201556 -238.615989)
			(xy 454.255147 -238.621886) (xy 454.307308 -238.635522) (xy 454.356928 -238.656609) (xy 454.402949 -238.684695)
			(xy 454.444391 -238.719183) (xy 454.480369 -238.759337) (xy 454.510117 -238.804301) (xy 454.533002 -238.853118)
			(xy 454.548534 -238.904747) (xy 454.556384 -238.958087) (xy 454.556876 -238.985044) (xy 454.556384 -239.012001)
			(xy 454.548534 -239.065341) (xy 454.533002 -239.11697) (xy 454.510117 -239.165787) (xy 454.480369 -239.210751)
			(xy 454.444391 -239.250905) (xy 454.402949 -239.285393) (xy 454.356928 -239.313479) (xy 454.307308 -239.334566)
			(xy 454.255147 -239.348202) (xy 454.201556 -239.354099) (xy 454.147677 -239.35213) (xy 454.094659 -239.342337)
			(xy 454.043632 -239.324929) (xy 453.995684 -239.300277) (xy 453.951836 -239.268907) (xy 453.913023 -239.231486)
			(xy 453.880071 -239.188813) (xy 453.853685 -239.141796) (xy 453.834425 -239.091439) (xy 453.822702 -239.038815)
			(xy 453.818767 -238.985044) (xy 450.456808 -238.985044) (xy 450.456316 -239.012001) (xy 450.448466 -239.065341)
			(xy 450.432934 -239.11697) (xy 450.410049 -239.165787) (xy 450.380301 -239.210751) (xy 450.344323 -239.250905)
			(xy 450.302881 -239.285393) (xy 450.25686 -239.313479) (xy 450.20724 -239.334566) (xy 450.155079 -239.348202)
			(xy 450.101488 -239.354099) (xy 450.047609 -239.35213) (xy 449.994591 -239.342337) (xy 449.943564 -239.324929)
			(xy 449.895616 -239.300277) (xy 449.851768 -239.268907) (xy 449.812955 -239.231486) (xy 449.780003 -239.188813)
			(xy 449.753617 -239.141796) (xy 449.734357 -239.091439) (xy 449.722634 -239.038815) (xy 449.718699 -238.985044)
			(xy 447.013076 -238.985044) (xy 447.012584 -239.012001) (xy 447.004734 -239.065341) (xy 446.989202 -239.11697)
			(xy 446.966317 -239.165787) (xy 446.936569 -239.210751) (xy 446.900591 -239.250905) (xy 446.859149 -239.285393)
			(xy 446.813128 -239.313479) (xy 446.763508 -239.334566) (xy 446.711347 -239.348202) (xy 446.657756 -239.354099)
			(xy 446.603877 -239.35213) (xy 446.550859 -239.342337) (xy 446.499832 -239.324929) (xy 446.451884 -239.300277)
			(xy 446.408036 -239.268907) (xy 446.369223 -239.231486) (xy 446.336271 -239.188813) (xy 446.309885 -239.141796)
			(xy 446.290625 -239.091439) (xy 446.278902 -239.038815) (xy 446.274967 -238.985044) (xy 442.913008 -238.985044)
			(xy 442.912516 -239.012001) (xy 442.904666 -239.065341) (xy 442.889134 -239.11697) (xy 442.866249 -239.165787)
			(xy 442.836501 -239.210751) (xy 442.800523 -239.250905) (xy 442.759081 -239.285393) (xy 442.71306 -239.313479)
			(xy 442.66344 -239.334566) (xy 442.611279 -239.348202) (xy 442.557688 -239.354099) (xy 442.503809 -239.35213)
			(xy 442.450791 -239.342337) (xy 442.399764 -239.324929) (xy 442.351816 -239.300277) (xy 442.307968 -239.268907)
			(xy 442.269155 -239.231486) (xy 442.236203 -239.188813) (xy 442.209817 -239.141796) (xy 442.190557 -239.091439)
			(xy 442.178834 -239.038815) (xy 442.174899 -238.985044) (xy 439.469022 -238.985044) (xy 439.46853 -239.012001)
			(xy 439.46068 -239.065341) (xy 439.445148 -239.11697) (xy 439.422263 -239.165787) (xy 439.392515 -239.210751)
			(xy 439.356537 -239.250905) (xy 439.315095 -239.285393) (xy 439.269074 -239.313479) (xy 439.219454 -239.334566)
			(xy 439.167293 -239.348202) (xy 439.113702 -239.354099) (xy 439.059823 -239.35213) (xy 439.006805 -239.342337)
			(xy 438.955778 -239.324929) (xy 438.90783 -239.300277) (xy 438.863982 -239.268907) (xy 438.825169 -239.231486)
			(xy 438.792217 -239.188813) (xy 438.765831 -239.141796) (xy 438.746571 -239.091439) (xy 438.734848 -239.038815)
			(xy 438.730913 -238.985044) (xy 435.368954 -238.985044) (xy 435.368462 -239.012001) (xy 435.360612 -239.065341)
			(xy 435.34508 -239.11697) (xy 435.322195 -239.165787) (xy 435.292447 -239.210751) (xy 435.256469 -239.250905)
			(xy 435.215027 -239.285393) (xy 435.169006 -239.313479) (xy 435.119386 -239.334566) (xy 435.067225 -239.348202)
			(xy 435.013634 -239.354099) (xy 434.959755 -239.35213) (xy 434.906737 -239.342337) (xy 434.85571 -239.324929)
			(xy 434.807762 -239.300277) (xy 434.763914 -239.268907) (xy 434.725101 -239.231486) (xy 434.692149 -239.188813)
			(xy 434.665763 -239.141796) (xy 434.646503 -239.091439) (xy 434.63478 -239.038815) (xy 434.630845 -238.985044)
			(xy 431.924968 -238.985044) (xy 431.924476 -239.012001) (xy 431.916626 -239.065341) (xy 431.901094 -239.11697)
			(xy 431.878209 -239.165787) (xy 431.848461 -239.210751) (xy 431.812483 -239.250905) (xy 431.771041 -239.285393)
			(xy 431.72502 -239.313479) (xy 431.6754 -239.334566) (xy 431.623239 -239.348202) (xy 431.569648 -239.354099)
			(xy 431.515769 -239.35213) (xy 431.462751 -239.342337) (xy 431.411724 -239.324929) (xy 431.363776 -239.300277)
			(xy 431.319928 -239.268907) (xy 431.281115 -239.231486) (xy 431.248163 -239.188813) (xy 431.221777 -239.141796)
			(xy 431.202517 -239.091439) (xy 431.190794 -239.038815) (xy 431.186859 -238.985044) (xy 427.8249 -238.985044)
			(xy 427.824408 -239.012001) (xy 427.816558 -239.065341) (xy 427.801026 -239.11697) (xy 427.778141 -239.165787)
			(xy 427.748393 -239.210751) (xy 427.712415 -239.250905) (xy 427.670973 -239.285393) (xy 427.624952 -239.313479)
			(xy 427.575332 -239.334566) (xy 427.523171 -239.348202) (xy 427.46958 -239.354099) (xy 427.415701 -239.35213)
			(xy 427.362683 -239.342337) (xy 427.311656 -239.324929) (xy 427.263708 -239.300277) (xy 427.21986 -239.268907)
			(xy 427.181047 -239.231486) (xy 427.148095 -239.188813) (xy 427.121709 -239.141796) (xy 427.102449 -239.091439)
			(xy 427.090726 -239.038815) (xy 427.086791 -238.985044) (xy 425.985178 -238.985044) (xy 425.985178 -239.835182)
			(xy 427.086791 -239.835182) (xy 427.090726 -239.781411) (xy 427.102449 -239.728787) (xy 427.121709 -239.67843)
			(xy 427.148095 -239.631413) (xy 427.181047 -239.58874) (xy 427.21986 -239.551319) (xy 427.263708 -239.519949)
			(xy 427.311656 -239.495297) (xy 427.362683 -239.477889) (xy 427.415701 -239.468096) (xy 427.46958 -239.466127)
			(xy 427.523171 -239.472024) (xy 427.575332 -239.48566) (xy 427.624952 -239.506747) (xy 427.670973 -239.534833)
			(xy 427.712415 -239.569321) (xy 427.748393 -239.609475) (xy 427.778141 -239.654439) (xy 427.801026 -239.703256)
			(xy 427.816558 -239.754885) (xy 427.824408 -239.808225) (xy 427.8249 -239.835182) (xy 434.630845 -239.835182)
			(xy 434.63478 -239.781411) (xy 434.646503 -239.728787) (xy 434.665763 -239.67843) (xy 434.692149 -239.631413)
			(xy 434.725101 -239.58874) (xy 434.763914 -239.551319) (xy 434.807762 -239.519949) (xy 434.85571 -239.495297)
			(xy 434.906737 -239.477889) (xy 434.959755 -239.468096) (xy 435.013634 -239.466127) (xy 435.067225 -239.472024)
			(xy 435.119386 -239.48566) (xy 435.169006 -239.506747) (xy 435.215027 -239.534833) (xy 435.256469 -239.569321)
			(xy 435.292447 -239.609475) (xy 435.322195 -239.654439) (xy 435.34508 -239.703256) (xy 435.360612 -239.754885)
			(xy 435.368462 -239.808225) (xy 435.368954 -239.835182) (xy 442.174899 -239.835182) (xy 442.178834 -239.781411)
			(xy 442.190557 -239.728787) (xy 442.209817 -239.67843) (xy 442.236203 -239.631413) (xy 442.269155 -239.58874)
			(xy 442.307968 -239.551319) (xy 442.351816 -239.519949) (xy 442.399764 -239.495297) (xy 442.450791 -239.477889)
			(xy 442.503809 -239.468096) (xy 442.557688 -239.466127) (xy 442.611279 -239.472024) (xy 442.66344 -239.48566)
			(xy 442.71306 -239.506747) (xy 442.759081 -239.534833) (xy 442.800523 -239.569321) (xy 442.836501 -239.609475)
			(xy 442.866249 -239.654439) (xy 442.889134 -239.703256) (xy 442.904666 -239.754885) (xy 442.912516 -239.808225)
			(xy 442.913008 -239.835182) (xy 449.718699 -239.835182) (xy 449.722634 -239.781411) (xy 449.734357 -239.728787)
			(xy 449.753617 -239.67843) (xy 449.780003 -239.631413) (xy 449.812955 -239.58874) (xy 449.851768 -239.551319)
			(xy 449.895616 -239.519949) (xy 449.943564 -239.495297) (xy 449.994591 -239.477889) (xy 450.047609 -239.468096)
			(xy 450.101488 -239.466127) (xy 450.155079 -239.472024) (xy 450.20724 -239.48566) (xy 450.25686 -239.506747)
			(xy 450.302881 -239.534833) (xy 450.344323 -239.569321) (xy 450.380301 -239.609475) (xy 450.410049 -239.654439)
			(xy 450.432934 -239.703256) (xy 450.448466 -239.754885) (xy 450.456316 -239.808225) (xy 450.456808 -239.835182)
			(xy 450.456316 -239.862139) (xy 450.448466 -239.915479) (xy 450.432934 -239.967108) (xy 450.410049 -240.015925)
			(xy 450.380301 -240.060889) (xy 450.344323 -240.101043) (xy 450.302881 -240.135531) (xy 450.25686 -240.163617)
			(xy 450.20724 -240.184704) (xy 450.155079 -240.19834) (xy 450.101488 -240.204237) (xy 450.047609 -240.202268)
			(xy 449.994591 -240.192475) (xy 449.943564 -240.175067) (xy 449.895616 -240.150415) (xy 449.851768 -240.119045)
			(xy 449.812955 -240.081624) (xy 449.780003 -240.038951) (xy 449.753617 -239.991934) (xy 449.734357 -239.941577)
			(xy 449.722634 -239.888953) (xy 449.718699 -239.835182) (xy 442.913008 -239.835182) (xy 442.912516 -239.862139)
			(xy 442.904666 -239.915479) (xy 442.889134 -239.967108) (xy 442.866249 -240.015925) (xy 442.836501 -240.060889)
			(xy 442.800523 -240.101043) (xy 442.759081 -240.135531) (xy 442.71306 -240.163617) (xy 442.66344 -240.184704)
			(xy 442.611279 -240.19834) (xy 442.557688 -240.204237) (xy 442.503809 -240.202268) (xy 442.450791 -240.192475)
			(xy 442.399764 -240.175067) (xy 442.351816 -240.150415) (xy 442.307968 -240.119045) (xy 442.269155 -240.081624)
			(xy 442.236203 -240.038951) (xy 442.209817 -239.991934) (xy 442.190557 -239.941577) (xy 442.178834 -239.888953)
			(xy 442.174899 -239.835182) (xy 435.368954 -239.835182) (xy 435.368462 -239.862139) (xy 435.360612 -239.915479)
			(xy 435.34508 -239.967108) (xy 435.322195 -240.015925) (xy 435.292447 -240.060889) (xy 435.256469 -240.101043)
			(xy 435.215027 -240.135531) (xy 435.169006 -240.163617) (xy 435.119386 -240.184704) (xy 435.067225 -240.19834)
			(xy 435.013634 -240.204237) (xy 434.959755 -240.202268) (xy 434.906737 -240.192475) (xy 434.85571 -240.175067)
			(xy 434.807762 -240.150415) (xy 434.763914 -240.119045) (xy 434.725101 -240.081624) (xy 434.692149 -240.038951)
			(xy 434.665763 -239.991934) (xy 434.646503 -239.941577) (xy 434.63478 -239.888953) (xy 434.630845 -239.835182)
			(xy 427.8249 -239.835182) (xy 427.824408 -239.862139) (xy 427.816558 -239.915479) (xy 427.801026 -239.967108)
			(xy 427.778141 -240.015925) (xy 427.748393 -240.060889) (xy 427.712415 -240.101043) (xy 427.670973 -240.135531)
			(xy 427.624952 -240.163617) (xy 427.575332 -240.184704) (xy 427.523171 -240.19834) (xy 427.46958 -240.204237)
			(xy 427.415701 -240.202268) (xy 427.362683 -240.192475) (xy 427.311656 -240.175067) (xy 427.263708 -240.150415)
			(xy 427.21986 -240.119045) (xy 427.181047 -240.081624) (xy 427.148095 -240.038951) (xy 427.121709 -239.991934)
			(xy 427.102449 -239.941577) (xy 427.090726 -239.888953) (xy 427.086791 -239.835182) (xy 425.985178 -239.835182)
			(xy 425.985178 -240.685066) (xy 431.186859 -240.685066) (xy 431.190794 -240.631295) (xy 431.202517 -240.578671)
			(xy 431.221777 -240.528314) (xy 431.248163 -240.481297) (xy 431.281115 -240.438624) (xy 431.319928 -240.401203)
			(xy 431.363776 -240.369833) (xy 431.411724 -240.345181) (xy 431.462751 -240.327773) (xy 431.515769 -240.31798)
			(xy 431.569648 -240.316011) (xy 431.623239 -240.321908) (xy 431.6754 -240.335544) (xy 431.72502 -240.356631)
			(xy 431.771041 -240.384717) (xy 431.812483 -240.419205) (xy 431.848461 -240.459359) (xy 431.878209 -240.504323)
			(xy 431.901094 -240.55314) (xy 431.916626 -240.604769) (xy 431.924476 -240.658109) (xy 431.924968 -240.685066)
			(xy 438.730913 -240.685066) (xy 438.734848 -240.631295) (xy 438.746571 -240.578671) (xy 438.765831 -240.528314)
			(xy 438.792217 -240.481297) (xy 438.825169 -240.438624) (xy 438.863982 -240.401203) (xy 438.90783 -240.369833)
			(xy 438.955778 -240.345181) (xy 439.006805 -240.327773) (xy 439.059823 -240.31798) (xy 439.113702 -240.316011)
			(xy 439.167293 -240.321908) (xy 439.219454 -240.335544) (xy 439.269074 -240.356631) (xy 439.315095 -240.384717)
			(xy 439.356537 -240.419205) (xy 439.392515 -240.459359) (xy 439.422263 -240.504323) (xy 439.445148 -240.55314)
			(xy 439.46068 -240.604769) (xy 439.46853 -240.658109) (xy 439.469022 -240.685066) (xy 446.274967 -240.685066)
			(xy 446.278902 -240.631295) (xy 446.290625 -240.578671) (xy 446.309885 -240.528314) (xy 446.336271 -240.481297)
			(xy 446.369223 -240.438624) (xy 446.408036 -240.401203) (xy 446.451884 -240.369833) (xy 446.499832 -240.345181)
			(xy 446.550859 -240.327773) (xy 446.603877 -240.31798) (xy 446.657756 -240.316011) (xy 446.711347 -240.321908)
			(xy 446.763508 -240.335544) (xy 446.813128 -240.356631) (xy 446.859149 -240.384717) (xy 446.900591 -240.419205)
			(xy 446.936569 -240.459359) (xy 446.966317 -240.504323) (xy 446.989202 -240.55314) (xy 447.004734 -240.604769)
			(xy 447.012584 -240.658109) (xy 447.013076 -240.685066) (xy 453.818767 -240.685066) (xy 453.822702 -240.631295)
			(xy 453.834425 -240.578671) (xy 453.853685 -240.528314) (xy 453.880071 -240.481297) (xy 453.913023 -240.438624)
			(xy 453.951836 -240.401203) (xy 453.995684 -240.369833) (xy 454.043632 -240.345181) (xy 454.094659 -240.327773)
			(xy 454.147677 -240.31798) (xy 454.201556 -240.316011) (xy 454.255147 -240.321908) (xy 454.307308 -240.335544)
			(xy 454.356928 -240.356631) (xy 454.402949 -240.384717) (xy 454.444391 -240.419205) (xy 454.480369 -240.459359)
			(xy 454.510117 -240.504323) (xy 454.533002 -240.55314) (xy 454.548534 -240.604769) (xy 454.556384 -240.658109)
			(xy 454.556876 -240.685066) (xy 454.556384 -240.712023) (xy 454.548534 -240.765363) (xy 454.533002 -240.816992)
			(xy 454.510117 -240.865809) (xy 454.480369 -240.910773) (xy 454.444391 -240.950927) (xy 454.402949 -240.985415)
			(xy 454.356928 -241.013501) (xy 454.307308 -241.034588) (xy 454.255147 -241.048224) (xy 454.201556 -241.054121)
			(xy 454.147677 -241.052152) (xy 454.094659 -241.042359) (xy 454.043632 -241.024951) (xy 453.995684 -241.000299)
			(xy 453.951836 -240.968929) (xy 453.913023 -240.931508) (xy 453.880071 -240.888835) (xy 453.853685 -240.841818)
			(xy 453.834425 -240.791461) (xy 453.822702 -240.738837) (xy 453.818767 -240.685066) (xy 447.013076 -240.685066)
			(xy 447.012584 -240.712023) (xy 447.004734 -240.765363) (xy 446.989202 -240.816992) (xy 446.966317 -240.865809)
			(xy 446.936569 -240.910773) (xy 446.900591 -240.950927) (xy 446.859149 -240.985415) (xy 446.813128 -241.013501)
			(xy 446.763508 -241.034588) (xy 446.711347 -241.048224) (xy 446.657756 -241.054121) (xy 446.603877 -241.052152)
			(xy 446.550859 -241.042359) (xy 446.499832 -241.024951) (xy 446.451884 -241.000299) (xy 446.408036 -240.968929)
			(xy 446.369223 -240.931508) (xy 446.336271 -240.888835) (xy 446.309885 -240.841818) (xy 446.290625 -240.791461)
			(xy 446.278902 -240.738837) (xy 446.274967 -240.685066) (xy 439.469022 -240.685066) (xy 439.46853 -240.712023)
			(xy 439.46068 -240.765363) (xy 439.445148 -240.816992) (xy 439.422263 -240.865809) (xy 439.392515 -240.910773)
			(xy 439.356537 -240.950927) (xy 439.315095 -240.985415) (xy 439.269074 -241.013501) (xy 439.219454 -241.034588)
			(xy 439.167293 -241.048224) (xy 439.113702 -241.054121) (xy 439.059823 -241.052152) (xy 439.006805 -241.042359)
			(xy 438.955778 -241.024951) (xy 438.90783 -241.000299) (xy 438.863982 -240.968929) (xy 438.825169 -240.931508)
			(xy 438.792217 -240.888835) (xy 438.765831 -240.841818) (xy 438.746571 -240.791461) (xy 438.734848 -240.738837)
			(xy 438.730913 -240.685066) (xy 431.924968 -240.685066) (xy 431.924476 -240.712023) (xy 431.916626 -240.765363)
			(xy 431.901094 -240.816992) (xy 431.878209 -240.865809) (xy 431.848461 -240.910773) (xy 431.812483 -240.950927)
			(xy 431.771041 -240.985415) (xy 431.72502 -241.013501) (xy 431.6754 -241.034588) (xy 431.623239 -241.048224)
			(xy 431.569648 -241.054121) (xy 431.515769 -241.052152) (xy 431.462751 -241.042359) (xy 431.411724 -241.024951)
			(xy 431.363776 -241.000299) (xy 431.319928 -240.968929) (xy 431.281115 -240.931508) (xy 431.248163 -240.888835)
			(xy 431.221777 -240.841818) (xy 431.202517 -240.791461) (xy 431.190794 -240.738837) (xy 431.186859 -240.685066)
			(xy 425.985178 -240.685066) (xy 425.985178 -241.53495) (xy 427.086791 -241.53495) (xy 427.090726 -241.481179)
			(xy 427.102449 -241.428555) (xy 427.121709 -241.378198) (xy 427.148095 -241.331181) (xy 427.181047 -241.288508)
			(xy 427.21986 -241.251087) (xy 427.263708 -241.219717) (xy 427.311656 -241.195065) (xy 427.362683 -241.177657)
			(xy 427.415701 -241.167864) (xy 427.46958 -241.165895) (xy 427.523171 -241.171792) (xy 427.575332 -241.185428)
			(xy 427.624952 -241.206515) (xy 427.670973 -241.234601) (xy 427.712415 -241.269089) (xy 427.748393 -241.309243)
			(xy 427.778141 -241.354207) (xy 427.801026 -241.403024) (xy 427.816558 -241.454653) (xy 427.824408 -241.507993)
			(xy 427.8249 -241.53495) (xy 434.630845 -241.53495) (xy 434.63478 -241.481179) (xy 434.646503 -241.428555)
			(xy 434.665763 -241.378198) (xy 434.692149 -241.331181) (xy 434.725101 -241.288508) (xy 434.763914 -241.251087)
			(xy 434.807762 -241.219717) (xy 434.85571 -241.195065) (xy 434.906737 -241.177657) (xy 434.959755 -241.167864)
			(xy 435.013634 -241.165895) (xy 435.067225 -241.171792) (xy 435.119386 -241.185428) (xy 435.169006 -241.206515)
			(xy 435.215027 -241.234601) (xy 435.256469 -241.269089) (xy 435.292447 -241.309243) (xy 435.322195 -241.354207)
			(xy 435.34508 -241.403024) (xy 435.360612 -241.454653) (xy 435.368462 -241.507993) (xy 435.368954 -241.53495)
			(xy 442.174899 -241.53495) (xy 442.178834 -241.481179) (xy 442.190557 -241.428555) (xy 442.209817 -241.378198)
			(xy 442.236203 -241.331181) (xy 442.269155 -241.288508) (xy 442.307968 -241.251087) (xy 442.351816 -241.219717)
			(xy 442.399764 -241.195065) (xy 442.450791 -241.177657) (xy 442.503809 -241.167864) (xy 442.557688 -241.165895)
			(xy 442.611279 -241.171792) (xy 442.66344 -241.185428) (xy 442.71306 -241.206515) (xy 442.759081 -241.234601)
			(xy 442.800523 -241.269089) (xy 442.836501 -241.309243) (xy 442.866249 -241.354207) (xy 442.889134 -241.403024)
			(xy 442.904666 -241.454653) (xy 442.912516 -241.507993) (xy 442.913008 -241.53495) (xy 449.718699 -241.53495)
			(xy 449.722634 -241.481179) (xy 449.734357 -241.428555) (xy 449.753617 -241.378198) (xy 449.780003 -241.331181)
			(xy 449.812955 -241.288508) (xy 449.851768 -241.251087) (xy 449.895616 -241.219717) (xy 449.943564 -241.195065)
			(xy 449.994591 -241.177657) (xy 450.047609 -241.167864) (xy 450.101488 -241.165895) (xy 450.155079 -241.171792)
			(xy 450.20724 -241.185428) (xy 450.25686 -241.206515) (xy 450.302881 -241.234601) (xy 450.344323 -241.269089)
			(xy 450.380301 -241.309243) (xy 450.410049 -241.354207) (xy 450.432934 -241.403024) (xy 450.448466 -241.454653)
			(xy 450.456316 -241.507993) (xy 450.456808 -241.53495) (xy 450.456316 -241.561907) (xy 450.448466 -241.615247)
			(xy 450.432934 -241.666876) (xy 450.410049 -241.715693) (xy 450.380301 -241.760657) (xy 450.344323 -241.800811)
			(xy 450.302881 -241.835299) (xy 450.25686 -241.863385) (xy 450.20724 -241.884472) (xy 450.155079 -241.898108)
			(xy 450.101488 -241.904005) (xy 450.047609 -241.902036) (xy 449.994591 -241.892243) (xy 449.943564 -241.874835)
			(xy 449.895616 -241.850183) (xy 449.851768 -241.818813) (xy 449.812955 -241.781392) (xy 449.780003 -241.738719)
			(xy 449.753617 -241.691702) (xy 449.734357 -241.641345) (xy 449.722634 -241.588721) (xy 449.718699 -241.53495)
			(xy 442.913008 -241.53495) (xy 442.912516 -241.561907) (xy 442.904666 -241.615247) (xy 442.889134 -241.666876)
			(xy 442.866249 -241.715693) (xy 442.836501 -241.760657) (xy 442.800523 -241.800811) (xy 442.759081 -241.835299)
			(xy 442.71306 -241.863385) (xy 442.66344 -241.884472) (xy 442.611279 -241.898108) (xy 442.557688 -241.904005)
			(xy 442.503809 -241.902036) (xy 442.450791 -241.892243) (xy 442.399764 -241.874835) (xy 442.351816 -241.850183)
			(xy 442.307968 -241.818813) (xy 442.269155 -241.781392) (xy 442.236203 -241.738719) (xy 442.209817 -241.691702)
			(xy 442.190557 -241.641345) (xy 442.178834 -241.588721) (xy 442.174899 -241.53495) (xy 435.368954 -241.53495)
			(xy 435.368462 -241.561907) (xy 435.360612 -241.615247) (xy 435.34508 -241.666876) (xy 435.322195 -241.715693)
			(xy 435.292447 -241.760657) (xy 435.256469 -241.800811) (xy 435.215027 -241.835299) (xy 435.169006 -241.863385)
			(xy 435.119386 -241.884472) (xy 435.067225 -241.898108) (xy 435.013634 -241.904005) (xy 434.959755 -241.902036)
			(xy 434.906737 -241.892243) (xy 434.85571 -241.874835) (xy 434.807762 -241.850183) (xy 434.763914 -241.818813)
			(xy 434.725101 -241.781392) (xy 434.692149 -241.738719) (xy 434.665763 -241.691702) (xy 434.646503 -241.641345)
			(xy 434.63478 -241.588721) (xy 434.630845 -241.53495) (xy 427.8249 -241.53495) (xy 427.824408 -241.561907)
			(xy 427.816558 -241.615247) (xy 427.801026 -241.666876) (xy 427.778141 -241.715693) (xy 427.748393 -241.760657)
			(xy 427.712415 -241.800811) (xy 427.670973 -241.835299) (xy 427.624952 -241.863385) (xy 427.575332 -241.884472)
			(xy 427.523171 -241.898108) (xy 427.46958 -241.904005) (xy 427.415701 -241.902036) (xy 427.362683 -241.892243)
			(xy 427.311656 -241.874835) (xy 427.263708 -241.850183) (xy 427.21986 -241.818813) (xy 427.181047 -241.781392)
			(xy 427.148095 -241.738719) (xy 427.121709 -241.691702) (xy 427.102449 -241.641345) (xy 427.090726 -241.588721)
			(xy 427.086791 -241.53495) (xy 425.985178 -241.53495) (xy 425.985178 -242.385088) (xy 431.186859 -242.385088)
			(xy 431.190794 -242.331317) (xy 431.202517 -242.278693) (xy 431.221777 -242.228336) (xy 431.248163 -242.181319)
			(xy 431.281115 -242.138646) (xy 431.319928 -242.101225) (xy 431.363776 -242.069855) (xy 431.411724 -242.045203)
			(xy 431.462751 -242.027795) (xy 431.515769 -242.018002) (xy 431.569648 -242.016033) (xy 431.623239 -242.02193)
			(xy 431.6754 -242.035566) (xy 431.72502 -242.056653) (xy 431.771041 -242.084739) (xy 431.812483 -242.119227)
			(xy 431.848461 -242.159381) (xy 431.878209 -242.204345) (xy 431.901094 -242.253162) (xy 431.916626 -242.304791)
			(xy 431.924476 -242.358131) (xy 431.924968 -242.385088) (xy 438.730913 -242.385088) (xy 438.734848 -242.331317)
			(xy 438.746571 -242.278693) (xy 438.765831 -242.228336) (xy 438.792217 -242.181319) (xy 438.825169 -242.138646)
			(xy 438.863982 -242.101225) (xy 438.90783 -242.069855) (xy 438.955778 -242.045203) (xy 439.006805 -242.027795)
			(xy 439.059823 -242.018002) (xy 439.113702 -242.016033) (xy 439.167293 -242.02193) (xy 439.219454 -242.035566)
			(xy 439.269074 -242.056653) (xy 439.315095 -242.084739) (xy 439.356537 -242.119227) (xy 439.392515 -242.159381)
			(xy 439.422263 -242.204345) (xy 439.445148 -242.253162) (xy 439.46068 -242.304791) (xy 439.46853 -242.358131)
			(xy 439.469022 -242.385088) (xy 446.274967 -242.385088) (xy 446.278902 -242.331317) (xy 446.290625 -242.278693)
			(xy 446.309885 -242.228336) (xy 446.336271 -242.181319) (xy 446.369223 -242.138646) (xy 446.408036 -242.101225)
			(xy 446.451884 -242.069855) (xy 446.499832 -242.045203) (xy 446.550859 -242.027795) (xy 446.603877 -242.018002)
			(xy 446.657756 -242.016033) (xy 446.711347 -242.02193) (xy 446.763508 -242.035566) (xy 446.813128 -242.056653)
			(xy 446.859149 -242.084739) (xy 446.900591 -242.119227) (xy 446.936569 -242.159381) (xy 446.966317 -242.204345)
			(xy 446.989202 -242.253162) (xy 447.004734 -242.304791) (xy 447.012584 -242.358131) (xy 447.013076 -242.385088)
			(xy 453.818767 -242.385088) (xy 453.822702 -242.331317) (xy 453.834425 -242.278693) (xy 453.853685 -242.228336)
			(xy 453.880071 -242.181319) (xy 453.913023 -242.138646) (xy 453.951836 -242.101225) (xy 453.995684 -242.069855)
			(xy 454.043632 -242.045203) (xy 454.094659 -242.027795) (xy 454.147677 -242.018002) (xy 454.201556 -242.016033)
			(xy 454.255147 -242.02193) (xy 454.307308 -242.035566) (xy 454.356928 -242.056653) (xy 454.402949 -242.084739)
			(xy 454.444391 -242.119227) (xy 454.480369 -242.159381) (xy 454.510117 -242.204345) (xy 454.533002 -242.253162)
			(xy 454.548534 -242.304791) (xy 454.556384 -242.358131) (xy 454.556876 -242.385088) (xy 454.556384 -242.412045)
			(xy 454.548534 -242.465385) (xy 454.533002 -242.517014) (xy 454.510117 -242.565831) (xy 454.480369 -242.610795)
			(xy 454.444391 -242.650949) (xy 454.402949 -242.685437) (xy 454.356928 -242.713523) (xy 454.307308 -242.73461)
			(xy 454.255147 -242.748246) (xy 454.201556 -242.754143) (xy 454.147677 -242.752174) (xy 454.094659 -242.742381)
			(xy 454.043632 -242.724973) (xy 453.995684 -242.700321) (xy 453.951836 -242.668951) (xy 453.913023 -242.63153)
			(xy 453.880071 -242.588857) (xy 453.853685 -242.54184) (xy 453.834425 -242.491483) (xy 453.822702 -242.438859)
			(xy 453.818767 -242.385088) (xy 447.013076 -242.385088) (xy 447.012584 -242.412045) (xy 447.004734 -242.465385)
			(xy 446.989202 -242.517014) (xy 446.966317 -242.565831) (xy 446.936569 -242.610795) (xy 446.900591 -242.650949)
			(xy 446.859149 -242.685437) (xy 446.813128 -242.713523) (xy 446.763508 -242.73461) (xy 446.711347 -242.748246)
			(xy 446.657756 -242.754143) (xy 446.603877 -242.752174) (xy 446.550859 -242.742381) (xy 446.499832 -242.724973)
			(xy 446.451884 -242.700321) (xy 446.408036 -242.668951) (xy 446.369223 -242.63153) (xy 446.336271 -242.588857)
			(xy 446.309885 -242.54184) (xy 446.290625 -242.491483) (xy 446.278902 -242.438859) (xy 446.274967 -242.385088)
			(xy 439.469022 -242.385088) (xy 439.46853 -242.412045) (xy 439.46068 -242.465385) (xy 439.445148 -242.517014)
			(xy 439.422263 -242.565831) (xy 439.392515 -242.610795) (xy 439.356537 -242.650949) (xy 439.315095 -242.685437)
			(xy 439.269074 -242.713523) (xy 439.219454 -242.73461) (xy 439.167293 -242.748246) (xy 439.113702 -242.754143)
			(xy 439.059823 -242.752174) (xy 439.006805 -242.742381) (xy 438.955778 -242.724973) (xy 438.90783 -242.700321)
			(xy 438.863982 -242.668951) (xy 438.825169 -242.63153) (xy 438.792217 -242.588857) (xy 438.765831 -242.54184)
			(xy 438.746571 -242.491483) (xy 438.734848 -242.438859) (xy 438.730913 -242.385088) (xy 431.924968 -242.385088)
			(xy 431.924476 -242.412045) (xy 431.916626 -242.465385) (xy 431.901094 -242.517014) (xy 431.878209 -242.565831)
			(xy 431.848461 -242.610795) (xy 431.812483 -242.650949) (xy 431.771041 -242.685437) (xy 431.72502 -242.713523)
			(xy 431.6754 -242.73461) (xy 431.623239 -242.748246) (xy 431.569648 -242.754143) (xy 431.515769 -242.752174)
			(xy 431.462751 -242.742381) (xy 431.411724 -242.724973) (xy 431.363776 -242.700321) (xy 431.319928 -242.668951)
			(xy 431.281115 -242.63153) (xy 431.248163 -242.588857) (xy 431.221777 -242.54184) (xy 431.202517 -242.491483)
			(xy 431.190794 -242.438859) (xy 431.186859 -242.385088) (xy 425.985178 -242.385088) (xy 425.985178 -243.234972)
			(xy 427.086791 -243.234972) (xy 427.090726 -243.181201) (xy 427.102449 -243.128577) (xy 427.121709 -243.07822)
			(xy 427.148095 -243.031203) (xy 427.181047 -242.98853) (xy 427.21986 -242.951109) (xy 427.263708 -242.919739)
			(xy 427.311656 -242.895087) (xy 427.362683 -242.877679) (xy 427.415701 -242.867886) (xy 427.46958 -242.865917)
			(xy 427.523171 -242.871814) (xy 427.575332 -242.88545) (xy 427.624952 -242.906537) (xy 427.670973 -242.934623)
			(xy 427.712415 -242.969111) (xy 427.748393 -243.009265) (xy 427.778141 -243.054229) (xy 427.801026 -243.103046)
			(xy 427.816558 -243.154675) (xy 427.824408 -243.208015) (xy 427.8249 -243.234972) (xy 434.630845 -243.234972)
			(xy 434.63478 -243.181201) (xy 434.646503 -243.128577) (xy 434.665763 -243.07822) (xy 434.692149 -243.031203)
			(xy 434.725101 -242.98853) (xy 434.763914 -242.951109) (xy 434.807762 -242.919739) (xy 434.85571 -242.895087)
			(xy 434.906737 -242.877679) (xy 434.959755 -242.867886) (xy 435.013634 -242.865917) (xy 435.067225 -242.871814)
			(xy 435.119386 -242.88545) (xy 435.169006 -242.906537) (xy 435.215027 -242.934623) (xy 435.256469 -242.969111)
			(xy 435.292447 -243.009265) (xy 435.322195 -243.054229) (xy 435.34508 -243.103046) (xy 435.360612 -243.154675)
			(xy 435.368462 -243.208015) (xy 435.368954 -243.234972) (xy 442.174899 -243.234972) (xy 442.178834 -243.181201)
			(xy 442.190557 -243.128577) (xy 442.209817 -243.07822) (xy 442.236203 -243.031203) (xy 442.269155 -242.98853)
			(xy 442.307968 -242.951109) (xy 442.351816 -242.919739) (xy 442.399764 -242.895087) (xy 442.450791 -242.877679)
			(xy 442.503809 -242.867886) (xy 442.557688 -242.865917) (xy 442.611279 -242.871814) (xy 442.66344 -242.88545)
			(xy 442.71306 -242.906537) (xy 442.759081 -242.934623) (xy 442.800523 -242.969111) (xy 442.836501 -243.009265)
			(xy 442.866249 -243.054229) (xy 442.889134 -243.103046) (xy 442.904666 -243.154675) (xy 442.912516 -243.208015)
			(xy 442.913008 -243.234972) (xy 449.718699 -243.234972) (xy 449.722634 -243.181201) (xy 449.734357 -243.128577)
			(xy 449.753617 -243.07822) (xy 449.780003 -243.031203) (xy 449.812955 -242.98853) (xy 449.851768 -242.951109)
			(xy 449.895616 -242.919739) (xy 449.943564 -242.895087) (xy 449.994591 -242.877679) (xy 450.047609 -242.867886)
			(xy 450.101488 -242.865917) (xy 450.155079 -242.871814) (xy 450.20724 -242.88545) (xy 450.25686 -242.906537)
			(xy 450.302881 -242.934623) (xy 450.344323 -242.969111) (xy 450.380301 -243.009265) (xy 450.410049 -243.054229)
			(xy 450.432934 -243.103046) (xy 450.448466 -243.154675) (xy 450.456316 -243.208015) (xy 450.456808 -243.234972)
			(xy 450.456316 -243.261929) (xy 450.448466 -243.315269) (xy 450.432934 -243.366898) (xy 450.410049 -243.415715)
			(xy 450.380301 -243.460679) (xy 450.344323 -243.500833) (xy 450.302881 -243.535321) (xy 450.25686 -243.563407)
			(xy 450.20724 -243.584494) (xy 450.155079 -243.59813) (xy 450.101488 -243.604027) (xy 450.047609 -243.602058)
			(xy 449.994591 -243.592265) (xy 449.943564 -243.574857) (xy 449.895616 -243.550205) (xy 449.851768 -243.518835)
			(xy 449.812955 -243.481414) (xy 449.780003 -243.438741) (xy 449.753617 -243.391724) (xy 449.734357 -243.341367)
			(xy 449.722634 -243.288743) (xy 449.718699 -243.234972) (xy 442.913008 -243.234972) (xy 442.912516 -243.261929)
			(xy 442.904666 -243.315269) (xy 442.889134 -243.366898) (xy 442.866249 -243.415715) (xy 442.836501 -243.460679)
			(xy 442.800523 -243.500833) (xy 442.759081 -243.535321) (xy 442.71306 -243.563407) (xy 442.66344 -243.584494)
			(xy 442.611279 -243.59813) (xy 442.557688 -243.604027) (xy 442.503809 -243.602058) (xy 442.450791 -243.592265)
			(xy 442.399764 -243.574857) (xy 442.351816 -243.550205) (xy 442.307968 -243.518835) (xy 442.269155 -243.481414)
			(xy 442.236203 -243.438741) (xy 442.209817 -243.391724) (xy 442.190557 -243.341367) (xy 442.178834 -243.288743)
			(xy 442.174899 -243.234972) (xy 435.368954 -243.234972) (xy 435.368462 -243.261929) (xy 435.360612 -243.315269)
			(xy 435.34508 -243.366898) (xy 435.322195 -243.415715) (xy 435.292447 -243.460679) (xy 435.256469 -243.500833)
			(xy 435.215027 -243.535321) (xy 435.169006 -243.563407) (xy 435.119386 -243.584494) (xy 435.067225 -243.59813)
			(xy 435.013634 -243.604027) (xy 434.959755 -243.602058) (xy 434.906737 -243.592265) (xy 434.85571 -243.574857)
			(xy 434.807762 -243.550205) (xy 434.763914 -243.518835) (xy 434.725101 -243.481414) (xy 434.692149 -243.438741)
			(xy 434.665763 -243.391724) (xy 434.646503 -243.341367) (xy 434.63478 -243.288743) (xy 434.630845 -243.234972)
			(xy 427.8249 -243.234972) (xy 427.824408 -243.261929) (xy 427.816558 -243.315269) (xy 427.801026 -243.366898)
			(xy 427.778141 -243.415715) (xy 427.748393 -243.460679) (xy 427.712415 -243.500833) (xy 427.670973 -243.535321)
			(xy 427.624952 -243.563407) (xy 427.575332 -243.584494) (xy 427.523171 -243.59813) (xy 427.46958 -243.604027)
			(xy 427.415701 -243.602058) (xy 427.362683 -243.592265) (xy 427.311656 -243.574857) (xy 427.263708 -243.550205)
			(xy 427.21986 -243.518835) (xy 427.181047 -243.481414) (xy 427.148095 -243.438741) (xy 427.121709 -243.391724)
			(xy 427.102449 -243.341367) (xy 427.090726 -243.288743) (xy 427.086791 -243.234972) (xy 425.985178 -243.234972)
			(xy 425.985178 -244.08511) (xy 429.790352 -244.08511) (xy 429.790711 -244.059964) (xy 429.797468 -244.01013)
			(xy 429.803814 -243.985796) (xy 429.805043 -243.980749) (xy 429.805678 -243.970382) (xy 429.805084 -243.965222)
			(xy 429.802612 -243.943872) (xy 429.804855 -243.900956) (xy 429.815154 -243.859233) (xy 429.833138 -243.820202)
			(xy 429.858162 -243.785265) (xy 429.889327 -243.755675) (xy 429.925514 -243.732495) (xy 429.965425 -243.716557)
			(xy 430.007625 -243.708434) (xy 430.029112 -243.70792) (xy 430.296574 -243.70792) (xy 430.296574 -243.724938)
			(xy 430.311814 -243.749322) (xy 430.325022 -243.755672) (xy 430.336706 -243.761768) (xy 430.342548 -243.764816)
			(xy 430.354486 -243.767864) (xy 430.794922 -243.767864) (xy 430.819814 -243.751608) (xy 430.826164 -243.737638)
			(xy 430.830441 -243.729031) (xy 430.84425 -243.71568) (xy 430.86203 -243.708415) (xy 430.87163 -243.70792)
			(xy 431.089308 -243.70792) (xy 431.109806 -243.708355) (xy 431.150124 -243.715784) (xy 431.188448 -243.730343)
			(xy 431.223528 -243.751558) (xy 431.239168 -243.764816) (xy 431.246304 -243.770626) (xy 431.263502 -243.777132)
			(xy 431.272696 -243.777516) (xy 431.345086 -243.777516) (xy 431.358294 -243.773706) (xy 431.36439 -243.77015)
			(xy 431.386151 -243.757389) (xy 431.432398 -243.737239) (xy 431.480963 -243.723595) (xy 431.530937 -243.716713)
			(xy 431.55616 -243.716302) (xy 431.583764 -243.716769) (xy 431.638357 -243.724992) (xy 431.691114 -243.741261)
			(xy 431.740857 -243.765211) (xy 431.786475 -243.796308) (xy 431.826947 -243.833857) (xy 431.861371 -243.877019)
			(xy 431.888977 -243.92483) (xy 431.909149 -243.976222) (xy 431.921434 -244.030046) (xy 431.925561 -244.0851)
			(xy 431.92556 -244.08511) (xy 437.334406 -244.08511) (xy 437.334715 -244.062201) (xy 437.340318 -244.01673)
			(xy 437.345582 -243.994432) (xy 437.347106 -243.988336) (xy 437.347106 -243.93525) (xy 437.347516 -243.912955)
			(xy 437.356002 -243.869184) (xy 437.372891 -243.827922) (xy 437.397531 -243.790764) (xy 437.428968 -243.759148)
			(xy 437.465986 -243.734297) (xy 437.507152 -243.717173) (xy 437.550873 -243.708439) (xy 437.573166 -243.70792)
			(xy 437.840882 -243.70792) (xy 437.840882 -243.724938) (xy 437.856122 -243.749322) (xy 437.86933 -243.755926)
			(xy 437.88076 -243.761768) (xy 437.886602 -243.764816) (xy 437.89854 -243.767864) (xy 438.338722 -243.767864)
			(xy 438.363868 -243.751608) (xy 438.369964 -243.737638) (xy 438.374312 -243.729018) (xy 438.388167 -243.715602)
			(xy 438.406042 -243.708363) (xy 438.415684 -243.70792) (xy 438.633362 -243.70792) (xy 438.653858 -243.708382)
			(xy 438.694175 -243.715802) (xy 438.7325 -243.730353) (xy 438.767581 -243.751561) (xy 438.783222 -243.764816)
			(xy 438.790372 -243.770606) (xy 438.807559 -243.777124) (xy 438.81675 -243.777516) (xy 438.88914 -243.777516)
			(xy 438.902348 -243.773706) (xy 438.908444 -243.77015) (xy 438.930193 -243.757367) (xy 438.976444 -243.737223)
			(xy 439.025013 -243.723585) (xy 439.07499 -243.716709) (xy 439.100214 -243.716302) (xy 439.127814 -243.716799)
			(xy 439.182396 -243.725028) (xy 439.235143 -243.7413) (xy 439.284876 -243.765251) (xy 439.330483 -243.796347)
			(xy 439.370946 -243.833893) (xy 439.405362 -243.877051) (xy 439.432961 -243.924855) (xy 439.453127 -243.976239)
			(xy 439.46541 -244.030055) (xy 439.469535 -244.0851) (xy 439.469534 -244.08511) (xy 444.87846 -244.08511)
			(xy 444.878819 -244.059964) (xy 444.885575 -244.01013) (xy 444.891922 -243.985796) (xy 444.893151 -243.980749)
			(xy 444.893786 -243.970382) (xy 444.893192 -243.965222) (xy 444.890712 -243.943873) (xy 444.892955 -243.900955)
			(xy 444.903254 -243.859232) (xy 444.921239 -243.8202) (xy 444.946264 -243.785262) (xy 444.977431 -243.755672)
			(xy 445.013619 -243.732492) (xy 445.053531 -243.716555) (xy 445.095732 -243.708433) (xy 445.11722 -243.70792)
			(xy 445.384682 -243.70792) (xy 445.384682 -243.724938) (xy 445.399922 -243.749322) (xy 445.41313 -243.755672)
			(xy 445.424814 -243.761768) (xy 445.430656 -243.764816) (xy 445.442594 -243.767864) (xy 445.88303 -243.767864)
			(xy 445.907922 -243.751608) (xy 445.914272 -243.737638) (xy 445.918543 -243.729028) (xy 445.932355 -243.715677)
			(xy 445.950137 -243.708413) (xy 445.959738 -243.70792) (xy 446.177416 -243.70792) (xy 446.197911 -243.708408)
			(xy 446.238227 -243.71582) (xy 446.276551 -243.730364) (xy 446.311634 -243.751564) (xy 446.327276 -243.764816)
			(xy 446.334409 -243.770629) (xy 446.351609 -243.777133) (xy 446.360804 -243.777516) (xy 446.433194 -243.777516)
			(xy 446.446402 -243.773706) (xy 446.452498 -243.77015) (xy 446.474257 -243.757386) (xy 446.520504 -243.737237)
			(xy 446.569071 -243.723594) (xy 446.619045 -243.716712) (xy 446.644268 -243.716302) (xy 446.671872 -243.71677)
			(xy 446.726464 -243.724994) (xy 446.77922 -243.741263) (xy 446.828962 -243.765214) (xy 446.874578 -243.796311)
			(xy 446.91505 -243.83386) (xy 446.949473 -243.877022) (xy 446.977078 -243.924832) (xy 446.997249 -243.976223)
			(xy 447.009535 -244.030047) (xy 447.013661 -244.0851) (xy 447.01366 -244.08511) (xy 452.42226 -244.08511)
			(xy 452.422619 -244.059964) (xy 452.429375 -244.01013) (xy 452.435722 -243.985796) (xy 452.436951 -243.980749)
			(xy 452.437586 -243.970382) (xy 452.436992 -243.965222) (xy 452.434512 -243.943873) (xy 452.436755 -243.900955)
			(xy 452.447054 -243.859232) (xy 452.465039 -243.8202) (xy 452.490064 -243.785262) (xy 452.521231 -243.755672)
			(xy 452.557419 -243.732492) (xy 452.597331 -243.716555) (xy 452.639532 -243.708433) (xy 452.66102 -243.70792)
			(xy 452.928482 -243.70792) (xy 452.928482 -243.724938) (xy 452.943722 -243.749322) (xy 452.95693 -243.755672)
			(xy 452.968614 -243.761768) (xy 452.974456 -243.764816) (xy 452.986394 -243.767864) (xy 453.42683 -243.767864)
			(xy 453.451722 -243.751608) (xy 453.458072 -243.737638) (xy 453.462343 -243.729028) (xy 453.476155 -243.715677)
			(xy 453.493937 -243.708413) (xy 453.503538 -243.70792) (xy 453.721216 -243.70792) (xy 453.741711 -243.708408)
			(xy 453.782027 -243.71582) (xy 453.820351 -243.730364) (xy 453.855434 -243.751564) (xy 453.871076 -243.764816)
			(xy 453.878209 -243.770629) (xy 453.895409 -243.777133) (xy 453.904604 -243.777516) (xy 453.976994 -243.777516)
			(xy 453.990202 -243.773706) (xy 453.996298 -243.77015) (xy 454.018057 -243.757386) (xy 454.064304 -243.737237)
			(xy 454.112871 -243.723594) (xy 454.162845 -243.716712) (xy 454.188068 -243.716302) (xy 454.215672 -243.71677)
			(xy 454.270264 -243.724994) (xy 454.32302 -243.741263) (xy 454.372762 -243.765214) (xy 454.418378 -243.796311)
			(xy 454.45885 -243.83386) (xy 454.493273 -243.877022) (xy 454.520878 -243.924832) (xy 454.541049 -243.976223)
			(xy 454.553335 -244.030047) (xy 454.557461 -244.0851) (xy 454.553335 -244.140153) (xy 454.541049 -244.193977)
			(xy 454.520878 -244.245368) (xy 454.493273 -244.293178) (xy 454.45885 -244.33634) (xy 454.418378 -244.373889)
			(xy 454.372762 -244.404986) (xy 454.32302 -244.428937) (xy 454.270264 -244.445206) (xy 454.215672 -244.45343)
			(xy 454.188068 -244.453918) (xy 454.162848 -244.453476) (xy 454.112883 -244.44657) (xy 454.064321 -244.432931)
			(xy 454.018066 -244.412814) (xy 453.996298 -244.40007) (xy 453.990202 -244.396514) (xy 453.976994 -244.392704)
			(xy 453.904604 -244.392704) (xy 453.895417 -244.393115) (xy 453.878233 -244.399628) (xy 453.871076 -244.405404)
			(xy 453.85545 -244.418682) (xy 453.820377 -244.439917) (xy 453.782046 -244.454469) (xy 453.741717 -244.461859)
			(xy 453.721216 -244.4623) (xy 453.453754 -244.4623) (xy 453.453754 -244.452648) (xy 453.453404 -244.442733)
			(xy 453.445925 -244.424376) (xy 453.431946 -244.410323) (xy 453.413629 -244.402747) (xy 453.403716 -244.402356)
			(xy 452.986394 -244.402356) (xy 452.974456 -244.405404) (xy 452.968614 -244.408452) (xy 452.956422 -244.414548)
			(xy 452.956168 -244.414802) (xy 452.944992 -244.42039) (xy 452.941432 -244.422263) (xy 452.934921 -244.426984)
			(xy 452.932038 -244.429788) (xy 452.914512 -244.447314) (xy 452.907103 -244.454143) (xy 452.888511 -244.461869)
			(xy 452.878444 -244.4623) (xy 452.66102 -244.4623) (xy 452.640731 -244.461841) (xy 452.600808 -244.454588)
			(xy 452.562818 -244.440331) (xy 452.52798 -244.419524) (xy 452.497413 -244.392838) (xy 452.472097 -244.361126)
			(xy 452.452844 -244.325408) (xy 452.440271 -244.286827) (xy 452.434782 -244.246623) (xy 452.435214 -244.226334)
			(xy 452.435214 -244.1829) (xy 452.43369 -244.17655) (xy 452.428332 -244.154071) (xy 452.422603 -244.108216)
			(xy 452.42226 -244.08511) (xy 447.01366 -244.08511) (xy 447.009535 -244.140153) (xy 446.997249 -244.193977)
			(xy 446.977078 -244.245368) (xy 446.949473 -244.293178) (xy 446.91505 -244.33634) (xy 446.874578 -244.373889)
			(xy 446.828962 -244.404986) (xy 446.77922 -244.428937) (xy 446.726464 -244.445206) (xy 446.671872 -244.45343)
			(xy 446.644268 -244.453918) (xy 446.619048 -244.453476) (xy 446.569083 -244.44657) (xy 446.520521 -244.432931)
			(xy 446.474266 -244.412814) (xy 446.452498 -244.40007) (xy 446.446402 -244.396514) (xy 446.433194 -244.392704)
			(xy 446.360804 -244.392704) (xy 446.351617 -244.393115) (xy 446.334433 -244.399628) (xy 446.327276 -244.405404)
			(xy 446.31165 -244.418682) (xy 446.276577 -244.439917) (xy 446.238246 -244.454469) (xy 446.197917 -244.461859)
			(xy 446.177416 -244.4623) (xy 445.909954 -244.4623) (xy 445.909954 -244.452648) (xy 445.909604 -244.442733)
			(xy 445.902125 -244.424376) (xy 445.888146 -244.410323) (xy 445.869829 -244.402747) (xy 445.859916 -244.402356)
			(xy 445.442594 -244.402356) (xy 445.430656 -244.405404) (xy 445.424814 -244.408452) (xy 445.412622 -244.414548)
			(xy 445.412368 -244.414802) (xy 445.401192 -244.42039) (xy 445.397632 -244.422263) (xy 445.391121 -244.426984)
			(xy 445.388238 -244.429788) (xy 445.370712 -244.447314) (xy 445.363303 -244.454143) (xy 445.344711 -244.461869)
			(xy 445.334644 -244.4623) (xy 445.11722 -244.4623) (xy 445.096931 -244.461841) (xy 445.057008 -244.454588)
			(xy 445.019018 -244.440331) (xy 444.98418 -244.419524) (xy 444.953613 -244.392838) (xy 444.928297 -244.361126)
			(xy 444.909044 -244.325408) (xy 444.896471 -244.286827) (xy 444.890982 -244.246623) (xy 444.891414 -244.226334)
			(xy 444.891414 -244.1829) (xy 444.88989 -244.17655) (xy 444.884532 -244.154071) (xy 444.878803 -244.108216)
			(xy 444.87846 -244.08511) (xy 439.469534 -244.08511) (xy 439.46541 -244.140145) (xy 439.453127 -244.193961)
			(xy 439.432961 -244.245345) (xy 439.405362 -244.293149) (xy 439.370946 -244.336307) (xy 439.330483 -244.373853)
			(xy 439.284876 -244.404949) (xy 439.235143 -244.4289) (xy 439.182396 -244.445172) (xy 439.127814 -244.453401)
			(xy 439.100214 -244.453918) (xy 439.074995 -244.453455) (xy 439.02503 -244.446555) (xy 438.976468 -244.432923)
			(xy 438.930212 -244.412812) (xy 438.908444 -244.40007) (xy 438.902348 -244.396514) (xy 438.88914 -244.392704)
			(xy 438.81675 -244.392704) (xy 438.807565 -244.393137) (xy 438.790381 -244.399635) (xy 438.783222 -244.405404)
			(xy 438.767616 -244.418707) (xy 438.732536 -244.439937) (xy 438.694199 -244.454483) (xy 438.653864 -244.461864)
			(xy 438.633362 -244.4623) (xy 438.365646 -244.4623) (xy 438.365646 -244.452648) (xy 438.365212 -244.442789)
			(xy 438.35776 -244.424537) (xy 438.343891 -244.410527) (xy 438.325716 -244.402888) (xy 438.315862 -244.402356)
			(xy 437.89854 -244.402356) (xy 437.886602 -244.405404) (xy 437.88076 -244.408452) (xy 437.868568 -244.414548)
			(xy 437.868314 -244.414802) (xy 437.857392 -244.42039) (xy 437.853999 -244.422191) (xy 437.84775 -244.426655)
			(xy 437.844946 -244.42928) (xy 437.82615 -244.447822) (xy 437.818741 -244.454365) (xy 437.800461 -244.461827)
			(xy 437.79059 -244.4623) (xy 437.573166 -244.4623) (xy 437.550873 -244.461778) (xy 437.50715 -244.453044)
			(xy 437.465983 -244.435921) (xy 437.428964 -244.411071) (xy 437.397525 -244.379456) (xy 437.372883 -244.342299)
			(xy 437.35599 -244.301036) (xy 437.347501 -244.257266) (xy 437.347106 -244.23497) (xy 437.347106 -244.181884)
			(xy 437.345582 -244.175788) (xy 437.340319 -244.15349) (xy 437.33472 -244.108018) (xy 437.334406 -244.08511)
			(xy 431.92556 -244.08511) (xy 431.921434 -244.140154) (xy 431.909149 -244.193978) (xy 431.888977 -244.24537)
			(xy 431.861371 -244.293181) (xy 431.826947 -244.336343) (xy 431.786475 -244.373892) (xy 431.740857 -244.404989)
			(xy 431.691114 -244.428939) (xy 431.638357 -244.445208) (xy 431.583764 -244.453431) (xy 431.55616 -244.453918)
			(xy 431.53094 -244.453479) (xy 431.480974 -244.446572) (xy 431.432413 -244.432933) (xy 431.386157 -244.412815)
			(xy 431.36439 -244.40007) (xy 431.358294 -244.396514) (xy 431.345086 -244.392704) (xy 431.272696 -244.392704)
			(xy 431.263509 -244.393111) (xy 431.246324 -244.399627) (xy 431.239168 -244.405404) (xy 431.223545 -244.418685)
			(xy 431.188471 -244.43992) (xy 431.150139 -244.454471) (xy 431.109809 -244.46186) (xy 431.089308 -244.4623)
			(xy 430.821846 -244.4623) (xy 430.821846 -244.452648) (xy 430.821504 -244.442732) (xy 430.814024 -244.424374)
			(xy 430.800042 -244.41032) (xy 430.781722 -244.402745) (xy 430.771808 -244.402356) (xy 430.354486 -244.402356)
			(xy 430.342548 -244.405404) (xy 430.336706 -244.408452) (xy 430.324514 -244.414548) (xy 430.32426 -244.414802)
			(xy 430.313084 -244.42039) (xy 430.309524 -244.422261) (xy 430.303013 -244.426983) (xy 430.30013 -244.429788)
			(xy 430.282604 -244.447314) (xy 430.275198 -244.454147) (xy 430.256603 -244.46187) (xy 430.246536 -244.4623)
			(xy 430.029112 -244.4623) (xy 430.008823 -244.461848) (xy 429.968899 -244.454594) (xy 429.930909 -244.440335)
			(xy 429.896072 -244.419528) (xy 429.865505 -244.392841) (xy 429.840189 -244.361128) (xy 429.820936 -244.325409)
			(xy 429.808363 -244.286828) (xy 429.802874 -244.246623) (xy 429.803306 -244.226334) (xy 429.803306 -244.1829)
			(xy 429.801782 -244.17655) (xy 429.796424 -244.154071) (xy 429.790695 -244.108216) (xy 429.790352 -244.08511)
			(xy 425.985178 -244.08511) (xy 425.985178 -244.934994) (xy 427.086791 -244.934994) (xy 427.090726 -244.881223)
			(xy 427.102449 -244.828599) (xy 427.121709 -244.778242) (xy 427.148095 -244.731225) (xy 427.181047 -244.688552)
			(xy 427.21986 -244.651131) (xy 427.263708 -244.619761) (xy 427.311656 -244.595109) (xy 427.362683 -244.577701)
			(xy 427.415701 -244.567908) (xy 427.46958 -244.565939) (xy 427.523171 -244.571836) (xy 427.575332 -244.585472)
			(xy 427.624952 -244.606559) (xy 427.670973 -244.634645) (xy 427.712415 -244.669133) (xy 427.748393 -244.709287)
			(xy 427.778141 -244.754251) (xy 427.801026 -244.803068) (xy 427.816558 -244.854697) (xy 427.824408 -244.908037)
			(xy 427.8249 -244.934994) (xy 434.630845 -244.934994) (xy 434.63478 -244.881223) (xy 434.646503 -244.828599)
			(xy 434.665763 -244.778242) (xy 434.692149 -244.731225) (xy 434.725101 -244.688552) (xy 434.763914 -244.651131)
			(xy 434.807762 -244.619761) (xy 434.85571 -244.595109) (xy 434.906737 -244.577701) (xy 434.959755 -244.567908)
			(xy 435.013634 -244.565939) (xy 435.067225 -244.571836) (xy 435.119386 -244.585472) (xy 435.169006 -244.606559)
			(xy 435.215027 -244.634645) (xy 435.256469 -244.669133) (xy 435.292447 -244.709287) (xy 435.322195 -244.754251)
			(xy 435.34508 -244.803068) (xy 435.360612 -244.854697) (xy 435.368462 -244.908037) (xy 435.368954 -244.934994)
			(xy 442.174899 -244.934994) (xy 442.178834 -244.881223) (xy 442.190557 -244.828599) (xy 442.209817 -244.778242)
			(xy 442.236203 -244.731225) (xy 442.269155 -244.688552) (xy 442.307968 -244.651131) (xy 442.351816 -244.619761)
			(xy 442.399764 -244.595109) (xy 442.450791 -244.577701) (xy 442.503809 -244.567908) (xy 442.557688 -244.565939)
			(xy 442.611279 -244.571836) (xy 442.66344 -244.585472) (xy 442.71306 -244.606559) (xy 442.759081 -244.634645)
			(xy 442.800523 -244.669133) (xy 442.836501 -244.709287) (xy 442.866249 -244.754251) (xy 442.889134 -244.803068)
			(xy 442.904666 -244.854697) (xy 442.912516 -244.908037) (xy 442.913008 -244.934994) (xy 449.718699 -244.934994)
			(xy 449.722634 -244.881223) (xy 449.734357 -244.828599) (xy 449.753617 -244.778242) (xy 449.780003 -244.731225)
			(xy 449.812955 -244.688552) (xy 449.851768 -244.651131) (xy 449.895616 -244.619761) (xy 449.943564 -244.595109)
			(xy 449.994591 -244.577701) (xy 450.047609 -244.567908) (xy 450.101488 -244.565939) (xy 450.155079 -244.571836)
			(xy 450.20724 -244.585472) (xy 450.25686 -244.606559) (xy 450.302881 -244.634645) (xy 450.344323 -244.669133)
			(xy 450.380301 -244.709287) (xy 450.410049 -244.754251) (xy 450.432934 -244.803068) (xy 450.448466 -244.854697)
			(xy 450.456316 -244.908037) (xy 450.456808 -244.934994) (xy 450.456316 -244.961951) (xy 450.448466 -245.015291)
			(xy 450.432934 -245.06692) (xy 450.410049 -245.115737) (xy 450.380301 -245.160701) (xy 450.344323 -245.200855)
			(xy 450.302881 -245.235343) (xy 450.25686 -245.263429) (xy 450.20724 -245.284516) (xy 450.155079 -245.298152)
			(xy 450.101488 -245.304049) (xy 450.047609 -245.30208) (xy 449.994591 -245.292287) (xy 449.943564 -245.274879)
			(xy 449.895616 -245.250227) (xy 449.851768 -245.218857) (xy 449.812955 -245.181436) (xy 449.780003 -245.138763)
			(xy 449.753617 -245.091746) (xy 449.734357 -245.041389) (xy 449.722634 -244.988765) (xy 449.718699 -244.934994)
			(xy 442.913008 -244.934994) (xy 442.912516 -244.961951) (xy 442.904666 -245.015291) (xy 442.889134 -245.06692)
			(xy 442.866249 -245.115737) (xy 442.836501 -245.160701) (xy 442.800523 -245.200855) (xy 442.759081 -245.235343)
			(xy 442.71306 -245.263429) (xy 442.66344 -245.284516) (xy 442.611279 -245.298152) (xy 442.557688 -245.304049)
			(xy 442.503809 -245.30208) (xy 442.450791 -245.292287) (xy 442.399764 -245.274879) (xy 442.351816 -245.250227)
			(xy 442.307968 -245.218857) (xy 442.269155 -245.181436) (xy 442.236203 -245.138763) (xy 442.209817 -245.091746)
			(xy 442.190557 -245.041389) (xy 442.178834 -244.988765) (xy 442.174899 -244.934994) (xy 435.368954 -244.934994)
			(xy 435.368462 -244.961951) (xy 435.360612 -245.015291) (xy 435.34508 -245.06692) (xy 435.322195 -245.115737)
			(xy 435.292447 -245.160701) (xy 435.256469 -245.200855) (xy 435.215027 -245.235343) (xy 435.169006 -245.263429)
			(xy 435.119386 -245.284516) (xy 435.067225 -245.298152) (xy 435.013634 -245.304049) (xy 434.959755 -245.30208)
			(xy 434.906737 -245.292287) (xy 434.85571 -245.274879) (xy 434.807762 -245.250227) (xy 434.763914 -245.218857)
			(xy 434.725101 -245.181436) (xy 434.692149 -245.138763) (xy 434.665763 -245.091746) (xy 434.646503 -245.041389)
			(xy 434.63478 -244.988765) (xy 434.630845 -244.934994) (xy 427.8249 -244.934994) (xy 427.824408 -244.961951)
			(xy 427.816558 -245.015291) (xy 427.801026 -245.06692) (xy 427.778141 -245.115737) (xy 427.748393 -245.160701)
			(xy 427.712415 -245.200855) (xy 427.670973 -245.235343) (xy 427.624952 -245.263429) (xy 427.575332 -245.284516)
			(xy 427.523171 -245.298152) (xy 427.46958 -245.304049) (xy 427.415701 -245.30208) (xy 427.362683 -245.292287)
			(xy 427.311656 -245.274879) (xy 427.263708 -245.250227) (xy 427.21986 -245.218857) (xy 427.181047 -245.181436)
			(xy 427.148095 -245.138763) (xy 427.121709 -245.091746) (xy 427.102449 -245.041389) (xy 427.090726 -244.988765)
			(xy 427.086791 -244.934994) (xy 425.985178 -244.934994) (xy 425.985178 -245.785132) (xy 431.186859 -245.785132)
			(xy 431.190794 -245.731361) (xy 431.202517 -245.678737) (xy 431.221777 -245.62838) (xy 431.248163 -245.581363)
			(xy 431.281115 -245.53869) (xy 431.319928 -245.501269) (xy 431.363776 -245.469899) (xy 431.411724 -245.445247)
			(xy 431.462751 -245.427839) (xy 431.515769 -245.418046) (xy 431.569648 -245.416077) (xy 431.623239 -245.421974)
			(xy 431.6754 -245.43561) (xy 431.72502 -245.456697) (xy 431.771041 -245.484783) (xy 431.812483 -245.519271)
			(xy 431.848461 -245.559425) (xy 431.878209 -245.604389) (xy 431.901094 -245.653206) (xy 431.916626 -245.704835)
			(xy 431.924476 -245.758175) (xy 431.924968 -245.785132) (xy 438.730913 -245.785132) (xy 438.734848 -245.731361)
			(xy 438.746571 -245.678737) (xy 438.765831 -245.62838) (xy 438.792217 -245.581363) (xy 438.825169 -245.53869)
			(xy 438.863982 -245.501269) (xy 438.90783 -245.469899) (xy 438.955778 -245.445247) (xy 439.006805 -245.427839)
			(xy 439.059823 -245.418046) (xy 439.113702 -245.416077) (xy 439.167293 -245.421974) (xy 439.219454 -245.43561)
			(xy 439.269074 -245.456697) (xy 439.315095 -245.484783) (xy 439.356537 -245.519271) (xy 439.392515 -245.559425)
			(xy 439.422263 -245.604389) (xy 439.445148 -245.653206) (xy 439.46068 -245.704835) (xy 439.46853 -245.758175)
			(xy 439.469022 -245.785132) (xy 446.274967 -245.785132) (xy 446.278902 -245.731361) (xy 446.290625 -245.678737)
			(xy 446.309885 -245.62838) (xy 446.336271 -245.581363) (xy 446.369223 -245.53869) (xy 446.408036 -245.501269)
			(xy 446.451884 -245.469899) (xy 446.499832 -245.445247) (xy 446.550859 -245.427839) (xy 446.603877 -245.418046)
			(xy 446.657756 -245.416077) (xy 446.711347 -245.421974) (xy 446.763508 -245.43561) (xy 446.813128 -245.456697)
			(xy 446.859149 -245.484783) (xy 446.900591 -245.519271) (xy 446.936569 -245.559425) (xy 446.966317 -245.604389)
			(xy 446.989202 -245.653206) (xy 447.004734 -245.704835) (xy 447.012584 -245.758175) (xy 447.013076 -245.785132)
			(xy 453.818767 -245.785132) (xy 453.822702 -245.731361) (xy 453.834425 -245.678737) (xy 453.853685 -245.62838)
			(xy 453.880071 -245.581363) (xy 453.913023 -245.53869) (xy 453.951836 -245.501269) (xy 453.995684 -245.469899)
			(xy 454.043632 -245.445247) (xy 454.094659 -245.427839) (xy 454.147677 -245.418046) (xy 454.201556 -245.416077)
			(xy 454.255147 -245.421974) (xy 454.307308 -245.43561) (xy 454.356928 -245.456697) (xy 454.402949 -245.484783)
			(xy 454.444391 -245.519271) (xy 454.480369 -245.559425) (xy 454.510117 -245.604389) (xy 454.533002 -245.653206)
			(xy 454.548534 -245.704835) (xy 454.556384 -245.758175) (xy 454.556876 -245.785132) (xy 454.556384 -245.812089)
			(xy 454.548534 -245.865429) (xy 454.533002 -245.917058) (xy 454.510117 -245.965875) (xy 454.480369 -246.010839)
			(xy 454.444391 -246.050993) (xy 454.402949 -246.085481) (xy 454.356928 -246.113567) (xy 454.307308 -246.134654)
			(xy 454.255147 -246.14829) (xy 454.201556 -246.154187) (xy 454.147677 -246.152218) (xy 454.094659 -246.142425)
			(xy 454.043632 -246.125017) (xy 453.995684 -246.100365) (xy 453.951836 -246.068995) (xy 453.913023 -246.031574)
			(xy 453.880071 -245.988901) (xy 453.853685 -245.941884) (xy 453.834425 -245.891527) (xy 453.822702 -245.838903)
			(xy 453.818767 -245.785132) (xy 447.013076 -245.785132) (xy 447.012584 -245.812089) (xy 447.004734 -245.865429)
			(xy 446.989202 -245.917058) (xy 446.966317 -245.965875) (xy 446.936569 -246.010839) (xy 446.900591 -246.050993)
			(xy 446.859149 -246.085481) (xy 446.813128 -246.113567) (xy 446.763508 -246.134654) (xy 446.711347 -246.14829)
			(xy 446.657756 -246.154187) (xy 446.603877 -246.152218) (xy 446.550859 -246.142425) (xy 446.499832 -246.125017)
			(xy 446.451884 -246.100365) (xy 446.408036 -246.068995) (xy 446.369223 -246.031574) (xy 446.336271 -245.988901)
			(xy 446.309885 -245.941884) (xy 446.290625 -245.891527) (xy 446.278902 -245.838903) (xy 446.274967 -245.785132)
			(xy 439.469022 -245.785132) (xy 439.46853 -245.812089) (xy 439.46068 -245.865429) (xy 439.445148 -245.917058)
			(xy 439.422263 -245.965875) (xy 439.392515 -246.010839) (xy 439.356537 -246.050993) (xy 439.315095 -246.085481)
			(xy 439.269074 -246.113567) (xy 439.219454 -246.134654) (xy 439.167293 -246.14829) (xy 439.113702 -246.154187)
			(xy 439.059823 -246.152218) (xy 439.006805 -246.142425) (xy 438.955778 -246.125017) (xy 438.90783 -246.100365)
			(xy 438.863982 -246.068995) (xy 438.825169 -246.031574) (xy 438.792217 -245.988901) (xy 438.765831 -245.941884)
			(xy 438.746571 -245.891527) (xy 438.734848 -245.838903) (xy 438.730913 -245.785132) (xy 431.924968 -245.785132)
			(xy 431.924476 -245.812089) (xy 431.916626 -245.865429) (xy 431.901094 -245.917058) (xy 431.878209 -245.965875)
			(xy 431.848461 -246.010839) (xy 431.812483 -246.050993) (xy 431.771041 -246.085481) (xy 431.72502 -246.113567)
			(xy 431.6754 -246.134654) (xy 431.623239 -246.14829) (xy 431.569648 -246.154187) (xy 431.515769 -246.152218)
			(xy 431.462751 -246.142425) (xy 431.411724 -246.125017) (xy 431.363776 -246.100365) (xy 431.319928 -246.068995)
			(xy 431.281115 -246.031574) (xy 431.248163 -245.988901) (xy 431.221777 -245.941884) (xy 431.202517 -245.891527)
			(xy 431.190794 -245.838903) (xy 431.186859 -245.785132) (xy 425.985178 -245.785132) (xy 425.985178 -246.635016)
			(xy 427.086791 -246.635016) (xy 427.090726 -246.581245) (xy 427.102449 -246.528621) (xy 427.121709 -246.478264)
			(xy 427.148095 -246.431247) (xy 427.181047 -246.388574) (xy 427.21986 -246.351153) (xy 427.263708 -246.319783)
			(xy 427.311656 -246.295131) (xy 427.362683 -246.277723) (xy 427.415701 -246.26793) (xy 427.46958 -246.265961)
			(xy 427.523171 -246.271858) (xy 427.575332 -246.285494) (xy 427.624952 -246.306581) (xy 427.670973 -246.334667)
			(xy 427.712415 -246.369155) (xy 427.748393 -246.409309) (xy 427.778141 -246.454273) (xy 427.801026 -246.50309)
			(xy 427.816558 -246.554719) (xy 427.824408 -246.608059) (xy 427.8249 -246.635016) (xy 434.630845 -246.635016)
			(xy 434.63478 -246.581245) (xy 434.646503 -246.528621) (xy 434.665763 -246.478264) (xy 434.692149 -246.431247)
			(xy 434.725101 -246.388574) (xy 434.763914 -246.351153) (xy 434.807762 -246.319783) (xy 434.85571 -246.295131)
			(xy 434.906737 -246.277723) (xy 434.959755 -246.26793) (xy 435.013634 -246.265961) (xy 435.067225 -246.271858)
			(xy 435.119386 -246.285494) (xy 435.169006 -246.306581) (xy 435.215027 -246.334667) (xy 435.256469 -246.369155)
			(xy 435.292447 -246.409309) (xy 435.322195 -246.454273) (xy 435.34508 -246.50309) (xy 435.360612 -246.554719)
			(xy 435.368462 -246.608059) (xy 435.368954 -246.635016) (xy 442.174899 -246.635016) (xy 442.178834 -246.581245)
			(xy 442.190557 -246.528621) (xy 442.209817 -246.478264) (xy 442.236203 -246.431247) (xy 442.269155 -246.388574)
			(xy 442.307968 -246.351153) (xy 442.351816 -246.319783) (xy 442.399764 -246.295131) (xy 442.450791 -246.277723)
			(xy 442.503809 -246.26793) (xy 442.557688 -246.265961) (xy 442.611279 -246.271858) (xy 442.66344 -246.285494)
			(xy 442.71306 -246.306581) (xy 442.759081 -246.334667) (xy 442.800523 -246.369155) (xy 442.836501 -246.409309)
			(xy 442.866249 -246.454273) (xy 442.889134 -246.50309) (xy 442.904666 -246.554719) (xy 442.912516 -246.608059)
			(xy 442.913008 -246.635016) (xy 449.718699 -246.635016) (xy 449.722634 -246.581245) (xy 449.734357 -246.528621)
			(xy 449.753617 -246.478264) (xy 449.780003 -246.431247) (xy 449.812955 -246.388574) (xy 449.851768 -246.351153)
			(xy 449.895616 -246.319783) (xy 449.943564 -246.295131) (xy 449.994591 -246.277723) (xy 450.047609 -246.26793)
			(xy 450.101488 -246.265961) (xy 450.155079 -246.271858) (xy 450.20724 -246.285494) (xy 450.25686 -246.306581)
			(xy 450.302881 -246.334667) (xy 450.344323 -246.369155) (xy 450.380301 -246.409309) (xy 450.410049 -246.454273)
			(xy 450.432934 -246.50309) (xy 450.448466 -246.554719) (xy 450.456316 -246.608059) (xy 450.456808 -246.635016)
			(xy 450.456316 -246.661973) (xy 450.448466 -246.715313) (xy 450.432934 -246.766942) (xy 450.410049 -246.815759)
			(xy 450.380301 -246.860723) (xy 450.344323 -246.900877) (xy 450.302881 -246.935365) (xy 450.25686 -246.963451)
			(xy 450.20724 -246.984538) (xy 450.155079 -246.998174) (xy 450.101488 -247.004071) (xy 450.047609 -247.002102)
			(xy 449.994591 -246.992309) (xy 449.943564 -246.974901) (xy 449.895616 -246.950249) (xy 449.851768 -246.918879)
			(xy 449.812955 -246.881458) (xy 449.780003 -246.838785) (xy 449.753617 -246.791768) (xy 449.734357 -246.741411)
			(xy 449.722634 -246.688787) (xy 449.718699 -246.635016) (xy 442.913008 -246.635016) (xy 442.912516 -246.661973)
			(xy 442.904666 -246.715313) (xy 442.889134 -246.766942) (xy 442.866249 -246.815759) (xy 442.836501 -246.860723)
			(xy 442.800523 -246.900877) (xy 442.759081 -246.935365) (xy 442.71306 -246.963451) (xy 442.66344 -246.984538)
			(xy 442.611279 -246.998174) (xy 442.557688 -247.004071) (xy 442.503809 -247.002102) (xy 442.450791 -246.992309)
			(xy 442.399764 -246.974901) (xy 442.351816 -246.950249) (xy 442.307968 -246.918879) (xy 442.269155 -246.881458)
			(xy 442.236203 -246.838785) (xy 442.209817 -246.791768) (xy 442.190557 -246.741411) (xy 442.178834 -246.688787)
			(xy 442.174899 -246.635016) (xy 435.368954 -246.635016) (xy 435.368462 -246.661973) (xy 435.360612 -246.715313)
			(xy 435.34508 -246.766942) (xy 435.322195 -246.815759) (xy 435.292447 -246.860723) (xy 435.256469 -246.900877)
			(xy 435.215027 -246.935365) (xy 435.169006 -246.963451) (xy 435.119386 -246.984538) (xy 435.067225 -246.998174)
			(xy 435.013634 -247.004071) (xy 434.959755 -247.002102) (xy 434.906737 -246.992309) (xy 434.85571 -246.974901)
			(xy 434.807762 -246.950249) (xy 434.763914 -246.918879) (xy 434.725101 -246.881458) (xy 434.692149 -246.838785)
			(xy 434.665763 -246.791768) (xy 434.646503 -246.741411) (xy 434.63478 -246.688787) (xy 434.630845 -246.635016)
			(xy 427.8249 -246.635016) (xy 427.824408 -246.661973) (xy 427.816558 -246.715313) (xy 427.801026 -246.766942)
			(xy 427.778141 -246.815759) (xy 427.748393 -246.860723) (xy 427.712415 -246.900877) (xy 427.670973 -246.935365)
			(xy 427.624952 -246.963451) (xy 427.575332 -246.984538) (xy 427.523171 -246.998174) (xy 427.46958 -247.004071)
			(xy 427.415701 -247.002102) (xy 427.362683 -246.992309) (xy 427.311656 -246.974901) (xy 427.263708 -246.950249)
			(xy 427.21986 -246.918879) (xy 427.181047 -246.881458) (xy 427.148095 -246.838785) (xy 427.121709 -246.791768)
			(xy 427.102449 -246.741411) (xy 427.090726 -246.688787) (xy 427.086791 -246.635016) (xy 425.985178 -246.635016)
			(xy 425.985178 -247.485154) (xy 431.186859 -247.485154) (xy 431.190794 -247.431383) (xy 431.202517 -247.378759)
			(xy 431.221777 -247.328402) (xy 431.248163 -247.281385) (xy 431.281115 -247.238712) (xy 431.319928 -247.201291)
			(xy 431.363776 -247.169921) (xy 431.411724 -247.145269) (xy 431.462751 -247.127861) (xy 431.515769 -247.118068)
			(xy 431.569648 -247.116099) (xy 431.623239 -247.121996) (xy 431.6754 -247.135632) (xy 431.72502 -247.156719)
			(xy 431.771041 -247.184805) (xy 431.812483 -247.219293) (xy 431.848461 -247.259447) (xy 431.878209 -247.304411)
			(xy 431.901094 -247.353228) (xy 431.916626 -247.404857) (xy 431.924476 -247.458197) (xy 431.924968 -247.485154)
			(xy 438.730913 -247.485154) (xy 438.734848 -247.431383) (xy 438.746571 -247.378759) (xy 438.765831 -247.328402)
			(xy 438.792217 -247.281385) (xy 438.825169 -247.238712) (xy 438.863982 -247.201291) (xy 438.90783 -247.169921)
			(xy 438.955778 -247.145269) (xy 439.006805 -247.127861) (xy 439.059823 -247.118068) (xy 439.113702 -247.116099)
			(xy 439.167293 -247.121996) (xy 439.219454 -247.135632) (xy 439.269074 -247.156719) (xy 439.315095 -247.184805)
			(xy 439.356537 -247.219293) (xy 439.392515 -247.259447) (xy 439.422263 -247.304411) (xy 439.445148 -247.353228)
			(xy 439.46068 -247.404857) (xy 439.46853 -247.458197) (xy 439.469022 -247.485154) (xy 446.274967 -247.485154)
			(xy 446.278902 -247.431383) (xy 446.290625 -247.378759) (xy 446.309885 -247.328402) (xy 446.336271 -247.281385)
			(xy 446.369223 -247.238712) (xy 446.408036 -247.201291) (xy 446.451884 -247.169921) (xy 446.499832 -247.145269)
			(xy 446.550859 -247.127861) (xy 446.603877 -247.118068) (xy 446.657756 -247.116099) (xy 446.711347 -247.121996)
			(xy 446.763508 -247.135632) (xy 446.813128 -247.156719) (xy 446.859149 -247.184805) (xy 446.900591 -247.219293)
			(xy 446.936569 -247.259447) (xy 446.966317 -247.304411) (xy 446.989202 -247.353228) (xy 447.004734 -247.404857)
			(xy 447.012584 -247.458197) (xy 447.013076 -247.485154) (xy 453.818767 -247.485154) (xy 453.822702 -247.431383)
			(xy 453.834425 -247.378759) (xy 453.853685 -247.328402) (xy 453.880071 -247.281385) (xy 453.913023 -247.238712)
			(xy 453.951836 -247.201291) (xy 453.995684 -247.169921) (xy 454.043632 -247.145269) (xy 454.094659 -247.127861)
			(xy 454.147677 -247.118068) (xy 454.201556 -247.116099) (xy 454.255147 -247.121996) (xy 454.307308 -247.135632)
			(xy 454.356928 -247.156719) (xy 454.402949 -247.184805) (xy 454.444391 -247.219293) (xy 454.480369 -247.259447)
			(xy 454.510117 -247.304411) (xy 454.533002 -247.353228) (xy 454.548534 -247.404857) (xy 454.556384 -247.458197)
			(xy 454.556876 -247.485154) (xy 454.556384 -247.512111) (xy 454.548534 -247.565451) (xy 454.533002 -247.61708)
			(xy 454.510117 -247.665897) (xy 454.480369 -247.710861) (xy 454.444391 -247.751015) (xy 454.402949 -247.785503)
			(xy 454.356928 -247.813589) (xy 454.307308 -247.834676) (xy 454.255147 -247.848312) (xy 454.201556 -247.854209)
			(xy 454.147677 -247.85224) (xy 454.094659 -247.842447) (xy 454.043632 -247.825039) (xy 453.995684 -247.800387)
			(xy 453.951836 -247.769017) (xy 453.913023 -247.731596) (xy 453.880071 -247.688923) (xy 453.853685 -247.641906)
			(xy 453.834425 -247.591549) (xy 453.822702 -247.538925) (xy 453.818767 -247.485154) (xy 447.013076 -247.485154)
			(xy 447.012584 -247.512111) (xy 447.004734 -247.565451) (xy 446.989202 -247.61708) (xy 446.966317 -247.665897)
			(xy 446.936569 -247.710861) (xy 446.900591 -247.751015) (xy 446.859149 -247.785503) (xy 446.813128 -247.813589)
			(xy 446.763508 -247.834676) (xy 446.711347 -247.848312) (xy 446.657756 -247.854209) (xy 446.603877 -247.85224)
			(xy 446.550859 -247.842447) (xy 446.499832 -247.825039) (xy 446.451884 -247.800387) (xy 446.408036 -247.769017)
			(xy 446.369223 -247.731596) (xy 446.336271 -247.688923) (xy 446.309885 -247.641906) (xy 446.290625 -247.591549)
			(xy 446.278902 -247.538925) (xy 446.274967 -247.485154) (xy 439.469022 -247.485154) (xy 439.46853 -247.512111)
			(xy 439.46068 -247.565451) (xy 439.445148 -247.61708) (xy 439.422263 -247.665897) (xy 439.392515 -247.710861)
			(xy 439.356537 -247.751015) (xy 439.315095 -247.785503) (xy 439.269074 -247.813589) (xy 439.219454 -247.834676)
			(xy 439.167293 -247.848312) (xy 439.113702 -247.854209) (xy 439.059823 -247.85224) (xy 439.006805 -247.842447)
			(xy 438.955778 -247.825039) (xy 438.90783 -247.800387) (xy 438.863982 -247.769017) (xy 438.825169 -247.731596)
			(xy 438.792217 -247.688923) (xy 438.765831 -247.641906) (xy 438.746571 -247.591549) (xy 438.734848 -247.538925)
			(xy 438.730913 -247.485154) (xy 431.924968 -247.485154) (xy 431.924476 -247.512111) (xy 431.916626 -247.565451)
			(xy 431.901094 -247.61708) (xy 431.878209 -247.665897) (xy 431.848461 -247.710861) (xy 431.812483 -247.751015)
			(xy 431.771041 -247.785503) (xy 431.72502 -247.813589) (xy 431.6754 -247.834676) (xy 431.623239 -247.848312)
			(xy 431.569648 -247.854209) (xy 431.515769 -247.85224) (xy 431.462751 -247.842447) (xy 431.411724 -247.825039)
			(xy 431.363776 -247.800387) (xy 431.319928 -247.769017) (xy 431.281115 -247.731596) (xy 431.248163 -247.688923)
			(xy 431.221777 -247.641906) (xy 431.202517 -247.591549) (xy 431.190794 -247.538925) (xy 431.186859 -247.485154)
			(xy 425.985178 -247.485154) (xy 425.985178 -248.335038) (xy 427.086791 -248.335038) (xy 427.090726 -248.281267)
			(xy 427.102449 -248.228643) (xy 427.121709 -248.178286) (xy 427.148095 -248.131269) (xy 427.181047 -248.088596)
			(xy 427.21986 -248.051175) (xy 427.263708 -248.019805) (xy 427.311656 -247.995153) (xy 427.362683 -247.977745)
			(xy 427.415701 -247.967952) (xy 427.46958 -247.965983) (xy 427.523171 -247.97188) (xy 427.575332 -247.985516)
			(xy 427.624952 -248.006603) (xy 427.670973 -248.034689) (xy 427.712415 -248.069177) (xy 427.748393 -248.109331)
			(xy 427.778141 -248.154295) (xy 427.801026 -248.203112) (xy 427.816558 -248.254741) (xy 427.824408 -248.308081)
			(xy 427.8249 -248.335038) (xy 434.630845 -248.335038) (xy 434.63478 -248.281267) (xy 434.646503 -248.228643)
			(xy 434.665763 -248.178286) (xy 434.692149 -248.131269) (xy 434.725101 -248.088596) (xy 434.763914 -248.051175)
			(xy 434.807762 -248.019805) (xy 434.85571 -247.995153) (xy 434.906737 -247.977745) (xy 434.959755 -247.967952)
			(xy 435.013634 -247.965983) (xy 435.067225 -247.97188) (xy 435.119386 -247.985516) (xy 435.169006 -248.006603)
			(xy 435.215027 -248.034689) (xy 435.256469 -248.069177) (xy 435.292447 -248.109331) (xy 435.322195 -248.154295)
			(xy 435.34508 -248.203112) (xy 435.360612 -248.254741) (xy 435.368462 -248.308081) (xy 435.368954 -248.335038)
			(xy 442.174899 -248.335038) (xy 442.178834 -248.281267) (xy 442.190557 -248.228643) (xy 442.209817 -248.178286)
			(xy 442.236203 -248.131269) (xy 442.269155 -248.088596) (xy 442.307968 -248.051175) (xy 442.351816 -248.019805)
			(xy 442.399764 -247.995153) (xy 442.450791 -247.977745) (xy 442.503809 -247.967952) (xy 442.557688 -247.965983)
			(xy 442.611279 -247.97188) (xy 442.66344 -247.985516) (xy 442.71306 -248.006603) (xy 442.759081 -248.034689)
			(xy 442.800523 -248.069177) (xy 442.836501 -248.109331) (xy 442.866249 -248.154295) (xy 442.889134 -248.203112)
			(xy 442.904666 -248.254741) (xy 442.912516 -248.308081) (xy 442.913008 -248.335038) (xy 449.718699 -248.335038)
			(xy 449.722634 -248.281267) (xy 449.734357 -248.228643) (xy 449.753617 -248.178286) (xy 449.780003 -248.131269)
			(xy 449.812955 -248.088596) (xy 449.851768 -248.051175) (xy 449.895616 -248.019805) (xy 449.943564 -247.995153)
			(xy 449.994591 -247.977745) (xy 450.047609 -247.967952) (xy 450.101488 -247.965983) (xy 450.155079 -247.97188)
			(xy 450.20724 -247.985516) (xy 450.25686 -248.006603) (xy 450.302881 -248.034689) (xy 450.344323 -248.069177)
			(xy 450.380301 -248.109331) (xy 450.410049 -248.154295) (xy 450.432934 -248.203112) (xy 450.448466 -248.254741)
			(xy 450.456316 -248.308081) (xy 450.456808 -248.335038) (xy 450.456316 -248.361995) (xy 450.448466 -248.415335)
			(xy 450.432934 -248.466964) (xy 450.410049 -248.515781) (xy 450.380301 -248.560745) (xy 450.344323 -248.600899)
			(xy 450.302881 -248.635387) (xy 450.25686 -248.663473) (xy 450.20724 -248.68456) (xy 450.155079 -248.698196)
			(xy 450.101488 -248.704093) (xy 450.047609 -248.702124) (xy 449.994591 -248.692331) (xy 449.943564 -248.674923)
			(xy 449.895616 -248.650271) (xy 449.851768 -248.618901) (xy 449.812955 -248.58148) (xy 449.780003 -248.538807)
			(xy 449.753617 -248.49179) (xy 449.734357 -248.441433) (xy 449.722634 -248.388809) (xy 449.718699 -248.335038)
			(xy 442.913008 -248.335038) (xy 442.912516 -248.361995) (xy 442.904666 -248.415335) (xy 442.889134 -248.466964)
			(xy 442.866249 -248.515781) (xy 442.836501 -248.560745) (xy 442.800523 -248.600899) (xy 442.759081 -248.635387)
			(xy 442.71306 -248.663473) (xy 442.66344 -248.68456) (xy 442.611279 -248.698196) (xy 442.557688 -248.704093)
			(xy 442.503809 -248.702124) (xy 442.450791 -248.692331) (xy 442.399764 -248.674923) (xy 442.351816 -248.650271)
			(xy 442.307968 -248.618901) (xy 442.269155 -248.58148) (xy 442.236203 -248.538807) (xy 442.209817 -248.49179)
			(xy 442.190557 -248.441433) (xy 442.178834 -248.388809) (xy 442.174899 -248.335038) (xy 435.368954 -248.335038)
			(xy 435.368462 -248.361995) (xy 435.360612 -248.415335) (xy 435.34508 -248.466964) (xy 435.322195 -248.515781)
			(xy 435.292447 -248.560745) (xy 435.256469 -248.600899) (xy 435.215027 -248.635387) (xy 435.169006 -248.663473)
			(xy 435.119386 -248.68456) (xy 435.067225 -248.698196) (xy 435.013634 -248.704093) (xy 434.959755 -248.702124)
			(xy 434.906737 -248.692331) (xy 434.85571 -248.674923) (xy 434.807762 -248.650271) (xy 434.763914 -248.618901)
			(xy 434.725101 -248.58148) (xy 434.692149 -248.538807) (xy 434.665763 -248.49179) (xy 434.646503 -248.441433)
			(xy 434.63478 -248.388809) (xy 434.630845 -248.335038) (xy 427.8249 -248.335038) (xy 427.824408 -248.361995)
			(xy 427.816558 -248.415335) (xy 427.801026 -248.466964) (xy 427.778141 -248.515781) (xy 427.748393 -248.560745)
			(xy 427.712415 -248.600899) (xy 427.670973 -248.635387) (xy 427.624952 -248.663473) (xy 427.575332 -248.68456)
			(xy 427.523171 -248.698196) (xy 427.46958 -248.704093) (xy 427.415701 -248.702124) (xy 427.362683 -248.692331)
			(xy 427.311656 -248.674923) (xy 427.263708 -248.650271) (xy 427.21986 -248.618901) (xy 427.181047 -248.58148)
			(xy 427.148095 -248.538807) (xy 427.121709 -248.49179) (xy 427.102449 -248.441433) (xy 427.090726 -248.388809)
			(xy 427.086791 -248.335038) (xy 425.985178 -248.335038) (xy 425.985178 -249.185176) (xy 431.186859 -249.185176)
			(xy 431.190794 -249.131405) (xy 431.202517 -249.078781) (xy 431.221777 -249.028424) (xy 431.248163 -248.981407)
			(xy 431.281115 -248.938734) (xy 431.319928 -248.901313) (xy 431.363776 -248.869943) (xy 431.411724 -248.845291)
			(xy 431.462751 -248.827883) (xy 431.515769 -248.81809) (xy 431.569648 -248.816121) (xy 431.623239 -248.822018)
			(xy 431.6754 -248.835654) (xy 431.72502 -248.856741) (xy 431.771041 -248.884827) (xy 431.812483 -248.919315)
			(xy 431.848461 -248.959469) (xy 431.878209 -249.004433) (xy 431.901094 -249.05325) (xy 431.916626 -249.104879)
			(xy 431.924476 -249.158219) (xy 431.924968 -249.185176) (xy 438.730913 -249.185176) (xy 438.734848 -249.131405)
			(xy 438.746571 -249.078781) (xy 438.765831 -249.028424) (xy 438.792217 -248.981407) (xy 438.825169 -248.938734)
			(xy 438.863982 -248.901313) (xy 438.90783 -248.869943) (xy 438.955778 -248.845291) (xy 439.006805 -248.827883)
			(xy 439.059823 -248.81809) (xy 439.113702 -248.816121) (xy 439.167293 -248.822018) (xy 439.219454 -248.835654)
			(xy 439.269074 -248.856741) (xy 439.315095 -248.884827) (xy 439.356537 -248.919315) (xy 439.392515 -248.959469)
			(xy 439.422263 -249.004433) (xy 439.445148 -249.05325) (xy 439.46068 -249.104879) (xy 439.46853 -249.158219)
			(xy 439.469022 -249.185176) (xy 446.274967 -249.185176) (xy 446.278902 -249.131405) (xy 446.290625 -249.078781)
			(xy 446.309885 -249.028424) (xy 446.336271 -248.981407) (xy 446.369223 -248.938734) (xy 446.408036 -248.901313)
			(xy 446.451884 -248.869943) (xy 446.499832 -248.845291) (xy 446.550859 -248.827883) (xy 446.603877 -248.81809)
			(xy 446.657756 -248.816121) (xy 446.711347 -248.822018) (xy 446.763508 -248.835654) (xy 446.813128 -248.856741)
			(xy 446.859149 -248.884827) (xy 446.900591 -248.919315) (xy 446.936569 -248.959469) (xy 446.966317 -249.004433)
			(xy 446.989202 -249.05325) (xy 447.004734 -249.104879) (xy 447.012584 -249.158219) (xy 447.013076 -249.185176)
			(xy 453.818767 -249.185176) (xy 453.822702 -249.131405) (xy 453.834425 -249.078781) (xy 453.853685 -249.028424)
			(xy 453.880071 -248.981407) (xy 453.913023 -248.938734) (xy 453.951836 -248.901313) (xy 453.995684 -248.869943)
			(xy 454.043632 -248.845291) (xy 454.094659 -248.827883) (xy 454.147677 -248.81809) (xy 454.201556 -248.816121)
			(xy 454.255147 -248.822018) (xy 454.307308 -248.835654) (xy 454.356928 -248.856741) (xy 454.402949 -248.884827)
			(xy 454.444391 -248.919315) (xy 454.480369 -248.959469) (xy 454.510117 -249.004433) (xy 454.533002 -249.05325)
			(xy 454.548534 -249.104879) (xy 454.556384 -249.158219) (xy 454.556876 -249.185176) (xy 454.556384 -249.212133)
			(xy 454.548534 -249.265473) (xy 454.533002 -249.317102) (xy 454.510117 -249.365919) (xy 454.480369 -249.410883)
			(xy 454.444391 -249.451037) (xy 454.402949 -249.485525) (xy 454.356928 -249.513611) (xy 454.307308 -249.534698)
			(xy 454.255147 -249.548334) (xy 454.201556 -249.554231) (xy 454.147677 -249.552262) (xy 454.094659 -249.542469)
			(xy 454.043632 -249.525061) (xy 453.995684 -249.500409) (xy 453.951836 -249.469039) (xy 453.913023 -249.431618)
			(xy 453.880071 -249.388945) (xy 453.853685 -249.341928) (xy 453.834425 -249.291571) (xy 453.822702 -249.238947)
			(xy 453.818767 -249.185176) (xy 447.013076 -249.185176) (xy 447.012584 -249.212133) (xy 447.004734 -249.265473)
			(xy 446.989202 -249.317102) (xy 446.966317 -249.365919) (xy 446.936569 -249.410883) (xy 446.900591 -249.451037)
			(xy 446.859149 -249.485525) (xy 446.813128 -249.513611) (xy 446.763508 -249.534698) (xy 446.711347 -249.548334)
			(xy 446.657756 -249.554231) (xy 446.603877 -249.552262) (xy 446.550859 -249.542469) (xy 446.499832 -249.525061)
			(xy 446.451884 -249.500409) (xy 446.408036 -249.469039) (xy 446.369223 -249.431618) (xy 446.336271 -249.388945)
			(xy 446.309885 -249.341928) (xy 446.290625 -249.291571) (xy 446.278902 -249.238947) (xy 446.274967 -249.185176)
			(xy 439.469022 -249.185176) (xy 439.46853 -249.212133) (xy 439.46068 -249.265473) (xy 439.445148 -249.317102)
			(xy 439.422263 -249.365919) (xy 439.392515 -249.410883) (xy 439.356537 -249.451037) (xy 439.315095 -249.485525)
			(xy 439.269074 -249.513611) (xy 439.219454 -249.534698) (xy 439.167293 -249.548334) (xy 439.113702 -249.554231)
			(xy 439.059823 -249.552262) (xy 439.006805 -249.542469) (xy 438.955778 -249.525061) (xy 438.90783 -249.500409)
			(xy 438.863982 -249.469039) (xy 438.825169 -249.431618) (xy 438.792217 -249.388945) (xy 438.765831 -249.341928)
			(xy 438.746571 -249.291571) (xy 438.734848 -249.238947) (xy 438.730913 -249.185176) (xy 431.924968 -249.185176)
			(xy 431.924476 -249.212133) (xy 431.916626 -249.265473) (xy 431.901094 -249.317102) (xy 431.878209 -249.365919)
			(xy 431.848461 -249.410883) (xy 431.812483 -249.451037) (xy 431.771041 -249.485525) (xy 431.72502 -249.513611)
			(xy 431.6754 -249.534698) (xy 431.623239 -249.548334) (xy 431.569648 -249.554231) (xy 431.515769 -249.552262)
			(xy 431.462751 -249.542469) (xy 431.411724 -249.525061) (xy 431.363776 -249.500409) (xy 431.319928 -249.469039)
			(xy 431.281115 -249.431618) (xy 431.248163 -249.388945) (xy 431.221777 -249.341928) (xy 431.202517 -249.291571)
			(xy 431.190794 -249.238947) (xy 431.186859 -249.185176) (xy 425.985178 -249.185176) (xy 425.985178 -250.03506)
			(xy 427.086791 -250.03506) (xy 427.090726 -249.981289) (xy 427.102449 -249.928665) (xy 427.121709 -249.878308)
			(xy 427.148095 -249.831291) (xy 427.181047 -249.788618) (xy 427.21986 -249.751197) (xy 427.263708 -249.719827)
			(xy 427.311656 -249.695175) (xy 427.362683 -249.677767) (xy 427.415701 -249.667974) (xy 427.46958 -249.666005)
			(xy 427.523171 -249.671902) (xy 427.575332 -249.685538) (xy 427.624952 -249.706625) (xy 427.670973 -249.734711)
			(xy 427.712415 -249.769199) (xy 427.748393 -249.809353) (xy 427.778141 -249.854317) (xy 427.801026 -249.903134)
			(xy 427.816558 -249.954763) (xy 427.824408 -250.008103) (xy 427.8249 -250.03506) (xy 434.630845 -250.03506)
			(xy 434.63478 -249.981289) (xy 434.646503 -249.928665) (xy 434.665763 -249.878308) (xy 434.692149 -249.831291)
			(xy 434.725101 -249.788618) (xy 434.763914 -249.751197) (xy 434.807762 -249.719827) (xy 434.85571 -249.695175)
			(xy 434.906737 -249.677767) (xy 434.959755 -249.667974) (xy 435.013634 -249.666005) (xy 435.067225 -249.671902)
			(xy 435.119386 -249.685538) (xy 435.169006 -249.706625) (xy 435.215027 -249.734711) (xy 435.256469 -249.769199)
			(xy 435.292447 -249.809353) (xy 435.322195 -249.854317) (xy 435.34508 -249.903134) (xy 435.360612 -249.954763)
			(xy 435.368462 -250.008103) (xy 435.368954 -250.03506) (xy 442.174899 -250.03506) (xy 442.178834 -249.981289)
			(xy 442.190557 -249.928665) (xy 442.209817 -249.878308) (xy 442.236203 -249.831291) (xy 442.269155 -249.788618)
			(xy 442.307968 -249.751197) (xy 442.351816 -249.719827) (xy 442.399764 -249.695175) (xy 442.450791 -249.677767)
			(xy 442.503809 -249.667974) (xy 442.557688 -249.666005) (xy 442.611279 -249.671902) (xy 442.66344 -249.685538)
			(xy 442.71306 -249.706625) (xy 442.759081 -249.734711) (xy 442.800523 -249.769199) (xy 442.836501 -249.809353)
			(xy 442.866249 -249.854317) (xy 442.889134 -249.903134) (xy 442.904666 -249.954763) (xy 442.912516 -250.008103)
			(xy 442.913008 -250.03506) (xy 449.718699 -250.03506) (xy 449.722634 -249.981289) (xy 449.734357 -249.928665)
			(xy 449.753617 -249.878308) (xy 449.780003 -249.831291) (xy 449.812955 -249.788618) (xy 449.851768 -249.751197)
			(xy 449.895616 -249.719827) (xy 449.943564 -249.695175) (xy 449.994591 -249.677767) (xy 450.047609 -249.667974)
			(xy 450.101488 -249.666005) (xy 450.155079 -249.671902) (xy 450.20724 -249.685538) (xy 450.25686 -249.706625)
			(xy 450.302881 -249.734711) (xy 450.344323 -249.769199) (xy 450.380301 -249.809353) (xy 450.410049 -249.854317)
			(xy 450.432934 -249.903134) (xy 450.448466 -249.954763) (xy 450.456316 -250.008103) (xy 450.456808 -250.03506)
			(xy 450.456316 -250.062017) (xy 450.448466 -250.115357) (xy 450.432934 -250.166986) (xy 450.410049 -250.215803)
			(xy 450.380301 -250.260767) (xy 450.344323 -250.300921) (xy 450.302881 -250.335409) (xy 450.25686 -250.363495)
			(xy 450.20724 -250.384582) (xy 450.155079 -250.398218) (xy 450.101488 -250.404115) (xy 450.047609 -250.402146)
			(xy 449.994591 -250.392353) (xy 449.943564 -250.374945) (xy 449.895616 -250.350293) (xy 449.851768 -250.318923)
			(xy 449.812955 -250.281502) (xy 449.780003 -250.238829) (xy 449.753617 -250.191812) (xy 449.734357 -250.141455)
			(xy 449.722634 -250.088831) (xy 449.718699 -250.03506) (xy 442.913008 -250.03506) (xy 442.912516 -250.062017)
			(xy 442.904666 -250.115357) (xy 442.889134 -250.166986) (xy 442.866249 -250.215803) (xy 442.836501 -250.260767)
			(xy 442.800523 -250.300921) (xy 442.759081 -250.335409) (xy 442.71306 -250.363495) (xy 442.66344 -250.384582)
			(xy 442.611279 -250.398218) (xy 442.557688 -250.404115) (xy 442.503809 -250.402146) (xy 442.450791 -250.392353)
			(xy 442.399764 -250.374945) (xy 442.351816 -250.350293) (xy 442.307968 -250.318923) (xy 442.269155 -250.281502)
			(xy 442.236203 -250.238829) (xy 442.209817 -250.191812) (xy 442.190557 -250.141455) (xy 442.178834 -250.088831)
			(xy 442.174899 -250.03506) (xy 435.368954 -250.03506) (xy 435.368462 -250.062017) (xy 435.360612 -250.115357)
			(xy 435.34508 -250.166986) (xy 435.322195 -250.215803) (xy 435.292447 -250.260767) (xy 435.256469 -250.300921)
			(xy 435.215027 -250.335409) (xy 435.169006 -250.363495) (xy 435.119386 -250.384582) (xy 435.067225 -250.398218)
			(xy 435.013634 -250.404115) (xy 434.959755 -250.402146) (xy 434.906737 -250.392353) (xy 434.85571 -250.374945)
			(xy 434.807762 -250.350293) (xy 434.763914 -250.318923) (xy 434.725101 -250.281502) (xy 434.692149 -250.238829)
			(xy 434.665763 -250.191812) (xy 434.646503 -250.141455) (xy 434.63478 -250.088831) (xy 434.630845 -250.03506)
			(xy 427.8249 -250.03506) (xy 427.824408 -250.062017) (xy 427.816558 -250.115357) (xy 427.801026 -250.166986)
			(xy 427.778141 -250.215803) (xy 427.748393 -250.260767) (xy 427.712415 -250.300921) (xy 427.670973 -250.335409)
			(xy 427.624952 -250.363495) (xy 427.575332 -250.384582) (xy 427.523171 -250.398218) (xy 427.46958 -250.404115)
			(xy 427.415701 -250.402146) (xy 427.362683 -250.392353) (xy 427.311656 -250.374945) (xy 427.263708 -250.350293)
			(xy 427.21986 -250.318923) (xy 427.181047 -250.281502) (xy 427.148095 -250.238829) (xy 427.121709 -250.191812)
			(xy 427.102449 -250.141455) (xy 427.090726 -250.088831) (xy 427.086791 -250.03506) (xy 425.985178 -250.03506)
			(xy 425.985178 -250.884944) (xy 431.186859 -250.884944) (xy 431.190794 -250.831173) (xy 431.202517 -250.778549)
			(xy 431.221777 -250.728192) (xy 431.248163 -250.681175) (xy 431.281115 -250.638502) (xy 431.319928 -250.601081)
			(xy 431.363776 -250.569711) (xy 431.411724 -250.545059) (xy 431.462751 -250.527651) (xy 431.515769 -250.517858)
			(xy 431.569648 -250.515889) (xy 431.623239 -250.521786) (xy 431.6754 -250.535422) (xy 431.72502 -250.556509)
			(xy 431.771041 -250.584595) (xy 431.812483 -250.619083) (xy 431.848461 -250.659237) (xy 431.878209 -250.704201)
			(xy 431.901094 -250.753018) (xy 431.916626 -250.804647) (xy 431.924476 -250.857987) (xy 431.924968 -250.884944)
			(xy 438.730913 -250.884944) (xy 438.734848 -250.831173) (xy 438.746571 -250.778549) (xy 438.765831 -250.728192)
			(xy 438.792217 -250.681175) (xy 438.825169 -250.638502) (xy 438.863982 -250.601081) (xy 438.90783 -250.569711)
			(xy 438.955778 -250.545059) (xy 439.006805 -250.527651) (xy 439.059823 -250.517858) (xy 439.113702 -250.515889)
			(xy 439.167293 -250.521786) (xy 439.219454 -250.535422) (xy 439.269074 -250.556509) (xy 439.315095 -250.584595)
			(xy 439.356537 -250.619083) (xy 439.392515 -250.659237) (xy 439.422263 -250.704201) (xy 439.445148 -250.753018)
			(xy 439.46068 -250.804647) (xy 439.46853 -250.857987) (xy 439.469022 -250.884944) (xy 446.274967 -250.884944)
			(xy 446.278902 -250.831173) (xy 446.290625 -250.778549) (xy 446.309885 -250.728192) (xy 446.336271 -250.681175)
			(xy 446.369223 -250.638502) (xy 446.408036 -250.601081) (xy 446.451884 -250.569711) (xy 446.499832 -250.545059)
			(xy 446.550859 -250.527651) (xy 446.603877 -250.517858) (xy 446.657756 -250.515889) (xy 446.711347 -250.521786)
			(xy 446.763508 -250.535422) (xy 446.813128 -250.556509) (xy 446.859149 -250.584595) (xy 446.900591 -250.619083)
			(xy 446.936569 -250.659237) (xy 446.966317 -250.704201) (xy 446.989202 -250.753018) (xy 447.004734 -250.804647)
			(xy 447.012584 -250.857987) (xy 447.013076 -250.884944) (xy 453.818767 -250.884944) (xy 453.822702 -250.831173)
			(xy 453.834425 -250.778549) (xy 453.853685 -250.728192) (xy 453.880071 -250.681175) (xy 453.913023 -250.638502)
			(xy 453.951836 -250.601081) (xy 453.995684 -250.569711) (xy 454.043632 -250.545059) (xy 454.094659 -250.527651)
			(xy 454.147677 -250.517858) (xy 454.201556 -250.515889) (xy 454.255147 -250.521786) (xy 454.307308 -250.535422)
			(xy 454.356928 -250.556509) (xy 454.402949 -250.584595) (xy 454.444391 -250.619083) (xy 454.480369 -250.659237)
			(xy 454.510117 -250.704201) (xy 454.533002 -250.753018) (xy 454.548534 -250.804647) (xy 454.556384 -250.857987)
			(xy 454.556876 -250.884944) (xy 454.556384 -250.911901) (xy 454.548534 -250.965241) (xy 454.533002 -251.01687)
			(xy 454.510117 -251.065687) (xy 454.480369 -251.110651) (xy 454.444391 -251.150805) (xy 454.402949 -251.185293)
			(xy 454.356928 -251.213379) (xy 454.307308 -251.234466) (xy 454.255147 -251.248102) (xy 454.201556 -251.253999)
			(xy 454.147677 -251.25203) (xy 454.094659 -251.242237) (xy 454.043632 -251.224829) (xy 453.995684 -251.200177)
			(xy 453.951836 -251.168807) (xy 453.913023 -251.131386) (xy 453.880071 -251.088713) (xy 453.853685 -251.041696)
			(xy 453.834425 -250.991339) (xy 453.822702 -250.938715) (xy 453.818767 -250.884944) (xy 447.013076 -250.884944)
			(xy 447.012584 -250.911901) (xy 447.004734 -250.965241) (xy 446.989202 -251.01687) (xy 446.966317 -251.065687)
			(xy 446.936569 -251.110651) (xy 446.900591 -251.150805) (xy 446.859149 -251.185293) (xy 446.813128 -251.213379)
			(xy 446.763508 -251.234466) (xy 446.711347 -251.248102) (xy 446.657756 -251.253999) (xy 446.603877 -251.25203)
			(xy 446.550859 -251.242237) (xy 446.499832 -251.224829) (xy 446.451884 -251.200177) (xy 446.408036 -251.168807)
			(xy 446.369223 -251.131386) (xy 446.336271 -251.088713) (xy 446.309885 -251.041696) (xy 446.290625 -250.991339)
			(xy 446.278902 -250.938715) (xy 446.274967 -250.884944) (xy 439.469022 -250.884944) (xy 439.46853 -250.911901)
			(xy 439.46068 -250.965241) (xy 439.445148 -251.01687) (xy 439.422263 -251.065687) (xy 439.392515 -251.110651)
			(xy 439.356537 -251.150805) (xy 439.315095 -251.185293) (xy 439.269074 -251.213379) (xy 439.219454 -251.234466)
			(xy 439.167293 -251.248102) (xy 439.113702 -251.253999) (xy 439.059823 -251.25203) (xy 439.006805 -251.242237)
			(xy 438.955778 -251.224829) (xy 438.90783 -251.200177) (xy 438.863982 -251.168807) (xy 438.825169 -251.131386)
			(xy 438.792217 -251.088713) (xy 438.765831 -251.041696) (xy 438.746571 -250.991339) (xy 438.734848 -250.938715)
			(xy 438.730913 -250.884944) (xy 431.924968 -250.884944) (xy 431.924476 -250.911901) (xy 431.916626 -250.965241)
			(xy 431.901094 -251.01687) (xy 431.878209 -251.065687) (xy 431.848461 -251.110651) (xy 431.812483 -251.150805)
			(xy 431.771041 -251.185293) (xy 431.72502 -251.213379) (xy 431.6754 -251.234466) (xy 431.623239 -251.248102)
			(xy 431.569648 -251.253999) (xy 431.515769 -251.25203) (xy 431.462751 -251.242237) (xy 431.411724 -251.224829)
			(xy 431.363776 -251.200177) (xy 431.319928 -251.168807) (xy 431.281115 -251.131386) (xy 431.248163 -251.088713)
			(xy 431.221777 -251.041696) (xy 431.202517 -250.991339) (xy 431.190794 -250.938715) (xy 431.186859 -250.884944)
			(xy 425.985178 -250.884944) (xy 425.985178 -251.735082) (xy 427.086791 -251.735082) (xy 427.090726 -251.681311)
			(xy 427.102449 -251.628687) (xy 427.121709 -251.57833) (xy 427.148095 -251.531313) (xy 427.181047 -251.48864)
			(xy 427.21986 -251.451219) (xy 427.263708 -251.419849) (xy 427.311656 -251.395197) (xy 427.362683 -251.377789)
			(xy 427.415701 -251.367996) (xy 427.46958 -251.366027) (xy 427.523171 -251.371924) (xy 427.575332 -251.38556)
			(xy 427.624952 -251.406647) (xy 427.670973 -251.434733) (xy 427.712415 -251.469221) (xy 427.748393 -251.509375)
			(xy 427.778141 -251.554339) (xy 427.801026 -251.603156) (xy 427.816558 -251.654785) (xy 427.824408 -251.708125)
			(xy 427.8249 -251.735082) (xy 434.630845 -251.735082) (xy 434.63478 -251.681311) (xy 434.646503 -251.628687)
			(xy 434.665763 -251.57833) (xy 434.692149 -251.531313) (xy 434.725101 -251.48864) (xy 434.763914 -251.451219)
			(xy 434.807762 -251.419849) (xy 434.85571 -251.395197) (xy 434.906737 -251.377789) (xy 434.959755 -251.367996)
			(xy 435.013634 -251.366027) (xy 435.067225 -251.371924) (xy 435.119386 -251.38556) (xy 435.169006 -251.406647)
			(xy 435.215027 -251.434733) (xy 435.256469 -251.469221) (xy 435.292447 -251.509375) (xy 435.322195 -251.554339)
			(xy 435.34508 -251.603156) (xy 435.360612 -251.654785) (xy 435.368462 -251.708125) (xy 435.368954 -251.735082)
			(xy 442.174899 -251.735082) (xy 442.178834 -251.681311) (xy 442.190557 -251.628687) (xy 442.209817 -251.57833)
			(xy 442.236203 -251.531313) (xy 442.269155 -251.48864) (xy 442.307968 -251.451219) (xy 442.351816 -251.419849)
			(xy 442.399764 -251.395197) (xy 442.450791 -251.377789) (xy 442.503809 -251.367996) (xy 442.557688 -251.366027)
			(xy 442.611279 -251.371924) (xy 442.66344 -251.38556) (xy 442.71306 -251.406647) (xy 442.759081 -251.434733)
			(xy 442.800523 -251.469221) (xy 442.836501 -251.509375) (xy 442.866249 -251.554339) (xy 442.889134 -251.603156)
			(xy 442.904666 -251.654785) (xy 442.912516 -251.708125) (xy 442.913008 -251.735082) (xy 449.718699 -251.735082)
			(xy 449.722634 -251.681311) (xy 449.734357 -251.628687) (xy 449.753617 -251.57833) (xy 449.780003 -251.531313)
			(xy 449.812955 -251.48864) (xy 449.851768 -251.451219) (xy 449.895616 -251.419849) (xy 449.943564 -251.395197)
			(xy 449.994591 -251.377789) (xy 450.047609 -251.367996) (xy 450.101488 -251.366027) (xy 450.155079 -251.371924)
			(xy 450.20724 -251.38556) (xy 450.25686 -251.406647) (xy 450.302881 -251.434733) (xy 450.344323 -251.469221)
			(xy 450.380301 -251.509375) (xy 450.410049 -251.554339) (xy 450.432934 -251.603156) (xy 450.448466 -251.654785)
			(xy 450.456316 -251.708125) (xy 450.456808 -251.735082) (xy 450.456316 -251.762039) (xy 450.448466 -251.815379)
			(xy 450.432934 -251.867008) (xy 450.410049 -251.915825) (xy 450.380301 -251.960789) (xy 450.344323 -252.000943)
			(xy 450.302881 -252.035431) (xy 450.25686 -252.063517) (xy 450.20724 -252.084604) (xy 450.155079 -252.09824)
			(xy 450.101488 -252.104137) (xy 450.047609 -252.102168) (xy 449.994591 -252.092375) (xy 449.943564 -252.074967)
			(xy 449.895616 -252.050315) (xy 449.851768 -252.018945) (xy 449.812955 -251.981524) (xy 449.780003 -251.938851)
			(xy 449.753617 -251.891834) (xy 449.734357 -251.841477) (xy 449.722634 -251.788853) (xy 449.718699 -251.735082)
			(xy 442.913008 -251.735082) (xy 442.912516 -251.762039) (xy 442.904666 -251.815379) (xy 442.889134 -251.867008)
			(xy 442.866249 -251.915825) (xy 442.836501 -251.960789) (xy 442.800523 -252.000943) (xy 442.759081 -252.035431)
			(xy 442.71306 -252.063517) (xy 442.66344 -252.084604) (xy 442.611279 -252.09824) (xy 442.557688 -252.104137)
			(xy 442.503809 -252.102168) (xy 442.450791 -252.092375) (xy 442.399764 -252.074967) (xy 442.351816 -252.050315)
			(xy 442.307968 -252.018945) (xy 442.269155 -251.981524) (xy 442.236203 -251.938851) (xy 442.209817 -251.891834)
			(xy 442.190557 -251.841477) (xy 442.178834 -251.788853) (xy 442.174899 -251.735082) (xy 435.368954 -251.735082)
			(xy 435.368462 -251.762039) (xy 435.360612 -251.815379) (xy 435.34508 -251.867008) (xy 435.322195 -251.915825)
			(xy 435.292447 -251.960789) (xy 435.256469 -252.000943) (xy 435.215027 -252.035431) (xy 435.169006 -252.063517)
			(xy 435.119386 -252.084604) (xy 435.067225 -252.09824) (xy 435.013634 -252.104137) (xy 434.959755 -252.102168)
			(xy 434.906737 -252.092375) (xy 434.85571 -252.074967) (xy 434.807762 -252.050315) (xy 434.763914 -252.018945)
			(xy 434.725101 -251.981524) (xy 434.692149 -251.938851) (xy 434.665763 -251.891834) (xy 434.646503 -251.841477)
			(xy 434.63478 -251.788853) (xy 434.630845 -251.735082) (xy 427.8249 -251.735082) (xy 427.824408 -251.762039)
			(xy 427.816558 -251.815379) (xy 427.801026 -251.867008) (xy 427.778141 -251.915825) (xy 427.748393 -251.960789)
			(xy 427.712415 -252.000943) (xy 427.670973 -252.035431) (xy 427.624952 -252.063517) (xy 427.575332 -252.084604)
			(xy 427.523171 -252.09824) (xy 427.46958 -252.104137) (xy 427.415701 -252.102168) (xy 427.362683 -252.092375)
			(xy 427.311656 -252.074967) (xy 427.263708 -252.050315) (xy 427.21986 -252.018945) (xy 427.181047 -251.981524)
			(xy 427.148095 -251.938851) (xy 427.121709 -251.891834) (xy 427.102449 -251.841477) (xy 427.090726 -251.788853)
			(xy 427.086791 -251.735082) (xy 425.985178 -251.735082) (xy 425.985178 -252.584966) (xy 431.186859 -252.584966)
			(xy 431.190794 -252.531195) (xy 431.202517 -252.478571) (xy 431.221777 -252.428214) (xy 431.248163 -252.381197)
			(xy 431.281115 -252.338524) (xy 431.319928 -252.301103) (xy 431.363776 -252.269733) (xy 431.411724 -252.245081)
			(xy 431.462751 -252.227673) (xy 431.515769 -252.21788) (xy 431.569648 -252.215911) (xy 431.623239 -252.221808)
			(xy 431.6754 -252.235444) (xy 431.72502 -252.256531) (xy 431.771041 -252.284617) (xy 431.812483 -252.319105)
			(xy 431.848461 -252.359259) (xy 431.878209 -252.404223) (xy 431.901094 -252.45304) (xy 431.916626 -252.504669)
			(xy 431.924476 -252.558009) (xy 431.924968 -252.584966) (xy 438.730913 -252.584966) (xy 438.734848 -252.531195)
			(xy 438.746571 -252.478571) (xy 438.765831 -252.428214) (xy 438.792217 -252.381197) (xy 438.825169 -252.338524)
			(xy 438.863982 -252.301103) (xy 438.90783 -252.269733) (xy 438.955778 -252.245081) (xy 439.006805 -252.227673)
			(xy 439.059823 -252.21788) (xy 439.113702 -252.215911) (xy 439.167293 -252.221808) (xy 439.219454 -252.235444)
			(xy 439.269074 -252.256531) (xy 439.315095 -252.284617) (xy 439.356537 -252.319105) (xy 439.392515 -252.359259)
			(xy 439.422263 -252.404223) (xy 439.445148 -252.45304) (xy 439.46068 -252.504669) (xy 439.46853 -252.558009)
			(xy 439.469022 -252.584966) (xy 446.274967 -252.584966) (xy 446.278902 -252.531195) (xy 446.290625 -252.478571)
			(xy 446.309885 -252.428214) (xy 446.336271 -252.381197) (xy 446.369223 -252.338524) (xy 446.408036 -252.301103)
			(xy 446.451884 -252.269733) (xy 446.499832 -252.245081) (xy 446.550859 -252.227673) (xy 446.603877 -252.21788)
			(xy 446.657756 -252.215911) (xy 446.711347 -252.221808) (xy 446.763508 -252.235444) (xy 446.813128 -252.256531)
			(xy 446.859149 -252.284617) (xy 446.900591 -252.319105) (xy 446.936569 -252.359259) (xy 446.966317 -252.404223)
			(xy 446.989202 -252.45304) (xy 447.004734 -252.504669) (xy 447.012584 -252.558009) (xy 447.013076 -252.584966)
			(xy 453.818767 -252.584966) (xy 453.822702 -252.531195) (xy 453.834425 -252.478571) (xy 453.853685 -252.428214)
			(xy 453.880071 -252.381197) (xy 453.913023 -252.338524) (xy 453.951836 -252.301103) (xy 453.995684 -252.269733)
			(xy 454.043632 -252.245081) (xy 454.094659 -252.227673) (xy 454.147677 -252.21788) (xy 454.201556 -252.215911)
			(xy 454.255147 -252.221808) (xy 454.307308 -252.235444) (xy 454.356928 -252.256531) (xy 454.402949 -252.284617)
			(xy 454.444391 -252.319105) (xy 454.480369 -252.359259) (xy 454.510117 -252.404223) (xy 454.533002 -252.45304)
			(xy 454.548534 -252.504669) (xy 454.556384 -252.558009) (xy 454.556876 -252.584966) (xy 454.556384 -252.611923)
			(xy 454.548534 -252.665263) (xy 454.533002 -252.716892) (xy 454.510117 -252.765709) (xy 454.480369 -252.810673)
			(xy 454.444391 -252.850827) (xy 454.402949 -252.885315) (xy 454.356928 -252.913401) (xy 454.307308 -252.934488)
			(xy 454.255147 -252.948124) (xy 454.201556 -252.954021) (xy 454.147677 -252.952052) (xy 454.094659 -252.942259)
			(xy 454.043632 -252.924851) (xy 453.995684 -252.900199) (xy 453.951836 -252.868829) (xy 453.913023 -252.831408)
			(xy 453.880071 -252.788735) (xy 453.853685 -252.741718) (xy 453.834425 -252.691361) (xy 453.822702 -252.638737)
			(xy 453.818767 -252.584966) (xy 447.013076 -252.584966) (xy 447.012584 -252.611923) (xy 447.004734 -252.665263)
			(xy 446.989202 -252.716892) (xy 446.966317 -252.765709) (xy 446.936569 -252.810673) (xy 446.900591 -252.850827)
			(xy 446.859149 -252.885315) (xy 446.813128 -252.913401) (xy 446.763508 -252.934488) (xy 446.711347 -252.948124)
			(xy 446.657756 -252.954021) (xy 446.603877 -252.952052) (xy 446.550859 -252.942259) (xy 446.499832 -252.924851)
			(xy 446.451884 -252.900199) (xy 446.408036 -252.868829) (xy 446.369223 -252.831408) (xy 446.336271 -252.788735)
			(xy 446.309885 -252.741718) (xy 446.290625 -252.691361) (xy 446.278902 -252.638737) (xy 446.274967 -252.584966)
			(xy 439.469022 -252.584966) (xy 439.46853 -252.611923) (xy 439.46068 -252.665263) (xy 439.445148 -252.716892)
			(xy 439.422263 -252.765709) (xy 439.392515 -252.810673) (xy 439.356537 -252.850827) (xy 439.315095 -252.885315)
			(xy 439.269074 -252.913401) (xy 439.219454 -252.934488) (xy 439.167293 -252.948124) (xy 439.113702 -252.954021)
			(xy 439.059823 -252.952052) (xy 439.006805 -252.942259) (xy 438.955778 -252.924851) (xy 438.90783 -252.900199)
			(xy 438.863982 -252.868829) (xy 438.825169 -252.831408) (xy 438.792217 -252.788735) (xy 438.765831 -252.741718)
			(xy 438.746571 -252.691361) (xy 438.734848 -252.638737) (xy 438.730913 -252.584966) (xy 431.924968 -252.584966)
			(xy 431.924476 -252.611923) (xy 431.916626 -252.665263) (xy 431.901094 -252.716892) (xy 431.878209 -252.765709)
			(xy 431.848461 -252.810673) (xy 431.812483 -252.850827) (xy 431.771041 -252.885315) (xy 431.72502 -252.913401)
			(xy 431.6754 -252.934488) (xy 431.623239 -252.948124) (xy 431.569648 -252.954021) (xy 431.515769 -252.952052)
			(xy 431.462751 -252.942259) (xy 431.411724 -252.924851) (xy 431.363776 -252.900199) (xy 431.319928 -252.868829)
			(xy 431.281115 -252.831408) (xy 431.248163 -252.788735) (xy 431.221777 -252.741718) (xy 431.202517 -252.691361)
			(xy 431.190794 -252.638737) (xy 431.186859 -252.584966) (xy 425.985178 -252.584966) (xy 425.985178 -253.435104)
			(xy 427.086791 -253.435104) (xy 427.090726 -253.381333) (xy 427.102449 -253.328709) (xy 427.121709 -253.278352)
			(xy 427.148095 -253.231335) (xy 427.181047 -253.188662) (xy 427.21986 -253.151241) (xy 427.263708 -253.119871)
			(xy 427.311656 -253.095219) (xy 427.362683 -253.077811) (xy 427.415701 -253.068018) (xy 427.46958 -253.066049)
			(xy 427.523171 -253.071946) (xy 427.575332 -253.085582) (xy 427.624952 -253.106669) (xy 427.670973 -253.134755)
			(xy 427.712415 -253.169243) (xy 427.748393 -253.209397) (xy 427.778141 -253.254361) (xy 427.801026 -253.303178)
			(xy 427.816558 -253.354807) (xy 427.824408 -253.408147) (xy 427.8249 -253.435104) (xy 434.630845 -253.435104)
			(xy 434.63478 -253.381333) (xy 434.646503 -253.328709) (xy 434.665763 -253.278352) (xy 434.692149 -253.231335)
			(xy 434.725101 -253.188662) (xy 434.763914 -253.151241) (xy 434.807762 -253.119871) (xy 434.85571 -253.095219)
			(xy 434.906737 -253.077811) (xy 434.959755 -253.068018) (xy 435.013634 -253.066049) (xy 435.067225 -253.071946)
			(xy 435.119386 -253.085582) (xy 435.169006 -253.106669) (xy 435.215027 -253.134755) (xy 435.256469 -253.169243)
			(xy 435.292447 -253.209397) (xy 435.322195 -253.254361) (xy 435.34508 -253.303178) (xy 435.360612 -253.354807)
			(xy 435.368462 -253.408147) (xy 435.368954 -253.435104) (xy 442.174899 -253.435104) (xy 442.178834 -253.381333)
			(xy 442.190557 -253.328709) (xy 442.209817 -253.278352) (xy 442.236203 -253.231335) (xy 442.269155 -253.188662)
			(xy 442.307968 -253.151241) (xy 442.351816 -253.119871) (xy 442.399764 -253.095219) (xy 442.450791 -253.077811)
			(xy 442.503809 -253.068018) (xy 442.557688 -253.066049) (xy 442.611279 -253.071946) (xy 442.66344 -253.085582)
			(xy 442.71306 -253.106669) (xy 442.759081 -253.134755) (xy 442.800523 -253.169243) (xy 442.836501 -253.209397)
			(xy 442.866249 -253.254361) (xy 442.889134 -253.303178) (xy 442.904666 -253.354807) (xy 442.912516 -253.408147)
			(xy 442.913008 -253.435104) (xy 449.718699 -253.435104) (xy 449.722634 -253.381333) (xy 449.734357 -253.328709)
			(xy 449.753617 -253.278352) (xy 449.780003 -253.231335) (xy 449.812955 -253.188662) (xy 449.851768 -253.151241)
			(xy 449.895616 -253.119871) (xy 449.943564 -253.095219) (xy 449.994591 -253.077811) (xy 450.047609 -253.068018)
			(xy 450.101488 -253.066049) (xy 450.155079 -253.071946) (xy 450.20724 -253.085582) (xy 450.25686 -253.106669)
			(xy 450.302881 -253.134755) (xy 450.344323 -253.169243) (xy 450.380301 -253.209397) (xy 450.410049 -253.254361)
			(xy 450.432934 -253.303178) (xy 450.448466 -253.354807) (xy 450.456316 -253.408147) (xy 450.456808 -253.435104)
			(xy 450.456316 -253.462061) (xy 450.448466 -253.515401) (xy 450.432934 -253.56703) (xy 450.410049 -253.615847)
			(xy 450.380301 -253.660811) (xy 450.344323 -253.700965) (xy 450.302881 -253.735453) (xy 450.25686 -253.763539)
			(xy 450.20724 -253.784626) (xy 450.155079 -253.798262) (xy 450.101488 -253.804159) (xy 450.047609 -253.80219)
			(xy 449.994591 -253.792397) (xy 449.943564 -253.774989) (xy 449.895616 -253.750337) (xy 449.851768 -253.718967)
			(xy 449.812955 -253.681546) (xy 449.780003 -253.638873) (xy 449.753617 -253.591856) (xy 449.734357 -253.541499)
			(xy 449.722634 -253.488875) (xy 449.718699 -253.435104) (xy 442.913008 -253.435104) (xy 442.912516 -253.462061)
			(xy 442.904666 -253.515401) (xy 442.889134 -253.56703) (xy 442.866249 -253.615847) (xy 442.836501 -253.660811)
			(xy 442.800523 -253.700965) (xy 442.759081 -253.735453) (xy 442.71306 -253.763539) (xy 442.66344 -253.784626)
			(xy 442.611279 -253.798262) (xy 442.557688 -253.804159) (xy 442.503809 -253.80219) (xy 442.450791 -253.792397)
			(xy 442.399764 -253.774989) (xy 442.351816 -253.750337) (xy 442.307968 -253.718967) (xy 442.269155 -253.681546)
			(xy 442.236203 -253.638873) (xy 442.209817 -253.591856) (xy 442.190557 -253.541499) (xy 442.178834 -253.488875)
			(xy 442.174899 -253.435104) (xy 435.368954 -253.435104) (xy 435.368462 -253.462061) (xy 435.360612 -253.515401)
			(xy 435.34508 -253.56703) (xy 435.322195 -253.615847) (xy 435.292447 -253.660811) (xy 435.256469 -253.700965)
			(xy 435.215027 -253.735453) (xy 435.169006 -253.763539) (xy 435.119386 -253.784626) (xy 435.067225 -253.798262)
			(xy 435.013634 -253.804159) (xy 434.959755 -253.80219) (xy 434.906737 -253.792397) (xy 434.85571 -253.774989)
			(xy 434.807762 -253.750337) (xy 434.763914 -253.718967) (xy 434.725101 -253.681546) (xy 434.692149 -253.638873)
			(xy 434.665763 -253.591856) (xy 434.646503 -253.541499) (xy 434.63478 -253.488875) (xy 434.630845 -253.435104)
			(xy 427.8249 -253.435104) (xy 427.824408 -253.462061) (xy 427.816558 -253.515401) (xy 427.801026 -253.56703)
			(xy 427.778141 -253.615847) (xy 427.748393 -253.660811) (xy 427.712415 -253.700965) (xy 427.670973 -253.735453)
			(xy 427.624952 -253.763539) (xy 427.575332 -253.784626) (xy 427.523171 -253.798262) (xy 427.46958 -253.804159)
			(xy 427.415701 -253.80219) (xy 427.362683 -253.792397) (xy 427.311656 -253.774989) (xy 427.263708 -253.750337)
			(xy 427.21986 -253.718967) (xy 427.181047 -253.681546) (xy 427.148095 -253.638873) (xy 427.121709 -253.591856)
			(xy 427.102449 -253.541499) (xy 427.090726 -253.488875) (xy 427.086791 -253.435104) (xy 425.985178 -253.435104)
			(xy 425.985178 -254.284988) (xy 427.086791 -254.284988) (xy 427.090726 -254.231217) (xy 427.102449 -254.178593)
			(xy 427.121709 -254.128236) (xy 427.148095 -254.081219) (xy 427.181047 -254.038546) (xy 427.21986 -254.001125)
			(xy 427.263708 -253.969755) (xy 427.311656 -253.945103) (xy 427.362683 -253.927695) (xy 427.415701 -253.917902)
			(xy 427.46958 -253.915933) (xy 427.523171 -253.92183) (xy 427.575332 -253.935466) (xy 427.624952 -253.956553)
			(xy 427.670973 -253.984639) (xy 427.712415 -254.019127) (xy 427.748393 -254.059281) (xy 427.778141 -254.104245)
			(xy 427.801026 -254.153062) (xy 427.816558 -254.204691) (xy 427.824408 -254.258031) (xy 427.8249 -254.284988)
			(xy 431.186859 -254.284988) (xy 431.190794 -254.231217) (xy 431.202517 -254.178593) (xy 431.221777 -254.128236)
			(xy 431.248163 -254.081219) (xy 431.281115 -254.038546) (xy 431.319928 -254.001125) (xy 431.363776 -253.969755)
			(xy 431.411724 -253.945103) (xy 431.462751 -253.927695) (xy 431.515769 -253.917902) (xy 431.569648 -253.915933)
			(xy 431.623239 -253.92183) (xy 431.6754 -253.935466) (xy 431.72502 -253.956553) (xy 431.771041 -253.984639)
			(xy 431.812483 -254.019127) (xy 431.848461 -254.059281) (xy 431.878209 -254.104245) (xy 431.901094 -254.153062)
			(xy 431.916626 -254.204691) (xy 431.924476 -254.258031) (xy 431.924968 -254.284988) (xy 434.630845 -254.284988)
			(xy 434.63478 -254.231217) (xy 434.646503 -254.178593) (xy 434.665763 -254.128236) (xy 434.692149 -254.081219)
			(xy 434.725101 -254.038546) (xy 434.763914 -254.001125) (xy 434.807762 -253.969755) (xy 434.85571 -253.945103)
			(xy 434.906737 -253.927695) (xy 434.959755 -253.917902) (xy 435.013634 -253.915933) (xy 435.067225 -253.92183)
			(xy 435.119386 -253.935466) (xy 435.169006 -253.956553) (xy 435.215027 -253.984639) (xy 435.256469 -254.019127)
			(xy 435.292447 -254.059281) (xy 435.322195 -254.104245) (xy 435.34508 -254.153062) (xy 435.360612 -254.204691)
			(xy 435.368462 -254.258031) (xy 435.368954 -254.284988) (xy 438.730913 -254.284988) (xy 438.734848 -254.231217)
			(xy 438.746571 -254.178593) (xy 438.765831 -254.128236) (xy 438.792217 -254.081219) (xy 438.825169 -254.038546)
			(xy 438.863982 -254.001125) (xy 438.90783 -253.969755) (xy 438.955778 -253.945103) (xy 439.006805 -253.927695)
			(xy 439.059823 -253.917902) (xy 439.113702 -253.915933) (xy 439.167293 -253.92183) (xy 439.219454 -253.935466)
			(xy 439.269074 -253.956553) (xy 439.315095 -253.984639) (xy 439.356537 -254.019127) (xy 439.392515 -254.059281)
			(xy 439.422263 -254.104245) (xy 439.445148 -254.153062) (xy 439.46068 -254.204691) (xy 439.46853 -254.258031)
			(xy 439.469022 -254.284988) (xy 442.174899 -254.284988) (xy 442.178834 -254.231217) (xy 442.190557 -254.178593)
			(xy 442.209817 -254.128236) (xy 442.236203 -254.081219) (xy 442.269155 -254.038546) (xy 442.307968 -254.001125)
			(xy 442.351816 -253.969755) (xy 442.399764 -253.945103) (xy 442.450791 -253.927695) (xy 442.503809 -253.917902)
			(xy 442.557688 -253.915933) (xy 442.611279 -253.92183) (xy 442.66344 -253.935466) (xy 442.71306 -253.956553)
			(xy 442.759081 -253.984639) (xy 442.800523 -254.019127) (xy 442.836501 -254.059281) (xy 442.866249 -254.104245)
			(xy 442.889134 -254.153062) (xy 442.904666 -254.204691) (xy 442.912516 -254.258031) (xy 442.913008 -254.284988)
			(xy 446.274967 -254.284988) (xy 446.278902 -254.231217) (xy 446.290625 -254.178593) (xy 446.309885 -254.128236)
			(xy 446.336271 -254.081219) (xy 446.369223 -254.038546) (xy 446.408036 -254.001125) (xy 446.451884 -253.969755)
			(xy 446.499832 -253.945103) (xy 446.550859 -253.927695) (xy 446.603877 -253.917902) (xy 446.657756 -253.915933)
			(xy 446.711347 -253.92183) (xy 446.763508 -253.935466) (xy 446.813128 -253.956553) (xy 446.859149 -253.984639)
			(xy 446.900591 -254.019127) (xy 446.936569 -254.059281) (xy 446.966317 -254.104245) (xy 446.989202 -254.153062)
			(xy 447.004734 -254.204691) (xy 447.012584 -254.258031) (xy 447.013076 -254.284988) (xy 449.718699 -254.284988)
			(xy 449.722634 -254.231217) (xy 449.734357 -254.178593) (xy 449.753617 -254.128236) (xy 449.780003 -254.081219)
			(xy 449.812955 -254.038546) (xy 449.851768 -254.001125) (xy 449.895616 -253.969755) (xy 449.943564 -253.945103)
			(xy 449.994591 -253.927695) (xy 450.047609 -253.917902) (xy 450.101488 -253.915933) (xy 450.155079 -253.92183)
			(xy 450.20724 -253.935466) (xy 450.25686 -253.956553) (xy 450.302881 -253.984639) (xy 450.344323 -254.019127)
			(xy 450.380301 -254.059281) (xy 450.410049 -254.104245) (xy 450.432934 -254.153062) (xy 450.448466 -254.204691)
			(xy 450.456316 -254.258031) (xy 450.456808 -254.284988) (xy 453.818767 -254.284988) (xy 453.822702 -254.231217)
			(xy 453.834425 -254.178593) (xy 453.853685 -254.128236) (xy 453.880071 -254.081219) (xy 453.913023 -254.038546)
			(xy 453.951836 -254.001125) (xy 453.995684 -253.969755) (xy 454.043632 -253.945103) (xy 454.094659 -253.927695)
			(xy 454.147677 -253.917902) (xy 454.201556 -253.915933) (xy 454.255147 -253.92183) (xy 454.307308 -253.935466)
			(xy 454.356928 -253.956553) (xy 454.402949 -253.984639) (xy 454.444391 -254.019127) (xy 454.480369 -254.059281)
			(xy 454.510117 -254.104245) (xy 454.533002 -254.153062) (xy 454.548534 -254.204691) (xy 454.556384 -254.258031)
			(xy 454.556876 -254.284988) (xy 454.556384 -254.311945) (xy 454.548534 -254.365285) (xy 454.533002 -254.416914)
			(xy 454.510117 -254.465731) (xy 454.480369 -254.510695) (xy 454.444391 -254.550849) (xy 454.402949 -254.585337)
			(xy 454.356928 -254.613423) (xy 454.307308 -254.63451) (xy 454.255147 -254.648146) (xy 454.201556 -254.654043)
			(xy 454.147677 -254.652074) (xy 454.094659 -254.642281) (xy 454.043632 -254.624873) (xy 453.995684 -254.600221)
			(xy 453.951836 -254.568851) (xy 453.913023 -254.53143) (xy 453.880071 -254.488757) (xy 453.853685 -254.44174)
			(xy 453.834425 -254.391383) (xy 453.822702 -254.338759) (xy 453.818767 -254.284988) (xy 450.456808 -254.284988)
			(xy 450.456316 -254.311945) (xy 450.448466 -254.365285) (xy 450.432934 -254.416914) (xy 450.410049 -254.465731)
			(xy 450.380301 -254.510695) (xy 450.344323 -254.550849) (xy 450.302881 -254.585337) (xy 450.25686 -254.613423)
			(xy 450.20724 -254.63451) (xy 450.155079 -254.648146) (xy 450.101488 -254.654043) (xy 450.047609 -254.652074)
			(xy 449.994591 -254.642281) (xy 449.943564 -254.624873) (xy 449.895616 -254.600221) (xy 449.851768 -254.568851)
			(xy 449.812955 -254.53143) (xy 449.780003 -254.488757) (xy 449.753617 -254.44174) (xy 449.734357 -254.391383)
			(xy 449.722634 -254.338759) (xy 449.718699 -254.284988) (xy 447.013076 -254.284988) (xy 447.012584 -254.311945)
			(xy 447.004734 -254.365285) (xy 446.989202 -254.416914) (xy 446.966317 -254.465731) (xy 446.936569 -254.510695)
			(xy 446.900591 -254.550849) (xy 446.859149 -254.585337) (xy 446.813128 -254.613423) (xy 446.763508 -254.63451)
			(xy 446.711347 -254.648146) (xy 446.657756 -254.654043) (xy 446.603877 -254.652074) (xy 446.550859 -254.642281)
			(xy 446.499832 -254.624873) (xy 446.451884 -254.600221) (xy 446.408036 -254.568851) (xy 446.369223 -254.53143)
			(xy 446.336271 -254.488757) (xy 446.309885 -254.44174) (xy 446.290625 -254.391383) (xy 446.278902 -254.338759)
			(xy 446.274967 -254.284988) (xy 442.913008 -254.284988) (xy 442.912516 -254.311945) (xy 442.904666 -254.365285)
			(xy 442.889134 -254.416914) (xy 442.866249 -254.465731) (xy 442.836501 -254.510695) (xy 442.800523 -254.550849)
			(xy 442.759081 -254.585337) (xy 442.71306 -254.613423) (xy 442.66344 -254.63451) (xy 442.611279 -254.648146)
			(xy 442.557688 -254.654043) (xy 442.503809 -254.652074) (xy 442.450791 -254.642281) (xy 442.399764 -254.624873)
			(xy 442.351816 -254.600221) (xy 442.307968 -254.568851) (xy 442.269155 -254.53143) (xy 442.236203 -254.488757)
			(xy 442.209817 -254.44174) (xy 442.190557 -254.391383) (xy 442.178834 -254.338759) (xy 442.174899 -254.284988)
			(xy 439.469022 -254.284988) (xy 439.46853 -254.311945) (xy 439.46068 -254.365285) (xy 439.445148 -254.416914)
			(xy 439.422263 -254.465731) (xy 439.392515 -254.510695) (xy 439.356537 -254.550849) (xy 439.315095 -254.585337)
			(xy 439.269074 -254.613423) (xy 439.219454 -254.63451) (xy 439.167293 -254.648146) (xy 439.113702 -254.654043)
			(xy 439.059823 -254.652074) (xy 439.006805 -254.642281) (xy 438.955778 -254.624873) (xy 438.90783 -254.600221)
			(xy 438.863982 -254.568851) (xy 438.825169 -254.53143) (xy 438.792217 -254.488757) (xy 438.765831 -254.44174)
			(xy 438.746571 -254.391383) (xy 438.734848 -254.338759) (xy 438.730913 -254.284988) (xy 435.368954 -254.284988)
			(xy 435.368462 -254.311945) (xy 435.360612 -254.365285) (xy 435.34508 -254.416914) (xy 435.322195 -254.465731)
			(xy 435.292447 -254.510695) (xy 435.256469 -254.550849) (xy 435.215027 -254.585337) (xy 435.169006 -254.613423)
			(xy 435.119386 -254.63451) (xy 435.067225 -254.648146) (xy 435.013634 -254.654043) (xy 434.959755 -254.652074)
			(xy 434.906737 -254.642281) (xy 434.85571 -254.624873) (xy 434.807762 -254.600221) (xy 434.763914 -254.568851)
			(xy 434.725101 -254.53143) (xy 434.692149 -254.488757) (xy 434.665763 -254.44174) (xy 434.646503 -254.391383)
			(xy 434.63478 -254.338759) (xy 434.630845 -254.284988) (xy 431.924968 -254.284988) (xy 431.924476 -254.311945)
			(xy 431.916626 -254.365285) (xy 431.901094 -254.416914) (xy 431.878209 -254.465731) (xy 431.848461 -254.510695)
			(xy 431.812483 -254.550849) (xy 431.771041 -254.585337) (xy 431.72502 -254.613423) (xy 431.6754 -254.63451)
			(xy 431.623239 -254.648146) (xy 431.569648 -254.654043) (xy 431.515769 -254.652074) (xy 431.462751 -254.642281)
			(xy 431.411724 -254.624873) (xy 431.363776 -254.600221) (xy 431.319928 -254.568851) (xy 431.281115 -254.53143)
			(xy 431.248163 -254.488757) (xy 431.221777 -254.44174) (xy 431.202517 -254.391383) (xy 431.190794 -254.338759)
			(xy 431.186859 -254.284988) (xy 427.8249 -254.284988) (xy 427.824408 -254.311945) (xy 427.816558 -254.365285)
			(xy 427.801026 -254.416914) (xy 427.778141 -254.465731) (xy 427.748393 -254.510695) (xy 427.712415 -254.550849)
			(xy 427.670973 -254.585337) (xy 427.624952 -254.613423) (xy 427.575332 -254.63451) (xy 427.523171 -254.648146)
			(xy 427.46958 -254.654043) (xy 427.415701 -254.652074) (xy 427.362683 -254.642281) (xy 427.311656 -254.624873)
			(xy 427.263708 -254.600221) (xy 427.21986 -254.568851) (xy 427.181047 -254.53143) (xy 427.148095 -254.488757)
			(xy 427.121709 -254.44174) (xy 427.102449 -254.391383) (xy 427.090726 -254.338759) (xy 427.086791 -254.284988)
			(xy 425.985178 -254.284988) (xy 425.985178 -261.085076) (xy 431.186859 -261.085076) (xy 431.190794 -261.031305)
			(xy 431.202517 -260.978681) (xy 431.221777 -260.928324) (xy 431.248163 -260.881307) (xy 431.281115 -260.838634)
			(xy 431.319928 -260.801213) (xy 431.363776 -260.769843) (xy 431.411724 -260.745191) (xy 431.462751 -260.727783)
			(xy 431.515769 -260.71799) (xy 431.569648 -260.716021) (xy 431.623239 -260.721918) (xy 431.6754 -260.735554)
			(xy 431.72502 -260.756641) (xy 431.771041 -260.784727) (xy 431.812483 -260.819215) (xy 431.848461 -260.859369)
			(xy 431.878209 -260.904333) (xy 431.901094 -260.95315) (xy 431.916626 -261.004779) (xy 431.924476 -261.058119)
			(xy 431.924968 -261.085076) (xy 438.730913 -261.085076) (xy 438.734848 -261.031305) (xy 438.746571 -260.978681)
			(xy 438.765831 -260.928324) (xy 438.792217 -260.881307) (xy 438.825169 -260.838634) (xy 438.863982 -260.801213)
			(xy 438.90783 -260.769843) (xy 438.955778 -260.745191) (xy 439.006805 -260.727783) (xy 439.059823 -260.71799)
			(xy 439.113702 -260.716021) (xy 439.167293 -260.721918) (xy 439.219454 -260.735554) (xy 439.269074 -260.756641)
			(xy 439.315095 -260.784727) (xy 439.356537 -260.819215) (xy 439.392515 -260.859369) (xy 439.422263 -260.904333)
			(xy 439.445148 -260.95315) (xy 439.46068 -261.004779) (xy 439.46853 -261.058119) (xy 439.469022 -261.085076)
			(xy 446.274967 -261.085076) (xy 446.278902 -261.031305) (xy 446.290625 -260.978681) (xy 446.309885 -260.928324)
			(xy 446.336271 -260.881307) (xy 446.369223 -260.838634) (xy 446.408036 -260.801213) (xy 446.451884 -260.769843)
			(xy 446.499832 -260.745191) (xy 446.550859 -260.727783) (xy 446.603877 -260.71799) (xy 446.657756 -260.716021)
			(xy 446.711347 -260.721918) (xy 446.763508 -260.735554) (xy 446.813128 -260.756641) (xy 446.859149 -260.784727)
			(xy 446.900591 -260.819215) (xy 446.936569 -260.859369) (xy 446.966317 -260.904333) (xy 446.989202 -260.95315)
			(xy 447.004734 -261.004779) (xy 447.012584 -261.058119) (xy 447.013076 -261.085076) (xy 453.818767 -261.085076)
			(xy 453.822702 -261.031305) (xy 453.834425 -260.978681) (xy 453.853685 -260.928324) (xy 453.880071 -260.881307)
			(xy 453.913023 -260.838634) (xy 453.951836 -260.801213) (xy 453.995684 -260.769843) (xy 454.043632 -260.745191)
			(xy 454.094659 -260.727783) (xy 454.147677 -260.71799) (xy 454.201556 -260.716021) (xy 454.255147 -260.721918)
			(xy 454.307308 -260.735554) (xy 454.356928 -260.756641) (xy 454.402949 -260.784727) (xy 454.444391 -260.819215)
			(xy 454.480369 -260.859369) (xy 454.510117 -260.904333) (xy 454.533002 -260.95315) (xy 454.548534 -261.004779)
			(xy 454.556384 -261.058119) (xy 454.556876 -261.085076) (xy 454.556384 -261.112033) (xy 454.548534 -261.165373)
			(xy 454.533002 -261.217002) (xy 454.510117 -261.265819) (xy 454.480369 -261.310783) (xy 454.444391 -261.350937)
			(xy 454.402949 -261.385425) (xy 454.356928 -261.413511) (xy 454.307308 -261.434598) (xy 454.255147 -261.448234)
			(xy 454.201556 -261.454131) (xy 454.147677 -261.452162) (xy 454.094659 -261.442369) (xy 454.043632 -261.424961)
			(xy 453.995684 -261.400309) (xy 453.951836 -261.368939) (xy 453.913023 -261.331518) (xy 453.880071 -261.288845)
			(xy 453.853685 -261.241828) (xy 453.834425 -261.191471) (xy 453.822702 -261.138847) (xy 453.818767 -261.085076)
			(xy 447.013076 -261.085076) (xy 447.012584 -261.112033) (xy 447.004734 -261.165373) (xy 446.989202 -261.217002)
			(xy 446.966317 -261.265819) (xy 446.936569 -261.310783) (xy 446.900591 -261.350937) (xy 446.859149 -261.385425)
			(xy 446.813128 -261.413511) (xy 446.763508 -261.434598) (xy 446.711347 -261.448234) (xy 446.657756 -261.454131)
			(xy 446.603877 -261.452162) (xy 446.550859 -261.442369) (xy 446.499832 -261.424961) (xy 446.451884 -261.400309)
			(xy 446.408036 -261.368939) (xy 446.369223 -261.331518) (xy 446.336271 -261.288845) (xy 446.309885 -261.241828)
			(xy 446.290625 -261.191471) (xy 446.278902 -261.138847) (xy 446.274967 -261.085076) (xy 439.469022 -261.085076)
			(xy 439.46853 -261.112033) (xy 439.46068 -261.165373) (xy 439.445148 -261.217002) (xy 439.422263 -261.265819)
			(xy 439.392515 -261.310783) (xy 439.356537 -261.350937) (xy 439.315095 -261.385425) (xy 439.269074 -261.413511)
			(xy 439.219454 -261.434598) (xy 439.167293 -261.448234) (xy 439.113702 -261.454131) (xy 439.059823 -261.452162)
			(xy 439.006805 -261.442369) (xy 438.955778 -261.424961) (xy 438.90783 -261.400309) (xy 438.863982 -261.368939)
			(xy 438.825169 -261.331518) (xy 438.792217 -261.288845) (xy 438.765831 -261.241828) (xy 438.746571 -261.191471)
			(xy 438.734848 -261.138847) (xy 438.730913 -261.085076) (xy 431.924968 -261.085076) (xy 431.924476 -261.112033)
			(xy 431.916626 -261.165373) (xy 431.901094 -261.217002) (xy 431.878209 -261.265819) (xy 431.848461 -261.310783)
			(xy 431.812483 -261.350937) (xy 431.771041 -261.385425) (xy 431.72502 -261.413511) (xy 431.6754 -261.434598)
			(xy 431.623239 -261.448234) (xy 431.569648 -261.454131) (xy 431.515769 -261.452162) (xy 431.462751 -261.442369)
			(xy 431.411724 -261.424961) (xy 431.363776 -261.400309) (xy 431.319928 -261.368939) (xy 431.281115 -261.331518)
			(xy 431.248163 -261.288845) (xy 431.221777 -261.241828) (xy 431.202517 -261.191471) (xy 431.190794 -261.138847)
			(xy 431.186859 -261.085076) (xy 425.985178 -261.085076) (xy 425.985178 -261.93496) (xy 427.086791 -261.93496)
			(xy 427.090726 -261.881189) (xy 427.102449 -261.828565) (xy 427.121709 -261.778208) (xy 427.148095 -261.731191)
			(xy 427.181047 -261.688518) (xy 427.21986 -261.651097) (xy 427.263708 -261.619727) (xy 427.311656 -261.595075)
			(xy 427.362683 -261.577667) (xy 427.415701 -261.567874) (xy 427.46958 -261.565905) (xy 427.523171 -261.571802)
			(xy 427.575332 -261.585438) (xy 427.624952 -261.606525) (xy 427.670973 -261.634611) (xy 427.712415 -261.669099)
			(xy 427.748393 -261.709253) (xy 427.778141 -261.754217) (xy 427.801026 -261.803034) (xy 427.816558 -261.854663)
			(xy 427.824408 -261.908003) (xy 427.8249 -261.93496) (xy 434.630845 -261.93496) (xy 434.63478 -261.881189)
			(xy 434.646503 -261.828565) (xy 434.665763 -261.778208) (xy 434.692149 -261.731191) (xy 434.725101 -261.688518)
			(xy 434.763914 -261.651097) (xy 434.807762 -261.619727) (xy 434.85571 -261.595075) (xy 434.906737 -261.577667)
			(xy 434.959755 -261.567874) (xy 435.013634 -261.565905) (xy 435.067225 -261.571802) (xy 435.119386 -261.585438)
			(xy 435.169006 -261.606525) (xy 435.215027 -261.634611) (xy 435.256469 -261.669099) (xy 435.292447 -261.709253)
			(xy 435.322195 -261.754217) (xy 435.34508 -261.803034) (xy 435.360612 -261.854663) (xy 435.368462 -261.908003)
			(xy 435.368954 -261.93496) (xy 442.174899 -261.93496) (xy 442.178834 -261.881189) (xy 442.190557 -261.828565)
			(xy 442.209817 -261.778208) (xy 442.236203 -261.731191) (xy 442.269155 -261.688518) (xy 442.307968 -261.651097)
			(xy 442.351816 -261.619727) (xy 442.399764 -261.595075) (xy 442.450791 -261.577667) (xy 442.503809 -261.567874)
			(xy 442.557688 -261.565905) (xy 442.611279 -261.571802) (xy 442.66344 -261.585438) (xy 442.71306 -261.606525)
			(xy 442.759081 -261.634611) (xy 442.800523 -261.669099) (xy 442.836501 -261.709253) (xy 442.866249 -261.754217)
			(xy 442.889134 -261.803034) (xy 442.904666 -261.854663) (xy 442.912516 -261.908003) (xy 442.913008 -261.93496)
			(xy 449.718699 -261.93496) (xy 449.722634 -261.881189) (xy 449.734357 -261.828565) (xy 449.753617 -261.778208)
			(xy 449.780003 -261.731191) (xy 449.812955 -261.688518) (xy 449.851768 -261.651097) (xy 449.895616 -261.619727)
			(xy 449.943564 -261.595075) (xy 449.994591 -261.577667) (xy 450.047609 -261.567874) (xy 450.101488 -261.565905)
			(xy 450.155079 -261.571802) (xy 450.20724 -261.585438) (xy 450.25686 -261.606525) (xy 450.302881 -261.634611)
			(xy 450.344323 -261.669099) (xy 450.380301 -261.709253) (xy 450.410049 -261.754217) (xy 450.432934 -261.803034)
			(xy 450.448466 -261.854663) (xy 450.456316 -261.908003) (xy 450.456808 -261.93496) (xy 450.456316 -261.961917)
			(xy 450.448466 -262.015257) (xy 450.432934 -262.066886) (xy 450.410049 -262.115703) (xy 450.380301 -262.160667)
			(xy 450.344323 -262.200821) (xy 450.302881 -262.235309) (xy 450.25686 -262.263395) (xy 450.20724 -262.284482)
			(xy 450.155079 -262.298118) (xy 450.101488 -262.304015) (xy 450.047609 -262.302046) (xy 449.994591 -262.292253)
			(xy 449.943564 -262.274845) (xy 449.895616 -262.250193) (xy 449.851768 -262.218823) (xy 449.812955 -262.181402)
			(xy 449.780003 -262.138729) (xy 449.753617 -262.091712) (xy 449.734357 -262.041355) (xy 449.722634 -261.988731)
			(xy 449.718699 -261.93496) (xy 442.913008 -261.93496) (xy 442.912516 -261.961917) (xy 442.904666 -262.015257)
			(xy 442.889134 -262.066886) (xy 442.866249 -262.115703) (xy 442.836501 -262.160667) (xy 442.800523 -262.200821)
			(xy 442.759081 -262.235309) (xy 442.71306 -262.263395) (xy 442.66344 -262.284482) (xy 442.611279 -262.298118)
			(xy 442.557688 -262.304015) (xy 442.503809 -262.302046) (xy 442.450791 -262.292253) (xy 442.399764 -262.274845)
			(xy 442.351816 -262.250193) (xy 442.307968 -262.218823) (xy 442.269155 -262.181402) (xy 442.236203 -262.138729)
			(xy 442.209817 -262.091712) (xy 442.190557 -262.041355) (xy 442.178834 -261.988731) (xy 442.174899 -261.93496)
			(xy 435.368954 -261.93496) (xy 435.368462 -261.961917) (xy 435.360612 -262.015257) (xy 435.34508 -262.066886)
			(xy 435.322195 -262.115703) (xy 435.292447 -262.160667) (xy 435.256469 -262.200821) (xy 435.215027 -262.235309)
			(xy 435.169006 -262.263395) (xy 435.119386 -262.284482) (xy 435.067225 -262.298118) (xy 435.013634 -262.304015)
			(xy 434.959755 -262.302046) (xy 434.906737 -262.292253) (xy 434.85571 -262.274845) (xy 434.807762 -262.250193)
			(xy 434.763914 -262.218823) (xy 434.725101 -262.181402) (xy 434.692149 -262.138729) (xy 434.665763 -262.091712)
			(xy 434.646503 -262.041355) (xy 434.63478 -261.988731) (xy 434.630845 -261.93496) (xy 427.8249 -261.93496)
			(xy 427.824408 -261.961917) (xy 427.816558 -262.015257) (xy 427.801026 -262.066886) (xy 427.778141 -262.115703)
			(xy 427.748393 -262.160667) (xy 427.712415 -262.200821) (xy 427.670973 -262.235309) (xy 427.624952 -262.263395)
			(xy 427.575332 -262.284482) (xy 427.523171 -262.298118) (xy 427.46958 -262.304015) (xy 427.415701 -262.302046)
			(xy 427.362683 -262.292253) (xy 427.311656 -262.274845) (xy 427.263708 -262.250193) (xy 427.21986 -262.218823)
			(xy 427.181047 -262.181402) (xy 427.148095 -262.138729) (xy 427.121709 -262.091712) (xy 427.102449 -262.041355)
			(xy 427.090726 -261.988731) (xy 427.086791 -261.93496) (xy 425.985178 -261.93496) (xy 425.985178 -262.785098)
			(xy 431.186859 -262.785098) (xy 431.190794 -262.731327) (xy 431.202517 -262.678703) (xy 431.221777 -262.628346)
			(xy 431.248163 -262.581329) (xy 431.281115 -262.538656) (xy 431.319928 -262.501235) (xy 431.363776 -262.469865)
			(xy 431.411724 -262.445213) (xy 431.462751 -262.427805) (xy 431.515769 -262.418012) (xy 431.569648 -262.416043)
			(xy 431.623239 -262.42194) (xy 431.6754 -262.435576) (xy 431.72502 -262.456663) (xy 431.771041 -262.484749)
			(xy 431.812483 -262.519237) (xy 431.848461 -262.559391) (xy 431.878209 -262.604355) (xy 431.901094 -262.653172)
			(xy 431.916626 -262.704801) (xy 431.924476 -262.758141) (xy 431.924968 -262.785098) (xy 438.730913 -262.785098)
			(xy 438.734848 -262.731327) (xy 438.746571 -262.678703) (xy 438.765831 -262.628346) (xy 438.792217 -262.581329)
			(xy 438.825169 -262.538656) (xy 438.863982 -262.501235) (xy 438.90783 -262.469865) (xy 438.955778 -262.445213)
			(xy 439.006805 -262.427805) (xy 439.059823 -262.418012) (xy 439.113702 -262.416043) (xy 439.167293 -262.42194)
			(xy 439.219454 -262.435576) (xy 439.269074 -262.456663) (xy 439.315095 -262.484749) (xy 439.356537 -262.519237)
			(xy 439.392515 -262.559391) (xy 439.422263 -262.604355) (xy 439.445148 -262.653172) (xy 439.46068 -262.704801)
			(xy 439.46853 -262.758141) (xy 439.469022 -262.785098) (xy 446.274967 -262.785098) (xy 446.278902 -262.731327)
			(xy 446.290625 -262.678703) (xy 446.309885 -262.628346) (xy 446.336271 -262.581329) (xy 446.369223 -262.538656)
			(xy 446.408036 -262.501235) (xy 446.451884 -262.469865) (xy 446.499832 -262.445213) (xy 446.550859 -262.427805)
			(xy 446.603877 -262.418012) (xy 446.657756 -262.416043) (xy 446.711347 -262.42194) (xy 446.763508 -262.435576)
			(xy 446.813128 -262.456663) (xy 446.859149 -262.484749) (xy 446.900591 -262.519237) (xy 446.936569 -262.559391)
			(xy 446.966317 -262.604355) (xy 446.989202 -262.653172) (xy 447.004734 -262.704801) (xy 447.012584 -262.758141)
			(xy 447.013076 -262.785098) (xy 453.818767 -262.785098) (xy 453.822702 -262.731327) (xy 453.834425 -262.678703)
			(xy 453.853685 -262.628346) (xy 453.880071 -262.581329) (xy 453.913023 -262.538656) (xy 453.951836 -262.501235)
			(xy 453.995684 -262.469865) (xy 454.043632 -262.445213) (xy 454.094659 -262.427805) (xy 454.147677 -262.418012)
			(xy 454.201556 -262.416043) (xy 454.255147 -262.42194) (xy 454.307308 -262.435576) (xy 454.356928 -262.456663)
			(xy 454.402949 -262.484749) (xy 454.444391 -262.519237) (xy 454.480369 -262.559391) (xy 454.510117 -262.604355)
			(xy 454.533002 -262.653172) (xy 454.548534 -262.704801) (xy 454.556384 -262.758141) (xy 454.556876 -262.785098)
			(xy 454.556384 -262.812055) (xy 454.548534 -262.865395) (xy 454.533002 -262.917024) (xy 454.510117 -262.965841)
			(xy 454.480369 -263.010805) (xy 454.444391 -263.050959) (xy 454.402949 -263.085447) (xy 454.356928 -263.113533)
			(xy 454.307308 -263.13462) (xy 454.255147 -263.148256) (xy 454.201556 -263.154153) (xy 454.147677 -263.152184)
			(xy 454.094659 -263.142391) (xy 454.043632 -263.124983) (xy 453.995684 -263.100331) (xy 453.951836 -263.068961)
			(xy 453.913023 -263.03154) (xy 453.880071 -262.988867) (xy 453.853685 -262.94185) (xy 453.834425 -262.891493)
			(xy 453.822702 -262.838869) (xy 453.818767 -262.785098) (xy 447.013076 -262.785098) (xy 447.012584 -262.812055)
			(xy 447.004734 -262.865395) (xy 446.989202 -262.917024) (xy 446.966317 -262.965841) (xy 446.936569 -263.010805)
			(xy 446.900591 -263.050959) (xy 446.859149 -263.085447) (xy 446.813128 -263.113533) (xy 446.763508 -263.13462)
			(xy 446.711347 -263.148256) (xy 446.657756 -263.154153) (xy 446.603877 -263.152184) (xy 446.550859 -263.142391)
			(xy 446.499832 -263.124983) (xy 446.451884 -263.100331) (xy 446.408036 -263.068961) (xy 446.369223 -263.03154)
			(xy 446.336271 -262.988867) (xy 446.309885 -262.94185) (xy 446.290625 -262.891493) (xy 446.278902 -262.838869)
			(xy 446.274967 -262.785098) (xy 439.469022 -262.785098) (xy 439.46853 -262.812055) (xy 439.46068 -262.865395)
			(xy 439.445148 -262.917024) (xy 439.422263 -262.965841) (xy 439.392515 -263.010805) (xy 439.356537 -263.050959)
			(xy 439.315095 -263.085447) (xy 439.269074 -263.113533) (xy 439.219454 -263.13462) (xy 439.167293 -263.148256)
			(xy 439.113702 -263.154153) (xy 439.059823 -263.152184) (xy 439.006805 -263.142391) (xy 438.955778 -263.124983)
			(xy 438.90783 -263.100331) (xy 438.863982 -263.068961) (xy 438.825169 -263.03154) (xy 438.792217 -262.988867)
			(xy 438.765831 -262.94185) (xy 438.746571 -262.891493) (xy 438.734848 -262.838869) (xy 438.730913 -262.785098)
			(xy 431.924968 -262.785098) (xy 431.924476 -262.812055) (xy 431.916626 -262.865395) (xy 431.901094 -262.917024)
			(xy 431.878209 -262.965841) (xy 431.848461 -263.010805) (xy 431.812483 -263.050959) (xy 431.771041 -263.085447)
			(xy 431.72502 -263.113533) (xy 431.6754 -263.13462) (xy 431.623239 -263.148256) (xy 431.569648 -263.154153)
			(xy 431.515769 -263.152184) (xy 431.462751 -263.142391) (xy 431.411724 -263.124983) (xy 431.363776 -263.100331)
			(xy 431.319928 -263.068961) (xy 431.281115 -263.03154) (xy 431.248163 -262.988867) (xy 431.221777 -262.94185)
			(xy 431.202517 -262.891493) (xy 431.190794 -262.838869) (xy 431.186859 -262.785098) (xy 425.985178 -262.785098)
			(xy 425.985178 -263.634982) (xy 427.086791 -263.634982) (xy 427.090726 -263.581211) (xy 427.102449 -263.528587)
			(xy 427.121709 -263.47823) (xy 427.148095 -263.431213) (xy 427.181047 -263.38854) (xy 427.21986 -263.351119)
			(xy 427.263708 -263.319749) (xy 427.311656 -263.295097) (xy 427.362683 -263.277689) (xy 427.415701 -263.267896)
			(xy 427.46958 -263.265927) (xy 427.523171 -263.271824) (xy 427.575332 -263.28546) (xy 427.624952 -263.306547)
			(xy 427.670973 -263.334633) (xy 427.712415 -263.369121) (xy 427.748393 -263.409275) (xy 427.778141 -263.454239)
			(xy 427.801026 -263.503056) (xy 427.816558 -263.554685) (xy 427.824408 -263.608025) (xy 427.8249 -263.634982)
			(xy 434.630845 -263.634982) (xy 434.63478 -263.581211) (xy 434.646503 -263.528587) (xy 434.665763 -263.47823)
			(xy 434.692149 -263.431213) (xy 434.725101 -263.38854) (xy 434.763914 -263.351119) (xy 434.807762 -263.319749)
			(xy 434.85571 -263.295097) (xy 434.906737 -263.277689) (xy 434.959755 -263.267896) (xy 435.013634 -263.265927)
			(xy 435.067225 -263.271824) (xy 435.119386 -263.28546) (xy 435.169006 -263.306547) (xy 435.215027 -263.334633)
			(xy 435.256469 -263.369121) (xy 435.292447 -263.409275) (xy 435.322195 -263.454239) (xy 435.34508 -263.503056)
			(xy 435.360612 -263.554685) (xy 435.368462 -263.608025) (xy 435.368954 -263.634982) (xy 442.174899 -263.634982)
			(xy 442.178834 -263.581211) (xy 442.190557 -263.528587) (xy 442.209817 -263.47823) (xy 442.236203 -263.431213)
			(xy 442.269155 -263.38854) (xy 442.307968 -263.351119) (xy 442.351816 -263.319749) (xy 442.399764 -263.295097)
			(xy 442.450791 -263.277689) (xy 442.503809 -263.267896) (xy 442.557688 -263.265927) (xy 442.611279 -263.271824)
			(xy 442.66344 -263.28546) (xy 442.71306 -263.306547) (xy 442.759081 -263.334633) (xy 442.800523 -263.369121)
			(xy 442.836501 -263.409275) (xy 442.866249 -263.454239) (xy 442.889134 -263.503056) (xy 442.904666 -263.554685)
			(xy 442.912516 -263.608025) (xy 442.913008 -263.634982) (xy 449.718699 -263.634982) (xy 449.722634 -263.581211)
			(xy 449.734357 -263.528587) (xy 449.753617 -263.47823) (xy 449.780003 -263.431213) (xy 449.812955 -263.38854)
			(xy 449.851768 -263.351119) (xy 449.895616 -263.319749) (xy 449.943564 -263.295097) (xy 449.994591 -263.277689)
			(xy 450.047609 -263.267896) (xy 450.101488 -263.265927) (xy 450.155079 -263.271824) (xy 450.20724 -263.28546)
			(xy 450.25686 -263.306547) (xy 450.302881 -263.334633) (xy 450.344323 -263.369121) (xy 450.380301 -263.409275)
			(xy 450.410049 -263.454239) (xy 450.432934 -263.503056) (xy 450.448466 -263.554685) (xy 450.456316 -263.608025)
			(xy 450.456808 -263.634982) (xy 450.456316 -263.661939) (xy 450.448466 -263.715279) (xy 450.432934 -263.766908)
			(xy 450.410049 -263.815725) (xy 450.380301 -263.860689) (xy 450.344323 -263.900843) (xy 450.302881 -263.935331)
			(xy 450.25686 -263.963417) (xy 450.20724 -263.984504) (xy 450.155079 -263.99814) (xy 450.101488 -264.004037)
			(xy 450.047609 -264.002068) (xy 449.994591 -263.992275) (xy 449.943564 -263.974867) (xy 449.895616 -263.950215)
			(xy 449.851768 -263.918845) (xy 449.812955 -263.881424) (xy 449.780003 -263.838751) (xy 449.753617 -263.791734)
			(xy 449.734357 -263.741377) (xy 449.722634 -263.688753) (xy 449.718699 -263.634982) (xy 442.913008 -263.634982)
			(xy 442.912516 -263.661939) (xy 442.904666 -263.715279) (xy 442.889134 -263.766908) (xy 442.866249 -263.815725)
			(xy 442.836501 -263.860689) (xy 442.800523 -263.900843) (xy 442.759081 -263.935331) (xy 442.71306 -263.963417)
			(xy 442.66344 -263.984504) (xy 442.611279 -263.99814) (xy 442.557688 -264.004037) (xy 442.503809 -264.002068)
			(xy 442.450791 -263.992275) (xy 442.399764 -263.974867) (xy 442.351816 -263.950215) (xy 442.307968 -263.918845)
			(xy 442.269155 -263.881424) (xy 442.236203 -263.838751) (xy 442.209817 -263.791734) (xy 442.190557 -263.741377)
			(xy 442.178834 -263.688753) (xy 442.174899 -263.634982) (xy 435.368954 -263.634982) (xy 435.368462 -263.661939)
			(xy 435.360612 -263.715279) (xy 435.34508 -263.766908) (xy 435.322195 -263.815725) (xy 435.292447 -263.860689)
			(xy 435.256469 -263.900843) (xy 435.215027 -263.935331) (xy 435.169006 -263.963417) (xy 435.119386 -263.984504)
			(xy 435.067225 -263.99814) (xy 435.013634 -264.004037) (xy 434.959755 -264.002068) (xy 434.906737 -263.992275)
			(xy 434.85571 -263.974867) (xy 434.807762 -263.950215) (xy 434.763914 -263.918845) (xy 434.725101 -263.881424)
			(xy 434.692149 -263.838751) (xy 434.665763 -263.791734) (xy 434.646503 -263.741377) (xy 434.63478 -263.688753)
			(xy 434.630845 -263.634982) (xy 427.8249 -263.634982) (xy 427.824408 -263.661939) (xy 427.816558 -263.715279)
			(xy 427.801026 -263.766908) (xy 427.778141 -263.815725) (xy 427.748393 -263.860689) (xy 427.712415 -263.900843)
			(xy 427.670973 -263.935331) (xy 427.624952 -263.963417) (xy 427.575332 -263.984504) (xy 427.523171 -263.99814)
			(xy 427.46958 -264.004037) (xy 427.415701 -264.002068) (xy 427.362683 -263.992275) (xy 427.311656 -263.974867)
			(xy 427.263708 -263.950215) (xy 427.21986 -263.918845) (xy 427.181047 -263.881424) (xy 427.148095 -263.838751)
			(xy 427.121709 -263.791734) (xy 427.102449 -263.741377) (xy 427.090726 -263.688753) (xy 427.086791 -263.634982)
			(xy 425.985178 -263.634982) (xy 425.985178 -264.48512) (xy 431.186859 -264.48512) (xy 431.190794 -264.431349)
			(xy 431.202517 -264.378725) (xy 431.221777 -264.328368) (xy 431.248163 -264.281351) (xy 431.281115 -264.238678)
			(xy 431.319928 -264.201257) (xy 431.363776 -264.169887) (xy 431.411724 -264.145235) (xy 431.462751 -264.127827)
			(xy 431.515769 -264.118034) (xy 431.569648 -264.116065) (xy 431.623239 -264.121962) (xy 431.6754 -264.135598)
			(xy 431.72502 -264.156685) (xy 431.771041 -264.184771) (xy 431.812483 -264.219259) (xy 431.848461 -264.259413)
			(xy 431.878209 -264.304377) (xy 431.901094 -264.353194) (xy 431.916626 -264.404823) (xy 431.924476 -264.458163)
			(xy 431.924968 -264.48512) (xy 438.730913 -264.48512) (xy 438.734848 -264.431349) (xy 438.746571 -264.378725)
			(xy 438.765831 -264.328368) (xy 438.792217 -264.281351) (xy 438.825169 -264.238678) (xy 438.863982 -264.201257)
			(xy 438.90783 -264.169887) (xy 438.955778 -264.145235) (xy 439.006805 -264.127827) (xy 439.059823 -264.118034)
			(xy 439.113702 -264.116065) (xy 439.167293 -264.121962) (xy 439.219454 -264.135598) (xy 439.269074 -264.156685)
			(xy 439.315095 -264.184771) (xy 439.356537 -264.219259) (xy 439.392515 -264.259413) (xy 439.422263 -264.304377)
			(xy 439.445148 -264.353194) (xy 439.46068 -264.404823) (xy 439.46853 -264.458163) (xy 439.469022 -264.48512)
			(xy 446.274967 -264.48512) (xy 446.278902 -264.431349) (xy 446.290625 -264.378725) (xy 446.309885 -264.328368)
			(xy 446.336271 -264.281351) (xy 446.369223 -264.238678) (xy 446.408036 -264.201257) (xy 446.451884 -264.169887)
			(xy 446.499832 -264.145235) (xy 446.550859 -264.127827) (xy 446.603877 -264.118034) (xy 446.657756 -264.116065)
			(xy 446.711347 -264.121962) (xy 446.763508 -264.135598) (xy 446.813128 -264.156685) (xy 446.859149 -264.184771)
			(xy 446.900591 -264.219259) (xy 446.936569 -264.259413) (xy 446.966317 -264.304377) (xy 446.989202 -264.353194)
			(xy 447.004734 -264.404823) (xy 447.012584 -264.458163) (xy 447.013076 -264.48512) (xy 453.818767 -264.48512)
			(xy 453.822702 -264.431349) (xy 453.834425 -264.378725) (xy 453.853685 -264.328368) (xy 453.880071 -264.281351)
			(xy 453.913023 -264.238678) (xy 453.951836 -264.201257) (xy 453.995684 -264.169887) (xy 454.043632 -264.145235)
			(xy 454.094659 -264.127827) (xy 454.147677 -264.118034) (xy 454.201556 -264.116065) (xy 454.255147 -264.121962)
			(xy 454.307308 -264.135598) (xy 454.356928 -264.156685) (xy 454.402949 -264.184771) (xy 454.444391 -264.219259)
			(xy 454.480369 -264.259413) (xy 454.510117 -264.304377) (xy 454.533002 -264.353194) (xy 454.548534 -264.404823)
			(xy 454.556384 -264.458163) (xy 454.556876 -264.48512) (xy 454.556384 -264.512077) (xy 454.548534 -264.565417)
			(xy 454.533002 -264.617046) (xy 454.510117 -264.665863) (xy 454.480369 -264.710827) (xy 454.444391 -264.750981)
			(xy 454.402949 -264.785469) (xy 454.356928 -264.813555) (xy 454.307308 -264.834642) (xy 454.255147 -264.848278)
			(xy 454.201556 -264.854175) (xy 454.147677 -264.852206) (xy 454.094659 -264.842413) (xy 454.043632 -264.825005)
			(xy 453.995684 -264.800353) (xy 453.951836 -264.768983) (xy 453.913023 -264.731562) (xy 453.880071 -264.688889)
			(xy 453.853685 -264.641872) (xy 453.834425 -264.591515) (xy 453.822702 -264.538891) (xy 453.818767 -264.48512)
			(xy 447.013076 -264.48512) (xy 447.012584 -264.512077) (xy 447.004734 -264.565417) (xy 446.989202 -264.617046)
			(xy 446.966317 -264.665863) (xy 446.936569 -264.710827) (xy 446.900591 -264.750981) (xy 446.859149 -264.785469)
			(xy 446.813128 -264.813555) (xy 446.763508 -264.834642) (xy 446.711347 -264.848278) (xy 446.657756 -264.854175)
			(xy 446.603877 -264.852206) (xy 446.550859 -264.842413) (xy 446.499832 -264.825005) (xy 446.451884 -264.800353)
			(xy 446.408036 -264.768983) (xy 446.369223 -264.731562) (xy 446.336271 -264.688889) (xy 446.309885 -264.641872)
			(xy 446.290625 -264.591515) (xy 446.278902 -264.538891) (xy 446.274967 -264.48512) (xy 439.469022 -264.48512)
			(xy 439.46853 -264.512077) (xy 439.46068 -264.565417) (xy 439.445148 -264.617046) (xy 439.422263 -264.665863)
			(xy 439.392515 -264.710827) (xy 439.356537 -264.750981) (xy 439.315095 -264.785469) (xy 439.269074 -264.813555)
			(xy 439.219454 -264.834642) (xy 439.167293 -264.848278) (xy 439.113702 -264.854175) (xy 439.059823 -264.852206)
			(xy 439.006805 -264.842413) (xy 438.955778 -264.825005) (xy 438.90783 -264.800353) (xy 438.863982 -264.768983)
			(xy 438.825169 -264.731562) (xy 438.792217 -264.688889) (xy 438.765831 -264.641872) (xy 438.746571 -264.591515)
			(xy 438.734848 -264.538891) (xy 438.730913 -264.48512) (xy 431.924968 -264.48512) (xy 431.924476 -264.512077)
			(xy 431.916626 -264.565417) (xy 431.901094 -264.617046) (xy 431.878209 -264.665863) (xy 431.848461 -264.710827)
			(xy 431.812483 -264.750981) (xy 431.771041 -264.785469) (xy 431.72502 -264.813555) (xy 431.6754 -264.834642)
			(xy 431.623239 -264.848278) (xy 431.569648 -264.854175) (xy 431.515769 -264.852206) (xy 431.462751 -264.842413)
			(xy 431.411724 -264.825005) (xy 431.363776 -264.800353) (xy 431.319928 -264.768983) (xy 431.281115 -264.731562)
			(xy 431.248163 -264.688889) (xy 431.221777 -264.641872) (xy 431.202517 -264.591515) (xy 431.190794 -264.538891)
			(xy 431.186859 -264.48512) (xy 425.985178 -264.48512) (xy 425.985178 -265.335004) (xy 427.086791 -265.335004)
			(xy 427.090726 -265.281233) (xy 427.102449 -265.228609) (xy 427.121709 -265.178252) (xy 427.148095 -265.131235)
			(xy 427.181047 -265.088562) (xy 427.21986 -265.051141) (xy 427.263708 -265.019771) (xy 427.311656 -264.995119)
			(xy 427.362683 -264.977711) (xy 427.415701 -264.967918) (xy 427.46958 -264.965949) (xy 427.523171 -264.971846)
			(xy 427.575332 -264.985482) (xy 427.624952 -265.006569) (xy 427.670973 -265.034655) (xy 427.712415 -265.069143)
			(xy 427.748393 -265.109297) (xy 427.778141 -265.154261) (xy 427.801026 -265.203078) (xy 427.816558 -265.254707)
			(xy 427.824408 -265.308047) (xy 427.8249 -265.335004) (xy 434.630845 -265.335004) (xy 434.63478 -265.281233)
			(xy 434.646503 -265.228609) (xy 434.665763 -265.178252) (xy 434.692149 -265.131235) (xy 434.725101 -265.088562)
			(xy 434.763914 -265.051141) (xy 434.807762 -265.019771) (xy 434.85571 -264.995119) (xy 434.906737 -264.977711)
			(xy 434.959755 -264.967918) (xy 435.013634 -264.965949) (xy 435.067225 -264.971846) (xy 435.119386 -264.985482)
			(xy 435.169006 -265.006569) (xy 435.215027 -265.034655) (xy 435.256469 -265.069143) (xy 435.292447 -265.109297)
			(xy 435.322195 -265.154261) (xy 435.34508 -265.203078) (xy 435.360612 -265.254707) (xy 435.368462 -265.308047)
			(xy 435.368954 -265.335004) (xy 442.174899 -265.335004) (xy 442.178834 -265.281233) (xy 442.190557 -265.228609)
			(xy 442.209817 -265.178252) (xy 442.236203 -265.131235) (xy 442.269155 -265.088562) (xy 442.307968 -265.051141)
			(xy 442.351816 -265.019771) (xy 442.399764 -264.995119) (xy 442.450791 -264.977711) (xy 442.503809 -264.967918)
			(xy 442.557688 -264.965949) (xy 442.611279 -264.971846) (xy 442.66344 -264.985482) (xy 442.71306 -265.006569)
			(xy 442.759081 -265.034655) (xy 442.800523 -265.069143) (xy 442.836501 -265.109297) (xy 442.866249 -265.154261)
			(xy 442.889134 -265.203078) (xy 442.904666 -265.254707) (xy 442.912516 -265.308047) (xy 442.913008 -265.335004)
			(xy 449.718699 -265.335004) (xy 449.722634 -265.281233) (xy 449.734357 -265.228609) (xy 449.753617 -265.178252)
			(xy 449.780003 -265.131235) (xy 449.812955 -265.088562) (xy 449.851768 -265.051141) (xy 449.895616 -265.019771)
			(xy 449.943564 -264.995119) (xy 449.994591 -264.977711) (xy 450.047609 -264.967918) (xy 450.101488 -264.965949)
			(xy 450.155079 -264.971846) (xy 450.20724 -264.985482) (xy 450.25686 -265.006569) (xy 450.302881 -265.034655)
			(xy 450.344323 -265.069143) (xy 450.380301 -265.109297) (xy 450.410049 -265.154261) (xy 450.432934 -265.203078)
			(xy 450.448466 -265.254707) (xy 450.456316 -265.308047) (xy 450.456808 -265.335004) (xy 450.456316 -265.361961)
			(xy 450.448466 -265.415301) (xy 450.432934 -265.46693) (xy 450.410049 -265.515747) (xy 450.380301 -265.560711)
			(xy 450.344323 -265.600865) (xy 450.302881 -265.635353) (xy 450.25686 -265.663439) (xy 450.20724 -265.684526)
			(xy 450.155079 -265.698162) (xy 450.101488 -265.704059) (xy 450.047609 -265.70209) (xy 449.994591 -265.692297)
			(xy 449.943564 -265.674889) (xy 449.895616 -265.650237) (xy 449.851768 -265.618867) (xy 449.812955 -265.581446)
			(xy 449.780003 -265.538773) (xy 449.753617 -265.491756) (xy 449.734357 -265.441399) (xy 449.722634 -265.388775)
			(xy 449.718699 -265.335004) (xy 442.913008 -265.335004) (xy 442.912516 -265.361961) (xy 442.904666 -265.415301)
			(xy 442.889134 -265.46693) (xy 442.866249 -265.515747) (xy 442.836501 -265.560711) (xy 442.800523 -265.600865)
			(xy 442.759081 -265.635353) (xy 442.71306 -265.663439) (xy 442.66344 -265.684526) (xy 442.611279 -265.698162)
			(xy 442.557688 -265.704059) (xy 442.503809 -265.70209) (xy 442.450791 -265.692297) (xy 442.399764 -265.674889)
			(xy 442.351816 -265.650237) (xy 442.307968 -265.618867) (xy 442.269155 -265.581446) (xy 442.236203 -265.538773)
			(xy 442.209817 -265.491756) (xy 442.190557 -265.441399) (xy 442.178834 -265.388775) (xy 442.174899 -265.335004)
			(xy 435.368954 -265.335004) (xy 435.368462 -265.361961) (xy 435.360612 -265.415301) (xy 435.34508 -265.46693)
			(xy 435.322195 -265.515747) (xy 435.292447 -265.560711) (xy 435.256469 -265.600865) (xy 435.215027 -265.635353)
			(xy 435.169006 -265.663439) (xy 435.119386 -265.684526) (xy 435.067225 -265.698162) (xy 435.013634 -265.704059)
			(xy 434.959755 -265.70209) (xy 434.906737 -265.692297) (xy 434.85571 -265.674889) (xy 434.807762 -265.650237)
			(xy 434.763914 -265.618867) (xy 434.725101 -265.581446) (xy 434.692149 -265.538773) (xy 434.665763 -265.491756)
			(xy 434.646503 -265.441399) (xy 434.63478 -265.388775) (xy 434.630845 -265.335004) (xy 427.8249 -265.335004)
			(xy 427.824408 -265.361961) (xy 427.816558 -265.415301) (xy 427.801026 -265.46693) (xy 427.778141 -265.515747)
			(xy 427.748393 -265.560711) (xy 427.712415 -265.600865) (xy 427.670973 -265.635353) (xy 427.624952 -265.663439)
			(xy 427.575332 -265.684526) (xy 427.523171 -265.698162) (xy 427.46958 -265.704059) (xy 427.415701 -265.70209)
			(xy 427.362683 -265.692297) (xy 427.311656 -265.674889) (xy 427.263708 -265.650237) (xy 427.21986 -265.618867)
			(xy 427.181047 -265.581446) (xy 427.148095 -265.538773) (xy 427.121709 -265.491756) (xy 427.102449 -265.441399)
			(xy 427.090726 -265.388775) (xy 427.086791 -265.335004) (xy 425.985178 -265.335004) (xy 425.985178 -266.185142)
			(xy 431.186859 -266.185142) (xy 431.190794 -266.131371) (xy 431.202517 -266.078747) (xy 431.221777 -266.02839)
			(xy 431.248163 -265.981373) (xy 431.281115 -265.9387) (xy 431.319928 -265.901279) (xy 431.363776 -265.869909)
			(xy 431.411724 -265.845257) (xy 431.462751 -265.827849) (xy 431.515769 -265.818056) (xy 431.569648 -265.816087)
			(xy 431.623239 -265.821984) (xy 431.6754 -265.83562) (xy 431.72502 -265.856707) (xy 431.771041 -265.884793)
			(xy 431.812483 -265.919281) (xy 431.848461 -265.959435) (xy 431.878209 -266.004399) (xy 431.901094 -266.053216)
			(xy 431.916626 -266.104845) (xy 431.924476 -266.158185) (xy 431.924968 -266.185142) (xy 438.730913 -266.185142)
			(xy 438.734848 -266.131371) (xy 438.746571 -266.078747) (xy 438.765831 -266.02839) (xy 438.792217 -265.981373)
			(xy 438.825169 -265.9387) (xy 438.863982 -265.901279) (xy 438.90783 -265.869909) (xy 438.955778 -265.845257)
			(xy 439.006805 -265.827849) (xy 439.059823 -265.818056) (xy 439.113702 -265.816087) (xy 439.167293 -265.821984)
			(xy 439.219454 -265.83562) (xy 439.269074 -265.856707) (xy 439.315095 -265.884793) (xy 439.356537 -265.919281)
			(xy 439.392515 -265.959435) (xy 439.422263 -266.004399) (xy 439.445148 -266.053216) (xy 439.46068 -266.104845)
			(xy 439.46853 -266.158185) (xy 439.469022 -266.185142) (xy 446.274967 -266.185142) (xy 446.278902 -266.131371)
			(xy 446.290625 -266.078747) (xy 446.309885 -266.02839) (xy 446.336271 -265.981373) (xy 446.369223 -265.9387)
			(xy 446.408036 -265.901279) (xy 446.451884 -265.869909) (xy 446.499832 -265.845257) (xy 446.550859 -265.827849)
			(xy 446.603877 -265.818056) (xy 446.657756 -265.816087) (xy 446.711347 -265.821984) (xy 446.763508 -265.83562)
			(xy 446.813128 -265.856707) (xy 446.859149 -265.884793) (xy 446.900591 -265.919281) (xy 446.936569 -265.959435)
			(xy 446.966317 -266.004399) (xy 446.989202 -266.053216) (xy 447.004734 -266.104845) (xy 447.012584 -266.158185)
			(xy 447.013076 -266.185142) (xy 453.818767 -266.185142) (xy 453.822702 -266.131371) (xy 453.834425 -266.078747)
			(xy 453.853685 -266.02839) (xy 453.880071 -265.981373) (xy 453.913023 -265.9387) (xy 453.951836 -265.901279)
			(xy 453.995684 -265.869909) (xy 454.043632 -265.845257) (xy 454.094659 -265.827849) (xy 454.147677 -265.818056)
			(xy 454.201556 -265.816087) (xy 454.255147 -265.821984) (xy 454.307308 -265.83562) (xy 454.356928 -265.856707)
			(xy 454.402949 -265.884793) (xy 454.444391 -265.919281) (xy 454.480369 -265.959435) (xy 454.510117 -266.004399)
			(xy 454.533002 -266.053216) (xy 454.548534 -266.104845) (xy 454.556384 -266.158185) (xy 454.556876 -266.185142)
			(xy 454.556384 -266.212099) (xy 454.548534 -266.265439) (xy 454.533002 -266.317068) (xy 454.510117 -266.365885)
			(xy 454.480369 -266.410849) (xy 454.444391 -266.451003) (xy 454.402949 -266.485491) (xy 454.356928 -266.513577)
			(xy 454.307308 -266.534664) (xy 454.255147 -266.5483) (xy 454.201556 -266.554197) (xy 454.147677 -266.552228)
			(xy 454.094659 -266.542435) (xy 454.043632 -266.525027) (xy 453.995684 -266.500375) (xy 453.951836 -266.469005)
			(xy 453.913023 -266.431584) (xy 453.880071 -266.388911) (xy 453.853685 -266.341894) (xy 453.834425 -266.291537)
			(xy 453.822702 -266.238913) (xy 453.818767 -266.185142) (xy 447.013076 -266.185142) (xy 447.012584 -266.212099)
			(xy 447.004734 -266.265439) (xy 446.989202 -266.317068) (xy 446.966317 -266.365885) (xy 446.936569 -266.410849)
			(xy 446.900591 -266.451003) (xy 446.859149 -266.485491) (xy 446.813128 -266.513577) (xy 446.763508 -266.534664)
			(xy 446.711347 -266.5483) (xy 446.657756 -266.554197) (xy 446.603877 -266.552228) (xy 446.550859 -266.542435)
			(xy 446.499832 -266.525027) (xy 446.451884 -266.500375) (xy 446.408036 -266.469005) (xy 446.369223 -266.431584)
			(xy 446.336271 -266.388911) (xy 446.309885 -266.341894) (xy 446.290625 -266.291537) (xy 446.278902 -266.238913)
			(xy 446.274967 -266.185142) (xy 439.469022 -266.185142) (xy 439.46853 -266.212099) (xy 439.46068 -266.265439)
			(xy 439.445148 -266.317068) (xy 439.422263 -266.365885) (xy 439.392515 -266.410849) (xy 439.356537 -266.451003)
			(xy 439.315095 -266.485491) (xy 439.269074 -266.513577) (xy 439.219454 -266.534664) (xy 439.167293 -266.5483)
			(xy 439.113702 -266.554197) (xy 439.059823 -266.552228) (xy 439.006805 -266.542435) (xy 438.955778 -266.525027)
			(xy 438.90783 -266.500375) (xy 438.863982 -266.469005) (xy 438.825169 -266.431584) (xy 438.792217 -266.388911)
			(xy 438.765831 -266.341894) (xy 438.746571 -266.291537) (xy 438.734848 -266.238913) (xy 438.730913 -266.185142)
			(xy 431.924968 -266.185142) (xy 431.924476 -266.212099) (xy 431.916626 -266.265439) (xy 431.901094 -266.317068)
			(xy 431.878209 -266.365885) (xy 431.848461 -266.410849) (xy 431.812483 -266.451003) (xy 431.771041 -266.485491)
			(xy 431.72502 -266.513577) (xy 431.6754 -266.534664) (xy 431.623239 -266.5483) (xy 431.569648 -266.554197)
			(xy 431.515769 -266.552228) (xy 431.462751 -266.542435) (xy 431.411724 -266.525027) (xy 431.363776 -266.500375)
			(xy 431.319928 -266.469005) (xy 431.281115 -266.431584) (xy 431.248163 -266.388911) (xy 431.221777 -266.341894)
			(xy 431.202517 -266.291537) (xy 431.190794 -266.238913) (xy 431.186859 -266.185142) (xy 425.985178 -266.185142)
			(xy 425.985178 -267.035026) (xy 427.086791 -267.035026) (xy 427.090726 -266.981255) (xy 427.102449 -266.928631)
			(xy 427.121709 -266.878274) (xy 427.148095 -266.831257) (xy 427.181047 -266.788584) (xy 427.21986 -266.751163)
			(xy 427.263708 -266.719793) (xy 427.311656 -266.695141) (xy 427.362683 -266.677733) (xy 427.415701 -266.66794)
			(xy 427.46958 -266.665971) (xy 427.523171 -266.671868) (xy 427.575332 -266.685504) (xy 427.624952 -266.706591)
			(xy 427.670973 -266.734677) (xy 427.712415 -266.769165) (xy 427.748393 -266.809319) (xy 427.778141 -266.854283)
			(xy 427.801026 -266.9031) (xy 427.816558 -266.954729) (xy 427.824408 -267.008069) (xy 427.8249 -267.035026)
			(xy 434.630845 -267.035026) (xy 434.63478 -266.981255) (xy 434.646503 -266.928631) (xy 434.665763 -266.878274)
			(xy 434.692149 -266.831257) (xy 434.725101 -266.788584) (xy 434.763914 -266.751163) (xy 434.807762 -266.719793)
			(xy 434.85571 -266.695141) (xy 434.906737 -266.677733) (xy 434.959755 -266.66794) (xy 435.013634 -266.665971)
			(xy 435.067225 -266.671868) (xy 435.119386 -266.685504) (xy 435.169006 -266.706591) (xy 435.215027 -266.734677)
			(xy 435.256469 -266.769165) (xy 435.292447 -266.809319) (xy 435.322195 -266.854283) (xy 435.34508 -266.9031)
			(xy 435.360612 -266.954729) (xy 435.368462 -267.008069) (xy 435.368954 -267.035026) (xy 442.174899 -267.035026)
			(xy 442.178834 -266.981255) (xy 442.190557 -266.928631) (xy 442.209817 -266.878274) (xy 442.236203 -266.831257)
			(xy 442.269155 -266.788584) (xy 442.307968 -266.751163) (xy 442.351816 -266.719793) (xy 442.399764 -266.695141)
			(xy 442.450791 -266.677733) (xy 442.503809 -266.66794) (xy 442.557688 -266.665971) (xy 442.611279 -266.671868)
			(xy 442.66344 -266.685504) (xy 442.71306 -266.706591) (xy 442.759081 -266.734677) (xy 442.800523 -266.769165)
			(xy 442.836501 -266.809319) (xy 442.866249 -266.854283) (xy 442.889134 -266.9031) (xy 442.904666 -266.954729)
			(xy 442.912516 -267.008069) (xy 442.913008 -267.035026) (xy 449.718699 -267.035026) (xy 449.722634 -266.981255)
			(xy 449.734357 -266.928631) (xy 449.753617 -266.878274) (xy 449.780003 -266.831257) (xy 449.812955 -266.788584)
			(xy 449.851768 -266.751163) (xy 449.895616 -266.719793) (xy 449.943564 -266.695141) (xy 449.994591 -266.677733)
			(xy 450.047609 -266.66794) (xy 450.101488 -266.665971) (xy 450.155079 -266.671868) (xy 450.20724 -266.685504)
			(xy 450.25686 -266.706591) (xy 450.302881 -266.734677) (xy 450.344323 -266.769165) (xy 450.380301 -266.809319)
			(xy 450.410049 -266.854283) (xy 450.432934 -266.9031) (xy 450.448466 -266.954729) (xy 450.456316 -267.008069)
			(xy 450.456808 -267.035026) (xy 450.456316 -267.061983) (xy 450.448466 -267.115323) (xy 450.432934 -267.166952)
			(xy 450.410049 -267.215769) (xy 450.380301 -267.260733) (xy 450.344323 -267.300887) (xy 450.302881 -267.335375)
			(xy 450.25686 -267.363461) (xy 450.20724 -267.384548) (xy 450.155079 -267.398184) (xy 450.101488 -267.404081)
			(xy 450.047609 -267.402112) (xy 449.994591 -267.392319) (xy 449.943564 -267.374911) (xy 449.895616 -267.350259)
			(xy 449.851768 -267.318889) (xy 449.812955 -267.281468) (xy 449.780003 -267.238795) (xy 449.753617 -267.191778)
			(xy 449.734357 -267.141421) (xy 449.722634 -267.088797) (xy 449.718699 -267.035026) (xy 442.913008 -267.035026)
			(xy 442.912516 -267.061983) (xy 442.904666 -267.115323) (xy 442.889134 -267.166952) (xy 442.866249 -267.215769)
			(xy 442.836501 -267.260733) (xy 442.800523 -267.300887) (xy 442.759081 -267.335375) (xy 442.71306 -267.363461)
			(xy 442.66344 -267.384548) (xy 442.611279 -267.398184) (xy 442.557688 -267.404081) (xy 442.503809 -267.402112)
			(xy 442.450791 -267.392319) (xy 442.399764 -267.374911) (xy 442.351816 -267.350259) (xy 442.307968 -267.318889)
			(xy 442.269155 -267.281468) (xy 442.236203 -267.238795) (xy 442.209817 -267.191778) (xy 442.190557 -267.141421)
			(xy 442.178834 -267.088797) (xy 442.174899 -267.035026) (xy 435.368954 -267.035026) (xy 435.368462 -267.061983)
			(xy 435.360612 -267.115323) (xy 435.34508 -267.166952) (xy 435.322195 -267.215769) (xy 435.292447 -267.260733)
			(xy 435.256469 -267.300887) (xy 435.215027 -267.335375) (xy 435.169006 -267.363461) (xy 435.119386 -267.384548)
			(xy 435.067225 -267.398184) (xy 435.013634 -267.404081) (xy 434.959755 -267.402112) (xy 434.906737 -267.392319)
			(xy 434.85571 -267.374911) (xy 434.807762 -267.350259) (xy 434.763914 -267.318889) (xy 434.725101 -267.281468)
			(xy 434.692149 -267.238795) (xy 434.665763 -267.191778) (xy 434.646503 -267.141421) (xy 434.63478 -267.088797)
			(xy 434.630845 -267.035026) (xy 427.8249 -267.035026) (xy 427.824408 -267.061983) (xy 427.816558 -267.115323)
			(xy 427.801026 -267.166952) (xy 427.778141 -267.215769) (xy 427.748393 -267.260733) (xy 427.712415 -267.300887)
			(xy 427.670973 -267.335375) (xy 427.624952 -267.363461) (xy 427.575332 -267.384548) (xy 427.523171 -267.398184)
			(xy 427.46958 -267.404081) (xy 427.415701 -267.402112) (xy 427.362683 -267.392319) (xy 427.311656 -267.374911)
			(xy 427.263708 -267.350259) (xy 427.21986 -267.318889) (xy 427.181047 -267.281468) (xy 427.148095 -267.238795)
			(xy 427.121709 -267.191778) (xy 427.102449 -267.141421) (xy 427.090726 -267.088797) (xy 427.086791 -267.035026)
			(xy 425.985178 -267.035026) (xy 425.985178 -267.885164) (xy 431.186859 -267.885164) (xy 431.190794 -267.831393)
			(xy 431.202517 -267.778769) (xy 431.221777 -267.728412) (xy 431.248163 -267.681395) (xy 431.281115 -267.638722)
			(xy 431.319928 -267.601301) (xy 431.363776 -267.569931) (xy 431.411724 -267.545279) (xy 431.462751 -267.527871)
			(xy 431.515769 -267.518078) (xy 431.569648 -267.516109) (xy 431.623239 -267.522006) (xy 431.6754 -267.535642)
			(xy 431.72502 -267.556729) (xy 431.771041 -267.584815) (xy 431.812483 -267.619303) (xy 431.848461 -267.659457)
			(xy 431.878209 -267.704421) (xy 431.901094 -267.753238) (xy 431.916626 -267.804867) (xy 431.924476 -267.858207)
			(xy 431.924968 -267.885164) (xy 438.730913 -267.885164) (xy 438.734848 -267.831393) (xy 438.746571 -267.778769)
			(xy 438.765831 -267.728412) (xy 438.792217 -267.681395) (xy 438.825169 -267.638722) (xy 438.863982 -267.601301)
			(xy 438.90783 -267.569931) (xy 438.955778 -267.545279) (xy 439.006805 -267.527871) (xy 439.059823 -267.518078)
			(xy 439.113702 -267.516109) (xy 439.167293 -267.522006) (xy 439.219454 -267.535642) (xy 439.269074 -267.556729)
			(xy 439.315095 -267.584815) (xy 439.356537 -267.619303) (xy 439.392515 -267.659457) (xy 439.422263 -267.704421)
			(xy 439.445148 -267.753238) (xy 439.46068 -267.804867) (xy 439.46853 -267.858207) (xy 439.469022 -267.885164)
			(xy 446.274967 -267.885164) (xy 446.278902 -267.831393) (xy 446.290625 -267.778769) (xy 446.309885 -267.728412)
			(xy 446.336271 -267.681395) (xy 446.369223 -267.638722) (xy 446.408036 -267.601301) (xy 446.451884 -267.569931)
			(xy 446.499832 -267.545279) (xy 446.550859 -267.527871) (xy 446.603877 -267.518078) (xy 446.657756 -267.516109)
			(xy 446.711347 -267.522006) (xy 446.763508 -267.535642) (xy 446.813128 -267.556729) (xy 446.859149 -267.584815)
			(xy 446.900591 -267.619303) (xy 446.936569 -267.659457) (xy 446.966317 -267.704421) (xy 446.989202 -267.753238)
			(xy 447.004734 -267.804867) (xy 447.012584 -267.858207) (xy 447.013076 -267.885164) (xy 453.818767 -267.885164)
			(xy 453.822702 -267.831393) (xy 453.834425 -267.778769) (xy 453.853685 -267.728412) (xy 453.880071 -267.681395)
			(xy 453.913023 -267.638722) (xy 453.951836 -267.601301) (xy 453.995684 -267.569931) (xy 454.043632 -267.545279)
			(xy 454.094659 -267.527871) (xy 454.147677 -267.518078) (xy 454.201556 -267.516109) (xy 454.255147 -267.522006)
			(xy 454.307308 -267.535642) (xy 454.356928 -267.556729) (xy 454.402949 -267.584815) (xy 454.444391 -267.619303)
			(xy 454.480369 -267.659457) (xy 454.510117 -267.704421) (xy 454.533002 -267.753238) (xy 454.548534 -267.804867)
			(xy 454.556384 -267.858207) (xy 454.556876 -267.885164) (xy 454.556384 -267.912121) (xy 454.548534 -267.965461)
			(xy 454.533002 -268.01709) (xy 454.510117 -268.065907) (xy 454.480369 -268.110871) (xy 454.444391 -268.151025)
			(xy 454.402949 -268.185513) (xy 454.356928 -268.213599) (xy 454.307308 -268.234686) (xy 454.255147 -268.248322)
			(xy 454.201556 -268.254219) (xy 454.147677 -268.25225) (xy 454.094659 -268.242457) (xy 454.043632 -268.225049)
			(xy 453.995684 -268.200397) (xy 453.951836 -268.169027) (xy 453.913023 -268.131606) (xy 453.880071 -268.088933)
			(xy 453.853685 -268.041916) (xy 453.834425 -267.991559) (xy 453.822702 -267.938935) (xy 453.818767 -267.885164)
			(xy 447.013076 -267.885164) (xy 447.012584 -267.912121) (xy 447.004734 -267.965461) (xy 446.989202 -268.01709)
			(xy 446.966317 -268.065907) (xy 446.936569 -268.110871) (xy 446.900591 -268.151025) (xy 446.859149 -268.185513)
			(xy 446.813128 -268.213599) (xy 446.763508 -268.234686) (xy 446.711347 -268.248322) (xy 446.657756 -268.254219)
			(xy 446.603877 -268.25225) (xy 446.550859 -268.242457) (xy 446.499832 -268.225049) (xy 446.451884 -268.200397)
			(xy 446.408036 -268.169027) (xy 446.369223 -268.131606) (xy 446.336271 -268.088933) (xy 446.309885 -268.041916)
			(xy 446.290625 -267.991559) (xy 446.278902 -267.938935) (xy 446.274967 -267.885164) (xy 439.469022 -267.885164)
			(xy 439.46853 -267.912121) (xy 439.46068 -267.965461) (xy 439.445148 -268.01709) (xy 439.422263 -268.065907)
			(xy 439.392515 -268.110871) (xy 439.356537 -268.151025) (xy 439.315095 -268.185513) (xy 439.269074 -268.213599)
			(xy 439.219454 -268.234686) (xy 439.167293 -268.248322) (xy 439.113702 -268.254219) (xy 439.059823 -268.25225)
			(xy 439.006805 -268.242457) (xy 438.955778 -268.225049) (xy 438.90783 -268.200397) (xy 438.863982 -268.169027)
			(xy 438.825169 -268.131606) (xy 438.792217 -268.088933) (xy 438.765831 -268.041916) (xy 438.746571 -267.991559)
			(xy 438.734848 -267.938935) (xy 438.730913 -267.885164) (xy 431.924968 -267.885164) (xy 431.924476 -267.912121)
			(xy 431.916626 -267.965461) (xy 431.901094 -268.01709) (xy 431.878209 -268.065907) (xy 431.848461 -268.110871)
			(xy 431.812483 -268.151025) (xy 431.771041 -268.185513) (xy 431.72502 -268.213599) (xy 431.6754 -268.234686)
			(xy 431.623239 -268.248322) (xy 431.569648 -268.254219) (xy 431.515769 -268.25225) (xy 431.462751 -268.242457)
			(xy 431.411724 -268.225049) (xy 431.363776 -268.200397) (xy 431.319928 -268.169027) (xy 431.281115 -268.131606)
			(xy 431.248163 -268.088933) (xy 431.221777 -268.041916) (xy 431.202517 -267.991559) (xy 431.190794 -267.938935)
			(xy 431.186859 -267.885164) (xy 425.985178 -267.885164) (xy 425.985178 -268.735048) (xy 427.086791 -268.735048)
			(xy 427.090726 -268.681277) (xy 427.102449 -268.628653) (xy 427.121709 -268.578296) (xy 427.148095 -268.531279)
			(xy 427.181047 -268.488606) (xy 427.21986 -268.451185) (xy 427.263708 -268.419815) (xy 427.311656 -268.395163)
			(xy 427.362683 -268.377755) (xy 427.415701 -268.367962) (xy 427.46958 -268.365993) (xy 427.523171 -268.37189)
			(xy 427.575332 -268.385526) (xy 427.624952 -268.406613) (xy 427.670973 -268.434699) (xy 427.712415 -268.469187)
			(xy 427.748393 -268.509341) (xy 427.778141 -268.554305) (xy 427.801026 -268.603122) (xy 427.816558 -268.654751)
			(xy 427.824408 -268.708091) (xy 427.8249 -268.735048) (xy 434.630845 -268.735048) (xy 434.63478 -268.681277)
			(xy 434.646503 -268.628653) (xy 434.665763 -268.578296) (xy 434.692149 -268.531279) (xy 434.725101 -268.488606)
			(xy 434.763914 -268.451185) (xy 434.807762 -268.419815) (xy 434.85571 -268.395163) (xy 434.906737 -268.377755)
			(xy 434.959755 -268.367962) (xy 435.013634 -268.365993) (xy 435.067225 -268.37189) (xy 435.119386 -268.385526)
			(xy 435.169006 -268.406613) (xy 435.215027 -268.434699) (xy 435.256469 -268.469187) (xy 435.292447 -268.509341)
			(xy 435.322195 -268.554305) (xy 435.34508 -268.603122) (xy 435.360612 -268.654751) (xy 435.368462 -268.708091)
			(xy 435.368954 -268.735048) (xy 442.174899 -268.735048) (xy 442.178834 -268.681277) (xy 442.190557 -268.628653)
			(xy 442.209817 -268.578296) (xy 442.236203 -268.531279) (xy 442.269155 -268.488606) (xy 442.307968 -268.451185)
			(xy 442.351816 -268.419815) (xy 442.399764 -268.395163) (xy 442.450791 -268.377755) (xy 442.503809 -268.367962)
			(xy 442.557688 -268.365993) (xy 442.611279 -268.37189) (xy 442.66344 -268.385526) (xy 442.71306 -268.406613)
			(xy 442.759081 -268.434699) (xy 442.800523 -268.469187) (xy 442.836501 -268.509341) (xy 442.866249 -268.554305)
			(xy 442.889134 -268.603122) (xy 442.904666 -268.654751) (xy 442.912516 -268.708091) (xy 442.913008 -268.735048)
			(xy 449.718699 -268.735048) (xy 449.722634 -268.681277) (xy 449.734357 -268.628653) (xy 449.753617 -268.578296)
			(xy 449.780003 -268.531279) (xy 449.812955 -268.488606) (xy 449.851768 -268.451185) (xy 449.895616 -268.419815)
			(xy 449.943564 -268.395163) (xy 449.994591 -268.377755) (xy 450.047609 -268.367962) (xy 450.101488 -268.365993)
			(xy 450.155079 -268.37189) (xy 450.20724 -268.385526) (xy 450.25686 -268.406613) (xy 450.302881 -268.434699)
			(xy 450.344323 -268.469187) (xy 450.380301 -268.509341) (xy 450.410049 -268.554305) (xy 450.432934 -268.603122)
			(xy 450.448466 -268.654751) (xy 450.456316 -268.708091) (xy 450.456808 -268.735048) (xy 450.456316 -268.762005)
			(xy 450.448466 -268.815345) (xy 450.432934 -268.866974) (xy 450.410049 -268.915791) (xy 450.380301 -268.960755)
			(xy 450.344323 -269.000909) (xy 450.302881 -269.035397) (xy 450.25686 -269.063483) (xy 450.20724 -269.08457)
			(xy 450.155079 -269.098206) (xy 450.101488 -269.104103) (xy 450.047609 -269.102134) (xy 449.994591 -269.092341)
			(xy 449.943564 -269.074933) (xy 449.895616 -269.050281) (xy 449.851768 -269.018911) (xy 449.812955 -268.98149)
			(xy 449.780003 -268.938817) (xy 449.753617 -268.8918) (xy 449.734357 -268.841443) (xy 449.722634 -268.788819)
			(xy 449.718699 -268.735048) (xy 442.913008 -268.735048) (xy 442.912516 -268.762005) (xy 442.904666 -268.815345)
			(xy 442.889134 -268.866974) (xy 442.866249 -268.915791) (xy 442.836501 -268.960755) (xy 442.800523 -269.000909)
			(xy 442.759081 -269.035397) (xy 442.71306 -269.063483) (xy 442.66344 -269.08457) (xy 442.611279 -269.098206)
			(xy 442.557688 -269.104103) (xy 442.503809 -269.102134) (xy 442.450791 -269.092341) (xy 442.399764 -269.074933)
			(xy 442.351816 -269.050281) (xy 442.307968 -269.018911) (xy 442.269155 -268.98149) (xy 442.236203 -268.938817)
			(xy 442.209817 -268.8918) (xy 442.190557 -268.841443) (xy 442.178834 -268.788819) (xy 442.174899 -268.735048)
			(xy 435.368954 -268.735048) (xy 435.368462 -268.762005) (xy 435.360612 -268.815345) (xy 435.34508 -268.866974)
			(xy 435.322195 -268.915791) (xy 435.292447 -268.960755) (xy 435.256469 -269.000909) (xy 435.215027 -269.035397)
			(xy 435.169006 -269.063483) (xy 435.119386 -269.08457) (xy 435.067225 -269.098206) (xy 435.013634 -269.104103)
			(xy 434.959755 -269.102134) (xy 434.906737 -269.092341) (xy 434.85571 -269.074933) (xy 434.807762 -269.050281)
			(xy 434.763914 -269.018911) (xy 434.725101 -268.98149) (xy 434.692149 -268.938817) (xy 434.665763 -268.8918)
			(xy 434.646503 -268.841443) (xy 434.63478 -268.788819) (xy 434.630845 -268.735048) (xy 427.8249 -268.735048)
			(xy 427.824408 -268.762005) (xy 427.816558 -268.815345) (xy 427.801026 -268.866974) (xy 427.778141 -268.915791)
			(xy 427.748393 -268.960755) (xy 427.712415 -269.000909) (xy 427.670973 -269.035397) (xy 427.624952 -269.063483)
			(xy 427.575332 -269.08457) (xy 427.523171 -269.098206) (xy 427.46958 -269.104103) (xy 427.415701 -269.102134)
			(xy 427.362683 -269.092341) (xy 427.311656 -269.074933) (xy 427.263708 -269.050281) (xy 427.21986 -269.018911)
			(xy 427.181047 -268.98149) (xy 427.148095 -268.938817) (xy 427.121709 -268.8918) (xy 427.102449 -268.841443)
			(xy 427.090726 -268.788819) (xy 427.086791 -268.735048) (xy 425.985178 -268.735048) (xy 425.985178 -269.585186)
			(xy 431.186859 -269.585186) (xy 431.190794 -269.531415) (xy 431.202517 -269.478791) (xy 431.221777 -269.428434)
			(xy 431.248163 -269.381417) (xy 431.281115 -269.338744) (xy 431.319928 -269.301323) (xy 431.363776 -269.269953)
			(xy 431.411724 -269.245301) (xy 431.462751 -269.227893) (xy 431.515769 -269.2181) (xy 431.569648 -269.216131)
			(xy 431.623239 -269.222028) (xy 431.6754 -269.235664) (xy 431.72502 -269.256751) (xy 431.771041 -269.284837)
			(xy 431.812483 -269.319325) (xy 431.848461 -269.359479) (xy 431.878209 -269.404443) (xy 431.901094 -269.45326)
			(xy 431.916626 -269.504889) (xy 431.924476 -269.558229) (xy 431.924968 -269.585186) (xy 438.730913 -269.585186)
			(xy 438.734848 -269.531415) (xy 438.746571 -269.478791) (xy 438.765831 -269.428434) (xy 438.792217 -269.381417)
			(xy 438.825169 -269.338744) (xy 438.863982 -269.301323) (xy 438.90783 -269.269953) (xy 438.955778 -269.245301)
			(xy 439.006805 -269.227893) (xy 439.059823 -269.2181) (xy 439.113702 -269.216131) (xy 439.167293 -269.222028)
			(xy 439.219454 -269.235664) (xy 439.269074 -269.256751) (xy 439.315095 -269.284837) (xy 439.356537 -269.319325)
			(xy 439.392515 -269.359479) (xy 439.422263 -269.404443) (xy 439.445148 -269.45326) (xy 439.46068 -269.504889)
			(xy 439.46853 -269.558229) (xy 439.469022 -269.585186) (xy 446.274967 -269.585186) (xy 446.278902 -269.531415)
			(xy 446.290625 -269.478791) (xy 446.309885 -269.428434) (xy 446.336271 -269.381417) (xy 446.369223 -269.338744)
			(xy 446.408036 -269.301323) (xy 446.451884 -269.269953) (xy 446.499832 -269.245301) (xy 446.550859 -269.227893)
			(xy 446.603877 -269.2181) (xy 446.657756 -269.216131) (xy 446.711347 -269.222028) (xy 446.763508 -269.235664)
			(xy 446.813128 -269.256751) (xy 446.859149 -269.284837) (xy 446.900591 -269.319325) (xy 446.936569 -269.359479)
			(xy 446.966317 -269.404443) (xy 446.989202 -269.45326) (xy 447.004734 -269.504889) (xy 447.012584 -269.558229)
			(xy 447.013076 -269.585186) (xy 453.818767 -269.585186) (xy 453.822702 -269.531415) (xy 453.834425 -269.478791)
			(xy 453.853685 -269.428434) (xy 453.880071 -269.381417) (xy 453.913023 -269.338744) (xy 453.951836 -269.301323)
			(xy 453.995684 -269.269953) (xy 454.043632 -269.245301) (xy 454.094659 -269.227893) (xy 454.147677 -269.2181)
			(xy 454.201556 -269.216131) (xy 454.255147 -269.222028) (xy 454.307308 -269.235664) (xy 454.356928 -269.256751)
			(xy 454.402949 -269.284837) (xy 454.444391 -269.319325) (xy 454.480369 -269.359479) (xy 454.510117 -269.404443)
			(xy 454.533002 -269.45326) (xy 454.548534 -269.504889) (xy 454.556384 -269.558229) (xy 454.556876 -269.585186)
			(xy 454.556384 -269.612143) (xy 454.548534 -269.665483) (xy 454.533002 -269.717112) (xy 454.510117 -269.765929)
			(xy 454.480369 -269.810893) (xy 454.444391 -269.851047) (xy 454.402949 -269.885535) (xy 454.356928 -269.913621)
			(xy 454.307308 -269.934708) (xy 454.255147 -269.948344) (xy 454.201556 -269.954241) (xy 454.147677 -269.952272)
			(xy 454.094659 -269.942479) (xy 454.043632 -269.925071) (xy 453.995684 -269.900419) (xy 453.951836 -269.869049)
			(xy 453.913023 -269.831628) (xy 453.880071 -269.788955) (xy 453.853685 -269.741938) (xy 453.834425 -269.691581)
			(xy 453.822702 -269.638957) (xy 453.818767 -269.585186) (xy 447.013076 -269.585186) (xy 447.012584 -269.612143)
			(xy 447.004734 -269.665483) (xy 446.989202 -269.717112) (xy 446.966317 -269.765929) (xy 446.936569 -269.810893)
			(xy 446.900591 -269.851047) (xy 446.859149 -269.885535) (xy 446.813128 -269.913621) (xy 446.763508 -269.934708)
			(xy 446.711347 -269.948344) (xy 446.657756 -269.954241) (xy 446.603877 -269.952272) (xy 446.550859 -269.942479)
			(xy 446.499832 -269.925071) (xy 446.451884 -269.900419) (xy 446.408036 -269.869049) (xy 446.369223 -269.831628)
			(xy 446.336271 -269.788955) (xy 446.309885 -269.741938) (xy 446.290625 -269.691581) (xy 446.278902 -269.638957)
			(xy 446.274967 -269.585186) (xy 439.469022 -269.585186) (xy 439.46853 -269.612143) (xy 439.46068 -269.665483)
			(xy 439.445148 -269.717112) (xy 439.422263 -269.765929) (xy 439.392515 -269.810893) (xy 439.356537 -269.851047)
			(xy 439.315095 -269.885535) (xy 439.269074 -269.913621) (xy 439.219454 -269.934708) (xy 439.167293 -269.948344)
			(xy 439.113702 -269.954241) (xy 439.059823 -269.952272) (xy 439.006805 -269.942479) (xy 438.955778 -269.925071)
			(xy 438.90783 -269.900419) (xy 438.863982 -269.869049) (xy 438.825169 -269.831628) (xy 438.792217 -269.788955)
			(xy 438.765831 -269.741938) (xy 438.746571 -269.691581) (xy 438.734848 -269.638957) (xy 438.730913 -269.585186)
			(xy 431.924968 -269.585186) (xy 431.924476 -269.612143) (xy 431.916626 -269.665483) (xy 431.901094 -269.717112)
			(xy 431.878209 -269.765929) (xy 431.848461 -269.810893) (xy 431.812483 -269.851047) (xy 431.771041 -269.885535)
			(xy 431.72502 -269.913621) (xy 431.6754 -269.934708) (xy 431.623239 -269.948344) (xy 431.569648 -269.954241)
			(xy 431.515769 -269.952272) (xy 431.462751 -269.942479) (xy 431.411724 -269.925071) (xy 431.363776 -269.900419)
			(xy 431.319928 -269.869049) (xy 431.281115 -269.831628) (xy 431.248163 -269.788955) (xy 431.221777 -269.741938)
			(xy 431.202517 -269.691581) (xy 431.190794 -269.638957) (xy 431.186859 -269.585186) (xy 425.985178 -269.585186)
			(xy 425.985178 -270.43507) (xy 427.086791 -270.43507) (xy 427.090726 -270.381299) (xy 427.102449 -270.328675)
			(xy 427.121709 -270.278318) (xy 427.148095 -270.231301) (xy 427.181047 -270.188628) (xy 427.21986 -270.151207)
			(xy 427.263708 -270.119837) (xy 427.311656 -270.095185) (xy 427.362683 -270.077777) (xy 427.415701 -270.067984)
			(xy 427.46958 -270.066015) (xy 427.523171 -270.071912) (xy 427.575332 -270.085548) (xy 427.624952 -270.106635)
			(xy 427.670973 -270.134721) (xy 427.712415 -270.169209) (xy 427.748393 -270.209363) (xy 427.778141 -270.254327)
			(xy 427.801026 -270.303144) (xy 427.816558 -270.354773) (xy 427.824408 -270.408113) (xy 427.8249 -270.43507)
			(xy 431.186859 -270.43507) (xy 431.190794 -270.381299) (xy 431.202517 -270.328675) (xy 431.221777 -270.278318)
			(xy 431.248163 -270.231301) (xy 431.281115 -270.188628) (xy 431.319928 -270.151207) (xy 431.363776 -270.119837)
			(xy 431.411724 -270.095185) (xy 431.462751 -270.077777) (xy 431.515769 -270.067984) (xy 431.569648 -270.066015)
			(xy 431.623239 -270.071912) (xy 431.6754 -270.085548) (xy 431.72502 -270.106635) (xy 431.771041 -270.134721)
			(xy 431.812483 -270.169209) (xy 431.848461 -270.209363) (xy 431.878209 -270.254327) (xy 431.901094 -270.303144)
			(xy 431.916626 -270.354773) (xy 431.924476 -270.408113) (xy 431.924968 -270.43507) (xy 434.630845 -270.43507)
			(xy 434.63478 -270.381299) (xy 434.646503 -270.328675) (xy 434.665763 -270.278318) (xy 434.692149 -270.231301)
			(xy 434.725101 -270.188628) (xy 434.763914 -270.151207) (xy 434.807762 -270.119837) (xy 434.85571 -270.095185)
			(xy 434.906737 -270.077777) (xy 434.959755 -270.067984) (xy 435.013634 -270.066015) (xy 435.067225 -270.071912)
			(xy 435.119386 -270.085548) (xy 435.169006 -270.106635) (xy 435.215027 -270.134721) (xy 435.256469 -270.169209)
			(xy 435.292447 -270.209363) (xy 435.322195 -270.254327) (xy 435.34508 -270.303144) (xy 435.360612 -270.354773)
			(xy 435.368462 -270.408113) (xy 435.368954 -270.43507) (xy 438.730913 -270.43507) (xy 438.734848 -270.381299)
			(xy 438.746571 -270.328675) (xy 438.765831 -270.278318) (xy 438.792217 -270.231301) (xy 438.825169 -270.188628)
			(xy 438.863982 -270.151207) (xy 438.90783 -270.119837) (xy 438.955778 -270.095185) (xy 439.006805 -270.077777)
			(xy 439.059823 -270.067984) (xy 439.113702 -270.066015) (xy 439.167293 -270.071912) (xy 439.219454 -270.085548)
			(xy 439.269074 -270.106635) (xy 439.315095 -270.134721) (xy 439.356537 -270.169209) (xy 439.392515 -270.209363)
			(xy 439.422263 -270.254327) (xy 439.445148 -270.303144) (xy 439.46068 -270.354773) (xy 439.46853 -270.408113)
			(xy 439.469022 -270.43507) (xy 442.174899 -270.43507) (xy 442.178834 -270.381299) (xy 442.190557 -270.328675)
			(xy 442.209817 -270.278318) (xy 442.236203 -270.231301) (xy 442.269155 -270.188628) (xy 442.307968 -270.151207)
			(xy 442.351816 -270.119837) (xy 442.399764 -270.095185) (xy 442.450791 -270.077777) (xy 442.503809 -270.067984)
			(xy 442.557688 -270.066015) (xy 442.611279 -270.071912) (xy 442.66344 -270.085548) (xy 442.71306 -270.106635)
			(xy 442.759081 -270.134721) (xy 442.800523 -270.169209) (xy 442.836501 -270.209363) (xy 442.866249 -270.254327)
			(xy 442.889134 -270.303144) (xy 442.904666 -270.354773) (xy 442.912516 -270.408113) (xy 442.913008 -270.43507)
			(xy 446.274967 -270.43507) (xy 446.278902 -270.381299) (xy 446.290625 -270.328675) (xy 446.309885 -270.278318)
			(xy 446.336271 -270.231301) (xy 446.369223 -270.188628) (xy 446.408036 -270.151207) (xy 446.451884 -270.119837)
			(xy 446.499832 -270.095185) (xy 446.550859 -270.077777) (xy 446.603877 -270.067984) (xy 446.657756 -270.066015)
			(xy 446.711347 -270.071912) (xy 446.763508 -270.085548) (xy 446.813128 -270.106635) (xy 446.859149 -270.134721)
			(xy 446.900591 -270.169209) (xy 446.936569 -270.209363) (xy 446.966317 -270.254327) (xy 446.989202 -270.303144)
			(xy 447.004734 -270.354773) (xy 447.012584 -270.408113) (xy 447.013076 -270.43507) (xy 449.718699 -270.43507)
			(xy 449.722634 -270.381299) (xy 449.734357 -270.328675) (xy 449.753617 -270.278318) (xy 449.780003 -270.231301)
			(xy 449.812955 -270.188628) (xy 449.851768 -270.151207) (xy 449.895616 -270.119837) (xy 449.943564 -270.095185)
			(xy 449.994591 -270.077777) (xy 450.047609 -270.067984) (xy 450.101488 -270.066015) (xy 450.155079 -270.071912)
			(xy 450.20724 -270.085548) (xy 450.25686 -270.106635) (xy 450.302881 -270.134721) (xy 450.344323 -270.169209)
			(xy 450.380301 -270.209363) (xy 450.410049 -270.254327) (xy 450.432934 -270.303144) (xy 450.448466 -270.354773)
			(xy 450.456316 -270.408113) (xy 450.456808 -270.43507) (xy 453.818767 -270.43507) (xy 453.822702 -270.381299)
			(xy 453.834425 -270.328675) (xy 453.853685 -270.278318) (xy 453.880071 -270.231301) (xy 453.913023 -270.188628)
			(xy 453.951836 -270.151207) (xy 453.995684 -270.119837) (xy 454.043632 -270.095185) (xy 454.094659 -270.077777)
			(xy 454.147677 -270.067984) (xy 454.201556 -270.066015) (xy 454.255147 -270.071912) (xy 454.307308 -270.085548)
			(xy 454.356928 -270.106635) (xy 454.402949 -270.134721) (xy 454.444391 -270.169209) (xy 454.480369 -270.209363)
			(xy 454.510117 -270.254327) (xy 454.533002 -270.303144) (xy 454.548534 -270.354773) (xy 454.556384 -270.408113)
			(xy 454.556876 -270.43507) (xy 454.556384 -270.462027) (xy 454.548534 -270.515367) (xy 454.533002 -270.566996)
			(xy 454.510117 -270.615813) (xy 454.480369 -270.660777) (xy 454.444391 -270.700931) (xy 454.402949 -270.735419)
			(xy 454.356928 -270.763505) (xy 454.307308 -270.784592) (xy 454.255147 -270.798228) (xy 454.201556 -270.804125)
			(xy 454.147677 -270.802156) (xy 454.094659 -270.792363) (xy 454.043632 -270.774955) (xy 453.995684 -270.750303)
			(xy 453.951836 -270.718933) (xy 453.913023 -270.681512) (xy 453.880071 -270.638839) (xy 453.853685 -270.591822)
			(xy 453.834425 -270.541465) (xy 453.822702 -270.488841) (xy 453.818767 -270.43507) (xy 450.456808 -270.43507)
			(xy 450.456316 -270.462027) (xy 450.448466 -270.515367) (xy 450.432934 -270.566996) (xy 450.410049 -270.615813)
			(xy 450.380301 -270.660777) (xy 450.344323 -270.700931) (xy 450.302881 -270.735419) (xy 450.25686 -270.763505)
			(xy 450.20724 -270.784592) (xy 450.155079 -270.798228) (xy 450.101488 -270.804125) (xy 450.047609 -270.802156)
			(xy 449.994591 -270.792363) (xy 449.943564 -270.774955) (xy 449.895616 -270.750303) (xy 449.851768 -270.718933)
			(xy 449.812955 -270.681512) (xy 449.780003 -270.638839) (xy 449.753617 -270.591822) (xy 449.734357 -270.541465)
			(xy 449.722634 -270.488841) (xy 449.718699 -270.43507) (xy 447.013076 -270.43507) (xy 447.012584 -270.462027)
			(xy 447.004734 -270.515367) (xy 446.989202 -270.566996) (xy 446.966317 -270.615813) (xy 446.936569 -270.660777)
			(xy 446.900591 -270.700931) (xy 446.859149 -270.735419) (xy 446.813128 -270.763505) (xy 446.763508 -270.784592)
			(xy 446.711347 -270.798228) (xy 446.657756 -270.804125) (xy 446.603877 -270.802156) (xy 446.550859 -270.792363)
			(xy 446.499832 -270.774955) (xy 446.451884 -270.750303) (xy 446.408036 -270.718933) (xy 446.369223 -270.681512)
			(xy 446.336271 -270.638839) (xy 446.309885 -270.591822) (xy 446.290625 -270.541465) (xy 446.278902 -270.488841)
			(xy 446.274967 -270.43507) (xy 442.913008 -270.43507) (xy 442.912516 -270.462027) (xy 442.904666 -270.515367)
			(xy 442.889134 -270.566996) (xy 442.866249 -270.615813) (xy 442.836501 -270.660777) (xy 442.800523 -270.700931)
			(xy 442.759081 -270.735419) (xy 442.71306 -270.763505) (xy 442.66344 -270.784592) (xy 442.611279 -270.798228)
			(xy 442.557688 -270.804125) (xy 442.503809 -270.802156) (xy 442.450791 -270.792363) (xy 442.399764 -270.774955)
			(xy 442.351816 -270.750303) (xy 442.307968 -270.718933) (xy 442.269155 -270.681512) (xy 442.236203 -270.638839)
			(xy 442.209817 -270.591822) (xy 442.190557 -270.541465) (xy 442.178834 -270.488841) (xy 442.174899 -270.43507)
			(xy 439.469022 -270.43507) (xy 439.46853 -270.462027) (xy 439.46068 -270.515367) (xy 439.445148 -270.566996)
			(xy 439.422263 -270.615813) (xy 439.392515 -270.660777) (xy 439.356537 -270.700931) (xy 439.315095 -270.735419)
			(xy 439.269074 -270.763505) (xy 439.219454 -270.784592) (xy 439.167293 -270.798228) (xy 439.113702 -270.804125)
			(xy 439.059823 -270.802156) (xy 439.006805 -270.792363) (xy 438.955778 -270.774955) (xy 438.90783 -270.750303)
			(xy 438.863982 -270.718933) (xy 438.825169 -270.681512) (xy 438.792217 -270.638839) (xy 438.765831 -270.591822)
			(xy 438.746571 -270.541465) (xy 438.734848 -270.488841) (xy 438.730913 -270.43507) (xy 435.368954 -270.43507)
			(xy 435.368462 -270.462027) (xy 435.360612 -270.515367) (xy 435.34508 -270.566996) (xy 435.322195 -270.615813)
			(xy 435.292447 -270.660777) (xy 435.256469 -270.700931) (xy 435.215027 -270.735419) (xy 435.169006 -270.763505)
			(xy 435.119386 -270.784592) (xy 435.067225 -270.798228) (xy 435.013634 -270.804125) (xy 434.959755 -270.802156)
			(xy 434.906737 -270.792363) (xy 434.85571 -270.774955) (xy 434.807762 -270.750303) (xy 434.763914 -270.718933)
			(xy 434.725101 -270.681512) (xy 434.692149 -270.638839) (xy 434.665763 -270.591822) (xy 434.646503 -270.541465)
			(xy 434.63478 -270.488841) (xy 434.630845 -270.43507) (xy 431.924968 -270.43507) (xy 431.924476 -270.462027)
			(xy 431.916626 -270.515367) (xy 431.901094 -270.566996) (xy 431.878209 -270.615813) (xy 431.848461 -270.660777)
			(xy 431.812483 -270.700931) (xy 431.771041 -270.735419) (xy 431.72502 -270.763505) (xy 431.6754 -270.784592)
			(xy 431.623239 -270.798228) (xy 431.569648 -270.804125) (xy 431.515769 -270.802156) (xy 431.462751 -270.792363)
			(xy 431.411724 -270.774955) (xy 431.363776 -270.750303) (xy 431.319928 -270.718933) (xy 431.281115 -270.681512)
			(xy 431.248163 -270.638839) (xy 431.221777 -270.591822) (xy 431.202517 -270.541465) (xy 431.190794 -270.488841)
			(xy 431.186859 -270.43507) (xy 427.8249 -270.43507) (xy 427.824408 -270.462027) (xy 427.816558 -270.515367)
			(xy 427.801026 -270.566996) (xy 427.778141 -270.615813) (xy 427.748393 -270.660777) (xy 427.712415 -270.700931)
			(xy 427.670973 -270.735419) (xy 427.624952 -270.763505) (xy 427.575332 -270.784592) (xy 427.523171 -270.798228)
			(xy 427.46958 -270.804125) (xy 427.415701 -270.802156) (xy 427.362683 -270.792363) (xy 427.311656 -270.774955)
			(xy 427.263708 -270.750303) (xy 427.21986 -270.718933) (xy 427.181047 -270.681512) (xy 427.148095 -270.638839)
			(xy 427.121709 -270.591822) (xy 427.102449 -270.541465) (xy 427.090726 -270.488841) (xy 427.086791 -270.43507)
			(xy 425.985178 -270.43507) (xy 425.985178 -271.284954) (xy 427.086791 -271.284954) (xy 427.090726 -271.231183)
			(xy 427.102449 -271.178559) (xy 427.121709 -271.128202) (xy 427.148095 -271.081185) (xy 427.181047 -271.038512)
			(xy 427.21986 -271.001091) (xy 427.263708 -270.969721) (xy 427.311656 -270.945069) (xy 427.362683 -270.927661)
			(xy 427.415701 -270.917868) (xy 427.46958 -270.915899) (xy 427.523171 -270.921796) (xy 427.575332 -270.935432)
			(xy 427.624952 -270.956519) (xy 427.670973 -270.984605) (xy 427.712415 -271.019093) (xy 427.748393 -271.059247)
			(xy 427.778141 -271.104211) (xy 427.801026 -271.153028) (xy 427.816558 -271.204657) (xy 427.824408 -271.257997)
			(xy 427.8249 -271.284954) (xy 434.630845 -271.284954) (xy 434.63478 -271.231183) (xy 434.646503 -271.178559)
			(xy 434.665763 -271.128202) (xy 434.692149 -271.081185) (xy 434.725101 -271.038512) (xy 434.763914 -271.001091)
			(xy 434.807762 -270.969721) (xy 434.85571 -270.945069) (xy 434.906737 -270.927661) (xy 434.959755 -270.917868)
			(xy 435.013634 -270.915899) (xy 435.067225 -270.921796) (xy 435.119386 -270.935432) (xy 435.169006 -270.956519)
			(xy 435.215027 -270.984605) (xy 435.256469 -271.019093) (xy 435.292447 -271.059247) (xy 435.322195 -271.104211)
			(xy 435.34508 -271.153028) (xy 435.360612 -271.204657) (xy 435.368462 -271.257997) (xy 435.368954 -271.284954)
			(xy 442.174899 -271.284954) (xy 442.178834 -271.231183) (xy 442.190557 -271.178559) (xy 442.209817 -271.128202)
			(xy 442.236203 -271.081185) (xy 442.269155 -271.038512) (xy 442.307968 -271.001091) (xy 442.351816 -270.969721)
			(xy 442.399764 -270.945069) (xy 442.450791 -270.927661) (xy 442.503809 -270.917868) (xy 442.557688 -270.915899)
			(xy 442.611279 -270.921796) (xy 442.66344 -270.935432) (xy 442.71306 -270.956519) (xy 442.759081 -270.984605)
			(xy 442.800523 -271.019093) (xy 442.836501 -271.059247) (xy 442.866249 -271.104211) (xy 442.889134 -271.153028)
			(xy 442.904666 -271.204657) (xy 442.912516 -271.257997) (xy 442.913008 -271.284954) (xy 449.718699 -271.284954)
			(xy 449.722634 -271.231183) (xy 449.734357 -271.178559) (xy 449.753617 -271.128202) (xy 449.780003 -271.081185)
			(xy 449.812955 -271.038512) (xy 449.851768 -271.001091) (xy 449.895616 -270.969721) (xy 449.943564 -270.945069)
			(xy 449.994591 -270.927661) (xy 450.047609 -270.917868) (xy 450.101488 -270.915899) (xy 450.155079 -270.921796)
			(xy 450.20724 -270.935432) (xy 450.25686 -270.956519) (xy 450.302881 -270.984605) (xy 450.344323 -271.019093)
			(xy 450.380301 -271.059247) (xy 450.410049 -271.104211) (xy 450.432934 -271.153028) (xy 450.448466 -271.204657)
			(xy 450.456316 -271.257997) (xy 450.456808 -271.284954) (xy 450.456316 -271.311911) (xy 450.448466 -271.365251)
			(xy 450.432934 -271.41688) (xy 450.410049 -271.465697) (xy 450.380301 -271.510661) (xy 450.344323 -271.550815)
			(xy 450.302881 -271.585303) (xy 450.25686 -271.613389) (xy 450.20724 -271.634476) (xy 450.155079 -271.648112)
			(xy 450.101488 -271.654009) (xy 450.047609 -271.65204) (xy 449.994591 -271.642247) (xy 449.943564 -271.624839)
			(xy 449.895616 -271.600187) (xy 449.851768 -271.568817) (xy 449.812955 -271.531396) (xy 449.780003 -271.488723)
			(xy 449.753617 -271.441706) (xy 449.734357 -271.391349) (xy 449.722634 -271.338725) (xy 449.718699 -271.284954)
			(xy 442.913008 -271.284954) (xy 442.912516 -271.311911) (xy 442.904666 -271.365251) (xy 442.889134 -271.41688)
			(xy 442.866249 -271.465697) (xy 442.836501 -271.510661) (xy 442.800523 -271.550815) (xy 442.759081 -271.585303)
			(xy 442.71306 -271.613389) (xy 442.66344 -271.634476) (xy 442.611279 -271.648112) (xy 442.557688 -271.654009)
			(xy 442.503809 -271.65204) (xy 442.450791 -271.642247) (xy 442.399764 -271.624839) (xy 442.351816 -271.600187)
			(xy 442.307968 -271.568817) (xy 442.269155 -271.531396) (xy 442.236203 -271.488723) (xy 442.209817 -271.441706)
			(xy 442.190557 -271.391349) (xy 442.178834 -271.338725) (xy 442.174899 -271.284954) (xy 435.368954 -271.284954)
			(xy 435.368462 -271.311911) (xy 435.360612 -271.365251) (xy 435.34508 -271.41688) (xy 435.322195 -271.465697)
			(xy 435.292447 -271.510661) (xy 435.256469 -271.550815) (xy 435.215027 -271.585303) (xy 435.169006 -271.613389)
			(xy 435.119386 -271.634476) (xy 435.067225 -271.648112) (xy 435.013634 -271.654009) (xy 434.959755 -271.65204)
			(xy 434.906737 -271.642247) (xy 434.85571 -271.624839) (xy 434.807762 -271.600187) (xy 434.763914 -271.568817)
			(xy 434.725101 -271.531396) (xy 434.692149 -271.488723) (xy 434.665763 -271.441706) (xy 434.646503 -271.391349)
			(xy 434.63478 -271.338725) (xy 434.630845 -271.284954) (xy 427.8249 -271.284954) (xy 427.824408 -271.311911)
			(xy 427.816558 -271.365251) (xy 427.801026 -271.41688) (xy 427.778141 -271.465697) (xy 427.748393 -271.510661)
			(xy 427.712415 -271.550815) (xy 427.670973 -271.585303) (xy 427.624952 -271.613389) (xy 427.575332 -271.634476)
			(xy 427.523171 -271.648112) (xy 427.46958 -271.654009) (xy 427.415701 -271.65204) (xy 427.362683 -271.642247)
			(xy 427.311656 -271.624839) (xy 427.263708 -271.600187) (xy 427.21986 -271.568817) (xy 427.181047 -271.531396)
			(xy 427.148095 -271.488723) (xy 427.121709 -271.441706) (xy 427.102449 -271.391349) (xy 427.090726 -271.338725)
			(xy 427.086791 -271.284954) (xy 425.985178 -271.284954) (xy 425.985178 -272.135092) (xy 431.186859 -272.135092)
			(xy 431.190794 -272.081321) (xy 431.202517 -272.028697) (xy 431.221777 -271.97834) (xy 431.248163 -271.931323)
			(xy 431.281115 -271.88865) (xy 431.319928 -271.851229) (xy 431.363776 -271.819859) (xy 431.411724 -271.795207)
			(xy 431.462751 -271.777799) (xy 431.515769 -271.768006) (xy 431.569648 -271.766037) (xy 431.623239 -271.771934)
			(xy 431.6754 -271.78557) (xy 431.72502 -271.806657) (xy 431.771041 -271.834743) (xy 431.812483 -271.869231)
			(xy 431.848461 -271.909385) (xy 431.878209 -271.954349) (xy 431.901094 -272.003166) (xy 431.916626 -272.054795)
			(xy 431.924476 -272.108135) (xy 431.924968 -272.135092) (xy 438.730913 -272.135092) (xy 438.734848 -272.081321)
			(xy 438.746571 -272.028697) (xy 438.765831 -271.97834) (xy 438.792217 -271.931323) (xy 438.825169 -271.88865)
			(xy 438.863982 -271.851229) (xy 438.90783 -271.819859) (xy 438.955778 -271.795207) (xy 439.006805 -271.777799)
			(xy 439.059823 -271.768006) (xy 439.113702 -271.766037) (xy 439.167293 -271.771934) (xy 439.219454 -271.78557)
			(xy 439.269074 -271.806657) (xy 439.315095 -271.834743) (xy 439.356537 -271.869231) (xy 439.392515 -271.909385)
			(xy 439.422263 -271.954349) (xy 439.445148 -272.003166) (xy 439.46068 -272.054795) (xy 439.46853 -272.108135)
			(xy 439.469022 -272.135092) (xy 446.274967 -272.135092) (xy 446.278902 -272.081321) (xy 446.290625 -272.028697)
			(xy 446.309885 -271.97834) (xy 446.336271 -271.931323) (xy 446.369223 -271.88865) (xy 446.408036 -271.851229)
			(xy 446.451884 -271.819859) (xy 446.499832 -271.795207) (xy 446.550859 -271.777799) (xy 446.603877 -271.768006)
			(xy 446.657756 -271.766037) (xy 446.711347 -271.771934) (xy 446.763508 -271.78557) (xy 446.813128 -271.806657)
			(xy 446.859149 -271.834743) (xy 446.900591 -271.869231) (xy 446.936569 -271.909385) (xy 446.966317 -271.954349)
			(xy 446.989202 -272.003166) (xy 447.004734 -272.054795) (xy 447.012584 -272.108135) (xy 447.013076 -272.135092)
			(xy 453.818767 -272.135092) (xy 453.822702 -272.081321) (xy 453.834425 -272.028697) (xy 453.853685 -271.97834)
			(xy 453.880071 -271.931323) (xy 453.913023 -271.88865) (xy 453.951836 -271.851229) (xy 453.995684 -271.819859)
			(xy 454.043632 -271.795207) (xy 454.094659 -271.777799) (xy 454.147677 -271.768006) (xy 454.201556 -271.766037)
			(xy 454.255147 -271.771934) (xy 454.307308 -271.78557) (xy 454.356928 -271.806657) (xy 454.402949 -271.834743)
			(xy 454.444391 -271.869231) (xy 454.480369 -271.909385) (xy 454.510117 -271.954349) (xy 454.533002 -272.003166)
			(xy 454.548534 -272.054795) (xy 454.556384 -272.108135) (xy 454.556876 -272.135092) (xy 454.556384 -272.162049)
			(xy 454.548534 -272.215389) (xy 454.533002 -272.267018) (xy 454.510117 -272.315835) (xy 454.480369 -272.360799)
			(xy 454.444391 -272.400953) (xy 454.402949 -272.435441) (xy 454.356928 -272.463527) (xy 454.307308 -272.484614)
			(xy 454.255147 -272.49825) (xy 454.201556 -272.504147) (xy 454.147677 -272.502178) (xy 454.094659 -272.492385)
			(xy 454.043632 -272.474977) (xy 453.995684 -272.450325) (xy 453.951836 -272.418955) (xy 453.913023 -272.381534)
			(xy 453.880071 -272.338861) (xy 453.853685 -272.291844) (xy 453.834425 -272.241487) (xy 453.822702 -272.188863)
			(xy 453.818767 -272.135092) (xy 447.013076 -272.135092) (xy 447.012584 -272.162049) (xy 447.004734 -272.215389)
			(xy 446.989202 -272.267018) (xy 446.966317 -272.315835) (xy 446.936569 -272.360799) (xy 446.900591 -272.400953)
			(xy 446.859149 -272.435441) (xy 446.813128 -272.463527) (xy 446.763508 -272.484614) (xy 446.711347 -272.49825)
			(xy 446.657756 -272.504147) (xy 446.603877 -272.502178) (xy 446.550859 -272.492385) (xy 446.499832 -272.474977)
			(xy 446.451884 -272.450325) (xy 446.408036 -272.418955) (xy 446.369223 -272.381534) (xy 446.336271 -272.338861)
			(xy 446.309885 -272.291844) (xy 446.290625 -272.241487) (xy 446.278902 -272.188863) (xy 446.274967 -272.135092)
			(xy 439.469022 -272.135092) (xy 439.46853 -272.162049) (xy 439.46068 -272.215389) (xy 439.445148 -272.267018)
			(xy 439.422263 -272.315835) (xy 439.392515 -272.360799) (xy 439.356537 -272.400953) (xy 439.315095 -272.435441)
			(xy 439.269074 -272.463527) (xy 439.219454 -272.484614) (xy 439.167293 -272.49825) (xy 439.113702 -272.504147)
			(xy 439.059823 -272.502178) (xy 439.006805 -272.492385) (xy 438.955778 -272.474977) (xy 438.90783 -272.450325)
			(xy 438.863982 -272.418955) (xy 438.825169 -272.381534) (xy 438.792217 -272.338861) (xy 438.765831 -272.291844)
			(xy 438.746571 -272.241487) (xy 438.734848 -272.188863) (xy 438.730913 -272.135092) (xy 431.924968 -272.135092)
			(xy 431.924476 -272.162049) (xy 431.916626 -272.215389) (xy 431.901094 -272.267018) (xy 431.878209 -272.315835)
			(xy 431.848461 -272.360799) (xy 431.812483 -272.400953) (xy 431.771041 -272.435441) (xy 431.72502 -272.463527)
			(xy 431.6754 -272.484614) (xy 431.623239 -272.49825) (xy 431.569648 -272.504147) (xy 431.515769 -272.502178)
			(xy 431.462751 -272.492385) (xy 431.411724 -272.474977) (xy 431.363776 -272.450325) (xy 431.319928 -272.418955)
			(xy 431.281115 -272.381534) (xy 431.248163 -272.338861) (xy 431.221777 -272.291844) (xy 431.202517 -272.241487)
			(xy 431.190794 -272.188863) (xy 431.186859 -272.135092) (xy 425.985178 -272.135092) (xy 425.985178 -272.984976)
			(xy 427.086791 -272.984976) (xy 427.090726 -272.931205) (xy 427.102449 -272.878581) (xy 427.121709 -272.828224)
			(xy 427.148095 -272.781207) (xy 427.181047 -272.738534) (xy 427.21986 -272.701113) (xy 427.263708 -272.669743)
			(xy 427.311656 -272.645091) (xy 427.362683 -272.627683) (xy 427.415701 -272.61789) (xy 427.46958 -272.615921)
			(xy 427.523171 -272.621818) (xy 427.575332 -272.635454) (xy 427.624952 -272.656541) (xy 427.670973 -272.684627)
			(xy 427.712415 -272.719115) (xy 427.748393 -272.759269) (xy 427.778141 -272.804233) (xy 427.801026 -272.85305)
			(xy 427.816558 -272.904679) (xy 427.824408 -272.958019) (xy 427.8249 -272.984976) (xy 434.630845 -272.984976)
			(xy 434.63478 -272.931205) (xy 434.646503 -272.878581) (xy 434.665763 -272.828224) (xy 434.692149 -272.781207)
			(xy 434.725101 -272.738534) (xy 434.763914 -272.701113) (xy 434.807762 -272.669743) (xy 434.85571 -272.645091)
			(xy 434.906737 -272.627683) (xy 434.959755 -272.61789) (xy 435.013634 -272.615921) (xy 435.067225 -272.621818)
			(xy 435.119386 -272.635454) (xy 435.169006 -272.656541) (xy 435.215027 -272.684627) (xy 435.256469 -272.719115)
			(xy 435.292447 -272.759269) (xy 435.322195 -272.804233) (xy 435.34508 -272.85305) (xy 435.360612 -272.904679)
			(xy 435.368462 -272.958019) (xy 435.368954 -272.984976) (xy 442.174899 -272.984976) (xy 442.178834 -272.931205)
			(xy 442.190557 -272.878581) (xy 442.209817 -272.828224) (xy 442.236203 -272.781207) (xy 442.269155 -272.738534)
			(xy 442.307968 -272.701113) (xy 442.351816 -272.669743) (xy 442.399764 -272.645091) (xy 442.450791 -272.627683)
			(xy 442.503809 -272.61789) (xy 442.557688 -272.615921) (xy 442.611279 -272.621818) (xy 442.66344 -272.635454)
			(xy 442.71306 -272.656541) (xy 442.759081 -272.684627) (xy 442.800523 -272.719115) (xy 442.836501 -272.759269)
			(xy 442.866249 -272.804233) (xy 442.889134 -272.85305) (xy 442.904666 -272.904679) (xy 442.912516 -272.958019)
			(xy 442.913008 -272.984976) (xy 449.718699 -272.984976) (xy 449.722634 -272.931205) (xy 449.734357 -272.878581)
			(xy 449.753617 -272.828224) (xy 449.780003 -272.781207) (xy 449.812955 -272.738534) (xy 449.851768 -272.701113)
			(xy 449.895616 -272.669743) (xy 449.943564 -272.645091) (xy 449.994591 -272.627683) (xy 450.047609 -272.61789)
			(xy 450.101488 -272.615921) (xy 450.155079 -272.621818) (xy 450.20724 -272.635454) (xy 450.25686 -272.656541)
			(xy 450.302881 -272.684627) (xy 450.344323 -272.719115) (xy 450.380301 -272.759269) (xy 450.410049 -272.804233)
			(xy 450.432934 -272.85305) (xy 450.448466 -272.904679) (xy 450.456316 -272.958019) (xy 450.456808 -272.984976)
			(xy 450.456316 -273.011933) (xy 450.448466 -273.065273) (xy 450.432934 -273.116902) (xy 450.410049 -273.165719)
			(xy 450.380301 -273.210683) (xy 450.344323 -273.250837) (xy 450.302881 -273.285325) (xy 450.25686 -273.313411)
			(xy 450.20724 -273.334498) (xy 450.155079 -273.348134) (xy 450.101488 -273.354031) (xy 450.047609 -273.352062)
			(xy 449.994591 -273.342269) (xy 449.943564 -273.324861) (xy 449.895616 -273.300209) (xy 449.851768 -273.268839)
			(xy 449.812955 -273.231418) (xy 449.780003 -273.188745) (xy 449.753617 -273.141728) (xy 449.734357 -273.091371)
			(xy 449.722634 -273.038747) (xy 449.718699 -272.984976) (xy 442.913008 -272.984976) (xy 442.912516 -273.011933)
			(xy 442.904666 -273.065273) (xy 442.889134 -273.116902) (xy 442.866249 -273.165719) (xy 442.836501 -273.210683)
			(xy 442.800523 -273.250837) (xy 442.759081 -273.285325) (xy 442.71306 -273.313411) (xy 442.66344 -273.334498)
			(xy 442.611279 -273.348134) (xy 442.557688 -273.354031) (xy 442.503809 -273.352062) (xy 442.450791 -273.342269)
			(xy 442.399764 -273.324861) (xy 442.351816 -273.300209) (xy 442.307968 -273.268839) (xy 442.269155 -273.231418)
			(xy 442.236203 -273.188745) (xy 442.209817 -273.141728) (xy 442.190557 -273.091371) (xy 442.178834 -273.038747)
			(xy 442.174899 -272.984976) (xy 435.368954 -272.984976) (xy 435.368462 -273.011933) (xy 435.360612 -273.065273)
			(xy 435.34508 -273.116902) (xy 435.322195 -273.165719) (xy 435.292447 -273.210683) (xy 435.256469 -273.250837)
			(xy 435.215027 -273.285325) (xy 435.169006 -273.313411) (xy 435.119386 -273.334498) (xy 435.067225 -273.348134)
			(xy 435.013634 -273.354031) (xy 434.959755 -273.352062) (xy 434.906737 -273.342269) (xy 434.85571 -273.324861)
			(xy 434.807762 -273.300209) (xy 434.763914 -273.268839) (xy 434.725101 -273.231418) (xy 434.692149 -273.188745)
			(xy 434.665763 -273.141728) (xy 434.646503 -273.091371) (xy 434.63478 -273.038747) (xy 434.630845 -272.984976)
			(xy 427.8249 -272.984976) (xy 427.824408 -273.011933) (xy 427.816558 -273.065273) (xy 427.801026 -273.116902)
			(xy 427.778141 -273.165719) (xy 427.748393 -273.210683) (xy 427.712415 -273.250837) (xy 427.670973 -273.285325)
			(xy 427.624952 -273.313411) (xy 427.575332 -273.334498) (xy 427.523171 -273.348134) (xy 427.46958 -273.354031)
			(xy 427.415701 -273.352062) (xy 427.362683 -273.342269) (xy 427.311656 -273.324861) (xy 427.263708 -273.300209)
			(xy 427.21986 -273.268839) (xy 427.181047 -273.231418) (xy 427.148095 -273.188745) (xy 427.121709 -273.141728)
			(xy 427.102449 -273.091371) (xy 427.090726 -273.038747) (xy 427.086791 -272.984976) (xy 425.985178 -272.984976)
			(xy 425.985178 -273.835114) (xy 431.186859 -273.835114) (xy 431.190794 -273.781343) (xy 431.202517 -273.728719)
			(xy 431.221777 -273.678362) (xy 431.248163 -273.631345) (xy 431.281115 -273.588672) (xy 431.319928 -273.551251)
			(xy 431.363776 -273.519881) (xy 431.411724 -273.495229) (xy 431.462751 -273.477821) (xy 431.515769 -273.468028)
			(xy 431.569648 -273.466059) (xy 431.623239 -273.471956) (xy 431.6754 -273.485592) (xy 431.72502 -273.506679)
			(xy 431.771041 -273.534765) (xy 431.812483 -273.569253) (xy 431.848461 -273.609407) (xy 431.878209 -273.654371)
			(xy 431.901094 -273.703188) (xy 431.916626 -273.754817) (xy 431.924476 -273.808157) (xy 431.924968 -273.835114)
			(xy 438.730913 -273.835114) (xy 438.734848 -273.781343) (xy 438.746571 -273.728719) (xy 438.765831 -273.678362)
			(xy 438.792217 -273.631345) (xy 438.825169 -273.588672) (xy 438.863982 -273.551251) (xy 438.90783 -273.519881)
			(xy 438.955778 -273.495229) (xy 439.006805 -273.477821) (xy 439.059823 -273.468028) (xy 439.113702 -273.466059)
			(xy 439.167293 -273.471956) (xy 439.219454 -273.485592) (xy 439.269074 -273.506679) (xy 439.315095 -273.534765)
			(xy 439.356537 -273.569253) (xy 439.392515 -273.609407) (xy 439.422263 -273.654371) (xy 439.445148 -273.703188)
			(xy 439.46068 -273.754817) (xy 439.46853 -273.808157) (xy 439.469022 -273.835114) (xy 446.274967 -273.835114)
			(xy 446.278902 -273.781343) (xy 446.290625 -273.728719) (xy 446.309885 -273.678362) (xy 446.336271 -273.631345)
			(xy 446.369223 -273.588672) (xy 446.408036 -273.551251) (xy 446.451884 -273.519881) (xy 446.499832 -273.495229)
			(xy 446.550859 -273.477821) (xy 446.603877 -273.468028) (xy 446.657756 -273.466059) (xy 446.711347 -273.471956)
			(xy 446.763508 -273.485592) (xy 446.813128 -273.506679) (xy 446.859149 -273.534765) (xy 446.900591 -273.569253)
			(xy 446.936569 -273.609407) (xy 446.966317 -273.654371) (xy 446.989202 -273.703188) (xy 447.004734 -273.754817)
			(xy 447.012584 -273.808157) (xy 447.013076 -273.835114) (xy 453.818767 -273.835114) (xy 453.822702 -273.781343)
			(xy 453.834425 -273.728719) (xy 453.853685 -273.678362) (xy 453.880071 -273.631345) (xy 453.913023 -273.588672)
			(xy 453.951836 -273.551251) (xy 453.995684 -273.519881) (xy 454.043632 -273.495229) (xy 454.094659 -273.477821)
			(xy 454.147677 -273.468028) (xy 454.201556 -273.466059) (xy 454.255147 -273.471956) (xy 454.307308 -273.485592)
			(xy 454.356928 -273.506679) (xy 454.402949 -273.534765) (xy 454.444391 -273.569253) (xy 454.480369 -273.609407)
			(xy 454.510117 -273.654371) (xy 454.533002 -273.703188) (xy 454.548534 -273.754817) (xy 454.556384 -273.808157)
			(xy 454.556876 -273.835114) (xy 454.556384 -273.862071) (xy 454.548534 -273.915411) (xy 454.533002 -273.96704)
			(xy 454.510117 -274.015857) (xy 454.480369 -274.060821) (xy 454.444391 -274.100975) (xy 454.402949 -274.135463)
			(xy 454.356928 -274.163549) (xy 454.307308 -274.184636) (xy 454.255147 -274.198272) (xy 454.201556 -274.204169)
			(xy 454.147677 -274.2022) (xy 454.094659 -274.192407) (xy 454.043632 -274.174999) (xy 453.995684 -274.150347)
			(xy 453.951836 -274.118977) (xy 453.913023 -274.081556) (xy 453.880071 -274.038883) (xy 453.853685 -273.991866)
			(xy 453.834425 -273.941509) (xy 453.822702 -273.888885) (xy 453.818767 -273.835114) (xy 447.013076 -273.835114)
			(xy 447.012584 -273.862071) (xy 447.004734 -273.915411) (xy 446.989202 -273.96704) (xy 446.966317 -274.015857)
			(xy 446.936569 -274.060821) (xy 446.900591 -274.100975) (xy 446.859149 -274.135463) (xy 446.813128 -274.163549)
			(xy 446.763508 -274.184636) (xy 446.711347 -274.198272) (xy 446.657756 -274.204169) (xy 446.603877 -274.2022)
			(xy 446.550859 -274.192407) (xy 446.499832 -274.174999) (xy 446.451884 -274.150347) (xy 446.408036 -274.118977)
			(xy 446.369223 -274.081556) (xy 446.336271 -274.038883) (xy 446.309885 -273.991866) (xy 446.290625 -273.941509)
			(xy 446.278902 -273.888885) (xy 446.274967 -273.835114) (xy 439.469022 -273.835114) (xy 439.46853 -273.862071)
			(xy 439.46068 -273.915411) (xy 439.445148 -273.96704) (xy 439.422263 -274.015857) (xy 439.392515 -274.060821)
			(xy 439.356537 -274.100975) (xy 439.315095 -274.135463) (xy 439.269074 -274.163549) (xy 439.219454 -274.184636)
			(xy 439.167293 -274.198272) (xy 439.113702 -274.204169) (xy 439.059823 -274.2022) (xy 439.006805 -274.192407)
			(xy 438.955778 -274.174999) (xy 438.90783 -274.150347) (xy 438.863982 -274.118977) (xy 438.825169 -274.081556)
			(xy 438.792217 -274.038883) (xy 438.765831 -273.991866) (xy 438.746571 -273.941509) (xy 438.734848 -273.888885)
			(xy 438.730913 -273.835114) (xy 431.924968 -273.835114) (xy 431.924476 -273.862071) (xy 431.916626 -273.915411)
			(xy 431.901094 -273.96704) (xy 431.878209 -274.015857) (xy 431.848461 -274.060821) (xy 431.812483 -274.100975)
			(xy 431.771041 -274.135463) (xy 431.72502 -274.163549) (xy 431.6754 -274.184636) (xy 431.623239 -274.198272)
			(xy 431.569648 -274.204169) (xy 431.515769 -274.2022) (xy 431.462751 -274.192407) (xy 431.411724 -274.174999)
			(xy 431.363776 -274.150347) (xy 431.319928 -274.118977) (xy 431.281115 -274.081556) (xy 431.248163 -274.038883)
			(xy 431.221777 -273.991866) (xy 431.202517 -273.941509) (xy 431.190794 -273.888885) (xy 431.186859 -273.835114)
			(xy 425.985178 -273.835114) (xy 425.985178 -274.684998) (xy 427.086791 -274.684998) (xy 427.090726 -274.631227)
			(xy 427.102449 -274.578603) (xy 427.121709 -274.528246) (xy 427.148095 -274.481229) (xy 427.181047 -274.438556)
			(xy 427.21986 -274.401135) (xy 427.263708 -274.369765) (xy 427.311656 -274.345113) (xy 427.362683 -274.327705)
			(xy 427.415701 -274.317912) (xy 427.46958 -274.315943) (xy 427.523171 -274.32184) (xy 427.575332 -274.335476)
			(xy 427.624952 -274.356563) (xy 427.670973 -274.384649) (xy 427.712415 -274.419137) (xy 427.748393 -274.459291)
			(xy 427.778141 -274.504255) (xy 427.801026 -274.553072) (xy 427.816558 -274.604701) (xy 427.824408 -274.658041)
			(xy 427.8249 -274.684998) (xy 434.630845 -274.684998) (xy 434.63478 -274.631227) (xy 434.646503 -274.578603)
			(xy 434.665763 -274.528246) (xy 434.692149 -274.481229) (xy 434.725101 -274.438556) (xy 434.763914 -274.401135)
			(xy 434.807762 -274.369765) (xy 434.85571 -274.345113) (xy 434.906737 -274.327705) (xy 434.959755 -274.317912)
			(xy 435.013634 -274.315943) (xy 435.067225 -274.32184) (xy 435.119386 -274.335476) (xy 435.169006 -274.356563)
			(xy 435.215027 -274.384649) (xy 435.256469 -274.419137) (xy 435.292447 -274.459291) (xy 435.322195 -274.504255)
			(xy 435.34508 -274.553072) (xy 435.360612 -274.604701) (xy 435.368462 -274.658041) (xy 435.368954 -274.684998)
			(xy 442.174899 -274.684998) (xy 442.178834 -274.631227) (xy 442.190557 -274.578603) (xy 442.209817 -274.528246)
			(xy 442.236203 -274.481229) (xy 442.269155 -274.438556) (xy 442.307968 -274.401135) (xy 442.351816 -274.369765)
			(xy 442.399764 -274.345113) (xy 442.450791 -274.327705) (xy 442.503809 -274.317912) (xy 442.557688 -274.315943)
			(xy 442.611279 -274.32184) (xy 442.66344 -274.335476) (xy 442.71306 -274.356563) (xy 442.759081 -274.384649)
			(xy 442.800523 -274.419137) (xy 442.836501 -274.459291) (xy 442.866249 -274.504255) (xy 442.889134 -274.553072)
			(xy 442.904666 -274.604701) (xy 442.912516 -274.658041) (xy 442.913008 -274.684998) (xy 449.718699 -274.684998)
			(xy 449.722634 -274.631227) (xy 449.734357 -274.578603) (xy 449.753617 -274.528246) (xy 449.780003 -274.481229)
			(xy 449.812955 -274.438556) (xy 449.851768 -274.401135) (xy 449.895616 -274.369765) (xy 449.943564 -274.345113)
			(xy 449.994591 -274.327705) (xy 450.047609 -274.317912) (xy 450.101488 -274.315943) (xy 450.155079 -274.32184)
			(xy 450.20724 -274.335476) (xy 450.25686 -274.356563) (xy 450.302881 -274.384649) (xy 450.344323 -274.419137)
			(xy 450.380301 -274.459291) (xy 450.410049 -274.504255) (xy 450.432934 -274.553072) (xy 450.448466 -274.604701)
			(xy 450.456316 -274.658041) (xy 450.456808 -274.684998) (xy 450.456316 -274.711955) (xy 450.448466 -274.765295)
			(xy 450.432934 -274.816924) (xy 450.410049 -274.865741) (xy 450.380301 -274.910705) (xy 450.344323 -274.950859)
			(xy 450.302881 -274.985347) (xy 450.25686 -275.013433) (xy 450.20724 -275.03452) (xy 450.155079 -275.048156)
			(xy 450.101488 -275.054053) (xy 450.047609 -275.052084) (xy 449.994591 -275.042291) (xy 449.943564 -275.024883)
			(xy 449.895616 -275.000231) (xy 449.851768 -274.968861) (xy 449.812955 -274.93144) (xy 449.780003 -274.888767)
			(xy 449.753617 -274.84175) (xy 449.734357 -274.791393) (xy 449.722634 -274.738769) (xy 449.718699 -274.684998)
			(xy 442.913008 -274.684998) (xy 442.912516 -274.711955) (xy 442.904666 -274.765295) (xy 442.889134 -274.816924)
			(xy 442.866249 -274.865741) (xy 442.836501 -274.910705) (xy 442.800523 -274.950859) (xy 442.759081 -274.985347)
			(xy 442.71306 -275.013433) (xy 442.66344 -275.03452) (xy 442.611279 -275.048156) (xy 442.557688 -275.054053)
			(xy 442.503809 -275.052084) (xy 442.450791 -275.042291) (xy 442.399764 -275.024883) (xy 442.351816 -275.000231)
			(xy 442.307968 -274.968861) (xy 442.269155 -274.93144) (xy 442.236203 -274.888767) (xy 442.209817 -274.84175)
			(xy 442.190557 -274.791393) (xy 442.178834 -274.738769) (xy 442.174899 -274.684998) (xy 435.368954 -274.684998)
			(xy 435.368462 -274.711955) (xy 435.360612 -274.765295) (xy 435.34508 -274.816924) (xy 435.322195 -274.865741)
			(xy 435.292447 -274.910705) (xy 435.256469 -274.950859) (xy 435.215027 -274.985347) (xy 435.169006 -275.013433)
			(xy 435.119386 -275.03452) (xy 435.067225 -275.048156) (xy 435.013634 -275.054053) (xy 434.959755 -275.052084)
			(xy 434.906737 -275.042291) (xy 434.85571 -275.024883) (xy 434.807762 -275.000231) (xy 434.763914 -274.968861)
			(xy 434.725101 -274.93144) (xy 434.692149 -274.888767) (xy 434.665763 -274.84175) (xy 434.646503 -274.791393)
			(xy 434.63478 -274.738769) (xy 434.630845 -274.684998) (xy 427.8249 -274.684998) (xy 427.824408 -274.711955)
			(xy 427.816558 -274.765295) (xy 427.801026 -274.816924) (xy 427.778141 -274.865741) (xy 427.748393 -274.910705)
			(xy 427.712415 -274.950859) (xy 427.670973 -274.985347) (xy 427.624952 -275.013433) (xy 427.575332 -275.03452)
			(xy 427.523171 -275.048156) (xy 427.46958 -275.054053) (xy 427.415701 -275.052084) (xy 427.362683 -275.042291)
			(xy 427.311656 -275.024883) (xy 427.263708 -275.000231) (xy 427.21986 -274.968861) (xy 427.181047 -274.93144)
			(xy 427.148095 -274.888767) (xy 427.121709 -274.84175) (xy 427.102449 -274.791393) (xy 427.090726 -274.738769)
			(xy 427.086791 -274.684998) (xy 425.985178 -274.684998) (xy 425.985178 -275.535136) (xy 431.186859 -275.535136)
			(xy 431.190794 -275.481365) (xy 431.202517 -275.428741) (xy 431.221777 -275.378384) (xy 431.248163 -275.331367)
			(xy 431.281115 -275.288694) (xy 431.319928 -275.251273) (xy 431.363776 -275.219903) (xy 431.411724 -275.195251)
			(xy 431.462751 -275.177843) (xy 431.515769 -275.16805) (xy 431.569648 -275.166081) (xy 431.623239 -275.171978)
			(xy 431.6754 -275.185614) (xy 431.72502 -275.206701) (xy 431.771041 -275.234787) (xy 431.812483 -275.269275)
			(xy 431.848461 -275.309429) (xy 431.878209 -275.354393) (xy 431.901094 -275.40321) (xy 431.916626 -275.454839)
			(xy 431.924476 -275.508179) (xy 431.924968 -275.535136) (xy 438.730913 -275.535136) (xy 438.734848 -275.481365)
			(xy 438.746571 -275.428741) (xy 438.765831 -275.378384) (xy 438.792217 -275.331367) (xy 438.825169 -275.288694)
			(xy 438.863982 -275.251273) (xy 438.90783 -275.219903) (xy 438.955778 -275.195251) (xy 439.006805 -275.177843)
			(xy 439.059823 -275.16805) (xy 439.113702 -275.166081) (xy 439.167293 -275.171978) (xy 439.219454 -275.185614)
			(xy 439.269074 -275.206701) (xy 439.315095 -275.234787) (xy 439.356537 -275.269275) (xy 439.392515 -275.309429)
			(xy 439.422263 -275.354393) (xy 439.445148 -275.40321) (xy 439.46068 -275.454839) (xy 439.46853 -275.508179)
			(xy 439.469022 -275.535136) (xy 446.274967 -275.535136) (xy 446.278902 -275.481365) (xy 446.290625 -275.428741)
			(xy 446.309885 -275.378384) (xy 446.336271 -275.331367) (xy 446.369223 -275.288694) (xy 446.408036 -275.251273)
			(xy 446.451884 -275.219903) (xy 446.499832 -275.195251) (xy 446.550859 -275.177843) (xy 446.603877 -275.16805)
			(xy 446.657756 -275.166081) (xy 446.711347 -275.171978) (xy 446.763508 -275.185614) (xy 446.813128 -275.206701)
			(xy 446.859149 -275.234787) (xy 446.900591 -275.269275) (xy 446.936569 -275.309429) (xy 446.966317 -275.354393)
			(xy 446.989202 -275.40321) (xy 447.004734 -275.454839) (xy 447.012584 -275.508179) (xy 447.013076 -275.535136)
			(xy 453.818767 -275.535136) (xy 453.822702 -275.481365) (xy 453.834425 -275.428741) (xy 453.853685 -275.378384)
			(xy 453.880071 -275.331367) (xy 453.913023 -275.288694) (xy 453.951836 -275.251273) (xy 453.995684 -275.219903)
			(xy 454.043632 -275.195251) (xy 454.094659 -275.177843) (xy 454.147677 -275.16805) (xy 454.201556 -275.166081)
			(xy 454.255147 -275.171978) (xy 454.307308 -275.185614) (xy 454.356928 -275.206701) (xy 454.402949 -275.234787)
			(xy 454.444391 -275.269275) (xy 454.480369 -275.309429) (xy 454.510117 -275.354393) (xy 454.533002 -275.40321)
			(xy 454.548534 -275.454839) (xy 454.556384 -275.508179) (xy 454.556876 -275.535136) (xy 454.556384 -275.562093)
			(xy 454.548534 -275.615433) (xy 454.533002 -275.667062) (xy 454.510117 -275.715879) (xy 454.480369 -275.760843)
			(xy 454.444391 -275.800997) (xy 454.402949 -275.835485) (xy 454.356928 -275.863571) (xy 454.307308 -275.884658)
			(xy 454.255147 -275.898294) (xy 454.201556 -275.904191) (xy 454.147677 -275.902222) (xy 454.094659 -275.892429)
			(xy 454.043632 -275.875021) (xy 453.995684 -275.850369) (xy 453.951836 -275.818999) (xy 453.913023 -275.781578)
			(xy 453.880071 -275.738905) (xy 453.853685 -275.691888) (xy 453.834425 -275.641531) (xy 453.822702 -275.588907)
			(xy 453.818767 -275.535136) (xy 447.013076 -275.535136) (xy 447.012584 -275.562093) (xy 447.004734 -275.615433)
			(xy 446.989202 -275.667062) (xy 446.966317 -275.715879) (xy 446.936569 -275.760843) (xy 446.900591 -275.800997)
			(xy 446.859149 -275.835485) (xy 446.813128 -275.863571) (xy 446.763508 -275.884658) (xy 446.711347 -275.898294)
			(xy 446.657756 -275.904191) (xy 446.603877 -275.902222) (xy 446.550859 -275.892429) (xy 446.499832 -275.875021)
			(xy 446.451884 -275.850369) (xy 446.408036 -275.818999) (xy 446.369223 -275.781578) (xy 446.336271 -275.738905)
			(xy 446.309885 -275.691888) (xy 446.290625 -275.641531) (xy 446.278902 -275.588907) (xy 446.274967 -275.535136)
			(xy 439.469022 -275.535136) (xy 439.46853 -275.562093) (xy 439.46068 -275.615433) (xy 439.445148 -275.667062)
			(xy 439.422263 -275.715879) (xy 439.392515 -275.760843) (xy 439.356537 -275.800997) (xy 439.315095 -275.835485)
			(xy 439.269074 -275.863571) (xy 439.219454 -275.884658) (xy 439.167293 -275.898294) (xy 439.113702 -275.904191)
			(xy 439.059823 -275.902222) (xy 439.006805 -275.892429) (xy 438.955778 -275.875021) (xy 438.90783 -275.850369)
			(xy 438.863982 -275.818999) (xy 438.825169 -275.781578) (xy 438.792217 -275.738905) (xy 438.765831 -275.691888)
			(xy 438.746571 -275.641531) (xy 438.734848 -275.588907) (xy 438.730913 -275.535136) (xy 431.924968 -275.535136)
			(xy 431.924476 -275.562093) (xy 431.916626 -275.615433) (xy 431.901094 -275.667062) (xy 431.878209 -275.715879)
			(xy 431.848461 -275.760843) (xy 431.812483 -275.800997) (xy 431.771041 -275.835485) (xy 431.72502 -275.863571)
			(xy 431.6754 -275.884658) (xy 431.623239 -275.898294) (xy 431.569648 -275.904191) (xy 431.515769 -275.902222)
			(xy 431.462751 -275.892429) (xy 431.411724 -275.875021) (xy 431.363776 -275.850369) (xy 431.319928 -275.818999)
			(xy 431.281115 -275.781578) (xy 431.248163 -275.738905) (xy 431.221777 -275.691888) (xy 431.202517 -275.641531)
			(xy 431.190794 -275.588907) (xy 431.186859 -275.535136) (xy 425.985178 -275.535136) (xy 425.985178 -276.38502)
			(xy 427.086791 -276.38502) (xy 427.090726 -276.331249) (xy 427.102449 -276.278625) (xy 427.121709 -276.228268)
			(xy 427.148095 -276.181251) (xy 427.181047 -276.138578) (xy 427.21986 -276.101157) (xy 427.263708 -276.069787)
			(xy 427.311656 -276.045135) (xy 427.362683 -276.027727) (xy 427.415701 -276.017934) (xy 427.46958 -276.015965)
			(xy 427.523171 -276.021862) (xy 427.575332 -276.035498) (xy 427.624952 -276.056585) (xy 427.670973 -276.084671)
			(xy 427.712415 -276.119159) (xy 427.748393 -276.159313) (xy 427.778141 -276.204277) (xy 427.801026 -276.253094)
			(xy 427.816558 -276.304723) (xy 427.824408 -276.358063) (xy 427.8249 -276.38502) (xy 431.186859 -276.38502)
			(xy 431.190794 -276.331249) (xy 431.202517 -276.278625) (xy 431.221777 -276.228268) (xy 431.248163 -276.181251)
			(xy 431.281115 -276.138578) (xy 431.319928 -276.101157) (xy 431.363776 -276.069787) (xy 431.411724 -276.045135)
			(xy 431.462751 -276.027727) (xy 431.515769 -276.017934) (xy 431.569648 -276.015965) (xy 431.623239 -276.021862)
			(xy 431.6754 -276.035498) (xy 431.72502 -276.056585) (xy 431.771041 -276.084671) (xy 431.812483 -276.119159)
			(xy 431.848461 -276.159313) (xy 431.878209 -276.204277) (xy 431.901094 -276.253094) (xy 431.916626 -276.304723)
			(xy 431.924476 -276.358063) (xy 431.924968 -276.38502) (xy 434.630845 -276.38502) (xy 434.63478 -276.331249)
			(xy 434.646503 -276.278625) (xy 434.665763 -276.228268) (xy 434.692149 -276.181251) (xy 434.725101 -276.138578)
			(xy 434.763914 -276.101157) (xy 434.807762 -276.069787) (xy 434.85571 -276.045135) (xy 434.906737 -276.027727)
			(xy 434.959755 -276.017934) (xy 435.013634 -276.015965) (xy 435.067225 -276.021862) (xy 435.119386 -276.035498)
			(xy 435.169006 -276.056585) (xy 435.215027 -276.084671) (xy 435.256469 -276.119159) (xy 435.292447 -276.159313)
			(xy 435.322195 -276.204277) (xy 435.34508 -276.253094) (xy 435.360612 -276.304723) (xy 435.368462 -276.358063)
			(xy 435.368954 -276.38502) (xy 438.730913 -276.38502) (xy 438.734848 -276.331249) (xy 438.746571 -276.278625)
			(xy 438.765831 -276.228268) (xy 438.792217 -276.181251) (xy 438.825169 -276.138578) (xy 438.863982 -276.101157)
			(xy 438.90783 -276.069787) (xy 438.955778 -276.045135) (xy 439.006805 -276.027727) (xy 439.059823 -276.017934)
			(xy 439.113702 -276.015965) (xy 439.167293 -276.021862) (xy 439.219454 -276.035498) (xy 439.269074 -276.056585)
			(xy 439.315095 -276.084671) (xy 439.356537 -276.119159) (xy 439.392515 -276.159313) (xy 439.422263 -276.204277)
			(xy 439.445148 -276.253094) (xy 439.46068 -276.304723) (xy 439.46853 -276.358063) (xy 439.469022 -276.38502)
			(xy 442.174899 -276.38502) (xy 442.178834 -276.331249) (xy 442.190557 -276.278625) (xy 442.209817 -276.228268)
			(xy 442.236203 -276.181251) (xy 442.269155 -276.138578) (xy 442.307968 -276.101157) (xy 442.351816 -276.069787)
			(xy 442.399764 -276.045135) (xy 442.450791 -276.027727) (xy 442.503809 -276.017934) (xy 442.557688 -276.015965)
			(xy 442.611279 -276.021862) (xy 442.66344 -276.035498) (xy 442.71306 -276.056585) (xy 442.759081 -276.084671)
			(xy 442.800523 -276.119159) (xy 442.836501 -276.159313) (xy 442.866249 -276.204277) (xy 442.889134 -276.253094)
			(xy 442.904666 -276.304723) (xy 442.912516 -276.358063) (xy 442.913008 -276.38502) (xy 446.274967 -276.38502)
			(xy 446.278902 -276.331249) (xy 446.290625 -276.278625) (xy 446.309885 -276.228268) (xy 446.336271 -276.181251)
			(xy 446.369223 -276.138578) (xy 446.408036 -276.101157) (xy 446.451884 -276.069787) (xy 446.499832 -276.045135)
			(xy 446.550859 -276.027727) (xy 446.603877 -276.017934) (xy 446.657756 -276.015965) (xy 446.711347 -276.021862)
			(xy 446.763508 -276.035498) (xy 446.813128 -276.056585) (xy 446.859149 -276.084671) (xy 446.900591 -276.119159)
			(xy 446.936569 -276.159313) (xy 446.966317 -276.204277) (xy 446.989202 -276.253094) (xy 447.004734 -276.304723)
			(xy 447.012584 -276.358063) (xy 447.013076 -276.38502) (xy 449.718699 -276.38502) (xy 449.722634 -276.331249)
			(xy 449.734357 -276.278625) (xy 449.753617 -276.228268) (xy 449.780003 -276.181251) (xy 449.812955 -276.138578)
			(xy 449.851768 -276.101157) (xy 449.895616 -276.069787) (xy 449.943564 -276.045135) (xy 449.994591 -276.027727)
			(xy 450.047609 -276.017934) (xy 450.101488 -276.015965) (xy 450.155079 -276.021862) (xy 450.20724 -276.035498)
			(xy 450.25686 -276.056585) (xy 450.302881 -276.084671) (xy 450.344323 -276.119159) (xy 450.380301 -276.159313)
			(xy 450.410049 -276.204277) (xy 450.432934 -276.253094) (xy 450.448466 -276.304723) (xy 450.456316 -276.358063)
			(xy 450.456808 -276.38502) (xy 453.818767 -276.38502) (xy 453.822702 -276.331249) (xy 453.834425 -276.278625)
			(xy 453.853685 -276.228268) (xy 453.880071 -276.181251) (xy 453.913023 -276.138578) (xy 453.951836 -276.101157)
			(xy 453.995684 -276.069787) (xy 454.043632 -276.045135) (xy 454.094659 -276.027727) (xy 454.147677 -276.017934)
			(xy 454.201556 -276.015965) (xy 454.255147 -276.021862) (xy 454.307308 -276.035498) (xy 454.356928 -276.056585)
			(xy 454.402949 -276.084671) (xy 454.444391 -276.119159) (xy 454.480369 -276.159313) (xy 454.510117 -276.204277)
			(xy 454.533002 -276.253094) (xy 454.548534 -276.304723) (xy 454.556384 -276.358063) (xy 454.556876 -276.38502)
			(xy 454.556384 -276.411977) (xy 454.548534 -276.465317) (xy 454.533002 -276.516946) (xy 454.510117 -276.565763)
			(xy 454.480369 -276.610727) (xy 454.444391 -276.650881) (xy 454.402949 -276.685369) (xy 454.356928 -276.713455)
			(xy 454.307308 -276.734542) (xy 454.255147 -276.748178) (xy 454.201556 -276.754075) (xy 454.147677 -276.752106)
			(xy 454.094659 -276.742313) (xy 454.043632 -276.724905) (xy 453.995684 -276.700253) (xy 453.951836 -276.668883)
			(xy 453.913023 -276.631462) (xy 453.880071 -276.588789) (xy 453.853685 -276.541772) (xy 453.834425 -276.491415)
			(xy 453.822702 -276.438791) (xy 453.818767 -276.38502) (xy 450.456808 -276.38502) (xy 450.456316 -276.411977)
			(xy 450.448466 -276.465317) (xy 450.432934 -276.516946) (xy 450.410049 -276.565763) (xy 450.380301 -276.610727)
			(xy 450.344323 -276.650881) (xy 450.302881 -276.685369) (xy 450.25686 -276.713455) (xy 450.20724 -276.734542)
			(xy 450.155079 -276.748178) (xy 450.101488 -276.754075) (xy 450.047609 -276.752106) (xy 449.994591 -276.742313)
			(xy 449.943564 -276.724905) (xy 449.895616 -276.700253) (xy 449.851768 -276.668883) (xy 449.812955 -276.631462)
			(xy 449.780003 -276.588789) (xy 449.753617 -276.541772) (xy 449.734357 -276.491415) (xy 449.722634 -276.438791)
			(xy 449.718699 -276.38502) (xy 447.013076 -276.38502) (xy 447.012584 -276.411977) (xy 447.004734 -276.465317)
			(xy 446.989202 -276.516946) (xy 446.966317 -276.565763) (xy 446.936569 -276.610727) (xy 446.900591 -276.650881)
			(xy 446.859149 -276.685369) (xy 446.813128 -276.713455) (xy 446.763508 -276.734542) (xy 446.711347 -276.748178)
			(xy 446.657756 -276.754075) (xy 446.603877 -276.752106) (xy 446.550859 -276.742313) (xy 446.499832 -276.724905)
			(xy 446.451884 -276.700253) (xy 446.408036 -276.668883) (xy 446.369223 -276.631462) (xy 446.336271 -276.588789)
			(xy 446.309885 -276.541772) (xy 446.290625 -276.491415) (xy 446.278902 -276.438791) (xy 446.274967 -276.38502)
			(xy 442.913008 -276.38502) (xy 442.912516 -276.411977) (xy 442.904666 -276.465317) (xy 442.889134 -276.516946)
			(xy 442.866249 -276.565763) (xy 442.836501 -276.610727) (xy 442.800523 -276.650881) (xy 442.759081 -276.685369)
			(xy 442.71306 -276.713455) (xy 442.66344 -276.734542) (xy 442.611279 -276.748178) (xy 442.557688 -276.754075)
			(xy 442.503809 -276.752106) (xy 442.450791 -276.742313) (xy 442.399764 -276.724905) (xy 442.351816 -276.700253)
			(xy 442.307968 -276.668883) (xy 442.269155 -276.631462) (xy 442.236203 -276.588789) (xy 442.209817 -276.541772)
			(xy 442.190557 -276.491415) (xy 442.178834 -276.438791) (xy 442.174899 -276.38502) (xy 439.469022 -276.38502)
			(xy 439.46853 -276.411977) (xy 439.46068 -276.465317) (xy 439.445148 -276.516946) (xy 439.422263 -276.565763)
			(xy 439.392515 -276.610727) (xy 439.356537 -276.650881) (xy 439.315095 -276.685369) (xy 439.269074 -276.713455)
			(xy 439.219454 -276.734542) (xy 439.167293 -276.748178) (xy 439.113702 -276.754075) (xy 439.059823 -276.752106)
			(xy 439.006805 -276.742313) (xy 438.955778 -276.724905) (xy 438.90783 -276.700253) (xy 438.863982 -276.668883)
			(xy 438.825169 -276.631462) (xy 438.792217 -276.588789) (xy 438.765831 -276.541772) (xy 438.746571 -276.491415)
			(xy 438.734848 -276.438791) (xy 438.730913 -276.38502) (xy 435.368954 -276.38502) (xy 435.368462 -276.411977)
			(xy 435.360612 -276.465317) (xy 435.34508 -276.516946) (xy 435.322195 -276.565763) (xy 435.292447 -276.610727)
			(xy 435.256469 -276.650881) (xy 435.215027 -276.685369) (xy 435.169006 -276.713455) (xy 435.119386 -276.734542)
			(xy 435.067225 -276.748178) (xy 435.013634 -276.754075) (xy 434.959755 -276.752106) (xy 434.906737 -276.742313)
			(xy 434.85571 -276.724905) (xy 434.807762 -276.700253) (xy 434.763914 -276.668883) (xy 434.725101 -276.631462)
			(xy 434.692149 -276.588789) (xy 434.665763 -276.541772) (xy 434.646503 -276.491415) (xy 434.63478 -276.438791)
			(xy 434.630845 -276.38502) (xy 431.924968 -276.38502) (xy 431.924476 -276.411977) (xy 431.916626 -276.465317)
			(xy 431.901094 -276.516946) (xy 431.878209 -276.565763) (xy 431.848461 -276.610727) (xy 431.812483 -276.650881)
			(xy 431.771041 -276.685369) (xy 431.72502 -276.713455) (xy 431.6754 -276.734542) (xy 431.623239 -276.748178)
			(xy 431.569648 -276.754075) (xy 431.515769 -276.752106) (xy 431.462751 -276.742313) (xy 431.411724 -276.724905)
			(xy 431.363776 -276.700253) (xy 431.319928 -276.668883) (xy 431.281115 -276.631462) (xy 431.248163 -276.588789)
			(xy 431.221777 -276.541772) (xy 431.202517 -276.491415) (xy 431.190794 -276.438791) (xy 431.186859 -276.38502)
			(xy 427.8249 -276.38502) (xy 427.824408 -276.411977) (xy 427.816558 -276.465317) (xy 427.801026 -276.516946)
			(xy 427.778141 -276.565763) (xy 427.748393 -276.610727) (xy 427.712415 -276.650881) (xy 427.670973 -276.685369)
			(xy 427.624952 -276.713455) (xy 427.575332 -276.734542) (xy 427.523171 -276.748178) (xy 427.46958 -276.754075)
			(xy 427.415701 -276.752106) (xy 427.362683 -276.742313) (xy 427.311656 -276.724905) (xy 427.263708 -276.700253)
			(xy 427.21986 -276.668883) (xy 427.181047 -276.631462) (xy 427.148095 -276.588789) (xy 427.121709 -276.541772)
			(xy 427.102449 -276.491415) (xy 427.090726 -276.438791) (xy 427.086791 -276.38502) (xy 425.985178 -276.38502)
			(xy 425.985178 -277.235158) (xy 427.086791 -277.235158) (xy 427.090726 -277.181387) (xy 427.102449 -277.128763)
			(xy 427.121709 -277.078406) (xy 427.148095 -277.031389) (xy 427.181047 -276.988716) (xy 427.21986 -276.951295)
			(xy 427.263708 -276.919925) (xy 427.311656 -276.895273) (xy 427.362683 -276.877865) (xy 427.415701 -276.868072)
			(xy 427.46958 -276.866103) (xy 427.523171 -276.872) (xy 427.575332 -276.885636) (xy 427.624952 -276.906723)
			(xy 427.670973 -276.934809) (xy 427.712415 -276.969297) (xy 427.748393 -277.009451) (xy 427.778141 -277.054415)
			(xy 427.801026 -277.103232) (xy 427.816558 -277.154861) (xy 427.824408 -277.208201) (xy 427.8249 -277.235158)
			(xy 434.630845 -277.235158) (xy 434.63478 -277.181387) (xy 434.646503 -277.128763) (xy 434.665763 -277.078406)
			(xy 434.692149 -277.031389) (xy 434.725101 -276.988716) (xy 434.763914 -276.951295) (xy 434.807762 -276.919925)
			(xy 434.85571 -276.895273) (xy 434.906737 -276.877865) (xy 434.959755 -276.868072) (xy 435.013634 -276.866103)
			(xy 435.067225 -276.872) (xy 435.119386 -276.885636) (xy 435.169006 -276.906723) (xy 435.215027 -276.934809)
			(xy 435.256469 -276.969297) (xy 435.292447 -277.009451) (xy 435.322195 -277.054415) (xy 435.34508 -277.103232)
			(xy 435.360612 -277.154861) (xy 435.368462 -277.208201) (xy 435.368954 -277.235158) (xy 442.174899 -277.235158)
			(xy 442.178834 -277.181387) (xy 442.190557 -277.128763) (xy 442.209817 -277.078406) (xy 442.236203 -277.031389)
			(xy 442.269155 -276.988716) (xy 442.307968 -276.951295) (xy 442.351816 -276.919925) (xy 442.399764 -276.895273)
			(xy 442.450791 -276.877865) (xy 442.503809 -276.868072) (xy 442.557688 -276.866103) (xy 442.611279 -276.872)
			(xy 442.66344 -276.885636) (xy 442.71306 -276.906723) (xy 442.759081 -276.934809) (xy 442.800523 -276.969297)
			(xy 442.836501 -277.009451) (xy 442.866249 -277.054415) (xy 442.889134 -277.103232) (xy 442.904666 -277.154861)
			(xy 442.912516 -277.208201) (xy 442.913008 -277.235158) (xy 449.718699 -277.235158) (xy 449.722634 -277.181387)
			(xy 449.734357 -277.128763) (xy 449.753617 -277.078406) (xy 449.780003 -277.031389) (xy 449.812955 -276.988716)
			(xy 449.851768 -276.951295) (xy 449.895616 -276.919925) (xy 449.943564 -276.895273) (xy 449.994591 -276.877865)
			(xy 450.047609 -276.868072) (xy 450.101488 -276.866103) (xy 450.155079 -276.872) (xy 450.20724 -276.885636)
			(xy 450.25686 -276.906723) (xy 450.302881 -276.934809) (xy 450.344323 -276.969297) (xy 450.380301 -277.009451)
			(xy 450.410049 -277.054415) (xy 450.432934 -277.103232) (xy 450.448466 -277.154861) (xy 450.456316 -277.208201)
			(xy 450.456808 -277.235158) (xy 450.456316 -277.262115) (xy 450.448466 -277.315455) (xy 450.432934 -277.367084)
			(xy 450.410049 -277.415901) (xy 450.380301 -277.460865) (xy 450.344323 -277.501019) (xy 450.302881 -277.535507)
			(xy 450.25686 -277.563593) (xy 450.20724 -277.58468) (xy 450.155079 -277.598316) (xy 450.101488 -277.604213)
			(xy 450.047609 -277.602244) (xy 449.994591 -277.592451) (xy 449.943564 -277.575043) (xy 449.895616 -277.550391)
			(xy 449.851768 -277.519021) (xy 449.812955 -277.4816) (xy 449.780003 -277.438927) (xy 449.753617 -277.39191)
			(xy 449.734357 -277.341553) (xy 449.722634 -277.288929) (xy 449.718699 -277.235158) (xy 442.913008 -277.235158)
			(xy 442.912516 -277.262115) (xy 442.904666 -277.315455) (xy 442.889134 -277.367084) (xy 442.866249 -277.415901)
			(xy 442.836501 -277.460865) (xy 442.800523 -277.501019) (xy 442.759081 -277.535507) (xy 442.71306 -277.563593)
			(xy 442.66344 -277.58468) (xy 442.611279 -277.598316) (xy 442.557688 -277.604213) (xy 442.503809 -277.602244)
			(xy 442.450791 -277.592451) (xy 442.399764 -277.575043) (xy 442.351816 -277.550391) (xy 442.307968 -277.519021)
			(xy 442.269155 -277.4816) (xy 442.236203 -277.438927) (xy 442.209817 -277.39191) (xy 442.190557 -277.341553)
			(xy 442.178834 -277.288929) (xy 442.174899 -277.235158) (xy 435.368954 -277.235158) (xy 435.368462 -277.262115)
			(xy 435.360612 -277.315455) (xy 435.34508 -277.367084) (xy 435.322195 -277.415901) (xy 435.292447 -277.460865)
			(xy 435.256469 -277.501019) (xy 435.215027 -277.535507) (xy 435.169006 -277.563593) (xy 435.119386 -277.58468)
			(xy 435.067225 -277.598316) (xy 435.013634 -277.604213) (xy 434.959755 -277.602244) (xy 434.906737 -277.592451)
			(xy 434.85571 -277.575043) (xy 434.807762 -277.550391) (xy 434.763914 -277.519021) (xy 434.725101 -277.4816)
			(xy 434.692149 -277.438927) (xy 434.665763 -277.39191) (xy 434.646503 -277.341553) (xy 434.63478 -277.288929)
			(xy 434.630845 -277.235158) (xy 427.8249 -277.235158) (xy 427.824408 -277.262115) (xy 427.816558 -277.315455)
			(xy 427.801026 -277.367084) (xy 427.778141 -277.415901) (xy 427.748393 -277.460865) (xy 427.712415 -277.501019)
			(xy 427.670973 -277.535507) (xy 427.624952 -277.563593) (xy 427.575332 -277.58468) (xy 427.523171 -277.598316)
			(xy 427.46958 -277.604213) (xy 427.415701 -277.602244) (xy 427.362683 -277.592451) (xy 427.311656 -277.575043)
			(xy 427.263708 -277.550391) (xy 427.21986 -277.519021) (xy 427.181047 -277.4816) (xy 427.148095 -277.438927)
			(xy 427.121709 -277.39191) (xy 427.102449 -277.341553) (xy 427.090726 -277.288929) (xy 427.086791 -277.235158)
			(xy 425.985178 -277.235158) (xy 425.985178 -278.085042) (xy 431.186859 -278.085042) (xy 431.190794 -278.031271)
			(xy 431.202517 -277.978647) (xy 431.221777 -277.92829) (xy 431.248163 -277.881273) (xy 431.281115 -277.8386)
			(xy 431.319928 -277.801179) (xy 431.363776 -277.769809) (xy 431.411724 -277.745157) (xy 431.462751 -277.727749)
			(xy 431.515769 -277.717956) (xy 431.569648 -277.715987) (xy 431.623239 -277.721884) (xy 431.6754 -277.73552)
			(xy 431.72502 -277.756607) (xy 431.771041 -277.784693) (xy 431.812483 -277.819181) (xy 431.848461 -277.859335)
			(xy 431.878209 -277.904299) (xy 431.901094 -277.953116) (xy 431.916626 -278.004745) (xy 431.924476 -278.058085)
			(xy 431.924968 -278.085042) (xy 438.730913 -278.085042) (xy 438.734848 -278.031271) (xy 438.746571 -277.978647)
			(xy 438.765831 -277.92829) (xy 438.792217 -277.881273) (xy 438.825169 -277.8386) (xy 438.863982 -277.801179)
			(xy 438.90783 -277.769809) (xy 438.955778 -277.745157) (xy 439.006805 -277.727749) (xy 439.059823 -277.717956)
			(xy 439.113702 -277.715987) (xy 439.167293 -277.721884) (xy 439.219454 -277.73552) (xy 439.269074 -277.756607)
			(xy 439.315095 -277.784693) (xy 439.356537 -277.819181) (xy 439.392515 -277.859335) (xy 439.422263 -277.904299)
			(xy 439.445148 -277.953116) (xy 439.46068 -278.004745) (xy 439.46853 -278.058085) (xy 439.469022 -278.085042)
			(xy 446.274967 -278.085042) (xy 446.278902 -278.031271) (xy 446.290625 -277.978647) (xy 446.309885 -277.92829)
			(xy 446.336271 -277.881273) (xy 446.369223 -277.8386) (xy 446.408036 -277.801179) (xy 446.451884 -277.769809)
			(xy 446.499832 -277.745157) (xy 446.550859 -277.727749) (xy 446.603877 -277.717956) (xy 446.657756 -277.715987)
			(xy 446.711347 -277.721884) (xy 446.763508 -277.73552) (xy 446.813128 -277.756607) (xy 446.859149 -277.784693)
			(xy 446.900591 -277.819181) (xy 446.936569 -277.859335) (xy 446.966317 -277.904299) (xy 446.989202 -277.953116)
			(xy 447.004734 -278.004745) (xy 447.012584 -278.058085) (xy 447.013076 -278.085042) (xy 453.818767 -278.085042)
			(xy 453.822702 -278.031271) (xy 453.834425 -277.978647) (xy 453.853685 -277.92829) (xy 453.880071 -277.881273)
			(xy 453.913023 -277.8386) (xy 453.951836 -277.801179) (xy 453.995684 -277.769809) (xy 454.043632 -277.745157)
			(xy 454.094659 -277.727749) (xy 454.147677 -277.717956) (xy 454.201556 -277.715987) (xy 454.255147 -277.721884)
			(xy 454.307308 -277.73552) (xy 454.356928 -277.756607) (xy 454.402949 -277.784693) (xy 454.444391 -277.819181)
			(xy 454.480369 -277.859335) (xy 454.510117 -277.904299) (xy 454.533002 -277.953116) (xy 454.548534 -278.004745)
			(xy 454.556384 -278.058085) (xy 454.556876 -278.085042) (xy 454.556384 -278.111999) (xy 454.548534 -278.165339)
			(xy 454.533002 -278.216968) (xy 454.510117 -278.265785) (xy 454.480369 -278.310749) (xy 454.444391 -278.350903)
			(xy 454.402949 -278.385391) (xy 454.356928 -278.413477) (xy 454.307308 -278.434564) (xy 454.255147 -278.4482)
			(xy 454.201556 -278.454097) (xy 454.147677 -278.452128) (xy 454.094659 -278.442335) (xy 454.043632 -278.424927)
			(xy 453.995684 -278.400275) (xy 453.951836 -278.368905) (xy 453.913023 -278.331484) (xy 453.880071 -278.288811)
			(xy 453.853685 -278.241794) (xy 453.834425 -278.191437) (xy 453.822702 -278.138813) (xy 453.818767 -278.085042)
			(xy 447.013076 -278.085042) (xy 447.012584 -278.111999) (xy 447.004734 -278.165339) (xy 446.989202 -278.216968)
			(xy 446.966317 -278.265785) (xy 446.936569 -278.310749) (xy 446.900591 -278.350903) (xy 446.859149 -278.385391)
			(xy 446.813128 -278.413477) (xy 446.763508 -278.434564) (xy 446.711347 -278.4482) (xy 446.657756 -278.454097)
			(xy 446.603877 -278.452128) (xy 446.550859 -278.442335) (xy 446.499832 -278.424927) (xy 446.451884 -278.400275)
			(xy 446.408036 -278.368905) (xy 446.369223 -278.331484) (xy 446.336271 -278.288811) (xy 446.309885 -278.241794)
			(xy 446.290625 -278.191437) (xy 446.278902 -278.138813) (xy 446.274967 -278.085042) (xy 439.469022 -278.085042)
			(xy 439.46853 -278.111999) (xy 439.46068 -278.165339) (xy 439.445148 -278.216968) (xy 439.422263 -278.265785)
			(xy 439.392515 -278.310749) (xy 439.356537 -278.350903) (xy 439.315095 -278.385391) (xy 439.269074 -278.413477)
			(xy 439.219454 -278.434564) (xy 439.167293 -278.4482) (xy 439.113702 -278.454097) (xy 439.059823 -278.452128)
			(xy 439.006805 -278.442335) (xy 438.955778 -278.424927) (xy 438.90783 -278.400275) (xy 438.863982 -278.368905)
			(xy 438.825169 -278.331484) (xy 438.792217 -278.288811) (xy 438.765831 -278.241794) (xy 438.746571 -278.191437)
			(xy 438.734848 -278.138813) (xy 438.730913 -278.085042) (xy 431.924968 -278.085042) (xy 431.924476 -278.111999)
			(xy 431.916626 -278.165339) (xy 431.901094 -278.216968) (xy 431.878209 -278.265785) (xy 431.848461 -278.310749)
			(xy 431.812483 -278.350903) (xy 431.771041 -278.385391) (xy 431.72502 -278.413477) (xy 431.6754 -278.434564)
			(xy 431.623239 -278.4482) (xy 431.569648 -278.454097) (xy 431.515769 -278.452128) (xy 431.462751 -278.442335)
			(xy 431.411724 -278.424927) (xy 431.363776 -278.400275) (xy 431.319928 -278.368905) (xy 431.281115 -278.331484)
			(xy 431.248163 -278.288811) (xy 431.221777 -278.241794) (xy 431.202517 -278.191437) (xy 431.190794 -278.138813)
			(xy 431.186859 -278.085042) (xy 425.985178 -278.085042) (xy 425.985178 -278.93518) (xy 427.086791 -278.93518)
			(xy 427.090726 -278.881409) (xy 427.102449 -278.828785) (xy 427.121709 -278.778428) (xy 427.148095 -278.731411)
			(xy 427.181047 -278.688738) (xy 427.21986 -278.651317) (xy 427.263708 -278.619947) (xy 427.311656 -278.595295)
			(xy 427.362683 -278.577887) (xy 427.415701 -278.568094) (xy 427.46958 -278.566125) (xy 427.523171 -278.572022)
			(xy 427.575332 -278.585658) (xy 427.624952 -278.606745) (xy 427.670973 -278.634831) (xy 427.712415 -278.669319)
			(xy 427.748393 -278.709473) (xy 427.778141 -278.754437) (xy 427.801026 -278.803254) (xy 427.816558 -278.854883)
			(xy 427.824408 -278.908223) (xy 427.8249 -278.93518) (xy 434.630845 -278.93518) (xy 434.63478 -278.881409)
			(xy 434.646503 -278.828785) (xy 434.665763 -278.778428) (xy 434.692149 -278.731411) (xy 434.725101 -278.688738)
			(xy 434.763914 -278.651317) (xy 434.807762 -278.619947) (xy 434.85571 -278.595295) (xy 434.906737 -278.577887)
			(xy 434.959755 -278.568094) (xy 435.013634 -278.566125) (xy 435.067225 -278.572022) (xy 435.119386 -278.585658)
			(xy 435.169006 -278.606745) (xy 435.215027 -278.634831) (xy 435.256469 -278.669319) (xy 435.292447 -278.709473)
			(xy 435.322195 -278.754437) (xy 435.34508 -278.803254) (xy 435.360612 -278.854883) (xy 435.368462 -278.908223)
			(xy 435.368954 -278.93518) (xy 442.174899 -278.93518) (xy 442.178834 -278.881409) (xy 442.190557 -278.828785)
			(xy 442.209817 -278.778428) (xy 442.236203 -278.731411) (xy 442.269155 -278.688738) (xy 442.307968 -278.651317)
			(xy 442.351816 -278.619947) (xy 442.399764 -278.595295) (xy 442.450791 -278.577887) (xy 442.503809 -278.568094)
			(xy 442.557688 -278.566125) (xy 442.611279 -278.572022) (xy 442.66344 -278.585658) (xy 442.71306 -278.606745)
			(xy 442.759081 -278.634831) (xy 442.800523 -278.669319) (xy 442.836501 -278.709473) (xy 442.866249 -278.754437)
			(xy 442.889134 -278.803254) (xy 442.904666 -278.854883) (xy 442.912516 -278.908223) (xy 442.913008 -278.93518)
			(xy 449.718699 -278.93518) (xy 449.722634 -278.881409) (xy 449.734357 -278.828785) (xy 449.753617 -278.778428)
			(xy 449.780003 -278.731411) (xy 449.812955 -278.688738) (xy 449.851768 -278.651317) (xy 449.895616 -278.619947)
			(xy 449.943564 -278.595295) (xy 449.994591 -278.577887) (xy 450.047609 -278.568094) (xy 450.101488 -278.566125)
			(xy 450.155079 -278.572022) (xy 450.20724 -278.585658) (xy 450.25686 -278.606745) (xy 450.302881 -278.634831)
			(xy 450.344323 -278.669319) (xy 450.380301 -278.709473) (xy 450.410049 -278.754437) (xy 450.432934 -278.803254)
			(xy 450.448466 -278.854883) (xy 450.456316 -278.908223) (xy 450.456808 -278.93518) (xy 450.456316 -278.962137)
			(xy 450.448466 -279.015477) (xy 450.432934 -279.067106) (xy 450.410049 -279.115923) (xy 450.380301 -279.160887)
			(xy 450.344323 -279.201041) (xy 450.302881 -279.235529) (xy 450.25686 -279.263615) (xy 450.20724 -279.284702)
			(xy 450.155079 -279.298338) (xy 450.101488 -279.304235) (xy 450.047609 -279.302266) (xy 449.994591 -279.292473)
			(xy 449.943564 -279.275065) (xy 449.895616 -279.250413) (xy 449.851768 -279.219043) (xy 449.812955 -279.181622)
			(xy 449.780003 -279.138949) (xy 449.753617 -279.091932) (xy 449.734357 -279.041575) (xy 449.722634 -278.988951)
			(xy 449.718699 -278.93518) (xy 442.913008 -278.93518) (xy 442.912516 -278.962137) (xy 442.904666 -279.015477)
			(xy 442.889134 -279.067106) (xy 442.866249 -279.115923) (xy 442.836501 -279.160887) (xy 442.800523 -279.201041)
			(xy 442.759081 -279.235529) (xy 442.71306 -279.263615) (xy 442.66344 -279.284702) (xy 442.611279 -279.298338)
			(xy 442.557688 -279.304235) (xy 442.503809 -279.302266) (xy 442.450791 -279.292473) (xy 442.399764 -279.275065)
			(xy 442.351816 -279.250413) (xy 442.307968 -279.219043) (xy 442.269155 -279.181622) (xy 442.236203 -279.138949)
			(xy 442.209817 -279.091932) (xy 442.190557 -279.041575) (xy 442.178834 -278.988951) (xy 442.174899 -278.93518)
			(xy 435.368954 -278.93518) (xy 435.368462 -278.962137) (xy 435.360612 -279.015477) (xy 435.34508 -279.067106)
			(xy 435.322195 -279.115923) (xy 435.292447 -279.160887) (xy 435.256469 -279.201041) (xy 435.215027 -279.235529)
			(xy 435.169006 -279.263615) (xy 435.119386 -279.284702) (xy 435.067225 -279.298338) (xy 435.013634 -279.304235)
			(xy 434.959755 -279.302266) (xy 434.906737 -279.292473) (xy 434.85571 -279.275065) (xy 434.807762 -279.250413)
			(xy 434.763914 -279.219043) (xy 434.725101 -279.181622) (xy 434.692149 -279.138949) (xy 434.665763 -279.091932)
			(xy 434.646503 -279.041575) (xy 434.63478 -278.988951) (xy 434.630845 -278.93518) (xy 427.8249 -278.93518)
			(xy 427.824408 -278.962137) (xy 427.816558 -279.015477) (xy 427.801026 -279.067106) (xy 427.778141 -279.115923)
			(xy 427.748393 -279.160887) (xy 427.712415 -279.201041) (xy 427.670973 -279.235529) (xy 427.624952 -279.263615)
			(xy 427.575332 -279.284702) (xy 427.523171 -279.298338) (xy 427.46958 -279.304235) (xy 427.415701 -279.302266)
			(xy 427.362683 -279.292473) (xy 427.311656 -279.275065) (xy 427.263708 -279.250413) (xy 427.21986 -279.219043)
			(xy 427.181047 -279.181622) (xy 427.148095 -279.138949) (xy 427.121709 -279.091932) (xy 427.102449 -279.041575)
			(xy 427.090726 -278.988951) (xy 427.086791 -278.93518) (xy 425.985178 -278.93518) (xy 425.985178 -279.785064)
			(xy 431.186859 -279.785064) (xy 431.190794 -279.731293) (xy 431.202517 -279.678669) (xy 431.221777 -279.628312)
			(xy 431.248163 -279.581295) (xy 431.281115 -279.538622) (xy 431.319928 -279.501201) (xy 431.363776 -279.469831)
			(xy 431.411724 -279.445179) (xy 431.462751 -279.427771) (xy 431.515769 -279.417978) (xy 431.569648 -279.416009)
			(xy 431.623239 -279.421906) (xy 431.6754 -279.435542) (xy 431.72502 -279.456629) (xy 431.771041 -279.484715)
			(xy 431.812483 -279.519203) (xy 431.848461 -279.559357) (xy 431.878209 -279.604321) (xy 431.901094 -279.653138)
			(xy 431.916626 -279.704767) (xy 431.924476 -279.758107) (xy 431.924968 -279.785064) (xy 438.730913 -279.785064)
			(xy 438.734848 -279.731293) (xy 438.746571 -279.678669) (xy 438.765831 -279.628312) (xy 438.792217 -279.581295)
			(xy 438.825169 -279.538622) (xy 438.863982 -279.501201) (xy 438.90783 -279.469831) (xy 438.955778 -279.445179)
			(xy 439.006805 -279.427771) (xy 439.059823 -279.417978) (xy 439.113702 -279.416009) (xy 439.167293 -279.421906)
			(xy 439.219454 -279.435542) (xy 439.269074 -279.456629) (xy 439.315095 -279.484715) (xy 439.356537 -279.519203)
			(xy 439.392515 -279.559357) (xy 439.422263 -279.604321) (xy 439.445148 -279.653138) (xy 439.46068 -279.704767)
			(xy 439.46853 -279.758107) (xy 439.469022 -279.785064) (xy 446.274967 -279.785064) (xy 446.278902 -279.731293)
			(xy 446.290625 -279.678669) (xy 446.309885 -279.628312) (xy 446.336271 -279.581295) (xy 446.369223 -279.538622)
			(xy 446.408036 -279.501201) (xy 446.451884 -279.469831) (xy 446.499832 -279.445179) (xy 446.550859 -279.427771)
			(xy 446.603877 -279.417978) (xy 446.657756 -279.416009) (xy 446.711347 -279.421906) (xy 446.763508 -279.435542)
			(xy 446.813128 -279.456629) (xy 446.859149 -279.484715) (xy 446.900591 -279.519203) (xy 446.936569 -279.559357)
			(xy 446.966317 -279.604321) (xy 446.989202 -279.653138) (xy 447.004734 -279.704767) (xy 447.012584 -279.758107)
			(xy 447.013076 -279.785064) (xy 453.818767 -279.785064) (xy 453.822702 -279.731293) (xy 453.834425 -279.678669)
			(xy 453.853685 -279.628312) (xy 453.880071 -279.581295) (xy 453.913023 -279.538622) (xy 453.951836 -279.501201)
			(xy 453.995684 -279.469831) (xy 454.043632 -279.445179) (xy 454.094659 -279.427771) (xy 454.147677 -279.417978)
			(xy 454.201556 -279.416009) (xy 454.255147 -279.421906) (xy 454.307308 -279.435542) (xy 454.356928 -279.456629)
			(xy 454.402949 -279.484715) (xy 454.444391 -279.519203) (xy 454.480369 -279.559357) (xy 454.510117 -279.604321)
			(xy 454.533002 -279.653138) (xy 454.548534 -279.704767) (xy 454.556384 -279.758107) (xy 454.556876 -279.785064)
			(xy 454.556384 -279.812021) (xy 454.548534 -279.865361) (xy 454.533002 -279.91699) (xy 454.510117 -279.965807)
			(xy 454.480369 -280.010771) (xy 454.444391 -280.050925) (xy 454.402949 -280.085413) (xy 454.356928 -280.113499)
			(xy 454.307308 -280.134586) (xy 454.255147 -280.148222) (xy 454.201556 -280.154119) (xy 454.147677 -280.15215)
			(xy 454.094659 -280.142357) (xy 454.043632 -280.124949) (xy 453.995684 -280.100297) (xy 453.951836 -280.068927)
			(xy 453.913023 -280.031506) (xy 453.880071 -279.988833) (xy 453.853685 -279.941816) (xy 453.834425 -279.891459)
			(xy 453.822702 -279.838835) (xy 453.818767 -279.785064) (xy 447.013076 -279.785064) (xy 447.012584 -279.812021)
			(xy 447.004734 -279.865361) (xy 446.989202 -279.91699) (xy 446.966317 -279.965807) (xy 446.936569 -280.010771)
			(xy 446.900591 -280.050925) (xy 446.859149 -280.085413) (xy 446.813128 -280.113499) (xy 446.763508 -280.134586)
			(xy 446.711347 -280.148222) (xy 446.657756 -280.154119) (xy 446.603877 -280.15215) (xy 446.550859 -280.142357)
			(xy 446.499832 -280.124949) (xy 446.451884 -280.100297) (xy 446.408036 -280.068927) (xy 446.369223 -280.031506)
			(xy 446.336271 -279.988833) (xy 446.309885 -279.941816) (xy 446.290625 -279.891459) (xy 446.278902 -279.838835)
			(xy 446.274967 -279.785064) (xy 439.469022 -279.785064) (xy 439.46853 -279.812021) (xy 439.46068 -279.865361)
			(xy 439.445148 -279.91699) (xy 439.422263 -279.965807) (xy 439.392515 -280.010771) (xy 439.356537 -280.050925)
			(xy 439.315095 -280.085413) (xy 439.269074 -280.113499) (xy 439.219454 -280.134586) (xy 439.167293 -280.148222)
			(xy 439.113702 -280.154119) (xy 439.059823 -280.15215) (xy 439.006805 -280.142357) (xy 438.955778 -280.124949)
			(xy 438.90783 -280.100297) (xy 438.863982 -280.068927) (xy 438.825169 -280.031506) (xy 438.792217 -279.988833)
			(xy 438.765831 -279.941816) (xy 438.746571 -279.891459) (xy 438.734848 -279.838835) (xy 438.730913 -279.785064)
			(xy 431.924968 -279.785064) (xy 431.924476 -279.812021) (xy 431.916626 -279.865361) (xy 431.901094 -279.91699)
			(xy 431.878209 -279.965807) (xy 431.848461 -280.010771) (xy 431.812483 -280.050925) (xy 431.771041 -280.085413)
			(xy 431.72502 -280.113499) (xy 431.6754 -280.134586) (xy 431.623239 -280.148222) (xy 431.569648 -280.154119)
			(xy 431.515769 -280.15215) (xy 431.462751 -280.142357) (xy 431.411724 -280.124949) (xy 431.363776 -280.100297)
			(xy 431.319928 -280.068927) (xy 431.281115 -280.031506) (xy 431.248163 -279.988833) (xy 431.221777 -279.941816)
			(xy 431.202517 -279.891459) (xy 431.190794 -279.838835) (xy 431.186859 -279.785064) (xy 425.985178 -279.785064)
			(xy 425.985178 -280.634948) (xy 427.086791 -280.634948) (xy 427.090726 -280.581177) (xy 427.102449 -280.528553)
			(xy 427.121709 -280.478196) (xy 427.148095 -280.431179) (xy 427.181047 -280.388506) (xy 427.21986 -280.351085)
			(xy 427.263708 -280.319715) (xy 427.311656 -280.295063) (xy 427.362683 -280.277655) (xy 427.415701 -280.267862)
			(xy 427.46958 -280.265893) (xy 427.523171 -280.27179) (xy 427.575332 -280.285426) (xy 427.624952 -280.306513)
			(xy 427.670973 -280.334599) (xy 427.712415 -280.369087) (xy 427.748393 -280.409241) (xy 427.778141 -280.454205)
			(xy 427.801026 -280.503022) (xy 427.816558 -280.554651) (xy 427.824408 -280.607991) (xy 427.8249 -280.634948)
			(xy 434.630845 -280.634948) (xy 434.63478 -280.581177) (xy 434.646503 -280.528553) (xy 434.665763 -280.478196)
			(xy 434.692149 -280.431179) (xy 434.725101 -280.388506) (xy 434.763914 -280.351085) (xy 434.807762 -280.319715)
			(xy 434.85571 -280.295063) (xy 434.906737 -280.277655) (xy 434.959755 -280.267862) (xy 435.013634 -280.265893)
			(xy 435.067225 -280.27179) (xy 435.119386 -280.285426) (xy 435.169006 -280.306513) (xy 435.215027 -280.334599)
			(xy 435.256469 -280.369087) (xy 435.292447 -280.409241) (xy 435.322195 -280.454205) (xy 435.34508 -280.503022)
			(xy 435.360612 -280.554651) (xy 435.368462 -280.607991) (xy 435.368954 -280.634948) (xy 442.174899 -280.634948)
			(xy 442.178834 -280.581177) (xy 442.190557 -280.528553) (xy 442.209817 -280.478196) (xy 442.236203 -280.431179)
			(xy 442.269155 -280.388506) (xy 442.307968 -280.351085) (xy 442.351816 -280.319715) (xy 442.399764 -280.295063)
			(xy 442.450791 -280.277655) (xy 442.503809 -280.267862) (xy 442.557688 -280.265893) (xy 442.611279 -280.27179)
			(xy 442.66344 -280.285426) (xy 442.71306 -280.306513) (xy 442.759081 -280.334599) (xy 442.800523 -280.369087)
			(xy 442.836501 -280.409241) (xy 442.866249 -280.454205) (xy 442.889134 -280.503022) (xy 442.904666 -280.554651)
			(xy 442.912516 -280.607991) (xy 442.913008 -280.634948) (xy 449.718699 -280.634948) (xy 449.722634 -280.581177)
			(xy 449.734357 -280.528553) (xy 449.753617 -280.478196) (xy 449.780003 -280.431179) (xy 449.812955 -280.388506)
			(xy 449.851768 -280.351085) (xy 449.895616 -280.319715) (xy 449.943564 -280.295063) (xy 449.994591 -280.277655)
			(xy 450.047609 -280.267862) (xy 450.101488 -280.265893) (xy 450.155079 -280.27179) (xy 450.20724 -280.285426)
			(xy 450.25686 -280.306513) (xy 450.302881 -280.334599) (xy 450.344323 -280.369087) (xy 450.380301 -280.409241)
			(xy 450.410049 -280.454205) (xy 450.432934 -280.503022) (xy 450.448466 -280.554651) (xy 450.456316 -280.607991)
			(xy 450.456808 -280.634948) (xy 450.456316 -280.661905) (xy 450.448466 -280.715245) (xy 450.432934 -280.766874)
			(xy 450.410049 -280.815691) (xy 450.380301 -280.860655) (xy 450.344323 -280.900809) (xy 450.302881 -280.935297)
			(xy 450.25686 -280.963383) (xy 450.20724 -280.98447) (xy 450.155079 -280.998106) (xy 450.101488 -281.004003)
			(xy 450.047609 -281.002034) (xy 449.994591 -280.992241) (xy 449.943564 -280.974833) (xy 449.895616 -280.950181)
			(xy 449.851768 -280.918811) (xy 449.812955 -280.88139) (xy 449.780003 -280.838717) (xy 449.753617 -280.7917)
			(xy 449.734357 -280.741343) (xy 449.722634 -280.688719) (xy 449.718699 -280.634948) (xy 442.913008 -280.634948)
			(xy 442.912516 -280.661905) (xy 442.904666 -280.715245) (xy 442.889134 -280.766874) (xy 442.866249 -280.815691)
			(xy 442.836501 -280.860655) (xy 442.800523 -280.900809) (xy 442.759081 -280.935297) (xy 442.71306 -280.963383)
			(xy 442.66344 -280.98447) (xy 442.611279 -280.998106) (xy 442.557688 -281.004003) (xy 442.503809 -281.002034)
			(xy 442.450791 -280.992241) (xy 442.399764 -280.974833) (xy 442.351816 -280.950181) (xy 442.307968 -280.918811)
			(xy 442.269155 -280.88139) (xy 442.236203 -280.838717) (xy 442.209817 -280.7917) (xy 442.190557 -280.741343)
			(xy 442.178834 -280.688719) (xy 442.174899 -280.634948) (xy 435.368954 -280.634948) (xy 435.368462 -280.661905)
			(xy 435.360612 -280.715245) (xy 435.34508 -280.766874) (xy 435.322195 -280.815691) (xy 435.292447 -280.860655)
			(xy 435.256469 -280.900809) (xy 435.215027 -280.935297) (xy 435.169006 -280.963383) (xy 435.119386 -280.98447)
			(xy 435.067225 -280.998106) (xy 435.013634 -281.004003) (xy 434.959755 -281.002034) (xy 434.906737 -280.992241)
			(xy 434.85571 -280.974833) (xy 434.807762 -280.950181) (xy 434.763914 -280.918811) (xy 434.725101 -280.88139)
			(xy 434.692149 -280.838717) (xy 434.665763 -280.7917) (xy 434.646503 -280.741343) (xy 434.63478 -280.688719)
			(xy 434.630845 -280.634948) (xy 427.8249 -280.634948) (xy 427.824408 -280.661905) (xy 427.816558 -280.715245)
			(xy 427.801026 -280.766874) (xy 427.778141 -280.815691) (xy 427.748393 -280.860655) (xy 427.712415 -280.900809)
			(xy 427.670973 -280.935297) (xy 427.624952 -280.963383) (xy 427.575332 -280.98447) (xy 427.523171 -280.998106)
			(xy 427.46958 -281.004003) (xy 427.415701 -281.002034) (xy 427.362683 -280.992241) (xy 427.311656 -280.974833)
			(xy 427.263708 -280.950181) (xy 427.21986 -280.918811) (xy 427.181047 -280.88139) (xy 427.148095 -280.838717)
			(xy 427.121709 -280.7917) (xy 427.102449 -280.741343) (xy 427.090726 -280.688719) (xy 427.086791 -280.634948)
			(xy 425.985178 -280.634948) (xy 425.985178 -281.485086) (xy 431.186859 -281.485086) (xy 431.190794 -281.431315)
			(xy 431.202517 -281.378691) (xy 431.221777 -281.328334) (xy 431.248163 -281.281317) (xy 431.281115 -281.238644)
			(xy 431.319928 -281.201223) (xy 431.363776 -281.169853) (xy 431.411724 -281.145201) (xy 431.462751 -281.127793)
			(xy 431.515769 -281.118) (xy 431.569648 -281.116031) (xy 431.623239 -281.121928) (xy 431.6754 -281.135564)
			(xy 431.72502 -281.156651) (xy 431.771041 -281.184737) (xy 431.812483 -281.219225) (xy 431.848461 -281.259379)
			(xy 431.878209 -281.304343) (xy 431.901094 -281.35316) (xy 431.916626 -281.404789) (xy 431.924476 -281.458129)
			(xy 431.924968 -281.485086) (xy 438.730913 -281.485086) (xy 438.734848 -281.431315) (xy 438.746571 -281.378691)
			(xy 438.765831 -281.328334) (xy 438.792217 -281.281317) (xy 438.825169 -281.238644) (xy 438.863982 -281.201223)
			(xy 438.90783 -281.169853) (xy 438.955778 -281.145201) (xy 439.006805 -281.127793) (xy 439.059823 -281.118)
			(xy 439.113702 -281.116031) (xy 439.167293 -281.121928) (xy 439.219454 -281.135564) (xy 439.269074 -281.156651)
			(xy 439.315095 -281.184737) (xy 439.356537 -281.219225) (xy 439.392515 -281.259379) (xy 439.422263 -281.304343)
			(xy 439.445148 -281.35316) (xy 439.46068 -281.404789) (xy 439.46853 -281.458129) (xy 439.469022 -281.485086)
			(xy 446.274967 -281.485086) (xy 446.278902 -281.431315) (xy 446.290625 -281.378691) (xy 446.309885 -281.328334)
			(xy 446.336271 -281.281317) (xy 446.369223 -281.238644) (xy 446.408036 -281.201223) (xy 446.451884 -281.169853)
			(xy 446.499832 -281.145201) (xy 446.550859 -281.127793) (xy 446.603877 -281.118) (xy 446.657756 -281.116031)
			(xy 446.711347 -281.121928) (xy 446.763508 -281.135564) (xy 446.813128 -281.156651) (xy 446.859149 -281.184737)
			(xy 446.900591 -281.219225) (xy 446.936569 -281.259379) (xy 446.966317 -281.304343) (xy 446.989202 -281.35316)
			(xy 447.004734 -281.404789) (xy 447.012584 -281.458129) (xy 447.013076 -281.485086) (xy 453.818767 -281.485086)
			(xy 453.822702 -281.431315) (xy 453.834425 -281.378691) (xy 453.853685 -281.328334) (xy 453.880071 -281.281317)
			(xy 453.913023 -281.238644) (xy 453.951836 -281.201223) (xy 453.995684 -281.169853) (xy 454.043632 -281.145201)
			(xy 454.094659 -281.127793) (xy 454.147677 -281.118) (xy 454.201556 -281.116031) (xy 454.255147 -281.121928)
			(xy 454.307308 -281.135564) (xy 454.356928 -281.156651) (xy 454.402949 -281.184737) (xy 454.444391 -281.219225)
			(xy 454.480369 -281.259379) (xy 454.510117 -281.304343) (xy 454.533002 -281.35316) (xy 454.548534 -281.404789)
			(xy 454.556384 -281.458129) (xy 454.556876 -281.485086) (xy 454.556384 -281.512043) (xy 454.548534 -281.565383)
			(xy 454.533002 -281.617012) (xy 454.510117 -281.665829) (xy 454.480369 -281.710793) (xy 454.444391 -281.750947)
			(xy 454.402949 -281.785435) (xy 454.356928 -281.813521) (xy 454.307308 -281.834608) (xy 454.255147 -281.848244)
			(xy 454.201556 -281.854141) (xy 454.147677 -281.852172) (xy 454.094659 -281.842379) (xy 454.043632 -281.824971)
			(xy 453.995684 -281.800319) (xy 453.951836 -281.768949) (xy 453.913023 -281.731528) (xy 453.880071 -281.688855)
			(xy 453.853685 -281.641838) (xy 453.834425 -281.591481) (xy 453.822702 -281.538857) (xy 453.818767 -281.485086)
			(xy 447.013076 -281.485086) (xy 447.012584 -281.512043) (xy 447.004734 -281.565383) (xy 446.989202 -281.617012)
			(xy 446.966317 -281.665829) (xy 446.936569 -281.710793) (xy 446.900591 -281.750947) (xy 446.859149 -281.785435)
			(xy 446.813128 -281.813521) (xy 446.763508 -281.834608) (xy 446.711347 -281.848244) (xy 446.657756 -281.854141)
			(xy 446.603877 -281.852172) (xy 446.550859 -281.842379) (xy 446.499832 -281.824971) (xy 446.451884 -281.800319)
			(xy 446.408036 -281.768949) (xy 446.369223 -281.731528) (xy 446.336271 -281.688855) (xy 446.309885 -281.641838)
			(xy 446.290625 -281.591481) (xy 446.278902 -281.538857) (xy 446.274967 -281.485086) (xy 439.469022 -281.485086)
			(xy 439.46853 -281.512043) (xy 439.46068 -281.565383) (xy 439.445148 -281.617012) (xy 439.422263 -281.665829)
			(xy 439.392515 -281.710793) (xy 439.356537 -281.750947) (xy 439.315095 -281.785435) (xy 439.269074 -281.813521)
			(xy 439.219454 -281.834608) (xy 439.167293 -281.848244) (xy 439.113702 -281.854141) (xy 439.059823 -281.852172)
			(xy 439.006805 -281.842379) (xy 438.955778 -281.824971) (xy 438.90783 -281.800319) (xy 438.863982 -281.768949)
			(xy 438.825169 -281.731528) (xy 438.792217 -281.688855) (xy 438.765831 -281.641838) (xy 438.746571 -281.591481)
			(xy 438.734848 -281.538857) (xy 438.730913 -281.485086) (xy 431.924968 -281.485086) (xy 431.924476 -281.512043)
			(xy 431.916626 -281.565383) (xy 431.901094 -281.617012) (xy 431.878209 -281.665829) (xy 431.848461 -281.710793)
			(xy 431.812483 -281.750947) (xy 431.771041 -281.785435) (xy 431.72502 -281.813521) (xy 431.6754 -281.834608)
			(xy 431.623239 -281.848244) (xy 431.569648 -281.854141) (xy 431.515769 -281.852172) (xy 431.462751 -281.842379)
			(xy 431.411724 -281.824971) (xy 431.363776 -281.800319) (xy 431.319928 -281.768949) (xy 431.281115 -281.731528)
			(xy 431.248163 -281.688855) (xy 431.221777 -281.641838) (xy 431.202517 -281.591481) (xy 431.190794 -281.538857)
			(xy 431.186859 -281.485086) (xy 425.985178 -281.485086) (xy 425.985178 -282.33497) (xy 427.086791 -282.33497)
			(xy 427.090726 -282.281199) (xy 427.102449 -282.228575) (xy 427.121709 -282.178218) (xy 427.148095 -282.131201)
			(xy 427.181047 -282.088528) (xy 427.21986 -282.051107) (xy 427.263708 -282.019737) (xy 427.311656 -281.995085)
			(xy 427.362683 -281.977677) (xy 427.415701 -281.967884) (xy 427.46958 -281.965915) (xy 427.523171 -281.971812)
			(xy 427.575332 -281.985448) (xy 427.624952 -282.006535) (xy 427.670973 -282.034621) (xy 427.712415 -282.069109)
			(xy 427.748393 -282.109263) (xy 427.778141 -282.154227) (xy 427.801026 -282.203044) (xy 427.816558 -282.254673)
			(xy 427.824408 -282.308013) (xy 427.8249 -282.33497) (xy 434.630845 -282.33497) (xy 434.63478 -282.281199)
			(xy 434.646503 -282.228575) (xy 434.665763 -282.178218) (xy 434.692149 -282.131201) (xy 434.725101 -282.088528)
			(xy 434.763914 -282.051107) (xy 434.807762 -282.019737) (xy 434.85571 -281.995085) (xy 434.906737 -281.977677)
			(xy 434.959755 -281.967884) (xy 435.013634 -281.965915) (xy 435.067225 -281.971812) (xy 435.119386 -281.985448)
			(xy 435.169006 -282.006535) (xy 435.215027 -282.034621) (xy 435.256469 -282.069109) (xy 435.292447 -282.109263)
			(xy 435.322195 -282.154227) (xy 435.34508 -282.203044) (xy 435.360612 -282.254673) (xy 435.368462 -282.308013)
			(xy 435.368954 -282.33497) (xy 442.174899 -282.33497) (xy 442.178834 -282.281199) (xy 442.190557 -282.228575)
			(xy 442.209817 -282.178218) (xy 442.236203 -282.131201) (xy 442.269155 -282.088528) (xy 442.307968 -282.051107)
			(xy 442.351816 -282.019737) (xy 442.399764 -281.995085) (xy 442.450791 -281.977677) (xy 442.503809 -281.967884)
			(xy 442.557688 -281.965915) (xy 442.611279 -281.971812) (xy 442.66344 -281.985448) (xy 442.71306 -282.006535)
			(xy 442.759081 -282.034621) (xy 442.800523 -282.069109) (xy 442.836501 -282.109263) (xy 442.866249 -282.154227)
			(xy 442.889134 -282.203044) (xy 442.904666 -282.254673) (xy 442.912516 -282.308013) (xy 442.913008 -282.33497)
			(xy 449.718699 -282.33497) (xy 449.722634 -282.281199) (xy 449.734357 -282.228575) (xy 449.753617 -282.178218)
			(xy 449.780003 -282.131201) (xy 449.812955 -282.088528) (xy 449.851768 -282.051107) (xy 449.895616 -282.019737)
			(xy 449.943564 -281.995085) (xy 449.994591 -281.977677) (xy 450.047609 -281.967884) (xy 450.101488 -281.965915)
			(xy 450.155079 -281.971812) (xy 450.20724 -281.985448) (xy 450.25686 -282.006535) (xy 450.302881 -282.034621)
			(xy 450.344323 -282.069109) (xy 450.380301 -282.109263) (xy 450.410049 -282.154227) (xy 450.432934 -282.203044)
			(xy 450.448466 -282.254673) (xy 450.456316 -282.308013) (xy 450.456808 -282.33497) (xy 450.456316 -282.361927)
			(xy 450.448466 -282.415267) (xy 450.432934 -282.466896) (xy 450.410049 -282.515713) (xy 450.380301 -282.560677)
			(xy 450.344323 -282.600831) (xy 450.302881 -282.635319) (xy 450.25686 -282.663405) (xy 450.20724 -282.684492)
			(xy 450.155079 -282.698128) (xy 450.101488 -282.704025) (xy 450.047609 -282.702056) (xy 449.994591 -282.692263)
			(xy 449.943564 -282.674855) (xy 449.895616 -282.650203) (xy 449.851768 -282.618833) (xy 449.812955 -282.581412)
			(xy 449.780003 -282.538739) (xy 449.753617 -282.491722) (xy 449.734357 -282.441365) (xy 449.722634 -282.388741)
			(xy 449.718699 -282.33497) (xy 442.913008 -282.33497) (xy 442.912516 -282.361927) (xy 442.904666 -282.415267)
			(xy 442.889134 -282.466896) (xy 442.866249 -282.515713) (xy 442.836501 -282.560677) (xy 442.800523 -282.600831)
			(xy 442.759081 -282.635319) (xy 442.71306 -282.663405) (xy 442.66344 -282.684492) (xy 442.611279 -282.698128)
			(xy 442.557688 -282.704025) (xy 442.503809 -282.702056) (xy 442.450791 -282.692263) (xy 442.399764 -282.674855)
			(xy 442.351816 -282.650203) (xy 442.307968 -282.618833) (xy 442.269155 -282.581412) (xy 442.236203 -282.538739)
			(xy 442.209817 -282.491722) (xy 442.190557 -282.441365) (xy 442.178834 -282.388741) (xy 442.174899 -282.33497)
			(xy 435.368954 -282.33497) (xy 435.368462 -282.361927) (xy 435.360612 -282.415267) (xy 435.34508 -282.466896)
			(xy 435.322195 -282.515713) (xy 435.292447 -282.560677) (xy 435.256469 -282.600831) (xy 435.215027 -282.635319)
			(xy 435.169006 -282.663405) (xy 435.119386 -282.684492) (xy 435.067225 -282.698128) (xy 435.013634 -282.704025)
			(xy 434.959755 -282.702056) (xy 434.906737 -282.692263) (xy 434.85571 -282.674855) (xy 434.807762 -282.650203)
			(xy 434.763914 -282.618833) (xy 434.725101 -282.581412) (xy 434.692149 -282.538739) (xy 434.665763 -282.491722)
			(xy 434.646503 -282.441365) (xy 434.63478 -282.388741) (xy 434.630845 -282.33497) (xy 427.8249 -282.33497)
			(xy 427.824408 -282.361927) (xy 427.816558 -282.415267) (xy 427.801026 -282.466896) (xy 427.778141 -282.515713)
			(xy 427.748393 -282.560677) (xy 427.712415 -282.600831) (xy 427.670973 -282.635319) (xy 427.624952 -282.663405)
			(xy 427.575332 -282.684492) (xy 427.523171 -282.698128) (xy 427.46958 -282.704025) (xy 427.415701 -282.702056)
			(xy 427.362683 -282.692263) (xy 427.311656 -282.674855) (xy 427.263708 -282.650203) (xy 427.21986 -282.618833)
			(xy 427.181047 -282.581412) (xy 427.148095 -282.538739) (xy 427.121709 -282.491722) (xy 427.102449 -282.441365)
			(xy 427.090726 -282.388741) (xy 427.086791 -282.33497) (xy 425.985178 -282.33497) (xy 425.985178 -283.185108)
			(xy 431.186859 -283.185108) (xy 431.190794 -283.131337) (xy 431.202517 -283.078713) (xy 431.221777 -283.028356)
			(xy 431.248163 -282.981339) (xy 431.281115 -282.938666) (xy 431.319928 -282.901245) (xy 431.363776 -282.869875)
			(xy 431.411724 -282.845223) (xy 431.462751 -282.827815) (xy 431.515769 -282.818022) (xy 431.569648 -282.816053)
			(xy 431.623239 -282.82195) (xy 431.6754 -282.835586) (xy 431.72502 -282.856673) (xy 431.771041 -282.884759)
			(xy 431.812483 -282.919247) (xy 431.848461 -282.959401) (xy 431.878209 -283.004365) (xy 431.901094 -283.053182)
			(xy 431.916626 -283.104811) (xy 431.924476 -283.158151) (xy 431.924968 -283.185108) (xy 438.730913 -283.185108)
			(xy 438.734848 -283.131337) (xy 438.746571 -283.078713) (xy 438.765831 -283.028356) (xy 438.792217 -282.981339)
			(xy 438.825169 -282.938666) (xy 438.863982 -282.901245) (xy 438.90783 -282.869875) (xy 438.955778 -282.845223)
			(xy 439.006805 -282.827815) (xy 439.059823 -282.818022) (xy 439.113702 -282.816053) (xy 439.167293 -282.82195)
			(xy 439.219454 -282.835586) (xy 439.269074 -282.856673) (xy 439.315095 -282.884759) (xy 439.356537 -282.919247)
			(xy 439.392515 -282.959401) (xy 439.422263 -283.004365) (xy 439.445148 -283.053182) (xy 439.46068 -283.104811)
			(xy 439.46853 -283.158151) (xy 439.469022 -283.185108) (xy 446.274967 -283.185108) (xy 446.278902 -283.131337)
			(xy 446.290625 -283.078713) (xy 446.309885 -283.028356) (xy 446.336271 -282.981339) (xy 446.369223 -282.938666)
			(xy 446.408036 -282.901245) (xy 446.451884 -282.869875) (xy 446.499832 -282.845223) (xy 446.550859 -282.827815)
			(xy 446.603877 -282.818022) (xy 446.657756 -282.816053) (xy 446.711347 -282.82195) (xy 446.763508 -282.835586)
			(xy 446.813128 -282.856673) (xy 446.859149 -282.884759) (xy 446.900591 -282.919247) (xy 446.936569 -282.959401)
			(xy 446.966317 -283.004365) (xy 446.989202 -283.053182) (xy 447.004734 -283.104811) (xy 447.012584 -283.158151)
			(xy 447.013076 -283.185108) (xy 453.818767 -283.185108) (xy 453.822702 -283.131337) (xy 453.834425 -283.078713)
			(xy 453.853685 -283.028356) (xy 453.880071 -282.981339) (xy 453.913023 -282.938666) (xy 453.951836 -282.901245)
			(xy 453.995684 -282.869875) (xy 454.043632 -282.845223) (xy 454.094659 -282.827815) (xy 454.147677 -282.818022)
			(xy 454.201556 -282.816053) (xy 454.255147 -282.82195) (xy 454.307308 -282.835586) (xy 454.356928 -282.856673)
			(xy 454.402949 -282.884759) (xy 454.444391 -282.919247) (xy 454.480369 -282.959401) (xy 454.510117 -283.004365)
			(xy 454.533002 -283.053182) (xy 454.548534 -283.104811) (xy 454.556384 -283.158151) (xy 454.556876 -283.185108)
			(xy 454.556384 -283.212065) (xy 454.548534 -283.265405) (xy 454.533002 -283.317034) (xy 454.510117 -283.365851)
			(xy 454.480369 -283.410815) (xy 454.444391 -283.450969) (xy 454.402949 -283.485457) (xy 454.356928 -283.513543)
			(xy 454.307308 -283.53463) (xy 454.255147 -283.548266) (xy 454.201556 -283.554163) (xy 454.147677 -283.552194)
			(xy 454.094659 -283.542401) (xy 454.043632 -283.524993) (xy 453.995684 -283.500341) (xy 453.951836 -283.468971)
			(xy 453.913023 -283.43155) (xy 453.880071 -283.388877) (xy 453.853685 -283.34186) (xy 453.834425 -283.291503)
			(xy 453.822702 -283.238879) (xy 453.818767 -283.185108) (xy 447.013076 -283.185108) (xy 447.012584 -283.212065)
			(xy 447.004734 -283.265405) (xy 446.989202 -283.317034) (xy 446.966317 -283.365851) (xy 446.936569 -283.410815)
			(xy 446.900591 -283.450969) (xy 446.859149 -283.485457) (xy 446.813128 -283.513543) (xy 446.763508 -283.53463)
			(xy 446.711347 -283.548266) (xy 446.657756 -283.554163) (xy 446.603877 -283.552194) (xy 446.550859 -283.542401)
			(xy 446.499832 -283.524993) (xy 446.451884 -283.500341) (xy 446.408036 -283.468971) (xy 446.369223 -283.43155)
			(xy 446.336271 -283.388877) (xy 446.309885 -283.34186) (xy 446.290625 -283.291503) (xy 446.278902 -283.238879)
			(xy 446.274967 -283.185108) (xy 439.469022 -283.185108) (xy 439.46853 -283.212065) (xy 439.46068 -283.265405)
			(xy 439.445148 -283.317034) (xy 439.422263 -283.365851) (xy 439.392515 -283.410815) (xy 439.356537 -283.450969)
			(xy 439.315095 -283.485457) (xy 439.269074 -283.513543) (xy 439.219454 -283.53463) (xy 439.167293 -283.548266)
			(xy 439.113702 -283.554163) (xy 439.059823 -283.552194) (xy 439.006805 -283.542401) (xy 438.955778 -283.524993)
			(xy 438.90783 -283.500341) (xy 438.863982 -283.468971) (xy 438.825169 -283.43155) (xy 438.792217 -283.388877)
			(xy 438.765831 -283.34186) (xy 438.746571 -283.291503) (xy 438.734848 -283.238879) (xy 438.730913 -283.185108)
			(xy 431.924968 -283.185108) (xy 431.924476 -283.212065) (xy 431.916626 -283.265405) (xy 431.901094 -283.317034)
			(xy 431.878209 -283.365851) (xy 431.848461 -283.410815) (xy 431.812483 -283.450969) (xy 431.771041 -283.485457)
			(xy 431.72502 -283.513543) (xy 431.6754 -283.53463) (xy 431.623239 -283.548266) (xy 431.569648 -283.554163)
			(xy 431.515769 -283.552194) (xy 431.462751 -283.542401) (xy 431.411724 -283.524993) (xy 431.363776 -283.500341)
			(xy 431.319928 -283.468971) (xy 431.281115 -283.43155) (xy 431.248163 -283.388877) (xy 431.221777 -283.34186)
			(xy 431.202517 -283.291503) (xy 431.190794 -283.238879) (xy 431.186859 -283.185108) (xy 425.985178 -283.185108)
			(xy 425.985178 -284.034992) (xy 427.086791 -284.034992) (xy 427.090726 -283.981221) (xy 427.102449 -283.928597)
			(xy 427.121709 -283.87824) (xy 427.148095 -283.831223) (xy 427.181047 -283.78855) (xy 427.21986 -283.751129)
			(xy 427.263708 -283.719759) (xy 427.311656 -283.695107) (xy 427.362683 -283.677699) (xy 427.415701 -283.667906)
			(xy 427.46958 -283.665937) (xy 427.523171 -283.671834) (xy 427.575332 -283.68547) (xy 427.624952 -283.706557)
			(xy 427.670973 -283.734643) (xy 427.712415 -283.769131) (xy 427.748393 -283.809285) (xy 427.778141 -283.854249)
			(xy 427.801026 -283.903066) (xy 427.816558 -283.954695) (xy 427.824408 -284.008035) (xy 427.8249 -284.034992)
			(xy 434.630845 -284.034992) (xy 434.63478 -283.981221) (xy 434.646503 -283.928597) (xy 434.665763 -283.87824)
			(xy 434.692149 -283.831223) (xy 434.725101 -283.78855) (xy 434.763914 -283.751129) (xy 434.807762 -283.719759)
			(xy 434.85571 -283.695107) (xy 434.906737 -283.677699) (xy 434.959755 -283.667906) (xy 435.013634 -283.665937)
			(xy 435.067225 -283.671834) (xy 435.119386 -283.68547) (xy 435.169006 -283.706557) (xy 435.215027 -283.734643)
			(xy 435.256469 -283.769131) (xy 435.292447 -283.809285) (xy 435.322195 -283.854249) (xy 435.34508 -283.903066)
			(xy 435.360612 -283.954695) (xy 435.368462 -284.008035) (xy 435.368954 -284.034992) (xy 442.174899 -284.034992)
			(xy 442.178834 -283.981221) (xy 442.190557 -283.928597) (xy 442.209817 -283.87824) (xy 442.236203 -283.831223)
			(xy 442.269155 -283.78855) (xy 442.307968 -283.751129) (xy 442.351816 -283.719759) (xy 442.399764 -283.695107)
			(xy 442.450791 -283.677699) (xy 442.503809 -283.667906) (xy 442.557688 -283.665937) (xy 442.611279 -283.671834)
			(xy 442.66344 -283.68547) (xy 442.71306 -283.706557) (xy 442.759081 -283.734643) (xy 442.800523 -283.769131)
			(xy 442.836501 -283.809285) (xy 442.866249 -283.854249) (xy 442.889134 -283.903066) (xy 442.904666 -283.954695)
			(xy 442.912516 -284.008035) (xy 442.913008 -284.034992) (xy 449.718699 -284.034992) (xy 449.722634 -283.981221)
			(xy 449.734357 -283.928597) (xy 449.753617 -283.87824) (xy 449.780003 -283.831223) (xy 449.812955 -283.78855)
			(xy 449.851768 -283.751129) (xy 449.895616 -283.719759) (xy 449.943564 -283.695107) (xy 449.994591 -283.677699)
			(xy 450.047609 -283.667906) (xy 450.101488 -283.665937) (xy 450.155079 -283.671834) (xy 450.20724 -283.68547)
			(xy 450.25686 -283.706557) (xy 450.302881 -283.734643) (xy 450.344323 -283.769131) (xy 450.380301 -283.809285)
			(xy 450.410049 -283.854249) (xy 450.432934 -283.903066) (xy 450.448466 -283.954695) (xy 450.456316 -284.008035)
			(xy 450.456808 -284.034992) (xy 450.456316 -284.061949) (xy 450.448466 -284.115289) (xy 450.432934 -284.166918)
			(xy 450.410049 -284.215735) (xy 450.380301 -284.260699) (xy 450.344323 -284.300853) (xy 450.302881 -284.335341)
			(xy 450.25686 -284.363427) (xy 450.20724 -284.384514) (xy 450.155079 -284.39815) (xy 450.101488 -284.404047)
			(xy 450.047609 -284.402078) (xy 449.994591 -284.392285) (xy 449.943564 -284.374877) (xy 449.895616 -284.350225)
			(xy 449.851768 -284.318855) (xy 449.812955 -284.281434) (xy 449.780003 -284.238761) (xy 449.753617 -284.191744)
			(xy 449.734357 -284.141387) (xy 449.722634 -284.088763) (xy 449.718699 -284.034992) (xy 442.913008 -284.034992)
			(xy 442.912516 -284.061949) (xy 442.904666 -284.115289) (xy 442.889134 -284.166918) (xy 442.866249 -284.215735)
			(xy 442.836501 -284.260699) (xy 442.800523 -284.300853) (xy 442.759081 -284.335341) (xy 442.71306 -284.363427)
			(xy 442.66344 -284.384514) (xy 442.611279 -284.39815) (xy 442.557688 -284.404047) (xy 442.503809 -284.402078)
			(xy 442.450791 -284.392285) (xy 442.399764 -284.374877) (xy 442.351816 -284.350225) (xy 442.307968 -284.318855)
			(xy 442.269155 -284.281434) (xy 442.236203 -284.238761) (xy 442.209817 -284.191744) (xy 442.190557 -284.141387)
			(xy 442.178834 -284.088763) (xy 442.174899 -284.034992) (xy 435.368954 -284.034992) (xy 435.368462 -284.061949)
			(xy 435.360612 -284.115289) (xy 435.34508 -284.166918) (xy 435.322195 -284.215735) (xy 435.292447 -284.260699)
			(xy 435.256469 -284.300853) (xy 435.215027 -284.335341) (xy 435.169006 -284.363427) (xy 435.119386 -284.384514)
			(xy 435.067225 -284.39815) (xy 435.013634 -284.404047) (xy 434.959755 -284.402078) (xy 434.906737 -284.392285)
			(xy 434.85571 -284.374877) (xy 434.807762 -284.350225) (xy 434.763914 -284.318855) (xy 434.725101 -284.281434)
			(xy 434.692149 -284.238761) (xy 434.665763 -284.191744) (xy 434.646503 -284.141387) (xy 434.63478 -284.088763)
			(xy 434.630845 -284.034992) (xy 427.8249 -284.034992) (xy 427.824408 -284.061949) (xy 427.816558 -284.115289)
			(xy 427.801026 -284.166918) (xy 427.778141 -284.215735) (xy 427.748393 -284.260699) (xy 427.712415 -284.300853)
			(xy 427.670973 -284.335341) (xy 427.624952 -284.363427) (xy 427.575332 -284.384514) (xy 427.523171 -284.39815)
			(xy 427.46958 -284.404047) (xy 427.415701 -284.402078) (xy 427.362683 -284.392285) (xy 427.311656 -284.374877)
			(xy 427.263708 -284.350225) (xy 427.21986 -284.318855) (xy 427.181047 -284.281434) (xy 427.148095 -284.238761)
			(xy 427.121709 -284.191744) (xy 427.102449 -284.141387) (xy 427.090726 -284.088763) (xy 427.086791 -284.034992)
			(xy 425.985178 -284.034992) (xy 425.985178 -284.88513) (xy 431.186859 -284.88513) (xy 431.190794 -284.831359)
			(xy 431.202517 -284.778735) (xy 431.221777 -284.728378) (xy 431.248163 -284.681361) (xy 431.281115 -284.638688)
			(xy 431.319928 -284.601267) (xy 431.363776 -284.569897) (xy 431.411724 -284.545245) (xy 431.462751 -284.527837)
			(xy 431.515769 -284.518044) (xy 431.569648 -284.516075) (xy 431.623239 -284.521972) (xy 431.6754 -284.535608)
			(xy 431.72502 -284.556695) (xy 431.771041 -284.584781) (xy 431.812483 -284.619269) (xy 431.848461 -284.659423)
			(xy 431.878209 -284.704387) (xy 431.901094 -284.753204) (xy 431.916626 -284.804833) (xy 431.924476 -284.858173)
			(xy 431.924968 -284.88513) (xy 438.730913 -284.88513) (xy 438.734848 -284.831359) (xy 438.746571 -284.778735)
			(xy 438.765831 -284.728378) (xy 438.792217 -284.681361) (xy 438.825169 -284.638688) (xy 438.863982 -284.601267)
			(xy 438.90783 -284.569897) (xy 438.955778 -284.545245) (xy 439.006805 -284.527837) (xy 439.059823 -284.518044)
			(xy 439.113702 -284.516075) (xy 439.167293 -284.521972) (xy 439.219454 -284.535608) (xy 439.269074 -284.556695)
			(xy 439.315095 -284.584781) (xy 439.356537 -284.619269) (xy 439.392515 -284.659423) (xy 439.422263 -284.704387)
			(xy 439.445148 -284.753204) (xy 439.46068 -284.804833) (xy 439.46853 -284.858173) (xy 439.469022 -284.88513)
			(xy 446.274967 -284.88513) (xy 446.278902 -284.831359) (xy 446.290625 -284.778735) (xy 446.309885 -284.728378)
			(xy 446.336271 -284.681361) (xy 446.369223 -284.638688) (xy 446.408036 -284.601267) (xy 446.451884 -284.569897)
			(xy 446.499832 -284.545245) (xy 446.550859 -284.527837) (xy 446.603877 -284.518044) (xy 446.657756 -284.516075)
			(xy 446.711347 -284.521972) (xy 446.763508 -284.535608) (xy 446.813128 -284.556695) (xy 446.859149 -284.584781)
			(xy 446.900591 -284.619269) (xy 446.936569 -284.659423) (xy 446.966317 -284.704387) (xy 446.989202 -284.753204)
			(xy 447.004734 -284.804833) (xy 447.012584 -284.858173) (xy 447.013076 -284.88513) (xy 453.818767 -284.88513)
			(xy 453.822702 -284.831359) (xy 453.834425 -284.778735) (xy 453.853685 -284.728378) (xy 453.880071 -284.681361)
			(xy 453.913023 -284.638688) (xy 453.951836 -284.601267) (xy 453.995684 -284.569897) (xy 454.043632 -284.545245)
			(xy 454.094659 -284.527837) (xy 454.147677 -284.518044) (xy 454.201556 -284.516075) (xy 454.255147 -284.521972)
			(xy 454.307308 -284.535608) (xy 454.356928 -284.556695) (xy 454.402949 -284.584781) (xy 454.444391 -284.619269)
			(xy 454.480369 -284.659423) (xy 454.510117 -284.704387) (xy 454.533002 -284.753204) (xy 454.548534 -284.804833)
			(xy 454.556384 -284.858173) (xy 454.556876 -284.88513) (xy 454.556384 -284.912087) (xy 454.548534 -284.965427)
			(xy 454.533002 -285.017056) (xy 454.510117 -285.065873) (xy 454.480369 -285.110837) (xy 454.444391 -285.150991)
			(xy 454.402949 -285.185479) (xy 454.356928 -285.213565) (xy 454.307308 -285.234652) (xy 454.255147 -285.248288)
			(xy 454.201556 -285.254185) (xy 454.147677 -285.252216) (xy 454.094659 -285.242423) (xy 454.043632 -285.225015)
			(xy 453.995684 -285.200363) (xy 453.951836 -285.168993) (xy 453.913023 -285.131572) (xy 453.880071 -285.088899)
			(xy 453.853685 -285.041882) (xy 453.834425 -284.991525) (xy 453.822702 -284.938901) (xy 453.818767 -284.88513)
			(xy 447.013076 -284.88513) (xy 447.012584 -284.912087) (xy 447.004734 -284.965427) (xy 446.989202 -285.017056)
			(xy 446.966317 -285.065873) (xy 446.936569 -285.110837) (xy 446.900591 -285.150991) (xy 446.859149 -285.185479)
			(xy 446.813128 -285.213565) (xy 446.763508 -285.234652) (xy 446.711347 -285.248288) (xy 446.657756 -285.254185)
			(xy 446.603877 -285.252216) (xy 446.550859 -285.242423) (xy 446.499832 -285.225015) (xy 446.451884 -285.200363)
			(xy 446.408036 -285.168993) (xy 446.369223 -285.131572) (xy 446.336271 -285.088899) (xy 446.309885 -285.041882)
			(xy 446.290625 -284.991525) (xy 446.278902 -284.938901) (xy 446.274967 -284.88513) (xy 439.469022 -284.88513)
			(xy 439.46853 -284.912087) (xy 439.46068 -284.965427) (xy 439.445148 -285.017056) (xy 439.422263 -285.065873)
			(xy 439.392515 -285.110837) (xy 439.356537 -285.150991) (xy 439.315095 -285.185479) (xy 439.269074 -285.213565)
			(xy 439.219454 -285.234652) (xy 439.167293 -285.248288) (xy 439.113702 -285.254185) (xy 439.059823 -285.252216)
			(xy 439.006805 -285.242423) (xy 438.955778 -285.225015) (xy 438.90783 -285.200363) (xy 438.863982 -285.168993)
			(xy 438.825169 -285.131572) (xy 438.792217 -285.088899) (xy 438.765831 -285.041882) (xy 438.746571 -284.991525)
			(xy 438.734848 -284.938901) (xy 438.730913 -284.88513) (xy 431.924968 -284.88513) (xy 431.924476 -284.912087)
			(xy 431.916626 -284.965427) (xy 431.901094 -285.017056) (xy 431.878209 -285.065873) (xy 431.848461 -285.110837)
			(xy 431.812483 -285.150991) (xy 431.771041 -285.185479) (xy 431.72502 -285.213565) (xy 431.6754 -285.234652)
			(xy 431.623239 -285.248288) (xy 431.569648 -285.254185) (xy 431.515769 -285.252216) (xy 431.462751 -285.242423)
			(xy 431.411724 -285.225015) (xy 431.363776 -285.200363) (xy 431.319928 -285.168993) (xy 431.281115 -285.131572)
			(xy 431.248163 -285.088899) (xy 431.221777 -285.041882) (xy 431.202517 -284.991525) (xy 431.190794 -284.938901)
			(xy 431.186859 -284.88513) (xy 425.985178 -284.88513) (xy 425.985178 -285.735014) (xy 427.086791 -285.735014)
			(xy 427.090726 -285.681243) (xy 427.102449 -285.628619) (xy 427.121709 -285.578262) (xy 427.148095 -285.531245)
			(xy 427.181047 -285.488572) (xy 427.21986 -285.451151) (xy 427.263708 -285.419781) (xy 427.311656 -285.395129)
			(xy 427.362683 -285.377721) (xy 427.415701 -285.367928) (xy 427.46958 -285.365959) (xy 427.523171 -285.371856)
			(xy 427.575332 -285.385492) (xy 427.624952 -285.406579) (xy 427.670973 -285.434665) (xy 427.712415 -285.469153)
			(xy 427.748393 -285.509307) (xy 427.778141 -285.554271) (xy 427.801026 -285.603088) (xy 427.816558 -285.654717)
			(xy 427.824408 -285.708057) (xy 427.8249 -285.735014) (xy 431.186859 -285.735014) (xy 431.190794 -285.681243)
			(xy 431.202517 -285.628619) (xy 431.221777 -285.578262) (xy 431.248163 -285.531245) (xy 431.281115 -285.488572)
			(xy 431.319928 -285.451151) (xy 431.363776 -285.419781) (xy 431.411724 -285.395129) (xy 431.462751 -285.377721)
			(xy 431.515769 -285.367928) (xy 431.569648 -285.365959) (xy 431.623239 -285.371856) (xy 431.6754 -285.385492)
			(xy 431.72502 -285.406579) (xy 431.771041 -285.434665) (xy 431.812483 -285.469153) (xy 431.848461 -285.509307)
			(xy 431.878209 -285.554271) (xy 431.901094 -285.603088) (xy 431.916626 -285.654717) (xy 431.924476 -285.708057)
			(xy 431.924968 -285.735014) (xy 434.630845 -285.735014) (xy 434.63478 -285.681243) (xy 434.646503 -285.628619)
			(xy 434.665763 -285.578262) (xy 434.692149 -285.531245) (xy 434.725101 -285.488572) (xy 434.763914 -285.451151)
			(xy 434.807762 -285.419781) (xy 434.85571 -285.395129) (xy 434.906737 -285.377721) (xy 434.959755 -285.367928)
			(xy 435.013634 -285.365959) (xy 435.067225 -285.371856) (xy 435.119386 -285.385492) (xy 435.169006 -285.406579)
			(xy 435.215027 -285.434665) (xy 435.256469 -285.469153) (xy 435.292447 -285.509307) (xy 435.322195 -285.554271)
			(xy 435.34508 -285.603088) (xy 435.360612 -285.654717) (xy 435.368462 -285.708057) (xy 435.368954 -285.735014)
			(xy 438.730913 -285.735014) (xy 438.734848 -285.681243) (xy 438.746571 -285.628619) (xy 438.765831 -285.578262)
			(xy 438.792217 -285.531245) (xy 438.825169 -285.488572) (xy 438.863982 -285.451151) (xy 438.90783 -285.419781)
			(xy 438.955778 -285.395129) (xy 439.006805 -285.377721) (xy 439.059823 -285.367928) (xy 439.113702 -285.365959)
			(xy 439.167293 -285.371856) (xy 439.219454 -285.385492) (xy 439.269074 -285.406579) (xy 439.315095 -285.434665)
			(xy 439.356537 -285.469153) (xy 439.392515 -285.509307) (xy 439.422263 -285.554271) (xy 439.445148 -285.603088)
			(xy 439.46068 -285.654717) (xy 439.46853 -285.708057) (xy 439.469022 -285.735014) (xy 442.174899 -285.735014)
			(xy 442.178834 -285.681243) (xy 442.190557 -285.628619) (xy 442.209817 -285.578262) (xy 442.236203 -285.531245)
			(xy 442.269155 -285.488572) (xy 442.307968 -285.451151) (xy 442.351816 -285.419781) (xy 442.399764 -285.395129)
			(xy 442.450791 -285.377721) (xy 442.503809 -285.367928) (xy 442.557688 -285.365959) (xy 442.611279 -285.371856)
			(xy 442.66344 -285.385492) (xy 442.71306 -285.406579) (xy 442.759081 -285.434665) (xy 442.800523 -285.469153)
			(xy 442.836501 -285.509307) (xy 442.866249 -285.554271) (xy 442.889134 -285.603088) (xy 442.904666 -285.654717)
			(xy 442.912516 -285.708057) (xy 442.913008 -285.735014) (xy 446.274967 -285.735014) (xy 446.278902 -285.681243)
			(xy 446.290625 -285.628619) (xy 446.309885 -285.578262) (xy 446.336271 -285.531245) (xy 446.369223 -285.488572)
			(xy 446.408036 -285.451151) (xy 446.451884 -285.419781) (xy 446.499832 -285.395129) (xy 446.550859 -285.377721)
			(xy 446.603877 -285.367928) (xy 446.657756 -285.365959) (xy 446.711347 -285.371856) (xy 446.763508 -285.385492)
			(xy 446.813128 -285.406579) (xy 446.859149 -285.434665) (xy 446.900591 -285.469153) (xy 446.936569 -285.509307)
			(xy 446.966317 -285.554271) (xy 446.989202 -285.603088) (xy 447.004734 -285.654717) (xy 447.012584 -285.708057)
			(xy 447.013076 -285.735014) (xy 449.718699 -285.735014) (xy 449.722634 -285.681243) (xy 449.734357 -285.628619)
			(xy 449.753617 -285.578262) (xy 449.780003 -285.531245) (xy 449.812955 -285.488572) (xy 449.851768 -285.451151)
			(xy 449.895616 -285.419781) (xy 449.943564 -285.395129) (xy 449.994591 -285.377721) (xy 450.047609 -285.367928)
			(xy 450.101488 -285.365959) (xy 450.155079 -285.371856) (xy 450.20724 -285.385492) (xy 450.25686 -285.406579)
			(xy 450.302881 -285.434665) (xy 450.344323 -285.469153) (xy 450.380301 -285.509307) (xy 450.410049 -285.554271)
			(xy 450.432934 -285.603088) (xy 450.448466 -285.654717) (xy 450.456316 -285.708057) (xy 450.456808 -285.735014)
			(xy 453.818767 -285.735014) (xy 453.822702 -285.681243) (xy 453.834425 -285.628619) (xy 453.853685 -285.578262)
			(xy 453.880071 -285.531245) (xy 453.913023 -285.488572) (xy 453.951836 -285.451151) (xy 453.995684 -285.419781)
			(xy 454.043632 -285.395129) (xy 454.094659 -285.377721) (xy 454.147677 -285.367928) (xy 454.201556 -285.365959)
			(xy 454.255147 -285.371856) (xy 454.307308 -285.385492) (xy 454.356928 -285.406579) (xy 454.402949 -285.434665)
			(xy 454.444391 -285.469153) (xy 454.480369 -285.509307) (xy 454.510117 -285.554271) (xy 454.533002 -285.603088)
			(xy 454.548534 -285.654717) (xy 454.556384 -285.708057) (xy 454.556876 -285.735014) (xy 454.556384 -285.761971)
			(xy 454.548534 -285.815311) (xy 454.533002 -285.86694) (xy 454.510117 -285.915757) (xy 454.480369 -285.960721)
			(xy 454.444391 -286.000875) (xy 454.402949 -286.035363) (xy 454.356928 -286.063449) (xy 454.307308 -286.084536)
			(xy 454.255147 -286.098172) (xy 454.201556 -286.104069) (xy 454.147677 -286.1021) (xy 454.094659 -286.092307)
			(xy 454.043632 -286.074899) (xy 453.995684 -286.050247) (xy 453.951836 -286.018877) (xy 453.913023 -285.981456)
			(xy 453.880071 -285.938783) (xy 453.853685 -285.891766) (xy 453.834425 -285.841409) (xy 453.822702 -285.788785)
			(xy 453.818767 -285.735014) (xy 450.456808 -285.735014) (xy 450.456316 -285.761971) (xy 450.448466 -285.815311)
			(xy 450.432934 -285.86694) (xy 450.410049 -285.915757) (xy 450.380301 -285.960721) (xy 450.344323 -286.000875)
			(xy 450.302881 -286.035363) (xy 450.25686 -286.063449) (xy 450.20724 -286.084536) (xy 450.155079 -286.098172)
			(xy 450.101488 -286.104069) (xy 450.047609 -286.1021) (xy 449.994591 -286.092307) (xy 449.943564 -286.074899)
			(xy 449.895616 -286.050247) (xy 449.851768 -286.018877) (xy 449.812955 -285.981456) (xy 449.780003 -285.938783)
			(xy 449.753617 -285.891766) (xy 449.734357 -285.841409) (xy 449.722634 -285.788785) (xy 449.718699 -285.735014)
			(xy 447.013076 -285.735014) (xy 447.012584 -285.761971) (xy 447.004734 -285.815311) (xy 446.989202 -285.86694)
			(xy 446.966317 -285.915757) (xy 446.936569 -285.960721) (xy 446.900591 -286.000875) (xy 446.859149 -286.035363)
			(xy 446.813128 -286.063449) (xy 446.763508 -286.084536) (xy 446.711347 -286.098172) (xy 446.657756 -286.104069)
			(xy 446.603877 -286.1021) (xy 446.550859 -286.092307) (xy 446.499832 -286.074899) (xy 446.451884 -286.050247)
			(xy 446.408036 -286.018877) (xy 446.369223 -285.981456) (xy 446.336271 -285.938783) (xy 446.309885 -285.891766)
			(xy 446.290625 -285.841409) (xy 446.278902 -285.788785) (xy 446.274967 -285.735014) (xy 442.913008 -285.735014)
			(xy 442.912516 -285.761971) (xy 442.904666 -285.815311) (xy 442.889134 -285.86694) (xy 442.866249 -285.915757)
			(xy 442.836501 -285.960721) (xy 442.800523 -286.000875) (xy 442.759081 -286.035363) (xy 442.71306 -286.063449)
			(xy 442.66344 -286.084536) (xy 442.611279 -286.098172) (xy 442.557688 -286.104069) (xy 442.503809 -286.1021)
			(xy 442.450791 -286.092307) (xy 442.399764 -286.074899) (xy 442.351816 -286.050247) (xy 442.307968 -286.018877)
			(xy 442.269155 -285.981456) (xy 442.236203 -285.938783) (xy 442.209817 -285.891766) (xy 442.190557 -285.841409)
			(xy 442.178834 -285.788785) (xy 442.174899 -285.735014) (xy 439.469022 -285.735014) (xy 439.46853 -285.761971)
			(xy 439.46068 -285.815311) (xy 439.445148 -285.86694) (xy 439.422263 -285.915757) (xy 439.392515 -285.960721)
			(xy 439.356537 -286.000875) (xy 439.315095 -286.035363) (xy 439.269074 -286.063449) (xy 439.219454 -286.084536)
			(xy 439.167293 -286.098172) (xy 439.113702 -286.104069) (xy 439.059823 -286.1021) (xy 439.006805 -286.092307)
			(xy 438.955778 -286.074899) (xy 438.90783 -286.050247) (xy 438.863982 -286.018877) (xy 438.825169 -285.981456)
			(xy 438.792217 -285.938783) (xy 438.765831 -285.891766) (xy 438.746571 -285.841409) (xy 438.734848 -285.788785)
			(xy 438.730913 -285.735014) (xy 435.368954 -285.735014) (xy 435.368462 -285.761971) (xy 435.360612 -285.815311)
			(xy 435.34508 -285.86694) (xy 435.322195 -285.915757) (xy 435.292447 -285.960721) (xy 435.256469 -286.000875)
			(xy 435.215027 -286.035363) (xy 435.169006 -286.063449) (xy 435.119386 -286.084536) (xy 435.067225 -286.098172)
			(xy 435.013634 -286.104069) (xy 434.959755 -286.1021) (xy 434.906737 -286.092307) (xy 434.85571 -286.074899)
			(xy 434.807762 -286.050247) (xy 434.763914 -286.018877) (xy 434.725101 -285.981456) (xy 434.692149 -285.938783)
			(xy 434.665763 -285.891766) (xy 434.646503 -285.841409) (xy 434.63478 -285.788785) (xy 434.630845 -285.735014)
			(xy 431.924968 -285.735014) (xy 431.924476 -285.761971) (xy 431.916626 -285.815311) (xy 431.901094 -285.86694)
			(xy 431.878209 -285.915757) (xy 431.848461 -285.960721) (xy 431.812483 -286.000875) (xy 431.771041 -286.035363)
			(xy 431.72502 -286.063449) (xy 431.6754 -286.084536) (xy 431.623239 -286.098172) (xy 431.569648 -286.104069)
			(xy 431.515769 -286.1021) (xy 431.462751 -286.092307) (xy 431.411724 -286.074899) (xy 431.363776 -286.050247)
			(xy 431.319928 -286.018877) (xy 431.281115 -285.981456) (xy 431.248163 -285.938783) (xy 431.221777 -285.891766)
			(xy 431.202517 -285.841409) (xy 431.190794 -285.788785) (xy 431.186859 -285.735014) (xy 427.8249 -285.735014)
			(xy 427.824408 -285.761971) (xy 427.816558 -285.815311) (xy 427.801026 -285.86694) (xy 427.778141 -285.915757)
			(xy 427.748393 -285.960721) (xy 427.712415 -286.000875) (xy 427.670973 -286.035363) (xy 427.624952 -286.063449)
			(xy 427.575332 -286.084536) (xy 427.523171 -286.098172) (xy 427.46958 -286.104069) (xy 427.415701 -286.1021)
			(xy 427.362683 -286.092307) (xy 427.311656 -286.074899) (xy 427.263708 -286.050247) (xy 427.21986 -286.018877)
			(xy 427.181047 -285.981456) (xy 427.148095 -285.938783) (xy 427.121709 -285.891766) (xy 427.102449 -285.841409)
			(xy 427.090726 -285.788785) (xy 427.086791 -285.735014) (xy 425.985178 -285.735014) (xy 425.985178 -286.585152)
			(xy 427.086791 -286.585152) (xy 427.090726 -286.531381) (xy 427.102449 -286.478757) (xy 427.121709 -286.4284)
			(xy 427.148095 -286.381383) (xy 427.181047 -286.33871) (xy 427.21986 -286.301289) (xy 427.263708 -286.269919)
			(xy 427.311656 -286.245267) (xy 427.362683 -286.227859) (xy 427.415701 -286.218066) (xy 427.46958 -286.216097)
			(xy 427.523171 -286.221994) (xy 427.575332 -286.23563) (xy 427.624952 -286.256717) (xy 427.670973 -286.284803)
			(xy 427.712415 -286.319291) (xy 427.748393 -286.359445) (xy 427.778141 -286.404409) (xy 427.801026 -286.453226)
			(xy 427.816558 -286.504855) (xy 427.824408 -286.558195) (xy 427.8249 -286.585152) (xy 434.630845 -286.585152)
			(xy 434.63478 -286.531381) (xy 434.646503 -286.478757) (xy 434.665763 -286.4284) (xy 434.692149 -286.381383)
			(xy 434.725101 -286.33871) (xy 434.763914 -286.301289) (xy 434.807762 -286.269919) (xy 434.85571 -286.245267)
			(xy 434.906737 -286.227859) (xy 434.959755 -286.218066) (xy 435.013634 -286.216097) (xy 435.067225 -286.221994)
			(xy 435.119386 -286.23563) (xy 435.169006 -286.256717) (xy 435.215027 -286.284803) (xy 435.256469 -286.319291)
			(xy 435.292447 -286.359445) (xy 435.322195 -286.404409) (xy 435.34508 -286.453226) (xy 435.360612 -286.504855)
			(xy 435.368462 -286.558195) (xy 435.368954 -286.585152) (xy 442.174899 -286.585152) (xy 442.178834 -286.531381)
			(xy 442.190557 -286.478757) (xy 442.209817 -286.4284) (xy 442.236203 -286.381383) (xy 442.269155 -286.33871)
			(xy 442.307968 -286.301289) (xy 442.351816 -286.269919) (xy 442.399764 -286.245267) (xy 442.450791 -286.227859)
			(xy 442.503809 -286.218066) (xy 442.557688 -286.216097) (xy 442.611279 -286.221994) (xy 442.66344 -286.23563)
			(xy 442.71306 -286.256717) (xy 442.759081 -286.284803) (xy 442.800523 -286.319291) (xy 442.836501 -286.359445)
			(xy 442.866249 -286.404409) (xy 442.889134 -286.453226) (xy 442.904666 -286.504855) (xy 442.912516 -286.558195)
			(xy 442.913008 -286.585152) (xy 449.718699 -286.585152) (xy 449.722634 -286.531381) (xy 449.734357 -286.478757)
			(xy 449.753617 -286.4284) (xy 449.780003 -286.381383) (xy 449.812955 -286.33871) (xy 449.851768 -286.301289)
			(xy 449.895616 -286.269919) (xy 449.943564 -286.245267) (xy 449.994591 -286.227859) (xy 450.047609 -286.218066)
			(xy 450.101488 -286.216097) (xy 450.155079 -286.221994) (xy 450.20724 -286.23563) (xy 450.25686 -286.256717)
			(xy 450.302881 -286.284803) (xy 450.344323 -286.319291) (xy 450.380301 -286.359445) (xy 450.410049 -286.404409)
			(xy 450.432934 -286.453226) (xy 450.448466 -286.504855) (xy 450.456316 -286.558195) (xy 450.456808 -286.585152)
			(xy 450.456316 -286.612109) (xy 450.448466 -286.665449) (xy 450.432934 -286.717078) (xy 450.410049 -286.765895)
			(xy 450.380301 -286.810859) (xy 450.344323 -286.851013) (xy 450.302881 -286.885501) (xy 450.25686 -286.913587)
			(xy 450.20724 -286.934674) (xy 450.155079 -286.94831) (xy 450.101488 -286.954207) (xy 450.047609 -286.952238)
			(xy 449.994591 -286.942445) (xy 449.943564 -286.925037) (xy 449.895616 -286.900385) (xy 449.851768 -286.869015)
			(xy 449.812955 -286.831594) (xy 449.780003 -286.788921) (xy 449.753617 -286.741904) (xy 449.734357 -286.691547)
			(xy 449.722634 -286.638923) (xy 449.718699 -286.585152) (xy 442.913008 -286.585152) (xy 442.912516 -286.612109)
			(xy 442.904666 -286.665449) (xy 442.889134 -286.717078) (xy 442.866249 -286.765895) (xy 442.836501 -286.810859)
			(xy 442.800523 -286.851013) (xy 442.759081 -286.885501) (xy 442.71306 -286.913587) (xy 442.66344 -286.934674)
			(xy 442.611279 -286.94831) (xy 442.557688 -286.954207) (xy 442.503809 -286.952238) (xy 442.450791 -286.942445)
			(xy 442.399764 -286.925037) (xy 442.351816 -286.900385) (xy 442.307968 -286.869015) (xy 442.269155 -286.831594)
			(xy 442.236203 -286.788921) (xy 442.209817 -286.741904) (xy 442.190557 -286.691547) (xy 442.178834 -286.638923)
			(xy 442.174899 -286.585152) (xy 435.368954 -286.585152) (xy 435.368462 -286.612109) (xy 435.360612 -286.665449)
			(xy 435.34508 -286.717078) (xy 435.322195 -286.765895) (xy 435.292447 -286.810859) (xy 435.256469 -286.851013)
			(xy 435.215027 -286.885501) (xy 435.169006 -286.913587) (xy 435.119386 -286.934674) (xy 435.067225 -286.94831)
			(xy 435.013634 -286.954207) (xy 434.959755 -286.952238) (xy 434.906737 -286.942445) (xy 434.85571 -286.925037)
			(xy 434.807762 -286.900385) (xy 434.763914 -286.869015) (xy 434.725101 -286.831594) (xy 434.692149 -286.788921)
			(xy 434.665763 -286.741904) (xy 434.646503 -286.691547) (xy 434.63478 -286.638923) (xy 434.630845 -286.585152)
			(xy 427.8249 -286.585152) (xy 427.824408 -286.612109) (xy 427.816558 -286.665449) (xy 427.801026 -286.717078)
			(xy 427.778141 -286.765895) (xy 427.748393 -286.810859) (xy 427.712415 -286.851013) (xy 427.670973 -286.885501)
			(xy 427.624952 -286.913587) (xy 427.575332 -286.934674) (xy 427.523171 -286.94831) (xy 427.46958 -286.954207)
			(xy 427.415701 -286.952238) (xy 427.362683 -286.942445) (xy 427.311656 -286.925037) (xy 427.263708 -286.900385)
			(xy 427.21986 -286.869015) (xy 427.181047 -286.831594) (xy 427.148095 -286.788921) (xy 427.121709 -286.741904)
			(xy 427.102449 -286.691547) (xy 427.090726 -286.638923) (xy 427.086791 -286.585152) (xy 425.985178 -286.585152)
			(xy 425.985178 -287.435036) (xy 431.186859 -287.435036) (xy 431.190794 -287.381265) (xy 431.202517 -287.328641)
			(xy 431.221777 -287.278284) (xy 431.248163 -287.231267) (xy 431.281115 -287.188594) (xy 431.319928 -287.151173)
			(xy 431.363776 -287.119803) (xy 431.411724 -287.095151) (xy 431.462751 -287.077743) (xy 431.515769 -287.06795)
			(xy 431.569648 -287.065981) (xy 431.623239 -287.071878) (xy 431.6754 -287.085514) (xy 431.72502 -287.106601)
			(xy 431.771041 -287.134687) (xy 431.812483 -287.169175) (xy 431.848461 -287.209329) (xy 431.878209 -287.254293)
			(xy 431.901094 -287.30311) (xy 431.916626 -287.354739) (xy 431.924476 -287.408079) (xy 431.924968 -287.435036)
			(xy 438.730913 -287.435036) (xy 438.734848 -287.381265) (xy 438.746571 -287.328641) (xy 438.765831 -287.278284)
			(xy 438.792217 -287.231267) (xy 438.825169 -287.188594) (xy 438.863982 -287.151173) (xy 438.90783 -287.119803)
			(xy 438.955778 -287.095151) (xy 439.006805 -287.077743) (xy 439.059823 -287.06795) (xy 439.113702 -287.065981)
			(xy 439.167293 -287.071878) (xy 439.219454 -287.085514) (xy 439.269074 -287.106601) (xy 439.315095 -287.134687)
			(xy 439.356537 -287.169175) (xy 439.392515 -287.209329) (xy 439.422263 -287.254293) (xy 439.445148 -287.30311)
			(xy 439.46068 -287.354739) (xy 439.46853 -287.408079) (xy 439.469022 -287.435036) (xy 446.274967 -287.435036)
			(xy 446.278902 -287.381265) (xy 446.290625 -287.328641) (xy 446.309885 -287.278284) (xy 446.336271 -287.231267)
			(xy 446.369223 -287.188594) (xy 446.408036 -287.151173) (xy 446.451884 -287.119803) (xy 446.499832 -287.095151)
			(xy 446.550859 -287.077743) (xy 446.603877 -287.06795) (xy 446.657756 -287.065981) (xy 446.711347 -287.071878)
			(xy 446.763508 -287.085514) (xy 446.813128 -287.106601) (xy 446.859149 -287.134687) (xy 446.900591 -287.169175)
			(xy 446.936569 -287.209329) (xy 446.966317 -287.254293) (xy 446.989202 -287.30311) (xy 447.004734 -287.354739)
			(xy 447.012584 -287.408079) (xy 447.013076 -287.435036) (xy 453.818767 -287.435036) (xy 453.822702 -287.381265)
			(xy 453.834425 -287.328641) (xy 453.853685 -287.278284) (xy 453.880071 -287.231267) (xy 453.913023 -287.188594)
			(xy 453.951836 -287.151173) (xy 453.995684 -287.119803) (xy 454.043632 -287.095151) (xy 454.094659 -287.077743)
			(xy 454.147677 -287.06795) (xy 454.201556 -287.065981) (xy 454.255147 -287.071878) (xy 454.307308 -287.085514)
			(xy 454.356928 -287.106601) (xy 454.402949 -287.134687) (xy 454.444391 -287.169175) (xy 454.480369 -287.209329)
			(xy 454.510117 -287.254293) (xy 454.533002 -287.30311) (xy 454.548534 -287.354739) (xy 454.556384 -287.408079)
			(xy 454.556876 -287.435036) (xy 454.556384 -287.461993) (xy 454.548534 -287.515333) (xy 454.533002 -287.566962)
			(xy 454.510117 -287.615779) (xy 454.480369 -287.660743) (xy 454.444391 -287.700897) (xy 454.402949 -287.735385)
			(xy 454.356928 -287.763471) (xy 454.307308 -287.784558) (xy 454.255147 -287.798194) (xy 454.201556 -287.804091)
			(xy 454.147677 -287.802122) (xy 454.094659 -287.792329) (xy 454.043632 -287.774921) (xy 453.995684 -287.750269)
			(xy 453.951836 -287.718899) (xy 453.913023 -287.681478) (xy 453.880071 -287.638805) (xy 453.853685 -287.591788)
			(xy 453.834425 -287.541431) (xy 453.822702 -287.488807) (xy 453.818767 -287.435036) (xy 447.013076 -287.435036)
			(xy 447.012584 -287.461993) (xy 447.004734 -287.515333) (xy 446.989202 -287.566962) (xy 446.966317 -287.615779)
			(xy 446.936569 -287.660743) (xy 446.900591 -287.700897) (xy 446.859149 -287.735385) (xy 446.813128 -287.763471)
			(xy 446.763508 -287.784558) (xy 446.711347 -287.798194) (xy 446.657756 -287.804091) (xy 446.603877 -287.802122)
			(xy 446.550859 -287.792329) (xy 446.499832 -287.774921) (xy 446.451884 -287.750269) (xy 446.408036 -287.718899)
			(xy 446.369223 -287.681478) (xy 446.336271 -287.638805) (xy 446.309885 -287.591788) (xy 446.290625 -287.541431)
			(xy 446.278902 -287.488807) (xy 446.274967 -287.435036) (xy 439.469022 -287.435036) (xy 439.46853 -287.461993)
			(xy 439.46068 -287.515333) (xy 439.445148 -287.566962) (xy 439.422263 -287.615779) (xy 439.392515 -287.660743)
			(xy 439.356537 -287.700897) (xy 439.315095 -287.735385) (xy 439.269074 -287.763471) (xy 439.219454 -287.784558)
			(xy 439.167293 -287.798194) (xy 439.113702 -287.804091) (xy 439.059823 -287.802122) (xy 439.006805 -287.792329)
			(xy 438.955778 -287.774921) (xy 438.90783 -287.750269) (xy 438.863982 -287.718899) (xy 438.825169 -287.681478)
			(xy 438.792217 -287.638805) (xy 438.765831 -287.591788) (xy 438.746571 -287.541431) (xy 438.734848 -287.488807)
			(xy 438.730913 -287.435036) (xy 431.924968 -287.435036) (xy 431.924476 -287.461993) (xy 431.916626 -287.515333)
			(xy 431.901094 -287.566962) (xy 431.878209 -287.615779) (xy 431.848461 -287.660743) (xy 431.812483 -287.700897)
			(xy 431.771041 -287.735385) (xy 431.72502 -287.763471) (xy 431.6754 -287.784558) (xy 431.623239 -287.798194)
			(xy 431.569648 -287.804091) (xy 431.515769 -287.802122) (xy 431.462751 -287.792329) (xy 431.411724 -287.774921)
			(xy 431.363776 -287.750269) (xy 431.319928 -287.718899) (xy 431.281115 -287.681478) (xy 431.248163 -287.638805)
			(xy 431.221777 -287.591788) (xy 431.202517 -287.541431) (xy 431.190794 -287.488807) (xy 431.186859 -287.435036)
			(xy 425.985178 -287.435036) (xy 425.985178 -288.285174) (xy 427.086791 -288.285174) (xy 427.090726 -288.231403)
			(xy 427.102449 -288.178779) (xy 427.121709 -288.128422) (xy 427.148095 -288.081405) (xy 427.181047 -288.038732)
			(xy 427.21986 -288.001311) (xy 427.263708 -287.969941) (xy 427.311656 -287.945289) (xy 427.362683 -287.927881)
			(xy 427.415701 -287.918088) (xy 427.46958 -287.916119) (xy 427.523171 -287.922016) (xy 427.575332 -287.935652)
			(xy 427.624952 -287.956739) (xy 427.670973 -287.984825) (xy 427.712415 -288.019313) (xy 427.748393 -288.059467)
			(xy 427.778141 -288.104431) (xy 427.801026 -288.153248) (xy 427.816558 -288.204877) (xy 427.824408 -288.258217)
			(xy 427.8249 -288.285174) (xy 434.630845 -288.285174) (xy 434.63478 -288.231403) (xy 434.646503 -288.178779)
			(xy 434.665763 -288.128422) (xy 434.692149 -288.081405) (xy 434.725101 -288.038732) (xy 434.763914 -288.001311)
			(xy 434.807762 -287.969941) (xy 434.85571 -287.945289) (xy 434.906737 -287.927881) (xy 434.959755 -287.918088)
			(xy 435.013634 -287.916119) (xy 435.067225 -287.922016) (xy 435.119386 -287.935652) (xy 435.169006 -287.956739)
			(xy 435.215027 -287.984825) (xy 435.256469 -288.019313) (xy 435.292447 -288.059467) (xy 435.322195 -288.104431)
			(xy 435.34508 -288.153248) (xy 435.360612 -288.204877) (xy 435.368462 -288.258217) (xy 435.368954 -288.285174)
			(xy 442.174899 -288.285174) (xy 442.178834 -288.231403) (xy 442.190557 -288.178779) (xy 442.209817 -288.128422)
			(xy 442.236203 -288.081405) (xy 442.269155 -288.038732) (xy 442.307968 -288.001311) (xy 442.351816 -287.969941)
			(xy 442.399764 -287.945289) (xy 442.450791 -287.927881) (xy 442.503809 -287.918088) (xy 442.557688 -287.916119)
			(xy 442.611279 -287.922016) (xy 442.66344 -287.935652) (xy 442.71306 -287.956739) (xy 442.759081 -287.984825)
			(xy 442.800523 -288.019313) (xy 442.836501 -288.059467) (xy 442.866249 -288.104431) (xy 442.889134 -288.153248)
			(xy 442.904666 -288.204877) (xy 442.912516 -288.258217) (xy 442.913008 -288.285174) (xy 449.718699 -288.285174)
			(xy 449.722634 -288.231403) (xy 449.734357 -288.178779) (xy 449.753617 -288.128422) (xy 449.780003 -288.081405)
			(xy 449.812955 -288.038732) (xy 449.851768 -288.001311) (xy 449.895616 -287.969941) (xy 449.943564 -287.945289)
			(xy 449.994591 -287.927881) (xy 450.047609 -287.918088) (xy 450.101488 -287.916119) (xy 450.155079 -287.922016)
			(xy 450.20724 -287.935652) (xy 450.25686 -287.956739) (xy 450.302881 -287.984825) (xy 450.344323 -288.019313)
			(xy 450.380301 -288.059467) (xy 450.410049 -288.104431) (xy 450.432934 -288.153248) (xy 450.448466 -288.204877)
			(xy 450.456316 -288.258217) (xy 450.456808 -288.285174) (xy 450.456316 -288.312131) (xy 450.448466 -288.365471)
			(xy 450.432934 -288.4171) (xy 450.410049 -288.465917) (xy 450.380301 -288.510881) (xy 450.344323 -288.551035)
			(xy 450.302881 -288.585523) (xy 450.25686 -288.613609) (xy 450.20724 -288.634696) (xy 450.155079 -288.648332)
			(xy 450.101488 -288.654229) (xy 450.047609 -288.65226) (xy 449.994591 -288.642467) (xy 449.943564 -288.625059)
			(xy 449.895616 -288.600407) (xy 449.851768 -288.569037) (xy 449.812955 -288.531616) (xy 449.780003 -288.488943)
			(xy 449.753617 -288.441926) (xy 449.734357 -288.391569) (xy 449.722634 -288.338945) (xy 449.718699 -288.285174)
			(xy 442.913008 -288.285174) (xy 442.912516 -288.312131) (xy 442.904666 -288.365471) (xy 442.889134 -288.4171)
			(xy 442.866249 -288.465917) (xy 442.836501 -288.510881) (xy 442.800523 -288.551035) (xy 442.759081 -288.585523)
			(xy 442.71306 -288.613609) (xy 442.66344 -288.634696) (xy 442.611279 -288.648332) (xy 442.557688 -288.654229)
			(xy 442.503809 -288.65226) (xy 442.450791 -288.642467) (xy 442.399764 -288.625059) (xy 442.351816 -288.600407)
			(xy 442.307968 -288.569037) (xy 442.269155 -288.531616) (xy 442.236203 -288.488943) (xy 442.209817 -288.441926)
			(xy 442.190557 -288.391569) (xy 442.178834 -288.338945) (xy 442.174899 -288.285174) (xy 435.368954 -288.285174)
			(xy 435.368462 -288.312131) (xy 435.360612 -288.365471) (xy 435.34508 -288.4171) (xy 435.322195 -288.465917)
			(xy 435.292447 -288.510881) (xy 435.256469 -288.551035) (xy 435.215027 -288.585523) (xy 435.169006 -288.613609)
			(xy 435.119386 -288.634696) (xy 435.067225 -288.648332) (xy 435.013634 -288.654229) (xy 434.959755 -288.65226)
			(xy 434.906737 -288.642467) (xy 434.85571 -288.625059) (xy 434.807762 -288.600407) (xy 434.763914 -288.569037)
			(xy 434.725101 -288.531616) (xy 434.692149 -288.488943) (xy 434.665763 -288.441926) (xy 434.646503 -288.391569)
			(xy 434.63478 -288.338945) (xy 434.630845 -288.285174) (xy 427.8249 -288.285174) (xy 427.824408 -288.312131)
			(xy 427.816558 -288.365471) (xy 427.801026 -288.4171) (xy 427.778141 -288.465917) (xy 427.748393 -288.510881)
			(xy 427.712415 -288.551035) (xy 427.670973 -288.585523) (xy 427.624952 -288.613609) (xy 427.575332 -288.634696)
			(xy 427.523171 -288.648332) (xy 427.46958 -288.654229) (xy 427.415701 -288.65226) (xy 427.362683 -288.642467)
			(xy 427.311656 -288.625059) (xy 427.263708 -288.600407) (xy 427.21986 -288.569037) (xy 427.181047 -288.531616)
			(xy 427.148095 -288.488943) (xy 427.121709 -288.441926) (xy 427.102449 -288.391569) (xy 427.090726 -288.338945)
			(xy 427.086791 -288.285174) (xy 425.985178 -288.285174) (xy 425.985178 -289.135058) (xy 431.186859 -289.135058)
			(xy 431.190794 -289.081287) (xy 431.202517 -289.028663) (xy 431.221777 -288.978306) (xy 431.248163 -288.931289)
			(xy 431.281115 -288.888616) (xy 431.319928 -288.851195) (xy 431.363776 -288.819825) (xy 431.411724 -288.795173)
			(xy 431.462751 -288.777765) (xy 431.515769 -288.767972) (xy 431.569648 -288.766003) (xy 431.623239 -288.7719)
			(xy 431.6754 -288.785536) (xy 431.72502 -288.806623) (xy 431.771041 -288.834709) (xy 431.812483 -288.869197)
			(xy 431.848461 -288.909351) (xy 431.878209 -288.954315) (xy 431.901094 -289.003132) (xy 431.916626 -289.054761)
			(xy 431.924476 -289.108101) (xy 431.924968 -289.135058) (xy 438.730913 -289.135058) (xy 438.734848 -289.081287)
			(xy 438.746571 -289.028663) (xy 438.765831 -288.978306) (xy 438.792217 -288.931289) (xy 438.825169 -288.888616)
			(xy 438.863982 -288.851195) (xy 438.90783 -288.819825) (xy 438.955778 -288.795173) (xy 439.006805 -288.777765)
			(xy 439.059823 -288.767972) (xy 439.113702 -288.766003) (xy 439.167293 -288.7719) (xy 439.219454 -288.785536)
			(xy 439.269074 -288.806623) (xy 439.315095 -288.834709) (xy 439.356537 -288.869197) (xy 439.392515 -288.909351)
			(xy 439.422263 -288.954315) (xy 439.445148 -289.003132) (xy 439.46068 -289.054761) (xy 439.46853 -289.108101)
			(xy 439.469022 -289.135058) (xy 446.274967 -289.135058) (xy 446.278902 -289.081287) (xy 446.290625 -289.028663)
			(xy 446.309885 -288.978306) (xy 446.336271 -288.931289) (xy 446.369223 -288.888616) (xy 446.408036 -288.851195)
			(xy 446.451884 -288.819825) (xy 446.499832 -288.795173) (xy 446.550859 -288.777765) (xy 446.603877 -288.767972)
			(xy 446.657756 -288.766003) (xy 446.711347 -288.7719) (xy 446.763508 -288.785536) (xy 446.813128 -288.806623)
			(xy 446.859149 -288.834709) (xy 446.900591 -288.869197) (xy 446.936569 -288.909351) (xy 446.966317 -288.954315)
			(xy 446.989202 -289.003132) (xy 447.004734 -289.054761) (xy 447.012584 -289.108101) (xy 447.013076 -289.135058)
			(xy 453.818767 -289.135058) (xy 453.822702 -289.081287) (xy 453.834425 -289.028663) (xy 453.853685 -288.978306)
			(xy 453.880071 -288.931289) (xy 453.913023 -288.888616) (xy 453.951836 -288.851195) (xy 453.995684 -288.819825)
			(xy 454.043632 -288.795173) (xy 454.094659 -288.777765) (xy 454.147677 -288.767972) (xy 454.201556 -288.766003)
			(xy 454.255147 -288.7719) (xy 454.307308 -288.785536) (xy 454.356928 -288.806623) (xy 454.402949 -288.834709)
			(xy 454.444391 -288.869197) (xy 454.480369 -288.909351) (xy 454.510117 -288.954315) (xy 454.533002 -289.003132)
			(xy 454.548534 -289.054761) (xy 454.556384 -289.108101) (xy 454.556876 -289.135058) (xy 454.556384 -289.162015)
			(xy 454.548534 -289.215355) (xy 454.533002 -289.266984) (xy 454.510117 -289.315801) (xy 454.480369 -289.360765)
			(xy 454.444391 -289.400919) (xy 454.402949 -289.435407) (xy 454.356928 -289.463493) (xy 454.307308 -289.48458)
			(xy 454.255147 -289.498216) (xy 454.201556 -289.504113) (xy 454.147677 -289.502144) (xy 454.094659 -289.492351)
			(xy 454.043632 -289.474943) (xy 453.995684 -289.450291) (xy 453.951836 -289.418921) (xy 453.913023 -289.3815)
			(xy 453.880071 -289.338827) (xy 453.853685 -289.29181) (xy 453.834425 -289.241453) (xy 453.822702 -289.188829)
			(xy 453.818767 -289.135058) (xy 447.013076 -289.135058) (xy 447.012584 -289.162015) (xy 447.004734 -289.215355)
			(xy 446.989202 -289.266984) (xy 446.966317 -289.315801) (xy 446.936569 -289.360765) (xy 446.900591 -289.400919)
			(xy 446.859149 -289.435407) (xy 446.813128 -289.463493) (xy 446.763508 -289.48458) (xy 446.711347 -289.498216)
			(xy 446.657756 -289.504113) (xy 446.603877 -289.502144) (xy 446.550859 -289.492351) (xy 446.499832 -289.474943)
			(xy 446.451884 -289.450291) (xy 446.408036 -289.418921) (xy 446.369223 -289.3815) (xy 446.336271 -289.338827)
			(xy 446.309885 -289.29181) (xy 446.290625 -289.241453) (xy 446.278902 -289.188829) (xy 446.274967 -289.135058)
			(xy 439.469022 -289.135058) (xy 439.46853 -289.162015) (xy 439.46068 -289.215355) (xy 439.445148 -289.266984)
			(xy 439.422263 -289.315801) (xy 439.392515 -289.360765) (xy 439.356537 -289.400919) (xy 439.315095 -289.435407)
			(xy 439.269074 -289.463493) (xy 439.219454 -289.48458) (xy 439.167293 -289.498216) (xy 439.113702 -289.504113)
			(xy 439.059823 -289.502144) (xy 439.006805 -289.492351) (xy 438.955778 -289.474943) (xy 438.90783 -289.450291)
			(xy 438.863982 -289.418921) (xy 438.825169 -289.3815) (xy 438.792217 -289.338827) (xy 438.765831 -289.29181)
			(xy 438.746571 -289.241453) (xy 438.734848 -289.188829) (xy 438.730913 -289.135058) (xy 431.924968 -289.135058)
			(xy 431.924476 -289.162015) (xy 431.916626 -289.215355) (xy 431.901094 -289.266984) (xy 431.878209 -289.315801)
			(xy 431.848461 -289.360765) (xy 431.812483 -289.400919) (xy 431.771041 -289.435407) (xy 431.72502 -289.463493)
			(xy 431.6754 -289.48458) (xy 431.623239 -289.498216) (xy 431.569648 -289.504113) (xy 431.515769 -289.502144)
			(xy 431.462751 -289.492351) (xy 431.411724 -289.474943) (xy 431.363776 -289.450291) (xy 431.319928 -289.418921)
			(xy 431.281115 -289.3815) (xy 431.248163 -289.338827) (xy 431.221777 -289.29181) (xy 431.202517 -289.241453)
			(xy 431.190794 -289.188829) (xy 431.186859 -289.135058) (xy 425.985178 -289.135058) (xy 425.985178 -289.985196)
			(xy 427.086791 -289.985196) (xy 427.090726 -289.931425) (xy 427.102449 -289.878801) (xy 427.121709 -289.828444)
			(xy 427.148095 -289.781427) (xy 427.181047 -289.738754) (xy 427.21986 -289.701333) (xy 427.263708 -289.669963)
			(xy 427.311656 -289.645311) (xy 427.362683 -289.627903) (xy 427.415701 -289.61811) (xy 427.46958 -289.616141)
			(xy 427.523171 -289.622038) (xy 427.575332 -289.635674) (xy 427.624952 -289.656761) (xy 427.670973 -289.684847)
			(xy 427.712415 -289.719335) (xy 427.748393 -289.759489) (xy 427.778141 -289.804453) (xy 427.801026 -289.85327)
			(xy 427.816558 -289.904899) (xy 427.824408 -289.958239) (xy 427.8249 -289.985196) (xy 434.630845 -289.985196)
			(xy 434.63478 -289.931425) (xy 434.646503 -289.878801) (xy 434.665763 -289.828444) (xy 434.692149 -289.781427)
			(xy 434.725101 -289.738754) (xy 434.763914 -289.701333) (xy 434.807762 -289.669963) (xy 434.85571 -289.645311)
			(xy 434.906737 -289.627903) (xy 434.959755 -289.61811) (xy 435.013634 -289.616141) (xy 435.067225 -289.622038)
			(xy 435.119386 -289.635674) (xy 435.169006 -289.656761) (xy 435.215027 -289.684847) (xy 435.256469 -289.719335)
			(xy 435.292447 -289.759489) (xy 435.322195 -289.804453) (xy 435.34508 -289.85327) (xy 435.360612 -289.904899)
			(xy 435.368462 -289.958239) (xy 435.368954 -289.985196) (xy 442.174899 -289.985196) (xy 442.178834 -289.931425)
			(xy 442.190557 -289.878801) (xy 442.209817 -289.828444) (xy 442.236203 -289.781427) (xy 442.269155 -289.738754)
			(xy 442.307968 -289.701333) (xy 442.351816 -289.669963) (xy 442.399764 -289.645311) (xy 442.450791 -289.627903)
			(xy 442.503809 -289.61811) (xy 442.557688 -289.616141) (xy 442.611279 -289.622038) (xy 442.66344 -289.635674)
			(xy 442.71306 -289.656761) (xy 442.759081 -289.684847) (xy 442.800523 -289.719335) (xy 442.836501 -289.759489)
			(xy 442.866249 -289.804453) (xy 442.889134 -289.85327) (xy 442.904666 -289.904899) (xy 442.912516 -289.958239)
			(xy 442.913008 -289.985196) (xy 449.718699 -289.985196) (xy 449.722634 -289.931425) (xy 449.734357 -289.878801)
			(xy 449.753617 -289.828444) (xy 449.780003 -289.781427) (xy 449.812955 -289.738754) (xy 449.851768 -289.701333)
			(xy 449.895616 -289.669963) (xy 449.943564 -289.645311) (xy 449.994591 -289.627903) (xy 450.047609 -289.61811)
			(xy 450.101488 -289.616141) (xy 450.155079 -289.622038) (xy 450.20724 -289.635674) (xy 450.25686 -289.656761)
			(xy 450.302881 -289.684847) (xy 450.344323 -289.719335) (xy 450.380301 -289.759489) (xy 450.410049 -289.804453)
			(xy 450.432934 -289.85327) (xy 450.448466 -289.904899) (xy 450.456316 -289.958239) (xy 450.456808 -289.985196)
			(xy 450.456316 -290.012153) (xy 450.448466 -290.065493) (xy 450.432934 -290.117122) (xy 450.410049 -290.165939)
			(xy 450.380301 -290.210903) (xy 450.344323 -290.251057) (xy 450.302881 -290.285545) (xy 450.25686 -290.313631)
			(xy 450.20724 -290.334718) (xy 450.155079 -290.348354) (xy 450.101488 -290.354251) (xy 450.047609 -290.352282)
			(xy 449.994591 -290.342489) (xy 449.943564 -290.325081) (xy 449.895616 -290.300429) (xy 449.851768 -290.269059)
			(xy 449.812955 -290.231638) (xy 449.780003 -290.188965) (xy 449.753617 -290.141948) (xy 449.734357 -290.091591)
			(xy 449.722634 -290.038967) (xy 449.718699 -289.985196) (xy 442.913008 -289.985196) (xy 442.912516 -290.012153)
			(xy 442.904666 -290.065493) (xy 442.889134 -290.117122) (xy 442.866249 -290.165939) (xy 442.836501 -290.210903)
			(xy 442.800523 -290.251057) (xy 442.759081 -290.285545) (xy 442.71306 -290.313631) (xy 442.66344 -290.334718)
			(xy 442.611279 -290.348354) (xy 442.557688 -290.354251) (xy 442.503809 -290.352282) (xy 442.450791 -290.342489)
			(xy 442.399764 -290.325081) (xy 442.351816 -290.300429) (xy 442.307968 -290.269059) (xy 442.269155 -290.231638)
			(xy 442.236203 -290.188965) (xy 442.209817 -290.141948) (xy 442.190557 -290.091591) (xy 442.178834 -290.038967)
			(xy 442.174899 -289.985196) (xy 435.368954 -289.985196) (xy 435.368462 -290.012153) (xy 435.360612 -290.065493)
			(xy 435.34508 -290.117122) (xy 435.322195 -290.165939) (xy 435.292447 -290.210903) (xy 435.256469 -290.251057)
			(xy 435.215027 -290.285545) (xy 435.169006 -290.313631) (xy 435.119386 -290.334718) (xy 435.067225 -290.348354)
			(xy 435.013634 -290.354251) (xy 434.959755 -290.352282) (xy 434.906737 -290.342489) (xy 434.85571 -290.325081)
			(xy 434.807762 -290.300429) (xy 434.763914 -290.269059) (xy 434.725101 -290.231638) (xy 434.692149 -290.188965)
			(xy 434.665763 -290.141948) (xy 434.646503 -290.091591) (xy 434.63478 -290.038967) (xy 434.630845 -289.985196)
			(xy 427.8249 -289.985196) (xy 427.824408 -290.012153) (xy 427.816558 -290.065493) (xy 427.801026 -290.117122)
			(xy 427.778141 -290.165939) (xy 427.748393 -290.210903) (xy 427.712415 -290.251057) (xy 427.670973 -290.285545)
			(xy 427.624952 -290.313631) (xy 427.575332 -290.334718) (xy 427.523171 -290.348354) (xy 427.46958 -290.354251)
			(xy 427.415701 -290.352282) (xy 427.362683 -290.342489) (xy 427.311656 -290.325081) (xy 427.263708 -290.300429)
			(xy 427.21986 -290.269059) (xy 427.181047 -290.231638) (xy 427.148095 -290.188965) (xy 427.121709 -290.141948)
			(xy 427.102449 -290.091591) (xy 427.090726 -290.038967) (xy 427.086791 -289.985196) (xy 425.985178 -289.985196)
			(xy 425.985178 -290.83508) (xy 431.186859 -290.83508) (xy 431.190794 -290.781309) (xy 431.202517 -290.728685)
			(xy 431.221777 -290.678328) (xy 431.248163 -290.631311) (xy 431.281115 -290.588638) (xy 431.319928 -290.551217)
			(xy 431.363776 -290.519847) (xy 431.411724 -290.495195) (xy 431.462751 -290.477787) (xy 431.515769 -290.467994)
			(xy 431.569648 -290.466025) (xy 431.623239 -290.471922) (xy 431.6754 -290.485558) (xy 431.72502 -290.506645)
			(xy 431.771041 -290.534731) (xy 431.812483 -290.569219) (xy 431.848461 -290.609373) (xy 431.878209 -290.654337)
			(xy 431.901094 -290.703154) (xy 431.916626 -290.754783) (xy 431.924476 -290.808123) (xy 431.924968 -290.83508)
			(xy 438.730913 -290.83508) (xy 438.734848 -290.781309) (xy 438.746571 -290.728685) (xy 438.765831 -290.678328)
			(xy 438.792217 -290.631311) (xy 438.825169 -290.588638) (xy 438.863982 -290.551217) (xy 438.90783 -290.519847)
			(xy 438.955778 -290.495195) (xy 439.006805 -290.477787) (xy 439.059823 -290.467994) (xy 439.113702 -290.466025)
			(xy 439.167293 -290.471922) (xy 439.219454 -290.485558) (xy 439.269074 -290.506645) (xy 439.315095 -290.534731)
			(xy 439.356537 -290.569219) (xy 439.392515 -290.609373) (xy 439.422263 -290.654337) (xy 439.445148 -290.703154)
			(xy 439.46068 -290.754783) (xy 439.46853 -290.808123) (xy 439.469022 -290.83508) (xy 446.274967 -290.83508)
			(xy 446.278902 -290.781309) (xy 446.290625 -290.728685) (xy 446.309885 -290.678328) (xy 446.336271 -290.631311)
			(xy 446.369223 -290.588638) (xy 446.408036 -290.551217) (xy 446.451884 -290.519847) (xy 446.499832 -290.495195)
			(xy 446.550859 -290.477787) (xy 446.603877 -290.467994) (xy 446.657756 -290.466025) (xy 446.711347 -290.471922)
			(xy 446.763508 -290.485558) (xy 446.813128 -290.506645) (xy 446.859149 -290.534731) (xy 446.900591 -290.569219)
			(xy 446.936569 -290.609373) (xy 446.966317 -290.654337) (xy 446.989202 -290.703154) (xy 447.004734 -290.754783)
			(xy 447.012584 -290.808123) (xy 447.013076 -290.83508) (xy 453.818767 -290.83508) (xy 453.822702 -290.781309)
			(xy 453.834425 -290.728685) (xy 453.853685 -290.678328) (xy 453.880071 -290.631311) (xy 453.913023 -290.588638)
			(xy 453.951836 -290.551217) (xy 453.995684 -290.519847) (xy 454.043632 -290.495195) (xy 454.094659 -290.477787)
			(xy 454.147677 -290.467994) (xy 454.201556 -290.466025) (xy 454.255147 -290.471922) (xy 454.307308 -290.485558)
			(xy 454.356928 -290.506645) (xy 454.402949 -290.534731) (xy 454.444391 -290.569219) (xy 454.480369 -290.609373)
			(xy 454.510117 -290.654337) (xy 454.533002 -290.703154) (xy 454.548534 -290.754783) (xy 454.556384 -290.808123)
			(xy 454.556876 -290.83508) (xy 454.556384 -290.862037) (xy 454.548534 -290.915377) (xy 454.533002 -290.967006)
			(xy 454.510117 -291.015823) (xy 454.480369 -291.060787) (xy 454.444391 -291.100941) (xy 454.402949 -291.135429)
			(xy 454.356928 -291.163515) (xy 454.307308 -291.184602) (xy 454.255147 -291.198238) (xy 454.201556 -291.204135)
			(xy 454.147677 -291.202166) (xy 454.094659 -291.192373) (xy 454.043632 -291.174965) (xy 453.995684 -291.150313)
			(xy 453.951836 -291.118943) (xy 453.913023 -291.081522) (xy 453.880071 -291.038849) (xy 453.853685 -290.991832)
			(xy 453.834425 -290.941475) (xy 453.822702 -290.888851) (xy 453.818767 -290.83508) (xy 447.013076 -290.83508)
			(xy 447.012584 -290.862037) (xy 447.004734 -290.915377) (xy 446.989202 -290.967006) (xy 446.966317 -291.015823)
			(xy 446.936569 -291.060787) (xy 446.900591 -291.100941) (xy 446.859149 -291.135429) (xy 446.813128 -291.163515)
			(xy 446.763508 -291.184602) (xy 446.711347 -291.198238) (xy 446.657756 -291.204135) (xy 446.603877 -291.202166)
			(xy 446.550859 -291.192373) (xy 446.499832 -291.174965) (xy 446.451884 -291.150313) (xy 446.408036 -291.118943)
			(xy 446.369223 -291.081522) (xy 446.336271 -291.038849) (xy 446.309885 -290.991832) (xy 446.290625 -290.941475)
			(xy 446.278902 -290.888851) (xy 446.274967 -290.83508) (xy 439.469022 -290.83508) (xy 439.46853 -290.862037)
			(xy 439.46068 -290.915377) (xy 439.445148 -290.967006) (xy 439.422263 -291.015823) (xy 439.392515 -291.060787)
			(xy 439.356537 -291.100941) (xy 439.315095 -291.135429) (xy 439.269074 -291.163515) (xy 439.219454 -291.184602)
			(xy 439.167293 -291.198238) (xy 439.113702 -291.204135) (xy 439.059823 -291.202166) (xy 439.006805 -291.192373)
			(xy 438.955778 -291.174965) (xy 438.90783 -291.150313) (xy 438.863982 -291.118943) (xy 438.825169 -291.081522)
			(xy 438.792217 -291.038849) (xy 438.765831 -290.991832) (xy 438.746571 -290.941475) (xy 438.734848 -290.888851)
			(xy 438.730913 -290.83508) (xy 431.924968 -290.83508) (xy 431.924476 -290.862037) (xy 431.916626 -290.915377)
			(xy 431.901094 -290.967006) (xy 431.878209 -291.015823) (xy 431.848461 -291.060787) (xy 431.812483 -291.100941)
			(xy 431.771041 -291.135429) (xy 431.72502 -291.163515) (xy 431.6754 -291.184602) (xy 431.623239 -291.198238)
			(xy 431.569648 -291.204135) (xy 431.515769 -291.202166) (xy 431.462751 -291.192373) (xy 431.411724 -291.174965)
			(xy 431.363776 -291.150313) (xy 431.319928 -291.118943) (xy 431.281115 -291.081522) (xy 431.248163 -291.038849)
			(xy 431.221777 -290.991832) (xy 431.202517 -290.941475) (xy 431.190794 -290.888851) (xy 431.186859 -290.83508)
			(xy 425.985178 -290.83508) (xy 425.985178 -291.684964) (xy 427.086791 -291.684964) (xy 427.090726 -291.631193)
			(xy 427.102449 -291.578569) (xy 427.121709 -291.528212) (xy 427.148095 -291.481195) (xy 427.181047 -291.438522)
			(xy 427.21986 -291.401101) (xy 427.263708 -291.369731) (xy 427.311656 -291.345079) (xy 427.362683 -291.327671)
			(xy 427.415701 -291.317878) (xy 427.46958 -291.315909) (xy 427.523171 -291.321806) (xy 427.575332 -291.335442)
			(xy 427.624952 -291.356529) (xy 427.670973 -291.384615) (xy 427.712415 -291.419103) (xy 427.748393 -291.459257)
			(xy 427.778141 -291.504221) (xy 427.801026 -291.553038) (xy 427.816558 -291.604667) (xy 427.824408 -291.658007)
			(xy 427.8249 -291.684964) (xy 434.630845 -291.684964) (xy 434.63478 -291.631193) (xy 434.646503 -291.578569)
			(xy 434.665763 -291.528212) (xy 434.692149 -291.481195) (xy 434.725101 -291.438522) (xy 434.763914 -291.401101)
			(xy 434.807762 -291.369731) (xy 434.85571 -291.345079) (xy 434.906737 -291.327671) (xy 434.959755 -291.317878)
			(xy 435.013634 -291.315909) (xy 435.067225 -291.321806) (xy 435.119386 -291.335442) (xy 435.169006 -291.356529)
			(xy 435.215027 -291.384615) (xy 435.256469 -291.419103) (xy 435.292447 -291.459257) (xy 435.322195 -291.504221)
			(xy 435.34508 -291.553038) (xy 435.360612 -291.604667) (xy 435.368462 -291.658007) (xy 435.368954 -291.684964)
			(xy 442.174899 -291.684964) (xy 442.178834 -291.631193) (xy 442.190557 -291.578569) (xy 442.209817 -291.528212)
			(xy 442.236203 -291.481195) (xy 442.269155 -291.438522) (xy 442.307968 -291.401101) (xy 442.351816 -291.369731)
			(xy 442.399764 -291.345079) (xy 442.450791 -291.327671) (xy 442.503809 -291.317878) (xy 442.557688 -291.315909)
			(xy 442.611279 -291.321806) (xy 442.66344 -291.335442) (xy 442.71306 -291.356529) (xy 442.759081 -291.384615)
			(xy 442.800523 -291.419103) (xy 442.836501 -291.459257) (xy 442.866249 -291.504221) (xy 442.889134 -291.553038)
			(xy 442.904666 -291.604667) (xy 442.912516 -291.658007) (xy 442.913008 -291.684964) (xy 449.718699 -291.684964)
			(xy 449.722634 -291.631193) (xy 449.734357 -291.578569) (xy 449.753617 -291.528212) (xy 449.780003 -291.481195)
			(xy 449.812955 -291.438522) (xy 449.851768 -291.401101) (xy 449.895616 -291.369731) (xy 449.943564 -291.345079)
			(xy 449.994591 -291.327671) (xy 450.047609 -291.317878) (xy 450.101488 -291.315909) (xy 450.155079 -291.321806)
			(xy 450.20724 -291.335442) (xy 450.25686 -291.356529) (xy 450.302881 -291.384615) (xy 450.344323 -291.419103)
			(xy 450.380301 -291.459257) (xy 450.410049 -291.504221) (xy 450.432934 -291.553038) (xy 450.448466 -291.604667)
			(xy 450.456316 -291.658007) (xy 450.456808 -291.684964) (xy 450.456316 -291.711921) (xy 450.448466 -291.765261)
			(xy 450.432934 -291.81689) (xy 450.410049 -291.865707) (xy 450.380301 -291.910671) (xy 450.344323 -291.950825)
			(xy 450.302881 -291.985313) (xy 450.25686 -292.013399) (xy 450.20724 -292.034486) (xy 450.155079 -292.048122)
			(xy 450.101488 -292.054019) (xy 450.047609 -292.05205) (xy 449.994591 -292.042257) (xy 449.943564 -292.024849)
			(xy 449.895616 -292.000197) (xy 449.851768 -291.968827) (xy 449.812955 -291.931406) (xy 449.780003 -291.888733)
			(xy 449.753617 -291.841716) (xy 449.734357 -291.791359) (xy 449.722634 -291.738735) (xy 449.718699 -291.684964)
			(xy 442.913008 -291.684964) (xy 442.912516 -291.711921) (xy 442.904666 -291.765261) (xy 442.889134 -291.81689)
			(xy 442.866249 -291.865707) (xy 442.836501 -291.910671) (xy 442.800523 -291.950825) (xy 442.759081 -291.985313)
			(xy 442.71306 -292.013399) (xy 442.66344 -292.034486) (xy 442.611279 -292.048122) (xy 442.557688 -292.054019)
			(xy 442.503809 -292.05205) (xy 442.450791 -292.042257) (xy 442.399764 -292.024849) (xy 442.351816 -292.000197)
			(xy 442.307968 -291.968827) (xy 442.269155 -291.931406) (xy 442.236203 -291.888733) (xy 442.209817 -291.841716)
			(xy 442.190557 -291.791359) (xy 442.178834 -291.738735) (xy 442.174899 -291.684964) (xy 435.368954 -291.684964)
			(xy 435.368462 -291.711921) (xy 435.360612 -291.765261) (xy 435.34508 -291.81689) (xy 435.322195 -291.865707)
			(xy 435.292447 -291.910671) (xy 435.256469 -291.950825) (xy 435.215027 -291.985313) (xy 435.169006 -292.013399)
			(xy 435.119386 -292.034486) (xy 435.067225 -292.048122) (xy 435.013634 -292.054019) (xy 434.959755 -292.05205)
			(xy 434.906737 -292.042257) (xy 434.85571 -292.024849) (xy 434.807762 -292.000197) (xy 434.763914 -291.968827)
			(xy 434.725101 -291.931406) (xy 434.692149 -291.888733) (xy 434.665763 -291.841716) (xy 434.646503 -291.791359)
			(xy 434.63478 -291.738735) (xy 434.630845 -291.684964) (xy 427.8249 -291.684964) (xy 427.824408 -291.711921)
			(xy 427.816558 -291.765261) (xy 427.801026 -291.81689) (xy 427.778141 -291.865707) (xy 427.748393 -291.910671)
			(xy 427.712415 -291.950825) (xy 427.670973 -291.985313) (xy 427.624952 -292.013399) (xy 427.575332 -292.034486)
			(xy 427.523171 -292.048122) (xy 427.46958 -292.054019) (xy 427.415701 -292.05205) (xy 427.362683 -292.042257)
			(xy 427.311656 -292.024849) (xy 427.263708 -292.000197) (xy 427.21986 -291.968827) (xy 427.181047 -291.931406)
			(xy 427.148095 -291.888733) (xy 427.121709 -291.841716) (xy 427.102449 -291.791359) (xy 427.090726 -291.738735)
			(xy 427.086791 -291.684964) (xy 425.985178 -291.684964) (xy 425.985178 -292.535102) (xy 431.186859 -292.535102)
			(xy 431.190794 -292.481331) (xy 431.202517 -292.428707) (xy 431.221777 -292.37835) (xy 431.248163 -292.331333)
			(xy 431.281115 -292.28866) (xy 431.319928 -292.251239) (xy 431.363776 -292.219869) (xy 431.411724 -292.195217)
			(xy 431.462751 -292.177809) (xy 431.515769 -292.168016) (xy 431.569648 -292.166047) (xy 431.623239 -292.171944)
			(xy 431.6754 -292.18558) (xy 431.72502 -292.206667) (xy 431.771041 -292.234753) (xy 431.812483 -292.269241)
			(xy 431.848461 -292.309395) (xy 431.878209 -292.354359) (xy 431.901094 -292.403176) (xy 431.916626 -292.454805)
			(xy 431.924476 -292.508145) (xy 431.924968 -292.535102) (xy 438.730913 -292.535102) (xy 438.734848 -292.481331)
			(xy 438.746571 -292.428707) (xy 438.765831 -292.37835) (xy 438.792217 -292.331333) (xy 438.825169 -292.28866)
			(xy 438.863982 -292.251239) (xy 438.90783 -292.219869) (xy 438.955778 -292.195217) (xy 439.006805 -292.177809)
			(xy 439.059823 -292.168016) (xy 439.113702 -292.166047) (xy 439.167293 -292.171944) (xy 439.219454 -292.18558)
			(xy 439.269074 -292.206667) (xy 439.315095 -292.234753) (xy 439.356537 -292.269241) (xy 439.392515 -292.309395)
			(xy 439.422263 -292.354359) (xy 439.445148 -292.403176) (xy 439.46068 -292.454805) (xy 439.46853 -292.508145)
			(xy 439.469022 -292.535102) (xy 446.274967 -292.535102) (xy 446.278902 -292.481331) (xy 446.290625 -292.428707)
			(xy 446.309885 -292.37835) (xy 446.336271 -292.331333) (xy 446.369223 -292.28866) (xy 446.408036 -292.251239)
			(xy 446.451884 -292.219869) (xy 446.499832 -292.195217) (xy 446.550859 -292.177809) (xy 446.603877 -292.168016)
			(xy 446.657756 -292.166047) (xy 446.711347 -292.171944) (xy 446.763508 -292.18558) (xy 446.813128 -292.206667)
			(xy 446.859149 -292.234753) (xy 446.900591 -292.269241) (xy 446.936569 -292.309395) (xy 446.966317 -292.354359)
			(xy 446.989202 -292.403176) (xy 447.004734 -292.454805) (xy 447.012584 -292.508145) (xy 447.013076 -292.535102)
			(xy 453.818767 -292.535102) (xy 453.822702 -292.481331) (xy 453.834425 -292.428707) (xy 453.853685 -292.37835)
			(xy 453.880071 -292.331333) (xy 453.913023 -292.28866) (xy 453.951836 -292.251239) (xy 453.995684 -292.219869)
			(xy 454.043632 -292.195217) (xy 454.094659 -292.177809) (xy 454.147677 -292.168016) (xy 454.201556 -292.166047)
			(xy 454.255147 -292.171944) (xy 454.307308 -292.18558) (xy 454.356928 -292.206667) (xy 454.402949 -292.234753)
			(xy 454.444391 -292.269241) (xy 454.480369 -292.309395) (xy 454.510117 -292.354359) (xy 454.533002 -292.403176)
			(xy 454.548534 -292.454805) (xy 454.556384 -292.508145) (xy 454.556876 -292.535102) (xy 454.556384 -292.562059)
			(xy 454.548534 -292.615399) (xy 454.533002 -292.667028) (xy 454.510117 -292.715845) (xy 454.480369 -292.760809)
			(xy 454.444391 -292.800963) (xy 454.402949 -292.835451) (xy 454.356928 -292.863537) (xy 454.307308 -292.884624)
			(xy 454.255147 -292.89826) (xy 454.201556 -292.904157) (xy 454.147677 -292.902188) (xy 454.094659 -292.892395)
			(xy 454.043632 -292.874987) (xy 453.995684 -292.850335) (xy 453.951836 -292.818965) (xy 453.913023 -292.781544)
			(xy 453.880071 -292.738871) (xy 453.853685 -292.691854) (xy 453.834425 -292.641497) (xy 453.822702 -292.588873)
			(xy 453.818767 -292.535102) (xy 447.013076 -292.535102) (xy 447.012584 -292.562059) (xy 447.004734 -292.615399)
			(xy 446.989202 -292.667028) (xy 446.966317 -292.715845) (xy 446.936569 -292.760809) (xy 446.900591 -292.800963)
			(xy 446.859149 -292.835451) (xy 446.813128 -292.863537) (xy 446.763508 -292.884624) (xy 446.711347 -292.89826)
			(xy 446.657756 -292.904157) (xy 446.603877 -292.902188) (xy 446.550859 -292.892395) (xy 446.499832 -292.874987)
			(xy 446.451884 -292.850335) (xy 446.408036 -292.818965) (xy 446.369223 -292.781544) (xy 446.336271 -292.738871)
			(xy 446.309885 -292.691854) (xy 446.290625 -292.641497) (xy 446.278902 -292.588873) (xy 446.274967 -292.535102)
			(xy 439.469022 -292.535102) (xy 439.46853 -292.562059) (xy 439.46068 -292.615399) (xy 439.445148 -292.667028)
			(xy 439.422263 -292.715845) (xy 439.392515 -292.760809) (xy 439.356537 -292.800963) (xy 439.315095 -292.835451)
			(xy 439.269074 -292.863537) (xy 439.219454 -292.884624) (xy 439.167293 -292.89826) (xy 439.113702 -292.904157)
			(xy 439.059823 -292.902188) (xy 439.006805 -292.892395) (xy 438.955778 -292.874987) (xy 438.90783 -292.850335)
			(xy 438.863982 -292.818965) (xy 438.825169 -292.781544) (xy 438.792217 -292.738871) (xy 438.765831 -292.691854)
			(xy 438.746571 -292.641497) (xy 438.734848 -292.588873) (xy 438.730913 -292.535102) (xy 431.924968 -292.535102)
			(xy 431.924476 -292.562059) (xy 431.916626 -292.615399) (xy 431.901094 -292.667028) (xy 431.878209 -292.715845)
			(xy 431.848461 -292.760809) (xy 431.812483 -292.800963) (xy 431.771041 -292.835451) (xy 431.72502 -292.863537)
			(xy 431.6754 -292.884624) (xy 431.623239 -292.89826) (xy 431.569648 -292.904157) (xy 431.515769 -292.902188)
			(xy 431.462751 -292.892395) (xy 431.411724 -292.874987) (xy 431.363776 -292.850335) (xy 431.319928 -292.818965)
			(xy 431.281115 -292.781544) (xy 431.248163 -292.738871) (xy 431.221777 -292.691854) (xy 431.202517 -292.641497)
			(xy 431.190794 -292.588873) (xy 431.186859 -292.535102) (xy 425.985178 -292.535102) (xy 425.985178 -293.384986)
			(xy 427.086791 -293.384986) (xy 427.090726 -293.331215) (xy 427.102449 -293.278591) (xy 427.121709 -293.228234)
			(xy 427.148095 -293.181217) (xy 427.181047 -293.138544) (xy 427.21986 -293.101123) (xy 427.263708 -293.069753)
			(xy 427.311656 -293.045101) (xy 427.362683 -293.027693) (xy 427.415701 -293.0179) (xy 427.46958 -293.015931)
			(xy 427.523171 -293.021828) (xy 427.575332 -293.035464) (xy 427.624952 -293.056551) (xy 427.670973 -293.084637)
			(xy 427.712415 -293.119125) (xy 427.748393 -293.159279) (xy 427.778141 -293.204243) (xy 427.801026 -293.25306)
			(xy 427.816558 -293.304689) (xy 427.824408 -293.358029) (xy 427.8249 -293.384986) (xy 434.630845 -293.384986)
			(xy 434.63478 -293.331215) (xy 434.646503 -293.278591) (xy 434.665763 -293.228234) (xy 434.692149 -293.181217)
			(xy 434.725101 -293.138544) (xy 434.763914 -293.101123) (xy 434.807762 -293.069753) (xy 434.85571 -293.045101)
			(xy 434.906737 -293.027693) (xy 434.959755 -293.0179) (xy 435.013634 -293.015931) (xy 435.067225 -293.021828)
			(xy 435.119386 -293.035464) (xy 435.169006 -293.056551) (xy 435.215027 -293.084637) (xy 435.256469 -293.119125)
			(xy 435.292447 -293.159279) (xy 435.322195 -293.204243) (xy 435.34508 -293.25306) (xy 435.360612 -293.304689)
			(xy 435.368462 -293.358029) (xy 435.368954 -293.384986) (xy 442.174899 -293.384986) (xy 442.178834 -293.331215)
			(xy 442.190557 -293.278591) (xy 442.209817 -293.228234) (xy 442.236203 -293.181217) (xy 442.269155 -293.138544)
			(xy 442.307968 -293.101123) (xy 442.351816 -293.069753) (xy 442.399764 -293.045101) (xy 442.450791 -293.027693)
			(xy 442.503809 -293.0179) (xy 442.557688 -293.015931) (xy 442.611279 -293.021828) (xy 442.66344 -293.035464)
			(xy 442.71306 -293.056551) (xy 442.759081 -293.084637) (xy 442.800523 -293.119125) (xy 442.836501 -293.159279)
			(xy 442.866249 -293.204243) (xy 442.889134 -293.25306) (xy 442.904666 -293.304689) (xy 442.912516 -293.358029)
			(xy 442.913008 -293.384986) (xy 449.718699 -293.384986) (xy 449.722634 -293.331215) (xy 449.734357 -293.278591)
			(xy 449.753617 -293.228234) (xy 449.780003 -293.181217) (xy 449.812955 -293.138544) (xy 449.851768 -293.101123)
			(xy 449.895616 -293.069753) (xy 449.943564 -293.045101) (xy 449.994591 -293.027693) (xy 450.047609 -293.0179)
			(xy 450.101488 -293.015931) (xy 450.155079 -293.021828) (xy 450.20724 -293.035464) (xy 450.25686 -293.056551)
			(xy 450.302881 -293.084637) (xy 450.344323 -293.119125) (xy 450.380301 -293.159279) (xy 450.410049 -293.204243)
			(xy 450.432934 -293.25306) (xy 450.448466 -293.304689) (xy 450.456316 -293.358029) (xy 450.456808 -293.384986)
			(xy 450.456316 -293.411943) (xy 450.448466 -293.465283) (xy 450.432934 -293.516912) (xy 450.410049 -293.565729)
			(xy 450.380301 -293.610693) (xy 450.344323 -293.650847) (xy 450.302881 -293.685335) (xy 450.25686 -293.713421)
			(xy 450.20724 -293.734508) (xy 450.155079 -293.748144) (xy 450.101488 -293.754041) (xy 450.047609 -293.752072)
			(xy 449.994591 -293.742279) (xy 449.943564 -293.724871) (xy 449.895616 -293.700219) (xy 449.851768 -293.668849)
			(xy 449.812955 -293.631428) (xy 449.780003 -293.588755) (xy 449.753617 -293.541738) (xy 449.734357 -293.491381)
			(xy 449.722634 -293.438757) (xy 449.718699 -293.384986) (xy 442.913008 -293.384986) (xy 442.912516 -293.411943)
			(xy 442.904666 -293.465283) (xy 442.889134 -293.516912) (xy 442.866249 -293.565729) (xy 442.836501 -293.610693)
			(xy 442.800523 -293.650847) (xy 442.759081 -293.685335) (xy 442.71306 -293.713421) (xy 442.66344 -293.734508)
			(xy 442.611279 -293.748144) (xy 442.557688 -293.754041) (xy 442.503809 -293.752072) (xy 442.450791 -293.742279)
			(xy 442.399764 -293.724871) (xy 442.351816 -293.700219) (xy 442.307968 -293.668849) (xy 442.269155 -293.631428)
			(xy 442.236203 -293.588755) (xy 442.209817 -293.541738) (xy 442.190557 -293.491381) (xy 442.178834 -293.438757)
			(xy 442.174899 -293.384986) (xy 435.368954 -293.384986) (xy 435.368462 -293.411943) (xy 435.360612 -293.465283)
			(xy 435.34508 -293.516912) (xy 435.322195 -293.565729) (xy 435.292447 -293.610693) (xy 435.256469 -293.650847)
			(xy 435.215027 -293.685335) (xy 435.169006 -293.713421) (xy 435.119386 -293.734508) (xy 435.067225 -293.748144)
			(xy 435.013634 -293.754041) (xy 434.959755 -293.752072) (xy 434.906737 -293.742279) (xy 434.85571 -293.724871)
			(xy 434.807762 -293.700219) (xy 434.763914 -293.668849) (xy 434.725101 -293.631428) (xy 434.692149 -293.588755)
			(xy 434.665763 -293.541738) (xy 434.646503 -293.491381) (xy 434.63478 -293.438757) (xy 434.630845 -293.384986)
			(xy 427.8249 -293.384986) (xy 427.824408 -293.411943) (xy 427.816558 -293.465283) (xy 427.801026 -293.516912)
			(xy 427.778141 -293.565729) (xy 427.748393 -293.610693) (xy 427.712415 -293.650847) (xy 427.670973 -293.685335)
			(xy 427.624952 -293.713421) (xy 427.575332 -293.734508) (xy 427.523171 -293.748144) (xy 427.46958 -293.754041)
			(xy 427.415701 -293.752072) (xy 427.362683 -293.742279) (xy 427.311656 -293.724871) (xy 427.263708 -293.700219)
			(xy 427.21986 -293.668849) (xy 427.181047 -293.631428) (xy 427.148095 -293.588755) (xy 427.121709 -293.541738)
			(xy 427.102449 -293.491381) (xy 427.090726 -293.438757) (xy 427.086791 -293.384986) (xy 425.985178 -293.384986)
			(xy 425.985178 -294.235124) (xy 431.186859 -294.235124) (xy 431.190794 -294.181353) (xy 431.202517 -294.128729)
			(xy 431.221777 -294.078372) (xy 431.248163 -294.031355) (xy 431.281115 -293.988682) (xy 431.319928 -293.951261)
			(xy 431.363776 -293.919891) (xy 431.411724 -293.895239) (xy 431.462751 -293.877831) (xy 431.515769 -293.868038)
			(xy 431.569648 -293.866069) (xy 431.623239 -293.871966) (xy 431.6754 -293.885602) (xy 431.72502 -293.906689)
			(xy 431.771041 -293.934775) (xy 431.812483 -293.969263) (xy 431.848461 -294.009417) (xy 431.878209 -294.054381)
			(xy 431.901094 -294.103198) (xy 431.916626 -294.154827) (xy 431.924476 -294.208167) (xy 431.924968 -294.235124)
			(xy 438.730913 -294.235124) (xy 438.734848 -294.181353) (xy 438.746571 -294.128729) (xy 438.765831 -294.078372)
			(xy 438.792217 -294.031355) (xy 438.825169 -293.988682) (xy 438.863982 -293.951261) (xy 438.90783 -293.919891)
			(xy 438.955778 -293.895239) (xy 439.006805 -293.877831) (xy 439.059823 -293.868038) (xy 439.113702 -293.866069)
			(xy 439.167293 -293.871966) (xy 439.219454 -293.885602) (xy 439.269074 -293.906689) (xy 439.315095 -293.934775)
			(xy 439.356537 -293.969263) (xy 439.392515 -294.009417) (xy 439.422263 -294.054381) (xy 439.445148 -294.103198)
			(xy 439.46068 -294.154827) (xy 439.46853 -294.208167) (xy 439.469022 -294.235124) (xy 446.274967 -294.235124)
			(xy 446.278902 -294.181353) (xy 446.290625 -294.128729) (xy 446.309885 -294.078372) (xy 446.336271 -294.031355)
			(xy 446.369223 -293.988682) (xy 446.408036 -293.951261) (xy 446.451884 -293.919891) (xy 446.499832 -293.895239)
			(xy 446.550859 -293.877831) (xy 446.603877 -293.868038) (xy 446.657756 -293.866069) (xy 446.711347 -293.871966)
			(xy 446.763508 -293.885602) (xy 446.813128 -293.906689) (xy 446.859149 -293.934775) (xy 446.900591 -293.969263)
			(xy 446.936569 -294.009417) (xy 446.966317 -294.054381) (xy 446.989202 -294.103198) (xy 447.004734 -294.154827)
			(xy 447.012584 -294.208167) (xy 447.013076 -294.235124) (xy 453.818767 -294.235124) (xy 453.822702 -294.181353)
			(xy 453.834425 -294.128729) (xy 453.853685 -294.078372) (xy 453.880071 -294.031355) (xy 453.913023 -293.988682)
			(xy 453.951836 -293.951261) (xy 453.995684 -293.919891) (xy 454.043632 -293.895239) (xy 454.094659 -293.877831)
			(xy 454.147677 -293.868038) (xy 454.201556 -293.866069) (xy 454.255147 -293.871966) (xy 454.307308 -293.885602)
			(xy 454.356928 -293.906689) (xy 454.402949 -293.934775) (xy 454.444391 -293.969263) (xy 454.480369 -294.009417)
			(xy 454.510117 -294.054381) (xy 454.533002 -294.103198) (xy 454.548534 -294.154827) (xy 454.556384 -294.208167)
			(xy 454.556876 -294.235124) (xy 454.556384 -294.262081) (xy 454.548534 -294.315421) (xy 454.533002 -294.36705)
			(xy 454.510117 -294.415867) (xy 454.480369 -294.460831) (xy 454.444391 -294.500985) (xy 454.402949 -294.535473)
			(xy 454.356928 -294.563559) (xy 454.307308 -294.584646) (xy 454.255147 -294.598282) (xy 454.201556 -294.604179)
			(xy 454.147677 -294.60221) (xy 454.094659 -294.592417) (xy 454.043632 -294.575009) (xy 453.995684 -294.550357)
			(xy 453.951836 -294.518987) (xy 453.913023 -294.481566) (xy 453.880071 -294.438893) (xy 453.853685 -294.391876)
			(xy 453.834425 -294.341519) (xy 453.822702 -294.288895) (xy 453.818767 -294.235124) (xy 447.013076 -294.235124)
			(xy 447.012584 -294.262081) (xy 447.004734 -294.315421) (xy 446.989202 -294.36705) (xy 446.966317 -294.415867)
			(xy 446.936569 -294.460831) (xy 446.900591 -294.500985) (xy 446.859149 -294.535473) (xy 446.813128 -294.563559)
			(xy 446.763508 -294.584646) (xy 446.711347 -294.598282) (xy 446.657756 -294.604179) (xy 446.603877 -294.60221)
			(xy 446.550859 -294.592417) (xy 446.499832 -294.575009) (xy 446.451884 -294.550357) (xy 446.408036 -294.518987)
			(xy 446.369223 -294.481566) (xy 446.336271 -294.438893) (xy 446.309885 -294.391876) (xy 446.290625 -294.341519)
			(xy 446.278902 -294.288895) (xy 446.274967 -294.235124) (xy 439.469022 -294.235124) (xy 439.46853 -294.262081)
			(xy 439.46068 -294.315421) (xy 439.445148 -294.36705) (xy 439.422263 -294.415867) (xy 439.392515 -294.460831)
			(xy 439.356537 -294.500985) (xy 439.315095 -294.535473) (xy 439.269074 -294.563559) (xy 439.219454 -294.584646)
			(xy 439.167293 -294.598282) (xy 439.113702 -294.604179) (xy 439.059823 -294.60221) (xy 439.006805 -294.592417)
			(xy 438.955778 -294.575009) (xy 438.90783 -294.550357) (xy 438.863982 -294.518987) (xy 438.825169 -294.481566)
			(xy 438.792217 -294.438893) (xy 438.765831 -294.391876) (xy 438.746571 -294.341519) (xy 438.734848 -294.288895)
			(xy 438.730913 -294.235124) (xy 431.924968 -294.235124) (xy 431.924476 -294.262081) (xy 431.916626 -294.315421)
			(xy 431.901094 -294.36705) (xy 431.878209 -294.415867) (xy 431.848461 -294.460831) (xy 431.812483 -294.500985)
			(xy 431.771041 -294.535473) (xy 431.72502 -294.563559) (xy 431.6754 -294.584646) (xy 431.623239 -294.598282)
			(xy 431.569648 -294.604179) (xy 431.515769 -294.60221) (xy 431.462751 -294.592417) (xy 431.411724 -294.575009)
			(xy 431.363776 -294.550357) (xy 431.319928 -294.518987) (xy 431.281115 -294.481566) (xy 431.248163 -294.438893)
			(xy 431.221777 -294.391876) (xy 431.202517 -294.341519) (xy 431.190794 -294.288895) (xy 431.186859 -294.235124)
			(xy 425.985178 -294.235124) (xy 425.985178 -295.085008) (xy 427.086791 -295.085008) (xy 427.090726 -295.031237)
			(xy 427.102449 -294.978613) (xy 427.121709 -294.928256) (xy 427.148095 -294.881239) (xy 427.181047 -294.838566)
			(xy 427.21986 -294.801145) (xy 427.263708 -294.769775) (xy 427.311656 -294.745123) (xy 427.362683 -294.727715)
			(xy 427.415701 -294.717922) (xy 427.46958 -294.715953) (xy 427.523171 -294.72185) (xy 427.575332 -294.735486)
			(xy 427.624952 -294.756573) (xy 427.670973 -294.784659) (xy 427.712415 -294.819147) (xy 427.748393 -294.859301)
			(xy 427.778141 -294.904265) (xy 427.801026 -294.953082) (xy 427.816558 -295.004711) (xy 427.824408 -295.058051)
			(xy 427.8249 -295.085008) (xy 431.186859 -295.085008) (xy 431.190794 -295.031237) (xy 431.202517 -294.978613)
			(xy 431.221777 -294.928256) (xy 431.248163 -294.881239) (xy 431.281115 -294.838566) (xy 431.319928 -294.801145)
			(xy 431.363776 -294.769775) (xy 431.411724 -294.745123) (xy 431.462751 -294.727715) (xy 431.515769 -294.717922)
			(xy 431.569648 -294.715953) (xy 431.623239 -294.72185) (xy 431.6754 -294.735486) (xy 431.72502 -294.756573)
			(xy 431.771041 -294.784659) (xy 431.812483 -294.819147) (xy 431.848461 -294.859301) (xy 431.878209 -294.904265)
			(xy 431.901094 -294.953082) (xy 431.916626 -295.004711) (xy 431.924476 -295.058051) (xy 431.924968 -295.085008)
			(xy 434.630845 -295.085008) (xy 434.63478 -295.031237) (xy 434.646503 -294.978613) (xy 434.665763 -294.928256)
			(xy 434.692149 -294.881239) (xy 434.725101 -294.838566) (xy 434.763914 -294.801145) (xy 434.807762 -294.769775)
			(xy 434.85571 -294.745123) (xy 434.906737 -294.727715) (xy 434.959755 -294.717922) (xy 435.013634 -294.715953)
			(xy 435.067225 -294.72185) (xy 435.119386 -294.735486) (xy 435.169006 -294.756573) (xy 435.215027 -294.784659)
			(xy 435.256469 -294.819147) (xy 435.292447 -294.859301) (xy 435.322195 -294.904265) (xy 435.34508 -294.953082)
			(xy 435.360612 -295.004711) (xy 435.368462 -295.058051) (xy 435.368954 -295.085008) (xy 438.730913 -295.085008)
			(xy 438.734848 -295.031237) (xy 438.746571 -294.978613) (xy 438.765831 -294.928256) (xy 438.792217 -294.881239)
			(xy 438.825169 -294.838566) (xy 438.863982 -294.801145) (xy 438.90783 -294.769775) (xy 438.955778 -294.745123)
			(xy 439.006805 -294.727715) (xy 439.059823 -294.717922) (xy 439.113702 -294.715953) (xy 439.167293 -294.72185)
			(xy 439.219454 -294.735486) (xy 439.269074 -294.756573) (xy 439.315095 -294.784659) (xy 439.356537 -294.819147)
			(xy 439.392515 -294.859301) (xy 439.422263 -294.904265) (xy 439.445148 -294.953082) (xy 439.46068 -295.004711)
			(xy 439.46853 -295.058051) (xy 439.469022 -295.085008) (xy 442.174899 -295.085008) (xy 442.178834 -295.031237)
			(xy 442.190557 -294.978613) (xy 442.209817 -294.928256) (xy 442.236203 -294.881239) (xy 442.269155 -294.838566)
			(xy 442.307968 -294.801145) (xy 442.351816 -294.769775) (xy 442.399764 -294.745123) (xy 442.450791 -294.727715)
			(xy 442.503809 -294.717922) (xy 442.557688 -294.715953) (xy 442.611279 -294.72185) (xy 442.66344 -294.735486)
			(xy 442.71306 -294.756573) (xy 442.759081 -294.784659) (xy 442.800523 -294.819147) (xy 442.836501 -294.859301)
			(xy 442.866249 -294.904265) (xy 442.889134 -294.953082) (xy 442.904666 -295.004711) (xy 442.912516 -295.058051)
			(xy 442.913008 -295.085008) (xy 446.274967 -295.085008) (xy 446.278902 -295.031237) (xy 446.290625 -294.978613)
			(xy 446.309885 -294.928256) (xy 446.336271 -294.881239) (xy 446.369223 -294.838566) (xy 446.408036 -294.801145)
			(xy 446.451884 -294.769775) (xy 446.499832 -294.745123) (xy 446.550859 -294.727715) (xy 446.603877 -294.717922)
			(xy 446.657756 -294.715953) (xy 446.711347 -294.72185) (xy 446.763508 -294.735486) (xy 446.813128 -294.756573)
			(xy 446.859149 -294.784659) (xy 446.900591 -294.819147) (xy 446.936569 -294.859301) (xy 446.966317 -294.904265)
			(xy 446.989202 -294.953082) (xy 447.004734 -295.004711) (xy 447.012584 -295.058051) (xy 447.013076 -295.085008)
			(xy 449.718699 -295.085008) (xy 449.722634 -295.031237) (xy 449.734357 -294.978613) (xy 449.753617 -294.928256)
			(xy 449.780003 -294.881239) (xy 449.812955 -294.838566) (xy 449.851768 -294.801145) (xy 449.895616 -294.769775)
			(xy 449.943564 -294.745123) (xy 449.994591 -294.727715) (xy 450.047609 -294.717922) (xy 450.101488 -294.715953)
			(xy 450.155079 -294.72185) (xy 450.20724 -294.735486) (xy 450.25686 -294.756573) (xy 450.302881 -294.784659)
			(xy 450.344323 -294.819147) (xy 450.380301 -294.859301) (xy 450.410049 -294.904265) (xy 450.432934 -294.953082)
			(xy 450.448466 -295.004711) (xy 450.456316 -295.058051) (xy 450.456808 -295.085008) (xy 453.818767 -295.085008)
			(xy 453.822702 -295.031237) (xy 453.834425 -294.978613) (xy 453.853685 -294.928256) (xy 453.880071 -294.881239)
			(xy 453.913023 -294.838566) (xy 453.951836 -294.801145) (xy 453.995684 -294.769775) (xy 454.043632 -294.745123)
			(xy 454.094659 -294.727715) (xy 454.147677 -294.717922) (xy 454.201556 -294.715953) (xy 454.255147 -294.72185)
			(xy 454.307308 -294.735486) (xy 454.356928 -294.756573) (xy 454.402949 -294.784659) (xy 454.444391 -294.819147)
			(xy 454.480369 -294.859301) (xy 454.510117 -294.904265) (xy 454.533002 -294.953082) (xy 454.548534 -295.004711)
			(xy 454.556384 -295.058051) (xy 454.556876 -295.085008) (xy 454.556384 -295.111965) (xy 454.548534 -295.165305)
			(xy 454.533002 -295.216934) (xy 454.510117 -295.265751) (xy 454.480369 -295.310715) (xy 454.444391 -295.350869)
			(xy 454.402949 -295.385357) (xy 454.356928 -295.413443) (xy 454.307308 -295.43453) (xy 454.255147 -295.448166)
			(xy 454.201556 -295.454063) (xy 454.147677 -295.452094) (xy 454.094659 -295.442301) (xy 454.043632 -295.424893)
			(xy 453.995684 -295.400241) (xy 453.951836 -295.368871) (xy 453.913023 -295.33145) (xy 453.880071 -295.288777)
			(xy 453.853685 -295.24176) (xy 453.834425 -295.191403) (xy 453.822702 -295.138779) (xy 453.818767 -295.085008)
			(xy 450.456808 -295.085008) (xy 450.456316 -295.111965) (xy 450.448466 -295.165305) (xy 450.432934 -295.216934)
			(xy 450.410049 -295.265751) (xy 450.380301 -295.310715) (xy 450.344323 -295.350869) (xy 450.302881 -295.385357)
			(xy 450.25686 -295.413443) (xy 450.20724 -295.43453) (xy 450.155079 -295.448166) (xy 450.101488 -295.454063)
			(xy 450.047609 -295.452094) (xy 449.994591 -295.442301) (xy 449.943564 -295.424893) (xy 449.895616 -295.400241)
			(xy 449.851768 -295.368871) (xy 449.812955 -295.33145) (xy 449.780003 -295.288777) (xy 449.753617 -295.24176)
			(xy 449.734357 -295.191403) (xy 449.722634 -295.138779) (xy 449.718699 -295.085008) (xy 447.013076 -295.085008)
			(xy 447.012584 -295.111965) (xy 447.004734 -295.165305) (xy 446.989202 -295.216934) (xy 446.966317 -295.265751)
			(xy 446.936569 -295.310715) (xy 446.900591 -295.350869) (xy 446.859149 -295.385357) (xy 446.813128 -295.413443)
			(xy 446.763508 -295.43453) (xy 446.711347 -295.448166) (xy 446.657756 -295.454063) (xy 446.603877 -295.452094)
			(xy 446.550859 -295.442301) (xy 446.499832 -295.424893) (xy 446.451884 -295.400241) (xy 446.408036 -295.368871)
			(xy 446.369223 -295.33145) (xy 446.336271 -295.288777) (xy 446.309885 -295.24176) (xy 446.290625 -295.191403)
			(xy 446.278902 -295.138779) (xy 446.274967 -295.085008) (xy 442.913008 -295.085008) (xy 442.912516 -295.111965)
			(xy 442.904666 -295.165305) (xy 442.889134 -295.216934) (xy 442.866249 -295.265751) (xy 442.836501 -295.310715)
			(xy 442.800523 -295.350869) (xy 442.759081 -295.385357) (xy 442.71306 -295.413443) (xy 442.66344 -295.43453)
			(xy 442.611279 -295.448166) (xy 442.557688 -295.454063) (xy 442.503809 -295.452094) (xy 442.450791 -295.442301)
			(xy 442.399764 -295.424893) (xy 442.351816 -295.400241) (xy 442.307968 -295.368871) (xy 442.269155 -295.33145)
			(xy 442.236203 -295.288777) (xy 442.209817 -295.24176) (xy 442.190557 -295.191403) (xy 442.178834 -295.138779)
			(xy 442.174899 -295.085008) (xy 439.469022 -295.085008) (xy 439.46853 -295.111965) (xy 439.46068 -295.165305)
			(xy 439.445148 -295.216934) (xy 439.422263 -295.265751) (xy 439.392515 -295.310715) (xy 439.356537 -295.350869)
			(xy 439.315095 -295.385357) (xy 439.269074 -295.413443) (xy 439.219454 -295.43453) (xy 439.167293 -295.448166)
			(xy 439.113702 -295.454063) (xy 439.059823 -295.452094) (xy 439.006805 -295.442301) (xy 438.955778 -295.424893)
			(xy 438.90783 -295.400241) (xy 438.863982 -295.368871) (xy 438.825169 -295.33145) (xy 438.792217 -295.288777)
			(xy 438.765831 -295.24176) (xy 438.746571 -295.191403) (xy 438.734848 -295.138779) (xy 438.730913 -295.085008)
			(xy 435.368954 -295.085008) (xy 435.368462 -295.111965) (xy 435.360612 -295.165305) (xy 435.34508 -295.216934)
			(xy 435.322195 -295.265751) (xy 435.292447 -295.310715) (xy 435.256469 -295.350869) (xy 435.215027 -295.385357)
			(xy 435.169006 -295.413443) (xy 435.119386 -295.43453) (xy 435.067225 -295.448166) (xy 435.013634 -295.454063)
			(xy 434.959755 -295.452094) (xy 434.906737 -295.442301) (xy 434.85571 -295.424893) (xy 434.807762 -295.400241)
			(xy 434.763914 -295.368871) (xy 434.725101 -295.33145) (xy 434.692149 -295.288777) (xy 434.665763 -295.24176)
			(xy 434.646503 -295.191403) (xy 434.63478 -295.138779) (xy 434.630845 -295.085008) (xy 431.924968 -295.085008)
			(xy 431.924476 -295.111965) (xy 431.916626 -295.165305) (xy 431.901094 -295.216934) (xy 431.878209 -295.265751)
			(xy 431.848461 -295.310715) (xy 431.812483 -295.350869) (xy 431.771041 -295.385357) (xy 431.72502 -295.413443)
			(xy 431.6754 -295.43453) (xy 431.623239 -295.448166) (xy 431.569648 -295.454063) (xy 431.515769 -295.452094)
			(xy 431.462751 -295.442301) (xy 431.411724 -295.424893) (xy 431.363776 -295.400241) (xy 431.319928 -295.368871)
			(xy 431.281115 -295.33145) (xy 431.248163 -295.288777) (xy 431.221777 -295.24176) (xy 431.202517 -295.191403)
			(xy 431.190794 -295.138779) (xy 431.186859 -295.085008) (xy 427.8249 -295.085008) (xy 427.824408 -295.111965)
			(xy 427.816558 -295.165305) (xy 427.801026 -295.216934) (xy 427.778141 -295.265751) (xy 427.748393 -295.310715)
			(xy 427.712415 -295.350869) (xy 427.670973 -295.385357) (xy 427.624952 -295.413443) (xy 427.575332 -295.43453)
			(xy 427.523171 -295.448166) (xy 427.46958 -295.454063) (xy 427.415701 -295.452094) (xy 427.362683 -295.442301)
			(xy 427.311656 -295.424893) (xy 427.263708 -295.400241) (xy 427.21986 -295.368871) (xy 427.181047 -295.33145)
			(xy 427.148095 -295.288777) (xy 427.121709 -295.24176) (xy 427.102449 -295.191403) (xy 427.090726 -295.138779)
			(xy 427.086791 -295.085008) (xy 425.985178 -295.085008) (xy 425.985178 -295.935146) (xy 427.086791 -295.935146)
			(xy 427.090726 -295.881375) (xy 427.102449 -295.828751) (xy 427.121709 -295.778394) (xy 427.148095 -295.731377)
			(xy 427.181047 -295.688704) (xy 427.21986 -295.651283) (xy 427.263708 -295.619913) (xy 427.311656 -295.595261)
			(xy 427.362683 -295.577853) (xy 427.415701 -295.56806) (xy 427.46958 -295.566091) (xy 427.523171 -295.571988)
			(xy 427.575332 -295.585624) (xy 427.624952 -295.606711) (xy 427.670973 -295.634797) (xy 427.712415 -295.669285)
			(xy 427.748393 -295.709439) (xy 427.778141 -295.754403) (xy 427.801026 -295.80322) (xy 427.816558 -295.854849)
			(xy 427.824408 -295.908189) (xy 427.8249 -295.935146) (xy 434.630845 -295.935146) (xy 434.63478 -295.881375)
			(xy 434.646503 -295.828751) (xy 434.665763 -295.778394) (xy 434.692149 -295.731377) (xy 434.725101 -295.688704)
			(xy 434.763914 -295.651283) (xy 434.807762 -295.619913) (xy 434.85571 -295.595261) (xy 434.906737 -295.577853)
			(xy 434.959755 -295.56806) (xy 435.013634 -295.566091) (xy 435.067225 -295.571988) (xy 435.119386 -295.585624)
			(xy 435.169006 -295.606711) (xy 435.215027 -295.634797) (xy 435.256469 -295.669285) (xy 435.292447 -295.709439)
			(xy 435.322195 -295.754403) (xy 435.34508 -295.80322) (xy 435.360612 -295.854849) (xy 435.368462 -295.908189)
			(xy 435.368954 -295.935146) (xy 442.174899 -295.935146) (xy 442.178834 -295.881375) (xy 442.190557 -295.828751)
			(xy 442.209817 -295.778394) (xy 442.236203 -295.731377) (xy 442.269155 -295.688704) (xy 442.307968 -295.651283)
			(xy 442.351816 -295.619913) (xy 442.399764 -295.595261) (xy 442.450791 -295.577853) (xy 442.503809 -295.56806)
			(xy 442.557688 -295.566091) (xy 442.611279 -295.571988) (xy 442.66344 -295.585624) (xy 442.71306 -295.606711)
			(xy 442.759081 -295.634797) (xy 442.800523 -295.669285) (xy 442.836501 -295.709439) (xy 442.866249 -295.754403)
			(xy 442.889134 -295.80322) (xy 442.904666 -295.854849) (xy 442.912516 -295.908189) (xy 442.913008 -295.935146)
			(xy 449.718699 -295.935146) (xy 449.722634 -295.881375) (xy 449.734357 -295.828751) (xy 449.753617 -295.778394)
			(xy 449.780003 -295.731377) (xy 449.812955 -295.688704) (xy 449.851768 -295.651283) (xy 449.895616 -295.619913)
			(xy 449.943564 -295.595261) (xy 449.994591 -295.577853) (xy 450.047609 -295.56806) (xy 450.101488 -295.566091)
			(xy 450.155079 -295.571988) (xy 450.20724 -295.585624) (xy 450.25686 -295.606711) (xy 450.302881 -295.634797)
			(xy 450.344323 -295.669285) (xy 450.380301 -295.709439) (xy 450.410049 -295.754403) (xy 450.432934 -295.80322)
			(xy 450.448466 -295.854849) (xy 450.456316 -295.908189) (xy 450.456808 -295.935146) (xy 450.456316 -295.962103)
			(xy 450.448466 -296.015443) (xy 450.432934 -296.067072) (xy 450.410049 -296.115889) (xy 450.380301 -296.160853)
			(xy 450.344323 -296.201007) (xy 450.302881 -296.235495) (xy 450.25686 -296.263581) (xy 450.20724 -296.284668)
			(xy 450.155079 -296.298304) (xy 450.101488 -296.304201) (xy 450.047609 -296.302232) (xy 449.994591 -296.292439)
			(xy 449.943564 -296.275031) (xy 449.895616 -296.250379) (xy 449.851768 -296.219009) (xy 449.812955 -296.181588)
			(xy 449.780003 -296.138915) (xy 449.753617 -296.091898) (xy 449.734357 -296.041541) (xy 449.722634 -295.988917)
			(xy 449.718699 -295.935146) (xy 442.913008 -295.935146) (xy 442.912516 -295.962103) (xy 442.904666 -296.015443)
			(xy 442.889134 -296.067072) (xy 442.866249 -296.115889) (xy 442.836501 -296.160853) (xy 442.800523 -296.201007)
			(xy 442.759081 -296.235495) (xy 442.71306 -296.263581) (xy 442.66344 -296.284668) (xy 442.611279 -296.298304)
			(xy 442.557688 -296.304201) (xy 442.503809 -296.302232) (xy 442.450791 -296.292439) (xy 442.399764 -296.275031)
			(xy 442.351816 -296.250379) (xy 442.307968 -296.219009) (xy 442.269155 -296.181588) (xy 442.236203 -296.138915)
			(xy 442.209817 -296.091898) (xy 442.190557 -296.041541) (xy 442.178834 -295.988917) (xy 442.174899 -295.935146)
			(xy 435.368954 -295.935146) (xy 435.368462 -295.962103) (xy 435.360612 -296.015443) (xy 435.34508 -296.067072)
			(xy 435.322195 -296.115889) (xy 435.292447 -296.160853) (xy 435.256469 -296.201007) (xy 435.215027 -296.235495)
			(xy 435.169006 -296.263581) (xy 435.119386 -296.284668) (xy 435.067225 -296.298304) (xy 435.013634 -296.304201)
			(xy 434.959755 -296.302232) (xy 434.906737 -296.292439) (xy 434.85571 -296.275031) (xy 434.807762 -296.250379)
			(xy 434.763914 -296.219009) (xy 434.725101 -296.181588) (xy 434.692149 -296.138915) (xy 434.665763 -296.091898)
			(xy 434.646503 -296.041541) (xy 434.63478 -295.988917) (xy 434.630845 -295.935146) (xy 427.8249 -295.935146)
			(xy 427.824408 -295.962103) (xy 427.816558 -296.015443) (xy 427.801026 -296.067072) (xy 427.778141 -296.115889)
			(xy 427.748393 -296.160853) (xy 427.712415 -296.201007) (xy 427.670973 -296.235495) (xy 427.624952 -296.263581)
			(xy 427.575332 -296.284668) (xy 427.523171 -296.298304) (xy 427.46958 -296.304201) (xy 427.415701 -296.302232)
			(xy 427.362683 -296.292439) (xy 427.311656 -296.275031) (xy 427.263708 -296.250379) (xy 427.21986 -296.219009)
			(xy 427.181047 -296.181588) (xy 427.148095 -296.138915) (xy 427.121709 -296.091898) (xy 427.102449 -296.041541)
			(xy 427.090726 -295.988917) (xy 427.086791 -295.935146) (xy 425.985178 -295.935146) (xy 425.985178 -296.78503)
			(xy 431.186859 -296.78503) (xy 431.190794 -296.731259) (xy 431.202517 -296.678635) (xy 431.221777 -296.628278)
			(xy 431.248163 -296.581261) (xy 431.281115 -296.538588) (xy 431.319928 -296.501167) (xy 431.363776 -296.469797)
			(xy 431.411724 -296.445145) (xy 431.462751 -296.427737) (xy 431.515769 -296.417944) (xy 431.569648 -296.415975)
			(xy 431.623239 -296.421872) (xy 431.6754 -296.435508) (xy 431.72502 -296.456595) (xy 431.771041 -296.484681)
			(xy 431.812483 -296.519169) (xy 431.848461 -296.559323) (xy 431.878209 -296.604287) (xy 431.901094 -296.653104)
			(xy 431.916626 -296.704733) (xy 431.924476 -296.758073) (xy 431.924968 -296.78503) (xy 438.730913 -296.78503)
			(xy 438.734848 -296.731259) (xy 438.746571 -296.678635) (xy 438.765831 -296.628278) (xy 438.792217 -296.581261)
			(xy 438.825169 -296.538588) (xy 438.863982 -296.501167) (xy 438.90783 -296.469797) (xy 438.955778 -296.445145)
			(xy 439.006805 -296.427737) (xy 439.059823 -296.417944) (xy 439.113702 -296.415975) (xy 439.167293 -296.421872)
			(xy 439.219454 -296.435508) (xy 439.269074 -296.456595) (xy 439.315095 -296.484681) (xy 439.356537 -296.519169)
			(xy 439.392515 -296.559323) (xy 439.422263 -296.604287) (xy 439.445148 -296.653104) (xy 439.46068 -296.704733)
			(xy 439.46853 -296.758073) (xy 439.469022 -296.78503) (xy 446.274967 -296.78503) (xy 446.278902 -296.731259)
			(xy 446.290625 -296.678635) (xy 446.309885 -296.628278) (xy 446.336271 -296.581261) (xy 446.369223 -296.538588)
			(xy 446.408036 -296.501167) (xy 446.451884 -296.469797) (xy 446.499832 -296.445145) (xy 446.550859 -296.427737)
			(xy 446.603877 -296.417944) (xy 446.657756 -296.415975) (xy 446.711347 -296.421872) (xy 446.763508 -296.435508)
			(xy 446.813128 -296.456595) (xy 446.859149 -296.484681) (xy 446.900591 -296.519169) (xy 446.936569 -296.559323)
			(xy 446.966317 -296.604287) (xy 446.989202 -296.653104) (xy 447.004734 -296.704733) (xy 447.012584 -296.758073)
			(xy 447.013076 -296.78503) (xy 453.818767 -296.78503) (xy 453.822702 -296.731259) (xy 453.834425 -296.678635)
			(xy 453.853685 -296.628278) (xy 453.880071 -296.581261) (xy 453.913023 -296.538588) (xy 453.951836 -296.501167)
			(xy 453.995684 -296.469797) (xy 454.043632 -296.445145) (xy 454.094659 -296.427737) (xy 454.147677 -296.417944)
			(xy 454.201556 -296.415975) (xy 454.255147 -296.421872) (xy 454.307308 -296.435508) (xy 454.356928 -296.456595)
			(xy 454.402949 -296.484681) (xy 454.444391 -296.519169) (xy 454.480369 -296.559323) (xy 454.510117 -296.604287)
			(xy 454.533002 -296.653104) (xy 454.548534 -296.704733) (xy 454.556384 -296.758073) (xy 454.556876 -296.78503)
			(xy 454.556384 -296.811987) (xy 454.548534 -296.865327) (xy 454.533002 -296.916956) (xy 454.510117 -296.965773)
			(xy 454.480369 -297.010737) (xy 454.444391 -297.050891) (xy 454.402949 -297.085379) (xy 454.356928 -297.113465)
			(xy 454.307308 -297.134552) (xy 454.255147 -297.148188) (xy 454.201556 -297.154085) (xy 454.147677 -297.152116)
			(xy 454.094659 -297.142323) (xy 454.043632 -297.124915) (xy 453.995684 -297.100263) (xy 453.951836 -297.068893)
			(xy 453.913023 -297.031472) (xy 453.880071 -296.988799) (xy 453.853685 -296.941782) (xy 453.834425 -296.891425)
			(xy 453.822702 -296.838801) (xy 453.818767 -296.78503) (xy 447.013076 -296.78503) (xy 447.012584 -296.811987)
			(xy 447.004734 -296.865327) (xy 446.989202 -296.916956) (xy 446.966317 -296.965773) (xy 446.936569 -297.010737)
			(xy 446.900591 -297.050891) (xy 446.859149 -297.085379) (xy 446.813128 -297.113465) (xy 446.763508 -297.134552)
			(xy 446.711347 -297.148188) (xy 446.657756 -297.154085) (xy 446.603877 -297.152116) (xy 446.550859 -297.142323)
			(xy 446.499832 -297.124915) (xy 446.451884 -297.100263) (xy 446.408036 -297.068893) (xy 446.369223 -297.031472)
			(xy 446.336271 -296.988799) (xy 446.309885 -296.941782) (xy 446.290625 -296.891425) (xy 446.278902 -296.838801)
			(xy 446.274967 -296.78503) (xy 439.469022 -296.78503) (xy 439.46853 -296.811987) (xy 439.46068 -296.865327)
			(xy 439.445148 -296.916956) (xy 439.422263 -296.965773) (xy 439.392515 -297.010737) (xy 439.356537 -297.050891)
			(xy 439.315095 -297.085379) (xy 439.269074 -297.113465) (xy 439.219454 -297.134552) (xy 439.167293 -297.148188)
			(xy 439.113702 -297.154085) (xy 439.059823 -297.152116) (xy 439.006805 -297.142323) (xy 438.955778 -297.124915)
			(xy 438.90783 -297.100263) (xy 438.863982 -297.068893) (xy 438.825169 -297.031472) (xy 438.792217 -296.988799)
			(xy 438.765831 -296.941782) (xy 438.746571 -296.891425) (xy 438.734848 -296.838801) (xy 438.730913 -296.78503)
			(xy 431.924968 -296.78503) (xy 431.924476 -296.811987) (xy 431.916626 -296.865327) (xy 431.901094 -296.916956)
			(xy 431.878209 -296.965773) (xy 431.848461 -297.010737) (xy 431.812483 -297.050891) (xy 431.771041 -297.085379)
			(xy 431.72502 -297.113465) (xy 431.6754 -297.134552) (xy 431.623239 -297.148188) (xy 431.569648 -297.154085)
			(xy 431.515769 -297.152116) (xy 431.462751 -297.142323) (xy 431.411724 -297.124915) (xy 431.363776 -297.100263)
			(xy 431.319928 -297.068893) (xy 431.281115 -297.031472) (xy 431.248163 -296.988799) (xy 431.221777 -296.941782)
			(xy 431.202517 -296.891425) (xy 431.190794 -296.838801) (xy 431.186859 -296.78503) (xy 425.985178 -296.78503)
			(xy 425.985178 -297.635168) (xy 427.086791 -297.635168) (xy 427.090726 -297.581397) (xy 427.102449 -297.528773)
			(xy 427.121709 -297.478416) (xy 427.148095 -297.431399) (xy 427.181047 -297.388726) (xy 427.21986 -297.351305)
			(xy 427.263708 -297.319935) (xy 427.311656 -297.295283) (xy 427.362683 -297.277875) (xy 427.415701 -297.268082)
			(xy 427.46958 -297.266113) (xy 427.523171 -297.27201) (xy 427.575332 -297.285646) (xy 427.624952 -297.306733)
			(xy 427.670973 -297.334819) (xy 427.712415 -297.369307) (xy 427.748393 -297.409461) (xy 427.778141 -297.454425)
			(xy 427.801026 -297.503242) (xy 427.816558 -297.554871) (xy 427.824408 -297.608211) (xy 427.8249 -297.635168)
			(xy 434.630845 -297.635168) (xy 434.63478 -297.581397) (xy 434.646503 -297.528773) (xy 434.665763 -297.478416)
			(xy 434.692149 -297.431399) (xy 434.725101 -297.388726) (xy 434.763914 -297.351305) (xy 434.807762 -297.319935)
			(xy 434.85571 -297.295283) (xy 434.906737 -297.277875) (xy 434.959755 -297.268082) (xy 435.013634 -297.266113)
			(xy 435.067225 -297.27201) (xy 435.119386 -297.285646) (xy 435.169006 -297.306733) (xy 435.215027 -297.334819)
			(xy 435.256469 -297.369307) (xy 435.292447 -297.409461) (xy 435.322195 -297.454425) (xy 435.34508 -297.503242)
			(xy 435.360612 -297.554871) (xy 435.368462 -297.608211) (xy 435.368954 -297.635168) (xy 442.174899 -297.635168)
			(xy 442.178834 -297.581397) (xy 442.190557 -297.528773) (xy 442.209817 -297.478416) (xy 442.236203 -297.431399)
			(xy 442.269155 -297.388726) (xy 442.307968 -297.351305) (xy 442.351816 -297.319935) (xy 442.399764 -297.295283)
			(xy 442.450791 -297.277875) (xy 442.503809 -297.268082) (xy 442.557688 -297.266113) (xy 442.611279 -297.27201)
			(xy 442.66344 -297.285646) (xy 442.71306 -297.306733) (xy 442.759081 -297.334819) (xy 442.800523 -297.369307)
			(xy 442.836501 -297.409461) (xy 442.866249 -297.454425) (xy 442.889134 -297.503242) (xy 442.904666 -297.554871)
			(xy 442.912516 -297.608211) (xy 442.913008 -297.635168) (xy 449.718699 -297.635168) (xy 449.722634 -297.581397)
			(xy 449.734357 -297.528773) (xy 449.753617 -297.478416) (xy 449.780003 -297.431399) (xy 449.812955 -297.388726)
			(xy 449.851768 -297.351305) (xy 449.895616 -297.319935) (xy 449.943564 -297.295283) (xy 449.994591 -297.277875)
			(xy 450.047609 -297.268082) (xy 450.101488 -297.266113) (xy 450.155079 -297.27201) (xy 450.20724 -297.285646)
			(xy 450.25686 -297.306733) (xy 450.302881 -297.334819) (xy 450.344323 -297.369307) (xy 450.380301 -297.409461)
			(xy 450.410049 -297.454425) (xy 450.432934 -297.503242) (xy 450.448466 -297.554871) (xy 450.456316 -297.608211)
			(xy 450.456808 -297.635168) (xy 450.456316 -297.662125) (xy 450.448466 -297.715465) (xy 450.432934 -297.767094)
			(xy 450.410049 -297.815911) (xy 450.380301 -297.860875) (xy 450.344323 -297.901029) (xy 450.302881 -297.935517)
			(xy 450.25686 -297.963603) (xy 450.20724 -297.98469) (xy 450.155079 -297.998326) (xy 450.101488 -298.004223)
			(xy 450.047609 -298.002254) (xy 449.994591 -297.992461) (xy 449.943564 -297.975053) (xy 449.895616 -297.950401)
			(xy 449.851768 -297.919031) (xy 449.812955 -297.88161) (xy 449.780003 -297.838937) (xy 449.753617 -297.79192)
			(xy 449.734357 -297.741563) (xy 449.722634 -297.688939) (xy 449.718699 -297.635168) (xy 442.913008 -297.635168)
			(xy 442.912516 -297.662125) (xy 442.904666 -297.715465) (xy 442.889134 -297.767094) (xy 442.866249 -297.815911)
			(xy 442.836501 -297.860875) (xy 442.800523 -297.901029) (xy 442.759081 -297.935517) (xy 442.71306 -297.963603)
			(xy 442.66344 -297.98469) (xy 442.611279 -297.998326) (xy 442.557688 -298.004223) (xy 442.503809 -298.002254)
			(xy 442.450791 -297.992461) (xy 442.399764 -297.975053) (xy 442.351816 -297.950401) (xy 442.307968 -297.919031)
			(xy 442.269155 -297.88161) (xy 442.236203 -297.838937) (xy 442.209817 -297.79192) (xy 442.190557 -297.741563)
			(xy 442.178834 -297.688939) (xy 442.174899 -297.635168) (xy 435.368954 -297.635168) (xy 435.368462 -297.662125)
			(xy 435.360612 -297.715465) (xy 435.34508 -297.767094) (xy 435.322195 -297.815911) (xy 435.292447 -297.860875)
			(xy 435.256469 -297.901029) (xy 435.215027 -297.935517) (xy 435.169006 -297.963603) (xy 435.119386 -297.98469)
			(xy 435.067225 -297.998326) (xy 435.013634 -298.004223) (xy 434.959755 -298.002254) (xy 434.906737 -297.992461)
			(xy 434.85571 -297.975053) (xy 434.807762 -297.950401) (xy 434.763914 -297.919031) (xy 434.725101 -297.88161)
			(xy 434.692149 -297.838937) (xy 434.665763 -297.79192) (xy 434.646503 -297.741563) (xy 434.63478 -297.688939)
			(xy 434.630845 -297.635168) (xy 427.8249 -297.635168) (xy 427.824408 -297.662125) (xy 427.816558 -297.715465)
			(xy 427.801026 -297.767094) (xy 427.778141 -297.815911) (xy 427.748393 -297.860875) (xy 427.712415 -297.901029)
			(xy 427.670973 -297.935517) (xy 427.624952 -297.963603) (xy 427.575332 -297.98469) (xy 427.523171 -297.998326)
			(xy 427.46958 -298.004223) (xy 427.415701 -298.002254) (xy 427.362683 -297.992461) (xy 427.311656 -297.975053)
			(xy 427.263708 -297.950401) (xy 427.21986 -297.919031) (xy 427.181047 -297.88161) (xy 427.148095 -297.838937)
			(xy 427.121709 -297.79192) (xy 427.102449 -297.741563) (xy 427.090726 -297.688939) (xy 427.086791 -297.635168)
			(xy 425.985178 -297.635168) (xy 425.985178 -298.485052) (xy 431.186859 -298.485052) (xy 431.190794 -298.431281)
			(xy 431.202517 -298.378657) (xy 431.221777 -298.3283) (xy 431.248163 -298.281283) (xy 431.281115 -298.23861)
			(xy 431.319928 -298.201189) (xy 431.363776 -298.169819) (xy 431.411724 -298.145167) (xy 431.462751 -298.127759)
			(xy 431.515769 -298.117966) (xy 431.569648 -298.115997) (xy 431.623239 -298.121894) (xy 431.6754 -298.13553)
			(xy 431.72502 -298.156617) (xy 431.771041 -298.184703) (xy 431.812483 -298.219191) (xy 431.848461 -298.259345)
			(xy 431.878209 -298.304309) (xy 431.901094 -298.353126) (xy 431.916626 -298.404755) (xy 431.924476 -298.458095)
			(xy 431.924968 -298.485052) (xy 438.730913 -298.485052) (xy 438.734848 -298.431281) (xy 438.746571 -298.378657)
			(xy 438.765831 -298.3283) (xy 438.792217 -298.281283) (xy 438.825169 -298.23861) (xy 438.863982 -298.201189)
			(xy 438.90783 -298.169819) (xy 438.955778 -298.145167) (xy 439.006805 -298.127759) (xy 439.059823 -298.117966)
			(xy 439.113702 -298.115997) (xy 439.167293 -298.121894) (xy 439.219454 -298.13553) (xy 439.269074 -298.156617)
			(xy 439.315095 -298.184703) (xy 439.356537 -298.219191) (xy 439.392515 -298.259345) (xy 439.422263 -298.304309)
			(xy 439.445148 -298.353126) (xy 439.46068 -298.404755) (xy 439.46853 -298.458095) (xy 439.469022 -298.485052)
			(xy 446.274967 -298.485052) (xy 446.278902 -298.431281) (xy 446.290625 -298.378657) (xy 446.309885 -298.3283)
			(xy 446.336271 -298.281283) (xy 446.369223 -298.23861) (xy 446.408036 -298.201189) (xy 446.451884 -298.169819)
			(xy 446.499832 -298.145167) (xy 446.550859 -298.127759) (xy 446.603877 -298.117966) (xy 446.657756 -298.115997)
			(xy 446.711347 -298.121894) (xy 446.763508 -298.13553) (xy 446.813128 -298.156617) (xy 446.859149 -298.184703)
			(xy 446.900591 -298.219191) (xy 446.936569 -298.259345) (xy 446.966317 -298.304309) (xy 446.989202 -298.353126)
			(xy 447.004734 -298.404755) (xy 447.012584 -298.458095) (xy 447.013076 -298.485052) (xy 453.818767 -298.485052)
			(xy 453.822702 -298.431281) (xy 453.834425 -298.378657) (xy 453.853685 -298.3283) (xy 453.880071 -298.281283)
			(xy 453.913023 -298.23861) (xy 453.951836 -298.201189) (xy 453.995684 -298.169819) (xy 454.043632 -298.145167)
			(xy 454.094659 -298.127759) (xy 454.147677 -298.117966) (xy 454.201556 -298.115997) (xy 454.255147 -298.121894)
			(xy 454.307308 -298.13553) (xy 454.356928 -298.156617) (xy 454.402949 -298.184703) (xy 454.444391 -298.219191)
			(xy 454.480369 -298.259345) (xy 454.510117 -298.304309) (xy 454.533002 -298.353126) (xy 454.548534 -298.404755)
			(xy 454.556384 -298.458095) (xy 454.556876 -298.485052) (xy 454.556384 -298.512009) (xy 454.548534 -298.565349)
			(xy 454.533002 -298.616978) (xy 454.510117 -298.665795) (xy 454.480369 -298.710759) (xy 454.444391 -298.750913)
			(xy 454.402949 -298.785401) (xy 454.356928 -298.813487) (xy 454.307308 -298.834574) (xy 454.255147 -298.84821)
			(xy 454.201556 -298.854107) (xy 454.147677 -298.852138) (xy 454.094659 -298.842345) (xy 454.043632 -298.824937)
			(xy 453.995684 -298.800285) (xy 453.951836 -298.768915) (xy 453.913023 -298.731494) (xy 453.880071 -298.688821)
			(xy 453.853685 -298.641804) (xy 453.834425 -298.591447) (xy 453.822702 -298.538823) (xy 453.818767 -298.485052)
			(xy 447.013076 -298.485052) (xy 447.012584 -298.512009) (xy 447.004734 -298.565349) (xy 446.989202 -298.616978)
			(xy 446.966317 -298.665795) (xy 446.936569 -298.710759) (xy 446.900591 -298.750913) (xy 446.859149 -298.785401)
			(xy 446.813128 -298.813487) (xy 446.763508 -298.834574) (xy 446.711347 -298.84821) (xy 446.657756 -298.854107)
			(xy 446.603877 -298.852138) (xy 446.550859 -298.842345) (xy 446.499832 -298.824937) (xy 446.451884 -298.800285)
			(xy 446.408036 -298.768915) (xy 446.369223 -298.731494) (xy 446.336271 -298.688821) (xy 446.309885 -298.641804)
			(xy 446.290625 -298.591447) (xy 446.278902 -298.538823) (xy 446.274967 -298.485052) (xy 439.469022 -298.485052)
			(xy 439.46853 -298.512009) (xy 439.46068 -298.565349) (xy 439.445148 -298.616978) (xy 439.422263 -298.665795)
			(xy 439.392515 -298.710759) (xy 439.356537 -298.750913) (xy 439.315095 -298.785401) (xy 439.269074 -298.813487)
			(xy 439.219454 -298.834574) (xy 439.167293 -298.84821) (xy 439.113702 -298.854107) (xy 439.059823 -298.852138)
			(xy 439.006805 -298.842345) (xy 438.955778 -298.824937) (xy 438.90783 -298.800285) (xy 438.863982 -298.768915)
			(xy 438.825169 -298.731494) (xy 438.792217 -298.688821) (xy 438.765831 -298.641804) (xy 438.746571 -298.591447)
			(xy 438.734848 -298.538823) (xy 438.730913 -298.485052) (xy 431.924968 -298.485052) (xy 431.924476 -298.512009)
			(xy 431.916626 -298.565349) (xy 431.901094 -298.616978) (xy 431.878209 -298.665795) (xy 431.848461 -298.710759)
			(xy 431.812483 -298.750913) (xy 431.771041 -298.785401) (xy 431.72502 -298.813487) (xy 431.6754 -298.834574)
			(xy 431.623239 -298.84821) (xy 431.569648 -298.854107) (xy 431.515769 -298.852138) (xy 431.462751 -298.842345)
			(xy 431.411724 -298.824937) (xy 431.363776 -298.800285) (xy 431.319928 -298.768915) (xy 431.281115 -298.731494)
			(xy 431.248163 -298.688821) (xy 431.221777 -298.641804) (xy 431.202517 -298.591447) (xy 431.190794 -298.538823)
			(xy 431.186859 -298.485052) (xy 425.985178 -298.485052) (xy 425.985178 -299.33519) (xy 427.086791 -299.33519)
			(xy 427.090726 -299.281419) (xy 427.102449 -299.228795) (xy 427.121709 -299.178438) (xy 427.148095 -299.131421)
			(xy 427.181047 -299.088748) (xy 427.21986 -299.051327) (xy 427.263708 -299.019957) (xy 427.311656 -298.995305)
			(xy 427.362683 -298.977897) (xy 427.415701 -298.968104) (xy 427.46958 -298.966135) (xy 427.523171 -298.972032)
			(xy 427.575332 -298.985668) (xy 427.624952 -299.006755) (xy 427.670973 -299.034841) (xy 427.712415 -299.069329)
			(xy 427.748393 -299.109483) (xy 427.778141 -299.154447) (xy 427.801026 -299.203264) (xy 427.816558 -299.254893)
			(xy 427.824408 -299.308233) (xy 427.8249 -299.33519) (xy 434.630845 -299.33519) (xy 434.63478 -299.281419)
			(xy 434.646503 -299.228795) (xy 434.665763 -299.178438) (xy 434.692149 -299.131421) (xy 434.725101 -299.088748)
			(xy 434.763914 -299.051327) (xy 434.807762 -299.019957) (xy 434.85571 -298.995305) (xy 434.906737 -298.977897)
			(xy 434.959755 -298.968104) (xy 435.013634 -298.966135) (xy 435.067225 -298.972032) (xy 435.119386 -298.985668)
			(xy 435.169006 -299.006755) (xy 435.215027 -299.034841) (xy 435.256469 -299.069329) (xy 435.292447 -299.109483)
			(xy 435.322195 -299.154447) (xy 435.34508 -299.203264) (xy 435.360612 -299.254893) (xy 435.368462 -299.308233)
			(xy 435.368954 -299.33519) (xy 442.174899 -299.33519) (xy 442.178834 -299.281419) (xy 442.190557 -299.228795)
			(xy 442.209817 -299.178438) (xy 442.236203 -299.131421) (xy 442.269155 -299.088748) (xy 442.307968 -299.051327)
			(xy 442.351816 -299.019957) (xy 442.399764 -298.995305) (xy 442.450791 -298.977897) (xy 442.503809 -298.968104)
			(xy 442.557688 -298.966135) (xy 442.611279 -298.972032) (xy 442.66344 -298.985668) (xy 442.71306 -299.006755)
			(xy 442.759081 -299.034841) (xy 442.800523 -299.069329) (xy 442.836501 -299.109483) (xy 442.866249 -299.154447)
			(xy 442.889134 -299.203264) (xy 442.904666 -299.254893) (xy 442.912516 -299.308233) (xy 442.913008 -299.33519)
			(xy 449.718699 -299.33519) (xy 449.722634 -299.281419) (xy 449.734357 -299.228795) (xy 449.753617 -299.178438)
			(xy 449.780003 -299.131421) (xy 449.812955 -299.088748) (xy 449.851768 -299.051327) (xy 449.895616 -299.019957)
			(xy 449.943564 -298.995305) (xy 449.994591 -298.977897) (xy 450.047609 -298.968104) (xy 450.101488 -298.966135)
			(xy 450.155079 -298.972032) (xy 450.20724 -298.985668) (xy 450.25686 -299.006755) (xy 450.302881 -299.034841)
			(xy 450.344323 -299.069329) (xy 450.380301 -299.109483) (xy 450.410049 -299.154447) (xy 450.432934 -299.203264)
			(xy 450.448466 -299.254893) (xy 450.456316 -299.308233) (xy 450.456808 -299.33519) (xy 450.456316 -299.362147)
			(xy 450.448466 -299.415487) (xy 450.432934 -299.467116) (xy 450.410049 -299.515933) (xy 450.380301 -299.560897)
			(xy 450.344323 -299.601051) (xy 450.302881 -299.635539) (xy 450.25686 -299.663625) (xy 450.20724 -299.684712)
			(xy 450.155079 -299.698348) (xy 450.101488 -299.704245) (xy 450.047609 -299.702276) (xy 449.994591 -299.692483)
			(xy 449.943564 -299.675075) (xy 449.895616 -299.650423) (xy 449.851768 -299.619053) (xy 449.812955 -299.581632)
			(xy 449.780003 -299.538959) (xy 449.753617 -299.491942) (xy 449.734357 -299.441585) (xy 449.722634 -299.388961)
			(xy 449.718699 -299.33519) (xy 442.913008 -299.33519) (xy 442.912516 -299.362147) (xy 442.904666 -299.415487)
			(xy 442.889134 -299.467116) (xy 442.866249 -299.515933) (xy 442.836501 -299.560897) (xy 442.800523 -299.601051)
			(xy 442.759081 -299.635539) (xy 442.71306 -299.663625) (xy 442.66344 -299.684712) (xy 442.611279 -299.698348)
			(xy 442.557688 -299.704245) (xy 442.503809 -299.702276) (xy 442.450791 -299.692483) (xy 442.399764 -299.675075)
			(xy 442.351816 -299.650423) (xy 442.307968 -299.619053) (xy 442.269155 -299.581632) (xy 442.236203 -299.538959)
			(xy 442.209817 -299.491942) (xy 442.190557 -299.441585) (xy 442.178834 -299.388961) (xy 442.174899 -299.33519)
			(xy 435.368954 -299.33519) (xy 435.368462 -299.362147) (xy 435.360612 -299.415487) (xy 435.34508 -299.467116)
			(xy 435.322195 -299.515933) (xy 435.292447 -299.560897) (xy 435.256469 -299.601051) (xy 435.215027 -299.635539)
			(xy 435.169006 -299.663625) (xy 435.119386 -299.684712) (xy 435.067225 -299.698348) (xy 435.013634 -299.704245)
			(xy 434.959755 -299.702276) (xy 434.906737 -299.692483) (xy 434.85571 -299.675075) (xy 434.807762 -299.650423)
			(xy 434.763914 -299.619053) (xy 434.725101 -299.581632) (xy 434.692149 -299.538959) (xy 434.665763 -299.491942)
			(xy 434.646503 -299.441585) (xy 434.63478 -299.388961) (xy 434.630845 -299.33519) (xy 427.8249 -299.33519)
			(xy 427.824408 -299.362147) (xy 427.816558 -299.415487) (xy 427.801026 -299.467116) (xy 427.778141 -299.515933)
			(xy 427.748393 -299.560897) (xy 427.712415 -299.601051) (xy 427.670973 -299.635539) (xy 427.624952 -299.663625)
			(xy 427.575332 -299.684712) (xy 427.523171 -299.698348) (xy 427.46958 -299.704245) (xy 427.415701 -299.702276)
			(xy 427.362683 -299.692483) (xy 427.311656 -299.675075) (xy 427.263708 -299.650423) (xy 427.21986 -299.619053)
			(xy 427.181047 -299.581632) (xy 427.148095 -299.538959) (xy 427.121709 -299.491942) (xy 427.102449 -299.441585)
			(xy 427.090726 -299.388961) (xy 427.086791 -299.33519) (xy 425.985178 -299.33519) (xy 425.985178 -300.185074)
			(xy 431.186859 -300.185074) (xy 431.190794 -300.131303) (xy 431.202517 -300.078679) (xy 431.221777 -300.028322)
			(xy 431.248163 -299.981305) (xy 431.281115 -299.938632) (xy 431.319928 -299.901211) (xy 431.363776 -299.869841)
			(xy 431.411724 -299.845189) (xy 431.462751 -299.827781) (xy 431.515769 -299.817988) (xy 431.569648 -299.816019)
			(xy 431.623239 -299.821916) (xy 431.6754 -299.835552) (xy 431.72502 -299.856639) (xy 431.771041 -299.884725)
			(xy 431.812483 -299.919213) (xy 431.848461 -299.959367) (xy 431.878209 -300.004331) (xy 431.901094 -300.053148)
			(xy 431.916626 -300.104777) (xy 431.924476 -300.158117) (xy 431.924968 -300.185074) (xy 438.730913 -300.185074)
			(xy 438.734848 -300.131303) (xy 438.746571 -300.078679) (xy 438.765831 -300.028322) (xy 438.792217 -299.981305)
			(xy 438.825169 -299.938632) (xy 438.863982 -299.901211) (xy 438.90783 -299.869841) (xy 438.955778 -299.845189)
			(xy 439.006805 -299.827781) (xy 439.059823 -299.817988) (xy 439.113702 -299.816019) (xy 439.167293 -299.821916)
			(xy 439.219454 -299.835552) (xy 439.269074 -299.856639) (xy 439.315095 -299.884725) (xy 439.356537 -299.919213)
			(xy 439.392515 -299.959367) (xy 439.422263 -300.004331) (xy 439.445148 -300.053148) (xy 439.46068 -300.104777)
			(xy 439.46853 -300.158117) (xy 439.469022 -300.185074) (xy 446.274967 -300.185074) (xy 446.278902 -300.131303)
			(xy 446.290625 -300.078679) (xy 446.309885 -300.028322) (xy 446.336271 -299.981305) (xy 446.369223 -299.938632)
			(xy 446.408036 -299.901211) (xy 446.451884 -299.869841) (xy 446.499832 -299.845189) (xy 446.550859 -299.827781)
			(xy 446.603877 -299.817988) (xy 446.657756 -299.816019) (xy 446.711347 -299.821916) (xy 446.763508 -299.835552)
			(xy 446.813128 -299.856639) (xy 446.859149 -299.884725) (xy 446.900591 -299.919213) (xy 446.936569 -299.959367)
			(xy 446.966317 -300.004331) (xy 446.989202 -300.053148) (xy 447.004734 -300.104777) (xy 447.012584 -300.158117)
			(xy 447.013076 -300.185074) (xy 453.818767 -300.185074) (xy 453.822702 -300.131303) (xy 453.834425 -300.078679)
			(xy 453.853685 -300.028322) (xy 453.880071 -299.981305) (xy 453.913023 -299.938632) (xy 453.951836 -299.901211)
			(xy 453.995684 -299.869841) (xy 454.043632 -299.845189) (xy 454.094659 -299.827781) (xy 454.147677 -299.817988)
			(xy 454.201556 -299.816019) (xy 454.255147 -299.821916) (xy 454.307308 -299.835552) (xy 454.356928 -299.856639)
			(xy 454.402949 -299.884725) (xy 454.444391 -299.919213) (xy 454.480369 -299.959367) (xy 454.510117 -300.004331)
			(xy 454.533002 -300.053148) (xy 454.548534 -300.104777) (xy 454.556384 -300.158117) (xy 454.556876 -300.185074)
			(xy 454.556384 -300.212031) (xy 454.548534 -300.265371) (xy 454.533002 -300.317) (xy 454.510117 -300.365817)
			(xy 454.480369 -300.410781) (xy 454.444391 -300.450935) (xy 454.402949 -300.485423) (xy 454.356928 -300.513509)
			(xy 454.307308 -300.534596) (xy 454.255147 -300.548232) (xy 454.201556 -300.554129) (xy 454.147677 -300.55216)
			(xy 454.094659 -300.542367) (xy 454.043632 -300.524959) (xy 453.995684 -300.500307) (xy 453.951836 -300.468937)
			(xy 453.913023 -300.431516) (xy 453.880071 -300.388843) (xy 453.853685 -300.341826) (xy 453.834425 -300.291469)
			(xy 453.822702 -300.238845) (xy 453.818767 -300.185074) (xy 447.013076 -300.185074) (xy 447.012584 -300.212031)
			(xy 447.004734 -300.265371) (xy 446.989202 -300.317) (xy 446.966317 -300.365817) (xy 446.936569 -300.410781)
			(xy 446.900591 -300.450935) (xy 446.859149 -300.485423) (xy 446.813128 -300.513509) (xy 446.763508 -300.534596)
			(xy 446.711347 -300.548232) (xy 446.657756 -300.554129) (xy 446.603877 -300.55216) (xy 446.550859 -300.542367)
			(xy 446.499832 -300.524959) (xy 446.451884 -300.500307) (xy 446.408036 -300.468937) (xy 446.369223 -300.431516)
			(xy 446.336271 -300.388843) (xy 446.309885 -300.341826) (xy 446.290625 -300.291469) (xy 446.278902 -300.238845)
			(xy 446.274967 -300.185074) (xy 439.469022 -300.185074) (xy 439.46853 -300.212031) (xy 439.46068 -300.265371)
			(xy 439.445148 -300.317) (xy 439.422263 -300.365817) (xy 439.392515 -300.410781) (xy 439.356537 -300.450935)
			(xy 439.315095 -300.485423) (xy 439.269074 -300.513509) (xy 439.219454 -300.534596) (xy 439.167293 -300.548232)
			(xy 439.113702 -300.554129) (xy 439.059823 -300.55216) (xy 439.006805 -300.542367) (xy 438.955778 -300.524959)
			(xy 438.90783 -300.500307) (xy 438.863982 -300.468937) (xy 438.825169 -300.431516) (xy 438.792217 -300.388843)
			(xy 438.765831 -300.341826) (xy 438.746571 -300.291469) (xy 438.734848 -300.238845) (xy 438.730913 -300.185074)
			(xy 431.924968 -300.185074) (xy 431.924476 -300.212031) (xy 431.916626 -300.265371) (xy 431.901094 -300.317)
			(xy 431.878209 -300.365817) (xy 431.848461 -300.410781) (xy 431.812483 -300.450935) (xy 431.771041 -300.485423)
			(xy 431.72502 -300.513509) (xy 431.6754 -300.534596) (xy 431.623239 -300.548232) (xy 431.569648 -300.554129)
			(xy 431.515769 -300.55216) (xy 431.462751 -300.542367) (xy 431.411724 -300.524959) (xy 431.363776 -300.500307)
			(xy 431.319928 -300.468937) (xy 431.281115 -300.431516) (xy 431.248163 -300.388843) (xy 431.221777 -300.341826)
			(xy 431.202517 -300.291469) (xy 431.190794 -300.238845) (xy 431.186859 -300.185074) (xy 425.985178 -300.185074)
			(xy 425.985178 -301.034958) (xy 427.086791 -301.034958) (xy 427.090726 -300.981187) (xy 427.102449 -300.928563)
			(xy 427.121709 -300.878206) (xy 427.148095 -300.831189) (xy 427.181047 -300.788516) (xy 427.21986 -300.751095)
			(xy 427.263708 -300.719725) (xy 427.311656 -300.695073) (xy 427.362683 -300.677665) (xy 427.415701 -300.667872)
			(xy 427.46958 -300.665903) (xy 427.523171 -300.6718) (xy 427.575332 -300.685436) (xy 427.624952 -300.706523)
			(xy 427.670973 -300.734609) (xy 427.712415 -300.769097) (xy 427.748393 -300.809251) (xy 427.778141 -300.854215)
			(xy 427.801026 -300.903032) (xy 427.816558 -300.954661) (xy 427.824408 -301.008001) (xy 427.8249 -301.034958)
			(xy 434.630845 -301.034958) (xy 434.63478 -300.981187) (xy 434.646503 -300.928563) (xy 434.665763 -300.878206)
			(xy 434.692149 -300.831189) (xy 434.725101 -300.788516) (xy 434.763914 -300.751095) (xy 434.807762 -300.719725)
			(xy 434.85571 -300.695073) (xy 434.906737 -300.677665) (xy 434.959755 -300.667872) (xy 435.013634 -300.665903)
			(xy 435.067225 -300.6718) (xy 435.119386 -300.685436) (xy 435.169006 -300.706523) (xy 435.215027 -300.734609)
			(xy 435.256469 -300.769097) (xy 435.292447 -300.809251) (xy 435.322195 -300.854215) (xy 435.34508 -300.903032)
			(xy 435.360612 -300.954661) (xy 435.368462 -301.008001) (xy 435.368954 -301.034958) (xy 442.174899 -301.034958)
			(xy 442.178834 -300.981187) (xy 442.190557 -300.928563) (xy 442.209817 -300.878206) (xy 442.236203 -300.831189)
			(xy 442.269155 -300.788516) (xy 442.307968 -300.751095) (xy 442.351816 -300.719725) (xy 442.399764 -300.695073)
			(xy 442.450791 -300.677665) (xy 442.503809 -300.667872) (xy 442.557688 -300.665903) (xy 442.611279 -300.6718)
			(xy 442.66344 -300.685436) (xy 442.71306 -300.706523) (xy 442.759081 -300.734609) (xy 442.800523 -300.769097)
			(xy 442.836501 -300.809251) (xy 442.866249 -300.854215) (xy 442.889134 -300.903032) (xy 442.904666 -300.954661)
			(xy 442.912516 -301.008001) (xy 442.913008 -301.034958) (xy 449.718699 -301.034958) (xy 449.722634 -300.981187)
			(xy 449.734357 -300.928563) (xy 449.753617 -300.878206) (xy 449.780003 -300.831189) (xy 449.812955 -300.788516)
			(xy 449.851768 -300.751095) (xy 449.895616 -300.719725) (xy 449.943564 -300.695073) (xy 449.994591 -300.677665)
			(xy 450.047609 -300.667872) (xy 450.101488 -300.665903) (xy 450.155079 -300.6718) (xy 450.20724 -300.685436)
			(xy 450.25686 -300.706523) (xy 450.302881 -300.734609) (xy 450.344323 -300.769097) (xy 450.380301 -300.809251)
			(xy 450.410049 -300.854215) (xy 450.432934 -300.903032) (xy 450.448466 -300.954661) (xy 450.456316 -301.008001)
			(xy 450.456808 -301.034958) (xy 450.456316 -301.061915) (xy 450.448466 -301.115255) (xy 450.432934 -301.166884)
			(xy 450.410049 -301.215701) (xy 450.380301 -301.260665) (xy 450.344323 -301.300819) (xy 450.302881 -301.335307)
			(xy 450.25686 -301.363393) (xy 450.20724 -301.38448) (xy 450.155079 -301.398116) (xy 450.101488 -301.404013)
			(xy 450.047609 -301.402044) (xy 449.994591 -301.392251) (xy 449.943564 -301.374843) (xy 449.895616 -301.350191)
			(xy 449.851768 -301.318821) (xy 449.812955 -301.2814) (xy 449.780003 -301.238727) (xy 449.753617 -301.19171)
			(xy 449.734357 -301.141353) (xy 449.722634 -301.088729) (xy 449.718699 -301.034958) (xy 442.913008 -301.034958)
			(xy 442.912516 -301.061915) (xy 442.904666 -301.115255) (xy 442.889134 -301.166884) (xy 442.866249 -301.215701)
			(xy 442.836501 -301.260665) (xy 442.800523 -301.300819) (xy 442.759081 -301.335307) (xy 442.71306 -301.363393)
			(xy 442.66344 -301.38448) (xy 442.611279 -301.398116) (xy 442.557688 -301.404013) (xy 442.503809 -301.402044)
			(xy 442.450791 -301.392251) (xy 442.399764 -301.374843) (xy 442.351816 -301.350191) (xy 442.307968 -301.318821)
			(xy 442.269155 -301.2814) (xy 442.236203 -301.238727) (xy 442.209817 -301.19171) (xy 442.190557 -301.141353)
			(xy 442.178834 -301.088729) (xy 442.174899 -301.034958) (xy 435.368954 -301.034958) (xy 435.368462 -301.061915)
			(xy 435.360612 -301.115255) (xy 435.34508 -301.166884) (xy 435.322195 -301.215701) (xy 435.292447 -301.260665)
			(xy 435.256469 -301.300819) (xy 435.215027 -301.335307) (xy 435.169006 -301.363393) (xy 435.119386 -301.38448)
			(xy 435.067225 -301.398116) (xy 435.013634 -301.404013) (xy 434.959755 -301.402044) (xy 434.906737 -301.392251)
			(xy 434.85571 -301.374843) (xy 434.807762 -301.350191) (xy 434.763914 -301.318821) (xy 434.725101 -301.2814)
			(xy 434.692149 -301.238727) (xy 434.665763 -301.19171) (xy 434.646503 -301.141353) (xy 434.63478 -301.088729)
			(xy 434.630845 -301.034958) (xy 427.8249 -301.034958) (xy 427.824408 -301.061915) (xy 427.816558 -301.115255)
			(xy 427.801026 -301.166884) (xy 427.778141 -301.215701) (xy 427.748393 -301.260665) (xy 427.712415 -301.300819)
			(xy 427.670973 -301.335307) (xy 427.624952 -301.363393) (xy 427.575332 -301.38448) (xy 427.523171 -301.398116)
			(xy 427.46958 -301.404013) (xy 427.415701 -301.402044) (xy 427.362683 -301.392251) (xy 427.311656 -301.374843)
			(xy 427.263708 -301.350191) (xy 427.21986 -301.318821) (xy 427.181047 -301.2814) (xy 427.148095 -301.238727)
			(xy 427.121709 -301.19171) (xy 427.102449 -301.141353) (xy 427.090726 -301.088729) (xy 427.086791 -301.034958)
			(xy 425.985178 -301.034958) (xy 425.985178 -301.885096) (xy 431.186859 -301.885096) (xy 431.190794 -301.831325)
			(xy 431.202517 -301.778701) (xy 431.221777 -301.728344) (xy 431.248163 -301.681327) (xy 431.281115 -301.638654)
			(xy 431.319928 -301.601233) (xy 431.363776 -301.569863) (xy 431.411724 -301.545211) (xy 431.462751 -301.527803)
			(xy 431.515769 -301.51801) (xy 431.569648 -301.516041) (xy 431.623239 -301.521938) (xy 431.6754 -301.535574)
			(xy 431.72502 -301.556661) (xy 431.771041 -301.584747) (xy 431.812483 -301.619235) (xy 431.848461 -301.659389)
			(xy 431.878209 -301.704353) (xy 431.901094 -301.75317) (xy 431.916626 -301.804799) (xy 431.924476 -301.858139)
			(xy 431.924968 -301.885096) (xy 438.730913 -301.885096) (xy 438.734848 -301.831325) (xy 438.746571 -301.778701)
			(xy 438.765831 -301.728344) (xy 438.792217 -301.681327) (xy 438.825169 -301.638654) (xy 438.863982 -301.601233)
			(xy 438.90783 -301.569863) (xy 438.955778 -301.545211) (xy 439.006805 -301.527803) (xy 439.059823 -301.51801)
			(xy 439.113702 -301.516041) (xy 439.167293 -301.521938) (xy 439.219454 -301.535574) (xy 439.269074 -301.556661)
			(xy 439.315095 -301.584747) (xy 439.356537 -301.619235) (xy 439.392515 -301.659389) (xy 439.422263 -301.704353)
			(xy 439.445148 -301.75317) (xy 439.46068 -301.804799) (xy 439.46853 -301.858139) (xy 439.469022 -301.885096)
			(xy 446.274967 -301.885096) (xy 446.278902 -301.831325) (xy 446.290625 -301.778701) (xy 446.309885 -301.728344)
			(xy 446.336271 -301.681327) (xy 446.369223 -301.638654) (xy 446.408036 -301.601233) (xy 446.451884 -301.569863)
			(xy 446.499832 -301.545211) (xy 446.550859 -301.527803) (xy 446.603877 -301.51801) (xy 446.657756 -301.516041)
			(xy 446.711347 -301.521938) (xy 446.763508 -301.535574) (xy 446.813128 -301.556661) (xy 446.859149 -301.584747)
			(xy 446.900591 -301.619235) (xy 446.936569 -301.659389) (xy 446.966317 -301.704353) (xy 446.989202 -301.75317)
			(xy 447.004734 -301.804799) (xy 447.012584 -301.858139) (xy 447.013076 -301.885096) (xy 453.818767 -301.885096)
			(xy 453.822702 -301.831325) (xy 453.834425 -301.778701) (xy 453.853685 -301.728344) (xy 453.880071 -301.681327)
			(xy 453.913023 -301.638654) (xy 453.951836 -301.601233) (xy 453.995684 -301.569863) (xy 454.043632 -301.545211)
			(xy 454.094659 -301.527803) (xy 454.147677 -301.51801) (xy 454.201556 -301.516041) (xy 454.255147 -301.521938)
			(xy 454.307308 -301.535574) (xy 454.356928 -301.556661) (xy 454.402949 -301.584747) (xy 454.444391 -301.619235)
			(xy 454.480369 -301.659389) (xy 454.510117 -301.704353) (xy 454.533002 -301.75317) (xy 454.548534 -301.804799)
			(xy 454.556384 -301.858139) (xy 454.556876 -301.885096) (xy 454.556384 -301.912053) (xy 454.548534 -301.965393)
			(xy 454.533002 -302.017022) (xy 454.510117 -302.065839) (xy 454.480369 -302.110803) (xy 454.444391 -302.150957)
			(xy 454.402949 -302.185445) (xy 454.356928 -302.213531) (xy 454.307308 -302.234618) (xy 454.255147 -302.248254)
			(xy 454.201556 -302.254151) (xy 454.147677 -302.252182) (xy 454.094659 -302.242389) (xy 454.043632 -302.224981)
			(xy 453.995684 -302.200329) (xy 453.951836 -302.168959) (xy 453.913023 -302.131538) (xy 453.880071 -302.088865)
			(xy 453.853685 -302.041848) (xy 453.834425 -301.991491) (xy 453.822702 -301.938867) (xy 453.818767 -301.885096)
			(xy 447.013076 -301.885096) (xy 447.012584 -301.912053) (xy 447.004734 -301.965393) (xy 446.989202 -302.017022)
			(xy 446.966317 -302.065839) (xy 446.936569 -302.110803) (xy 446.900591 -302.150957) (xy 446.859149 -302.185445)
			(xy 446.813128 -302.213531) (xy 446.763508 -302.234618) (xy 446.711347 -302.248254) (xy 446.657756 -302.254151)
			(xy 446.603877 -302.252182) (xy 446.550859 -302.242389) (xy 446.499832 -302.224981) (xy 446.451884 -302.200329)
			(xy 446.408036 -302.168959) (xy 446.369223 -302.131538) (xy 446.336271 -302.088865) (xy 446.309885 -302.041848)
			(xy 446.290625 -301.991491) (xy 446.278902 -301.938867) (xy 446.274967 -301.885096) (xy 439.469022 -301.885096)
			(xy 439.46853 -301.912053) (xy 439.46068 -301.965393) (xy 439.445148 -302.017022) (xy 439.422263 -302.065839)
			(xy 439.392515 -302.110803) (xy 439.356537 -302.150957) (xy 439.315095 -302.185445) (xy 439.269074 -302.213531)
			(xy 439.219454 -302.234618) (xy 439.167293 -302.248254) (xy 439.113702 -302.254151) (xy 439.059823 -302.252182)
			(xy 439.006805 -302.242389) (xy 438.955778 -302.224981) (xy 438.90783 -302.200329) (xy 438.863982 -302.168959)
			(xy 438.825169 -302.131538) (xy 438.792217 -302.088865) (xy 438.765831 -302.041848) (xy 438.746571 -301.991491)
			(xy 438.734848 -301.938867) (xy 438.730913 -301.885096) (xy 431.924968 -301.885096) (xy 431.924476 -301.912053)
			(xy 431.916626 -301.965393) (xy 431.901094 -302.017022) (xy 431.878209 -302.065839) (xy 431.848461 -302.110803)
			(xy 431.812483 -302.150957) (xy 431.771041 -302.185445) (xy 431.72502 -302.213531) (xy 431.6754 -302.234618)
			(xy 431.623239 -302.248254) (xy 431.569648 -302.254151) (xy 431.515769 -302.252182) (xy 431.462751 -302.242389)
			(xy 431.411724 -302.224981) (xy 431.363776 -302.200329) (xy 431.319928 -302.168959) (xy 431.281115 -302.131538)
			(xy 431.248163 -302.088865) (xy 431.221777 -302.041848) (xy 431.202517 -301.991491) (xy 431.190794 -301.938867)
			(xy 431.186859 -301.885096) (xy 425.985178 -301.885096) (xy 425.985178 -302.73498) (xy 427.086791 -302.73498)
			(xy 427.090726 -302.681209) (xy 427.102449 -302.628585) (xy 427.121709 -302.578228) (xy 427.148095 -302.531211)
			(xy 427.181047 -302.488538) (xy 427.21986 -302.451117) (xy 427.263708 -302.419747) (xy 427.311656 -302.395095)
			(xy 427.362683 -302.377687) (xy 427.415701 -302.367894) (xy 427.46958 -302.365925) (xy 427.523171 -302.371822)
			(xy 427.575332 -302.385458) (xy 427.624952 -302.406545) (xy 427.670973 -302.434631) (xy 427.712415 -302.469119)
			(xy 427.748393 -302.509273) (xy 427.778141 -302.554237) (xy 427.801026 -302.603054) (xy 427.816558 -302.654683)
			(xy 427.824408 -302.708023) (xy 427.8249 -302.73498) (xy 434.630845 -302.73498) (xy 434.63478 -302.681209)
			(xy 434.646503 -302.628585) (xy 434.665763 -302.578228) (xy 434.692149 -302.531211) (xy 434.725101 -302.488538)
			(xy 434.763914 -302.451117) (xy 434.807762 -302.419747) (xy 434.85571 -302.395095) (xy 434.906737 -302.377687)
			(xy 434.959755 -302.367894) (xy 435.013634 -302.365925) (xy 435.067225 -302.371822) (xy 435.119386 -302.385458)
			(xy 435.169006 -302.406545) (xy 435.215027 -302.434631) (xy 435.256469 -302.469119) (xy 435.292447 -302.509273)
			(xy 435.322195 -302.554237) (xy 435.34508 -302.603054) (xy 435.360612 -302.654683) (xy 435.368462 -302.708023)
			(xy 435.368954 -302.73498) (xy 442.174899 -302.73498) (xy 442.178834 -302.681209) (xy 442.190557 -302.628585)
			(xy 442.209817 -302.578228) (xy 442.236203 -302.531211) (xy 442.269155 -302.488538) (xy 442.307968 -302.451117)
			(xy 442.351816 -302.419747) (xy 442.399764 -302.395095) (xy 442.450791 -302.377687) (xy 442.503809 -302.367894)
			(xy 442.557688 -302.365925) (xy 442.611279 -302.371822) (xy 442.66344 -302.385458) (xy 442.71306 -302.406545)
			(xy 442.759081 -302.434631) (xy 442.800523 -302.469119) (xy 442.836501 -302.509273) (xy 442.866249 -302.554237)
			(xy 442.889134 -302.603054) (xy 442.904666 -302.654683) (xy 442.912516 -302.708023) (xy 442.913008 -302.73498)
			(xy 449.718699 -302.73498) (xy 449.722634 -302.681209) (xy 449.734357 -302.628585) (xy 449.753617 -302.578228)
			(xy 449.780003 -302.531211) (xy 449.812955 -302.488538) (xy 449.851768 -302.451117) (xy 449.895616 -302.419747)
			(xy 449.943564 -302.395095) (xy 449.994591 -302.377687) (xy 450.047609 -302.367894) (xy 450.101488 -302.365925)
			(xy 450.155079 -302.371822) (xy 450.20724 -302.385458) (xy 450.25686 -302.406545) (xy 450.302881 -302.434631)
			(xy 450.344323 -302.469119) (xy 450.380301 -302.509273) (xy 450.410049 -302.554237) (xy 450.432934 -302.603054)
			(xy 450.448466 -302.654683) (xy 450.456316 -302.708023) (xy 450.456808 -302.73498) (xy 450.456316 -302.761937)
			(xy 450.448466 -302.815277) (xy 450.432934 -302.866906) (xy 450.410049 -302.915723) (xy 450.380301 -302.960687)
			(xy 450.344323 -303.000841) (xy 450.302881 -303.035329) (xy 450.25686 -303.063415) (xy 450.20724 -303.084502)
			(xy 450.155079 -303.098138) (xy 450.101488 -303.104035) (xy 450.047609 -303.102066) (xy 449.994591 -303.092273)
			(xy 449.943564 -303.074865) (xy 449.895616 -303.050213) (xy 449.851768 -303.018843) (xy 449.812955 -302.981422)
			(xy 449.780003 -302.938749) (xy 449.753617 -302.891732) (xy 449.734357 -302.841375) (xy 449.722634 -302.788751)
			(xy 449.718699 -302.73498) (xy 442.913008 -302.73498) (xy 442.912516 -302.761937) (xy 442.904666 -302.815277)
			(xy 442.889134 -302.866906) (xy 442.866249 -302.915723) (xy 442.836501 -302.960687) (xy 442.800523 -303.000841)
			(xy 442.759081 -303.035329) (xy 442.71306 -303.063415) (xy 442.66344 -303.084502) (xy 442.611279 -303.098138)
			(xy 442.557688 -303.104035) (xy 442.503809 -303.102066) (xy 442.450791 -303.092273) (xy 442.399764 -303.074865)
			(xy 442.351816 -303.050213) (xy 442.307968 -303.018843) (xy 442.269155 -302.981422) (xy 442.236203 -302.938749)
			(xy 442.209817 -302.891732) (xy 442.190557 -302.841375) (xy 442.178834 -302.788751) (xy 442.174899 -302.73498)
			(xy 435.368954 -302.73498) (xy 435.368462 -302.761937) (xy 435.360612 -302.815277) (xy 435.34508 -302.866906)
			(xy 435.322195 -302.915723) (xy 435.292447 -302.960687) (xy 435.256469 -303.000841) (xy 435.215027 -303.035329)
			(xy 435.169006 -303.063415) (xy 435.119386 -303.084502) (xy 435.067225 -303.098138) (xy 435.013634 -303.104035)
			(xy 434.959755 -303.102066) (xy 434.906737 -303.092273) (xy 434.85571 -303.074865) (xy 434.807762 -303.050213)
			(xy 434.763914 -303.018843) (xy 434.725101 -302.981422) (xy 434.692149 -302.938749) (xy 434.665763 -302.891732)
			(xy 434.646503 -302.841375) (xy 434.63478 -302.788751) (xy 434.630845 -302.73498) (xy 427.8249 -302.73498)
			(xy 427.824408 -302.761937) (xy 427.816558 -302.815277) (xy 427.801026 -302.866906) (xy 427.778141 -302.915723)
			(xy 427.748393 -302.960687) (xy 427.712415 -303.000841) (xy 427.670973 -303.035329) (xy 427.624952 -303.063415)
			(xy 427.575332 -303.084502) (xy 427.523171 -303.098138) (xy 427.46958 -303.104035) (xy 427.415701 -303.102066)
			(xy 427.362683 -303.092273) (xy 427.311656 -303.074865) (xy 427.263708 -303.050213) (xy 427.21986 -303.018843)
			(xy 427.181047 -302.981422) (xy 427.148095 -302.938749) (xy 427.121709 -302.891732) (xy 427.102449 -302.841375)
			(xy 427.090726 -302.788751) (xy 427.086791 -302.73498) (xy 425.985178 -302.73498) (xy 425.985178 -303.585118)
			(xy 431.186859 -303.585118) (xy 431.190794 -303.531347) (xy 431.202517 -303.478723) (xy 431.221777 -303.428366)
			(xy 431.248163 -303.381349) (xy 431.281115 -303.338676) (xy 431.319928 -303.301255) (xy 431.363776 -303.269885)
			(xy 431.411724 -303.245233) (xy 431.462751 -303.227825) (xy 431.515769 -303.218032) (xy 431.569648 -303.216063)
			(xy 431.623239 -303.22196) (xy 431.6754 -303.235596) (xy 431.72502 -303.256683) (xy 431.771041 -303.284769)
			(xy 431.812483 -303.319257) (xy 431.848461 -303.359411) (xy 431.878209 -303.404375) (xy 431.901094 -303.453192)
			(xy 431.916626 -303.504821) (xy 431.924476 -303.558161) (xy 431.924968 -303.585118) (xy 438.730913 -303.585118)
			(xy 438.734848 -303.531347) (xy 438.746571 -303.478723) (xy 438.765831 -303.428366) (xy 438.792217 -303.381349)
			(xy 438.825169 -303.338676) (xy 438.863982 -303.301255) (xy 438.90783 -303.269885) (xy 438.955778 -303.245233)
			(xy 439.006805 -303.227825) (xy 439.059823 -303.218032) (xy 439.113702 -303.216063) (xy 439.167293 -303.22196)
			(xy 439.219454 -303.235596) (xy 439.269074 -303.256683) (xy 439.315095 -303.284769) (xy 439.356537 -303.319257)
			(xy 439.392515 -303.359411) (xy 439.422263 -303.404375) (xy 439.445148 -303.453192) (xy 439.46068 -303.504821)
			(xy 439.46853 -303.558161) (xy 439.469022 -303.585118) (xy 446.274967 -303.585118) (xy 446.278902 -303.531347)
			(xy 446.290625 -303.478723) (xy 446.309885 -303.428366) (xy 446.336271 -303.381349) (xy 446.369223 -303.338676)
			(xy 446.408036 -303.301255) (xy 446.451884 -303.269885) (xy 446.499832 -303.245233) (xy 446.550859 -303.227825)
			(xy 446.603877 -303.218032) (xy 446.657756 -303.216063) (xy 446.711347 -303.22196) (xy 446.763508 -303.235596)
			(xy 446.813128 -303.256683) (xy 446.859149 -303.284769) (xy 446.900591 -303.319257) (xy 446.936569 -303.359411)
			(xy 446.966317 -303.404375) (xy 446.989202 -303.453192) (xy 447.004734 -303.504821) (xy 447.012584 -303.558161)
			(xy 447.013076 -303.585118) (xy 453.818767 -303.585118) (xy 453.822702 -303.531347) (xy 453.834425 -303.478723)
			(xy 453.853685 -303.428366) (xy 453.880071 -303.381349) (xy 453.913023 -303.338676) (xy 453.951836 -303.301255)
			(xy 453.995684 -303.269885) (xy 454.043632 -303.245233) (xy 454.094659 -303.227825) (xy 454.147677 -303.218032)
			(xy 454.201556 -303.216063) (xy 454.255147 -303.22196) (xy 454.307308 -303.235596) (xy 454.356928 -303.256683)
			(xy 454.402949 -303.284769) (xy 454.444391 -303.319257) (xy 454.480369 -303.359411) (xy 454.510117 -303.404375)
			(xy 454.533002 -303.453192) (xy 454.548534 -303.504821) (xy 454.556384 -303.558161) (xy 454.556876 -303.585118)
			(xy 454.556384 -303.612075) (xy 454.548534 -303.665415) (xy 454.533002 -303.717044) (xy 454.510117 -303.765861)
			(xy 454.480369 -303.810825) (xy 454.444391 -303.850979) (xy 454.402949 -303.885467) (xy 454.356928 -303.913553)
			(xy 454.307308 -303.93464) (xy 454.255147 -303.948276) (xy 454.201556 -303.954173) (xy 454.147677 -303.952204)
			(xy 454.094659 -303.942411) (xy 454.043632 -303.925003) (xy 453.995684 -303.900351) (xy 453.951836 -303.868981)
			(xy 453.913023 -303.83156) (xy 453.880071 -303.788887) (xy 453.853685 -303.74187) (xy 453.834425 -303.691513)
			(xy 453.822702 -303.638889) (xy 453.818767 -303.585118) (xy 447.013076 -303.585118) (xy 447.012584 -303.612075)
			(xy 447.004734 -303.665415) (xy 446.989202 -303.717044) (xy 446.966317 -303.765861) (xy 446.936569 -303.810825)
			(xy 446.900591 -303.850979) (xy 446.859149 -303.885467) (xy 446.813128 -303.913553) (xy 446.763508 -303.93464)
			(xy 446.711347 -303.948276) (xy 446.657756 -303.954173) (xy 446.603877 -303.952204) (xy 446.550859 -303.942411)
			(xy 446.499832 -303.925003) (xy 446.451884 -303.900351) (xy 446.408036 -303.868981) (xy 446.369223 -303.83156)
			(xy 446.336271 -303.788887) (xy 446.309885 -303.74187) (xy 446.290625 -303.691513) (xy 446.278902 -303.638889)
			(xy 446.274967 -303.585118) (xy 439.469022 -303.585118) (xy 439.46853 -303.612075) (xy 439.46068 -303.665415)
			(xy 439.445148 -303.717044) (xy 439.422263 -303.765861) (xy 439.392515 -303.810825) (xy 439.356537 -303.850979)
			(xy 439.315095 -303.885467) (xy 439.269074 -303.913553) (xy 439.219454 -303.93464) (xy 439.167293 -303.948276)
			(xy 439.113702 -303.954173) (xy 439.059823 -303.952204) (xy 439.006805 -303.942411) (xy 438.955778 -303.925003)
			(xy 438.90783 -303.900351) (xy 438.863982 -303.868981) (xy 438.825169 -303.83156) (xy 438.792217 -303.788887)
			(xy 438.765831 -303.74187) (xy 438.746571 -303.691513) (xy 438.734848 -303.638889) (xy 438.730913 -303.585118)
			(xy 431.924968 -303.585118) (xy 431.924476 -303.612075) (xy 431.916626 -303.665415) (xy 431.901094 -303.717044)
			(xy 431.878209 -303.765861) (xy 431.848461 -303.810825) (xy 431.812483 -303.850979) (xy 431.771041 -303.885467)
			(xy 431.72502 -303.913553) (xy 431.6754 -303.93464) (xy 431.623239 -303.948276) (xy 431.569648 -303.954173)
			(xy 431.515769 -303.952204) (xy 431.462751 -303.942411) (xy 431.411724 -303.925003) (xy 431.363776 -303.900351)
			(xy 431.319928 -303.868981) (xy 431.281115 -303.83156) (xy 431.248163 -303.788887) (xy 431.221777 -303.74187)
			(xy 431.202517 -303.691513) (xy 431.190794 -303.638889) (xy 431.186859 -303.585118) (xy 425.985178 -303.585118)
			(xy 425.985178 -304.435002) (xy 427.086791 -304.435002) (xy 427.090726 -304.381231) (xy 427.102449 -304.328607)
			(xy 427.121709 -304.27825) (xy 427.148095 -304.231233) (xy 427.181047 -304.18856) (xy 427.21986 -304.151139)
			(xy 427.263708 -304.119769) (xy 427.311656 -304.095117) (xy 427.362683 -304.077709) (xy 427.415701 -304.067916)
			(xy 427.46958 -304.065947) (xy 427.523171 -304.071844) (xy 427.575332 -304.08548) (xy 427.624952 -304.106567)
			(xy 427.670973 -304.134653) (xy 427.712415 -304.169141) (xy 427.748393 -304.209295) (xy 427.778141 -304.254259)
			(xy 427.801026 -304.303076) (xy 427.816558 -304.354705) (xy 427.824408 -304.408045) (xy 427.8249 -304.435002)
			(xy 431.186859 -304.435002) (xy 431.190794 -304.381231) (xy 431.202517 -304.328607) (xy 431.221777 -304.27825)
			(xy 431.248163 -304.231233) (xy 431.281115 -304.18856) (xy 431.319928 -304.151139) (xy 431.363776 -304.119769)
			(xy 431.411724 -304.095117) (xy 431.462751 -304.077709) (xy 431.515769 -304.067916) (xy 431.569648 -304.065947)
			(xy 431.623239 -304.071844) (xy 431.6754 -304.08548) (xy 431.72502 -304.106567) (xy 431.771041 -304.134653)
			(xy 431.812483 -304.169141) (xy 431.848461 -304.209295) (xy 431.878209 -304.254259) (xy 431.901094 -304.303076)
			(xy 431.916626 -304.354705) (xy 431.924476 -304.408045) (xy 431.924968 -304.435002) (xy 434.630845 -304.435002)
			(xy 434.63478 -304.381231) (xy 434.646503 -304.328607) (xy 434.665763 -304.27825) (xy 434.692149 -304.231233)
			(xy 434.725101 -304.18856) (xy 434.763914 -304.151139) (xy 434.807762 -304.119769) (xy 434.85571 -304.095117)
			(xy 434.906737 -304.077709) (xy 434.959755 -304.067916) (xy 435.013634 -304.065947) (xy 435.067225 -304.071844)
			(xy 435.119386 -304.08548) (xy 435.169006 -304.106567) (xy 435.215027 -304.134653) (xy 435.256469 -304.169141)
			(xy 435.292447 -304.209295) (xy 435.322195 -304.254259) (xy 435.34508 -304.303076) (xy 435.360612 -304.354705)
			(xy 435.368462 -304.408045) (xy 435.368954 -304.435002) (xy 438.730913 -304.435002) (xy 438.734848 -304.381231)
			(xy 438.746571 -304.328607) (xy 438.765831 -304.27825) (xy 438.792217 -304.231233) (xy 438.825169 -304.18856)
			(xy 438.863982 -304.151139) (xy 438.90783 -304.119769) (xy 438.955778 -304.095117) (xy 439.006805 -304.077709)
			(xy 439.059823 -304.067916) (xy 439.113702 -304.065947) (xy 439.167293 -304.071844) (xy 439.219454 -304.08548)
			(xy 439.269074 -304.106567) (xy 439.315095 -304.134653) (xy 439.356537 -304.169141) (xy 439.392515 -304.209295)
			(xy 439.422263 -304.254259) (xy 439.445148 -304.303076) (xy 439.46068 -304.354705) (xy 439.46853 -304.408045)
			(xy 439.469022 -304.435002) (xy 442.174899 -304.435002) (xy 442.178834 -304.381231) (xy 442.190557 -304.328607)
			(xy 442.209817 -304.27825) (xy 442.236203 -304.231233) (xy 442.269155 -304.18856) (xy 442.307968 -304.151139)
			(xy 442.351816 -304.119769) (xy 442.399764 -304.095117) (xy 442.450791 -304.077709) (xy 442.503809 -304.067916)
			(xy 442.557688 -304.065947) (xy 442.611279 -304.071844) (xy 442.66344 -304.08548) (xy 442.71306 -304.106567)
			(xy 442.759081 -304.134653) (xy 442.800523 -304.169141) (xy 442.836501 -304.209295) (xy 442.866249 -304.254259)
			(xy 442.889134 -304.303076) (xy 442.904666 -304.354705) (xy 442.912516 -304.408045) (xy 442.913008 -304.435002)
			(xy 446.274967 -304.435002) (xy 446.278902 -304.381231) (xy 446.290625 -304.328607) (xy 446.309885 -304.27825)
			(xy 446.336271 -304.231233) (xy 446.369223 -304.18856) (xy 446.408036 -304.151139) (xy 446.451884 -304.119769)
			(xy 446.499832 -304.095117) (xy 446.550859 -304.077709) (xy 446.603877 -304.067916) (xy 446.657756 -304.065947)
			(xy 446.711347 -304.071844) (xy 446.763508 -304.08548) (xy 446.813128 -304.106567) (xy 446.859149 -304.134653)
			(xy 446.900591 -304.169141) (xy 446.936569 -304.209295) (xy 446.966317 -304.254259) (xy 446.989202 -304.303076)
			(xy 447.004734 -304.354705) (xy 447.012584 -304.408045) (xy 447.013076 -304.435002) (xy 449.718699 -304.435002)
			(xy 449.722634 -304.381231) (xy 449.734357 -304.328607) (xy 449.753617 -304.27825) (xy 449.780003 -304.231233)
			(xy 449.812955 -304.18856) (xy 449.851768 -304.151139) (xy 449.895616 -304.119769) (xy 449.943564 -304.095117)
			(xy 449.994591 -304.077709) (xy 450.047609 -304.067916) (xy 450.101488 -304.065947) (xy 450.155079 -304.071844)
			(xy 450.20724 -304.08548) (xy 450.25686 -304.106567) (xy 450.302881 -304.134653) (xy 450.344323 -304.169141)
			(xy 450.380301 -304.209295) (xy 450.410049 -304.254259) (xy 450.432934 -304.303076) (xy 450.448466 -304.354705)
			(xy 450.456316 -304.408045) (xy 450.456808 -304.435002) (xy 453.818767 -304.435002) (xy 453.822702 -304.381231)
			(xy 453.834425 -304.328607) (xy 453.853685 -304.27825) (xy 453.880071 -304.231233) (xy 453.913023 -304.18856)
			(xy 453.951836 -304.151139) (xy 453.995684 -304.119769) (xy 454.043632 -304.095117) (xy 454.094659 -304.077709)
			(xy 454.147677 -304.067916) (xy 454.201556 -304.065947) (xy 454.255147 -304.071844) (xy 454.307308 -304.08548)
			(xy 454.356928 -304.106567) (xy 454.402949 -304.134653) (xy 454.444391 -304.169141) (xy 454.480369 -304.209295)
			(xy 454.510117 -304.254259) (xy 454.533002 -304.303076) (xy 454.548534 -304.354705) (xy 454.556384 -304.408045)
			(xy 454.556876 -304.435002) (xy 454.556384 -304.461959) (xy 454.548534 -304.515299) (xy 454.533002 -304.566928)
			(xy 454.510117 -304.615745) (xy 454.480369 -304.660709) (xy 454.444391 -304.700863) (xy 454.402949 -304.735351)
			(xy 454.356928 -304.763437) (xy 454.307308 -304.784524) (xy 454.255147 -304.79816) (xy 454.201556 -304.804057)
			(xy 454.147677 -304.802088) (xy 454.094659 -304.792295) (xy 454.043632 -304.774887) (xy 453.995684 -304.750235)
			(xy 453.951836 -304.718865) (xy 453.913023 -304.681444) (xy 453.880071 -304.638771) (xy 453.853685 -304.591754)
			(xy 453.834425 -304.541397) (xy 453.822702 -304.488773) (xy 453.818767 -304.435002) (xy 450.456808 -304.435002)
			(xy 450.456316 -304.461959) (xy 450.448466 -304.515299) (xy 450.432934 -304.566928) (xy 450.410049 -304.615745)
			(xy 450.380301 -304.660709) (xy 450.344323 -304.700863) (xy 450.302881 -304.735351) (xy 450.25686 -304.763437)
			(xy 450.20724 -304.784524) (xy 450.155079 -304.79816) (xy 450.101488 -304.804057) (xy 450.047609 -304.802088)
			(xy 449.994591 -304.792295) (xy 449.943564 -304.774887) (xy 449.895616 -304.750235) (xy 449.851768 -304.718865)
			(xy 449.812955 -304.681444) (xy 449.780003 -304.638771) (xy 449.753617 -304.591754) (xy 449.734357 -304.541397)
			(xy 449.722634 -304.488773) (xy 449.718699 -304.435002) (xy 447.013076 -304.435002) (xy 447.012584 -304.461959)
			(xy 447.004734 -304.515299) (xy 446.989202 -304.566928) (xy 446.966317 -304.615745) (xy 446.936569 -304.660709)
			(xy 446.900591 -304.700863) (xy 446.859149 -304.735351) (xy 446.813128 -304.763437) (xy 446.763508 -304.784524)
			(xy 446.711347 -304.79816) (xy 446.657756 -304.804057) (xy 446.603877 -304.802088) (xy 446.550859 -304.792295)
			(xy 446.499832 -304.774887) (xy 446.451884 -304.750235) (xy 446.408036 -304.718865) (xy 446.369223 -304.681444)
			(xy 446.336271 -304.638771) (xy 446.309885 -304.591754) (xy 446.290625 -304.541397) (xy 446.278902 -304.488773)
			(xy 446.274967 -304.435002) (xy 442.913008 -304.435002) (xy 442.912516 -304.461959) (xy 442.904666 -304.515299)
			(xy 442.889134 -304.566928) (xy 442.866249 -304.615745) (xy 442.836501 -304.660709) (xy 442.800523 -304.700863)
			(xy 442.759081 -304.735351) (xy 442.71306 -304.763437) (xy 442.66344 -304.784524) (xy 442.611279 -304.79816)
			(xy 442.557688 -304.804057) (xy 442.503809 -304.802088) (xy 442.450791 -304.792295) (xy 442.399764 -304.774887)
			(xy 442.351816 -304.750235) (xy 442.307968 -304.718865) (xy 442.269155 -304.681444) (xy 442.236203 -304.638771)
			(xy 442.209817 -304.591754) (xy 442.190557 -304.541397) (xy 442.178834 -304.488773) (xy 442.174899 -304.435002)
			(xy 439.469022 -304.435002) (xy 439.46853 -304.461959) (xy 439.46068 -304.515299) (xy 439.445148 -304.566928)
			(xy 439.422263 -304.615745) (xy 439.392515 -304.660709) (xy 439.356537 -304.700863) (xy 439.315095 -304.735351)
			(xy 439.269074 -304.763437) (xy 439.219454 -304.784524) (xy 439.167293 -304.79816) (xy 439.113702 -304.804057)
			(xy 439.059823 -304.802088) (xy 439.006805 -304.792295) (xy 438.955778 -304.774887) (xy 438.90783 -304.750235)
			(xy 438.863982 -304.718865) (xy 438.825169 -304.681444) (xy 438.792217 -304.638771) (xy 438.765831 -304.591754)
			(xy 438.746571 -304.541397) (xy 438.734848 -304.488773) (xy 438.730913 -304.435002) (xy 435.368954 -304.435002)
			(xy 435.368462 -304.461959) (xy 435.360612 -304.515299) (xy 435.34508 -304.566928) (xy 435.322195 -304.615745)
			(xy 435.292447 -304.660709) (xy 435.256469 -304.700863) (xy 435.215027 -304.735351) (xy 435.169006 -304.763437)
			(xy 435.119386 -304.784524) (xy 435.067225 -304.79816) (xy 435.013634 -304.804057) (xy 434.959755 -304.802088)
			(xy 434.906737 -304.792295) (xy 434.85571 -304.774887) (xy 434.807762 -304.750235) (xy 434.763914 -304.718865)
			(xy 434.725101 -304.681444) (xy 434.692149 -304.638771) (xy 434.665763 -304.591754) (xy 434.646503 -304.541397)
			(xy 434.63478 -304.488773) (xy 434.630845 -304.435002) (xy 431.924968 -304.435002) (xy 431.924476 -304.461959)
			(xy 431.916626 -304.515299) (xy 431.901094 -304.566928) (xy 431.878209 -304.615745) (xy 431.848461 -304.660709)
			(xy 431.812483 -304.700863) (xy 431.771041 -304.735351) (xy 431.72502 -304.763437) (xy 431.6754 -304.784524)
			(xy 431.623239 -304.79816) (xy 431.569648 -304.804057) (xy 431.515769 -304.802088) (xy 431.462751 -304.792295)
			(xy 431.411724 -304.774887) (xy 431.363776 -304.750235) (xy 431.319928 -304.718865) (xy 431.281115 -304.681444)
			(xy 431.248163 -304.638771) (xy 431.221777 -304.591754) (xy 431.202517 -304.541397) (xy 431.190794 -304.488773)
			(xy 431.186859 -304.435002) (xy 427.8249 -304.435002) (xy 427.824408 -304.461959) (xy 427.816558 -304.515299)
			(xy 427.801026 -304.566928) (xy 427.778141 -304.615745) (xy 427.748393 -304.660709) (xy 427.712415 -304.700863)
			(xy 427.670973 -304.735351) (xy 427.624952 -304.763437) (xy 427.575332 -304.784524) (xy 427.523171 -304.79816)
			(xy 427.46958 -304.804057) (xy 427.415701 -304.802088) (xy 427.362683 -304.792295) (xy 427.311656 -304.774887)
			(xy 427.263708 -304.750235) (xy 427.21986 -304.718865) (xy 427.181047 -304.681444) (xy 427.148095 -304.638771)
			(xy 427.121709 -304.591754) (xy 427.102449 -304.541397) (xy 427.090726 -304.488773) (xy 427.086791 -304.435002)
			(xy 425.985178 -304.435002) (xy 425.985178 -305.28514) (xy 427.086791 -305.28514) (xy 427.090726 -305.231369)
			(xy 427.102449 -305.178745) (xy 427.121709 -305.128388) (xy 427.148095 -305.081371) (xy 427.181047 -305.038698)
			(xy 427.21986 -305.001277) (xy 427.263708 -304.969907) (xy 427.311656 -304.945255) (xy 427.362683 -304.927847)
			(xy 427.415701 -304.918054) (xy 427.46958 -304.916085) (xy 427.523171 -304.921982) (xy 427.575332 -304.935618)
			(xy 427.624952 -304.956705) (xy 427.670973 -304.984791) (xy 427.712415 -305.019279) (xy 427.748393 -305.059433)
			(xy 427.778141 -305.104397) (xy 427.801026 -305.153214) (xy 427.816558 -305.204843) (xy 427.824408 -305.258183)
			(xy 427.8249 -305.28514) (xy 434.630845 -305.28514) (xy 434.63478 -305.231369) (xy 434.646503 -305.178745)
			(xy 434.665763 -305.128388) (xy 434.692149 -305.081371) (xy 434.725101 -305.038698) (xy 434.763914 -305.001277)
			(xy 434.807762 -304.969907) (xy 434.85571 -304.945255) (xy 434.906737 -304.927847) (xy 434.959755 -304.918054)
			(xy 435.013634 -304.916085) (xy 435.067225 -304.921982) (xy 435.119386 -304.935618) (xy 435.169006 -304.956705)
			(xy 435.215027 -304.984791) (xy 435.256469 -305.019279) (xy 435.292447 -305.059433) (xy 435.322195 -305.104397)
			(xy 435.34508 -305.153214) (xy 435.360612 -305.204843) (xy 435.368462 -305.258183) (xy 435.368954 -305.28514)
			(xy 442.174899 -305.28514) (xy 442.178834 -305.231369) (xy 442.190557 -305.178745) (xy 442.209817 -305.128388)
			(xy 442.236203 -305.081371) (xy 442.269155 -305.038698) (xy 442.307968 -305.001277) (xy 442.351816 -304.969907)
			(xy 442.399764 -304.945255) (xy 442.450791 -304.927847) (xy 442.503809 -304.918054) (xy 442.557688 -304.916085)
			(xy 442.611279 -304.921982) (xy 442.66344 -304.935618) (xy 442.71306 -304.956705) (xy 442.759081 -304.984791)
			(xy 442.800523 -305.019279) (xy 442.836501 -305.059433) (xy 442.866249 -305.104397) (xy 442.889134 -305.153214)
			(xy 442.904666 -305.204843) (xy 442.912516 -305.258183) (xy 442.913008 -305.28514) (xy 449.718699 -305.28514)
			(xy 449.722634 -305.231369) (xy 449.734357 -305.178745) (xy 449.753617 -305.128388) (xy 449.780003 -305.081371)
			(xy 449.812955 -305.038698) (xy 449.851768 -305.001277) (xy 449.895616 -304.969907) (xy 449.943564 -304.945255)
			(xy 449.994591 -304.927847) (xy 450.047609 -304.918054) (xy 450.101488 -304.916085) (xy 450.155079 -304.921982)
			(xy 450.20724 -304.935618) (xy 450.25686 -304.956705) (xy 450.302881 -304.984791) (xy 450.344323 -305.019279)
			(xy 450.380301 -305.059433) (xy 450.410049 -305.104397) (xy 450.432934 -305.153214) (xy 450.448466 -305.204843)
			(xy 450.456316 -305.258183) (xy 450.456808 -305.28514) (xy 450.456316 -305.312097) (xy 450.448466 -305.365437)
			(xy 450.432934 -305.417066) (xy 450.410049 -305.465883) (xy 450.380301 -305.510847) (xy 450.344323 -305.551001)
			(xy 450.302881 -305.585489) (xy 450.25686 -305.613575) (xy 450.20724 -305.634662) (xy 450.155079 -305.648298)
			(xy 450.101488 -305.654195) (xy 450.047609 -305.652226) (xy 449.994591 -305.642433) (xy 449.943564 -305.625025)
			(xy 449.895616 -305.600373) (xy 449.851768 -305.569003) (xy 449.812955 -305.531582) (xy 449.780003 -305.488909)
			(xy 449.753617 -305.441892) (xy 449.734357 -305.391535) (xy 449.722634 -305.338911) (xy 449.718699 -305.28514)
			(xy 442.913008 -305.28514) (xy 442.912516 -305.312097) (xy 442.904666 -305.365437) (xy 442.889134 -305.417066)
			(xy 442.866249 -305.465883) (xy 442.836501 -305.510847) (xy 442.800523 -305.551001) (xy 442.759081 -305.585489)
			(xy 442.71306 -305.613575) (xy 442.66344 -305.634662) (xy 442.611279 -305.648298) (xy 442.557688 -305.654195)
			(xy 442.503809 -305.652226) (xy 442.450791 -305.642433) (xy 442.399764 -305.625025) (xy 442.351816 -305.600373)
			(xy 442.307968 -305.569003) (xy 442.269155 -305.531582) (xy 442.236203 -305.488909) (xy 442.209817 -305.441892)
			(xy 442.190557 -305.391535) (xy 442.178834 -305.338911) (xy 442.174899 -305.28514) (xy 435.368954 -305.28514)
			(xy 435.368462 -305.312097) (xy 435.360612 -305.365437) (xy 435.34508 -305.417066) (xy 435.322195 -305.465883)
			(xy 435.292447 -305.510847) (xy 435.256469 -305.551001) (xy 435.215027 -305.585489) (xy 435.169006 -305.613575)
			(xy 435.119386 -305.634662) (xy 435.067225 -305.648298) (xy 435.013634 -305.654195) (xy 434.959755 -305.652226)
			(xy 434.906737 -305.642433) (xy 434.85571 -305.625025) (xy 434.807762 -305.600373) (xy 434.763914 -305.569003)
			(xy 434.725101 -305.531582) (xy 434.692149 -305.488909) (xy 434.665763 -305.441892) (xy 434.646503 -305.391535)
			(xy 434.63478 -305.338911) (xy 434.630845 -305.28514) (xy 427.8249 -305.28514) (xy 427.824408 -305.312097)
			(xy 427.816558 -305.365437) (xy 427.801026 -305.417066) (xy 427.778141 -305.465883) (xy 427.748393 -305.510847)
			(xy 427.712415 -305.551001) (xy 427.670973 -305.585489) (xy 427.624952 -305.613575) (xy 427.575332 -305.634662)
			(xy 427.523171 -305.648298) (xy 427.46958 -305.654195) (xy 427.415701 -305.652226) (xy 427.362683 -305.642433)
			(xy 427.311656 -305.625025) (xy 427.263708 -305.600373) (xy 427.21986 -305.569003) (xy 427.181047 -305.531582)
			(xy 427.148095 -305.488909) (xy 427.121709 -305.441892) (xy 427.102449 -305.391535) (xy 427.090726 -305.338911)
			(xy 427.086791 -305.28514) (xy 425.985178 -305.28514) (xy 425.985178 -306.135024) (xy 431.186859 -306.135024)
			(xy 431.190794 -306.081253) (xy 431.202517 -306.028629) (xy 431.221777 -305.978272) (xy 431.248163 -305.931255)
			(xy 431.281115 -305.888582) (xy 431.319928 -305.851161) (xy 431.363776 -305.819791) (xy 431.411724 -305.795139)
			(xy 431.462751 -305.777731) (xy 431.515769 -305.767938) (xy 431.569648 -305.765969) (xy 431.623239 -305.771866)
			(xy 431.6754 -305.785502) (xy 431.72502 -305.806589) (xy 431.771041 -305.834675) (xy 431.812483 -305.869163)
			(xy 431.848461 -305.909317) (xy 431.878209 -305.954281) (xy 431.901094 -306.003098) (xy 431.916626 -306.054727)
			(xy 431.924476 -306.108067) (xy 431.924968 -306.135024) (xy 438.730913 -306.135024) (xy 438.734848 -306.081253)
			(xy 438.746571 -306.028629) (xy 438.765831 -305.978272) (xy 438.792217 -305.931255) (xy 438.825169 -305.888582)
			(xy 438.863982 -305.851161) (xy 438.90783 -305.819791) (xy 438.955778 -305.795139) (xy 439.006805 -305.777731)
			(xy 439.059823 -305.767938) (xy 439.113702 -305.765969) (xy 439.167293 -305.771866) (xy 439.219454 -305.785502)
			(xy 439.269074 -305.806589) (xy 439.315095 -305.834675) (xy 439.356537 -305.869163) (xy 439.392515 -305.909317)
			(xy 439.422263 -305.954281) (xy 439.445148 -306.003098) (xy 439.46068 -306.054727) (xy 439.46853 -306.108067)
			(xy 439.469022 -306.135024) (xy 446.274967 -306.135024) (xy 446.278902 -306.081253) (xy 446.290625 -306.028629)
			(xy 446.309885 -305.978272) (xy 446.336271 -305.931255) (xy 446.369223 -305.888582) (xy 446.408036 -305.851161)
			(xy 446.451884 -305.819791) (xy 446.499832 -305.795139) (xy 446.550859 -305.777731) (xy 446.603877 -305.767938)
			(xy 446.657756 -305.765969) (xy 446.711347 -305.771866) (xy 446.763508 -305.785502) (xy 446.813128 -305.806589)
			(xy 446.859149 -305.834675) (xy 446.900591 -305.869163) (xy 446.936569 -305.909317) (xy 446.966317 -305.954281)
			(xy 446.989202 -306.003098) (xy 447.004734 -306.054727) (xy 447.012584 -306.108067) (xy 447.013076 -306.135024)
			(xy 453.818767 -306.135024) (xy 453.822702 -306.081253) (xy 453.834425 -306.028629) (xy 453.853685 -305.978272)
			(xy 453.880071 -305.931255) (xy 453.913023 -305.888582) (xy 453.951836 -305.851161) (xy 453.995684 -305.819791)
			(xy 454.043632 -305.795139) (xy 454.094659 -305.777731) (xy 454.147677 -305.767938) (xy 454.201556 -305.765969)
			(xy 454.255147 -305.771866) (xy 454.307308 -305.785502) (xy 454.356928 -305.806589) (xy 454.402949 -305.834675)
			(xy 454.444391 -305.869163) (xy 454.480369 -305.909317) (xy 454.510117 -305.954281) (xy 454.533002 -306.003098)
			(xy 454.548534 -306.054727) (xy 454.556384 -306.108067) (xy 454.556876 -306.135024) (xy 454.556384 -306.161981)
			(xy 454.548534 -306.215321) (xy 454.533002 -306.26695) (xy 454.510117 -306.315767) (xy 454.480369 -306.360731)
			(xy 454.444391 -306.400885) (xy 454.402949 -306.435373) (xy 454.356928 -306.463459) (xy 454.307308 -306.484546)
			(xy 454.255147 -306.498182) (xy 454.201556 -306.504079) (xy 454.147677 -306.50211) (xy 454.094659 -306.492317)
			(xy 454.043632 -306.474909) (xy 453.995684 -306.450257) (xy 453.951836 -306.418887) (xy 453.913023 -306.381466)
			(xy 453.880071 -306.338793) (xy 453.853685 -306.291776) (xy 453.834425 -306.241419) (xy 453.822702 -306.188795)
			(xy 453.818767 -306.135024) (xy 447.013076 -306.135024) (xy 447.012584 -306.161981) (xy 447.004734 -306.215321)
			(xy 446.989202 -306.26695) (xy 446.966317 -306.315767) (xy 446.936569 -306.360731) (xy 446.900591 -306.400885)
			(xy 446.859149 -306.435373) (xy 446.813128 -306.463459) (xy 446.763508 -306.484546) (xy 446.711347 -306.498182)
			(xy 446.657756 -306.504079) (xy 446.603877 -306.50211) (xy 446.550859 -306.492317) (xy 446.499832 -306.474909)
			(xy 446.451884 -306.450257) (xy 446.408036 -306.418887) (xy 446.369223 -306.381466) (xy 446.336271 -306.338793)
			(xy 446.309885 -306.291776) (xy 446.290625 -306.241419) (xy 446.278902 -306.188795) (xy 446.274967 -306.135024)
			(xy 439.469022 -306.135024) (xy 439.46853 -306.161981) (xy 439.46068 -306.215321) (xy 439.445148 -306.26695)
			(xy 439.422263 -306.315767) (xy 439.392515 -306.360731) (xy 439.356537 -306.400885) (xy 439.315095 -306.435373)
			(xy 439.269074 -306.463459) (xy 439.219454 -306.484546) (xy 439.167293 -306.498182) (xy 439.113702 -306.504079)
			(xy 439.059823 -306.50211) (xy 439.006805 -306.492317) (xy 438.955778 -306.474909) (xy 438.90783 -306.450257)
			(xy 438.863982 -306.418887) (xy 438.825169 -306.381466) (xy 438.792217 -306.338793) (xy 438.765831 -306.291776)
			(xy 438.746571 -306.241419) (xy 438.734848 -306.188795) (xy 438.730913 -306.135024) (xy 431.924968 -306.135024)
			(xy 431.924476 -306.161981) (xy 431.916626 -306.215321) (xy 431.901094 -306.26695) (xy 431.878209 -306.315767)
			(xy 431.848461 -306.360731) (xy 431.812483 -306.400885) (xy 431.771041 -306.435373) (xy 431.72502 -306.463459)
			(xy 431.6754 -306.484546) (xy 431.623239 -306.498182) (xy 431.569648 -306.504079) (xy 431.515769 -306.50211)
			(xy 431.462751 -306.492317) (xy 431.411724 -306.474909) (xy 431.363776 -306.450257) (xy 431.319928 -306.418887)
			(xy 431.281115 -306.381466) (xy 431.248163 -306.338793) (xy 431.221777 -306.291776) (xy 431.202517 -306.241419)
			(xy 431.190794 -306.188795) (xy 431.186859 -306.135024) (xy 425.985178 -306.135024) (xy 425.985178 -306.985162)
			(xy 427.086791 -306.985162) (xy 427.090726 -306.931391) (xy 427.102449 -306.878767) (xy 427.121709 -306.82841)
			(xy 427.148095 -306.781393) (xy 427.181047 -306.73872) (xy 427.21986 -306.701299) (xy 427.263708 -306.669929)
			(xy 427.311656 -306.645277) (xy 427.362683 -306.627869) (xy 427.415701 -306.618076) (xy 427.46958 -306.616107)
			(xy 427.523171 -306.622004) (xy 427.575332 -306.63564) (xy 427.624952 -306.656727) (xy 427.670973 -306.684813)
			(xy 427.712415 -306.719301) (xy 427.748393 -306.759455) (xy 427.778141 -306.804419) (xy 427.801026 -306.853236)
			(xy 427.816558 -306.904865) (xy 427.824408 -306.958205) (xy 427.8249 -306.985162) (xy 434.630845 -306.985162)
			(xy 434.63478 -306.931391) (xy 434.646503 -306.878767) (xy 434.665763 -306.82841) (xy 434.692149 -306.781393)
			(xy 434.725101 -306.73872) (xy 434.763914 -306.701299) (xy 434.807762 -306.669929) (xy 434.85571 -306.645277)
			(xy 434.906737 -306.627869) (xy 434.959755 -306.618076) (xy 435.013634 -306.616107) (xy 435.067225 -306.622004)
			(xy 435.119386 -306.63564) (xy 435.169006 -306.656727) (xy 435.215027 -306.684813) (xy 435.256469 -306.719301)
			(xy 435.292447 -306.759455) (xy 435.322195 -306.804419) (xy 435.34508 -306.853236) (xy 435.360612 -306.904865)
			(xy 435.368462 -306.958205) (xy 435.368954 -306.985162) (xy 442.174899 -306.985162) (xy 442.178834 -306.931391)
			(xy 442.190557 -306.878767) (xy 442.209817 -306.82841) (xy 442.236203 -306.781393) (xy 442.269155 -306.73872)
			(xy 442.307968 -306.701299) (xy 442.351816 -306.669929) (xy 442.399764 -306.645277) (xy 442.450791 -306.627869)
			(xy 442.503809 -306.618076) (xy 442.557688 -306.616107) (xy 442.611279 -306.622004) (xy 442.66344 -306.63564)
			(xy 442.71306 -306.656727) (xy 442.759081 -306.684813) (xy 442.800523 -306.719301) (xy 442.836501 -306.759455)
			(xy 442.866249 -306.804419) (xy 442.889134 -306.853236) (xy 442.904666 -306.904865) (xy 442.912516 -306.958205)
			(xy 442.913008 -306.985162) (xy 449.718699 -306.985162) (xy 449.722634 -306.931391) (xy 449.734357 -306.878767)
			(xy 449.753617 -306.82841) (xy 449.780003 -306.781393) (xy 449.812955 -306.73872) (xy 449.851768 -306.701299)
			(xy 449.895616 -306.669929) (xy 449.943564 -306.645277) (xy 449.994591 -306.627869) (xy 450.047609 -306.618076)
			(xy 450.101488 -306.616107) (xy 450.155079 -306.622004) (xy 450.20724 -306.63564) (xy 450.25686 -306.656727)
			(xy 450.302881 -306.684813) (xy 450.344323 -306.719301) (xy 450.380301 -306.759455) (xy 450.410049 -306.804419)
			(xy 450.432934 -306.853236) (xy 450.448466 -306.904865) (xy 450.456316 -306.958205) (xy 450.456808 -306.985162)
			(xy 450.456316 -307.012119) (xy 450.448466 -307.065459) (xy 450.432934 -307.117088) (xy 450.410049 -307.165905)
			(xy 450.380301 -307.210869) (xy 450.344323 -307.251023) (xy 450.302881 -307.285511) (xy 450.25686 -307.313597)
			(xy 450.20724 -307.334684) (xy 450.155079 -307.34832) (xy 450.101488 -307.354217) (xy 450.047609 -307.352248)
			(xy 449.994591 -307.342455) (xy 449.943564 -307.325047) (xy 449.895616 -307.300395) (xy 449.851768 -307.269025)
			(xy 449.812955 -307.231604) (xy 449.780003 -307.188931) (xy 449.753617 -307.141914) (xy 449.734357 -307.091557)
			(xy 449.722634 -307.038933) (xy 449.718699 -306.985162) (xy 442.913008 -306.985162) (xy 442.912516 -307.012119)
			(xy 442.904666 -307.065459) (xy 442.889134 -307.117088) (xy 442.866249 -307.165905) (xy 442.836501 -307.210869)
			(xy 442.800523 -307.251023) (xy 442.759081 -307.285511) (xy 442.71306 -307.313597) (xy 442.66344 -307.334684)
			(xy 442.611279 -307.34832) (xy 442.557688 -307.354217) (xy 442.503809 -307.352248) (xy 442.450791 -307.342455)
			(xy 442.399764 -307.325047) (xy 442.351816 -307.300395) (xy 442.307968 -307.269025) (xy 442.269155 -307.231604)
			(xy 442.236203 -307.188931) (xy 442.209817 -307.141914) (xy 442.190557 -307.091557) (xy 442.178834 -307.038933)
			(xy 442.174899 -306.985162) (xy 435.368954 -306.985162) (xy 435.368462 -307.012119) (xy 435.360612 -307.065459)
			(xy 435.34508 -307.117088) (xy 435.322195 -307.165905) (xy 435.292447 -307.210869) (xy 435.256469 -307.251023)
			(xy 435.215027 -307.285511) (xy 435.169006 -307.313597) (xy 435.119386 -307.334684) (xy 435.067225 -307.34832)
			(xy 435.013634 -307.354217) (xy 434.959755 -307.352248) (xy 434.906737 -307.342455) (xy 434.85571 -307.325047)
			(xy 434.807762 -307.300395) (xy 434.763914 -307.269025) (xy 434.725101 -307.231604) (xy 434.692149 -307.188931)
			(xy 434.665763 -307.141914) (xy 434.646503 -307.091557) (xy 434.63478 -307.038933) (xy 434.630845 -306.985162)
			(xy 427.8249 -306.985162) (xy 427.824408 -307.012119) (xy 427.816558 -307.065459) (xy 427.801026 -307.117088)
			(xy 427.778141 -307.165905) (xy 427.748393 -307.210869) (xy 427.712415 -307.251023) (xy 427.670973 -307.285511)
			(xy 427.624952 -307.313597) (xy 427.575332 -307.334684) (xy 427.523171 -307.34832) (xy 427.46958 -307.354217)
			(xy 427.415701 -307.352248) (xy 427.362683 -307.342455) (xy 427.311656 -307.325047) (xy 427.263708 -307.300395)
			(xy 427.21986 -307.269025) (xy 427.181047 -307.231604) (xy 427.148095 -307.188931) (xy 427.121709 -307.141914)
			(xy 427.102449 -307.091557) (xy 427.090726 -307.038933) (xy 427.086791 -306.985162) (xy 425.985178 -306.985162)
			(xy 425.985178 -307.835046) (xy 431.186859 -307.835046) (xy 431.190794 -307.781275) (xy 431.202517 -307.728651)
			(xy 431.221777 -307.678294) (xy 431.248163 -307.631277) (xy 431.281115 -307.588604) (xy 431.319928 -307.551183)
			(xy 431.363776 -307.519813) (xy 431.411724 -307.495161) (xy 431.462751 -307.477753) (xy 431.515769 -307.46796)
			(xy 431.569648 -307.465991) (xy 431.623239 -307.471888) (xy 431.6754 -307.485524) (xy 431.72502 -307.506611)
			(xy 431.771041 -307.534697) (xy 431.812483 -307.569185) (xy 431.848461 -307.609339) (xy 431.878209 -307.654303)
			(xy 431.901094 -307.70312) (xy 431.916626 -307.754749) (xy 431.924476 -307.808089) (xy 431.924968 -307.835046)
			(xy 438.730913 -307.835046) (xy 438.734848 -307.781275) (xy 438.746571 -307.728651) (xy 438.765831 -307.678294)
			(xy 438.792217 -307.631277) (xy 438.825169 -307.588604) (xy 438.863982 -307.551183) (xy 438.90783 -307.519813)
			(xy 438.955778 -307.495161) (xy 439.006805 -307.477753) (xy 439.059823 -307.46796) (xy 439.113702 -307.465991)
			(xy 439.167293 -307.471888) (xy 439.219454 -307.485524) (xy 439.269074 -307.506611) (xy 439.315095 -307.534697)
			(xy 439.356537 -307.569185) (xy 439.392515 -307.609339) (xy 439.422263 -307.654303) (xy 439.445148 -307.70312)
			(xy 439.46068 -307.754749) (xy 439.46853 -307.808089) (xy 439.469022 -307.835046) (xy 446.274967 -307.835046)
			(xy 446.278902 -307.781275) (xy 446.290625 -307.728651) (xy 446.309885 -307.678294) (xy 446.336271 -307.631277)
			(xy 446.369223 -307.588604) (xy 446.408036 -307.551183) (xy 446.451884 -307.519813) (xy 446.499832 -307.495161)
			(xy 446.550859 -307.477753) (xy 446.603877 -307.46796) (xy 446.657756 -307.465991) (xy 446.711347 -307.471888)
			(xy 446.763508 -307.485524) (xy 446.813128 -307.506611) (xy 446.859149 -307.534697) (xy 446.900591 -307.569185)
			(xy 446.936569 -307.609339) (xy 446.966317 -307.654303) (xy 446.989202 -307.70312) (xy 447.004734 -307.754749)
			(xy 447.012584 -307.808089) (xy 447.013076 -307.835046) (xy 453.818767 -307.835046) (xy 453.822702 -307.781275)
			(xy 453.834425 -307.728651) (xy 453.853685 -307.678294) (xy 453.880071 -307.631277) (xy 453.913023 -307.588604)
			(xy 453.951836 -307.551183) (xy 453.995684 -307.519813) (xy 454.043632 -307.495161) (xy 454.094659 -307.477753)
			(xy 454.147677 -307.46796) (xy 454.201556 -307.465991) (xy 454.255147 -307.471888) (xy 454.307308 -307.485524)
			(xy 454.356928 -307.506611) (xy 454.402949 -307.534697) (xy 454.444391 -307.569185) (xy 454.480369 -307.609339)
			(xy 454.510117 -307.654303) (xy 454.533002 -307.70312) (xy 454.548534 -307.754749) (xy 454.556384 -307.808089)
			(xy 454.556876 -307.835046) (xy 454.556384 -307.862003) (xy 454.548534 -307.915343) (xy 454.533002 -307.966972)
			(xy 454.510117 -308.015789) (xy 454.480369 -308.060753) (xy 454.444391 -308.100907) (xy 454.402949 -308.135395)
			(xy 454.356928 -308.163481) (xy 454.307308 -308.184568) (xy 454.255147 -308.198204) (xy 454.201556 -308.204101)
			(xy 454.147677 -308.202132) (xy 454.094659 -308.192339) (xy 454.043632 -308.174931) (xy 453.995684 -308.150279)
			(xy 453.951836 -308.118909) (xy 453.913023 -308.081488) (xy 453.880071 -308.038815) (xy 453.853685 -307.991798)
			(xy 453.834425 -307.941441) (xy 453.822702 -307.888817) (xy 453.818767 -307.835046) (xy 447.013076 -307.835046)
			(xy 447.012584 -307.862003) (xy 447.004734 -307.915343) (xy 446.989202 -307.966972) (xy 446.966317 -308.015789)
			(xy 446.936569 -308.060753) (xy 446.900591 -308.100907) (xy 446.859149 -308.135395) (xy 446.813128 -308.163481)
			(xy 446.763508 -308.184568) (xy 446.711347 -308.198204) (xy 446.657756 -308.204101) (xy 446.603877 -308.202132)
			(xy 446.550859 -308.192339) (xy 446.499832 -308.174931) (xy 446.451884 -308.150279) (xy 446.408036 -308.118909)
			(xy 446.369223 -308.081488) (xy 446.336271 -308.038815) (xy 446.309885 -307.991798) (xy 446.290625 -307.941441)
			(xy 446.278902 -307.888817) (xy 446.274967 -307.835046) (xy 439.469022 -307.835046) (xy 439.46853 -307.862003)
			(xy 439.46068 -307.915343) (xy 439.445148 -307.966972) (xy 439.422263 -308.015789) (xy 439.392515 -308.060753)
			(xy 439.356537 -308.100907) (xy 439.315095 -308.135395) (xy 439.269074 -308.163481) (xy 439.219454 -308.184568)
			(xy 439.167293 -308.198204) (xy 439.113702 -308.204101) (xy 439.059823 -308.202132) (xy 439.006805 -308.192339)
			(xy 438.955778 -308.174931) (xy 438.90783 -308.150279) (xy 438.863982 -308.118909) (xy 438.825169 -308.081488)
			(xy 438.792217 -308.038815) (xy 438.765831 -307.991798) (xy 438.746571 -307.941441) (xy 438.734848 -307.888817)
			(xy 438.730913 -307.835046) (xy 431.924968 -307.835046) (xy 431.924476 -307.862003) (xy 431.916626 -307.915343)
			(xy 431.901094 -307.966972) (xy 431.878209 -308.015789) (xy 431.848461 -308.060753) (xy 431.812483 -308.100907)
			(xy 431.771041 -308.135395) (xy 431.72502 -308.163481) (xy 431.6754 -308.184568) (xy 431.623239 -308.198204)
			(xy 431.569648 -308.204101) (xy 431.515769 -308.202132) (xy 431.462751 -308.192339) (xy 431.411724 -308.174931)
			(xy 431.363776 -308.150279) (xy 431.319928 -308.118909) (xy 431.281115 -308.081488) (xy 431.248163 -308.038815)
			(xy 431.221777 -307.991798) (xy 431.202517 -307.941441) (xy 431.190794 -307.888817) (xy 431.186859 -307.835046)
			(xy 425.985178 -307.835046) (xy 425.985178 -308.685184) (xy 427.086791 -308.685184) (xy 427.090726 -308.631413)
			(xy 427.102449 -308.578789) (xy 427.121709 -308.528432) (xy 427.148095 -308.481415) (xy 427.181047 -308.438742)
			(xy 427.21986 -308.401321) (xy 427.263708 -308.369951) (xy 427.311656 -308.345299) (xy 427.362683 -308.327891)
			(xy 427.415701 -308.318098) (xy 427.46958 -308.316129) (xy 427.523171 -308.322026) (xy 427.575332 -308.335662)
			(xy 427.624952 -308.356749) (xy 427.670973 -308.384835) (xy 427.712415 -308.419323) (xy 427.748393 -308.459477)
			(xy 427.778141 -308.504441) (xy 427.801026 -308.553258) (xy 427.816558 -308.604887) (xy 427.824408 -308.658227)
			(xy 427.8249 -308.685184) (xy 434.630845 -308.685184) (xy 434.63478 -308.631413) (xy 434.646503 -308.578789)
			(xy 434.665763 -308.528432) (xy 434.692149 -308.481415) (xy 434.725101 -308.438742) (xy 434.763914 -308.401321)
			(xy 434.807762 -308.369951) (xy 434.85571 -308.345299) (xy 434.906737 -308.327891) (xy 434.959755 -308.318098)
			(xy 435.013634 -308.316129) (xy 435.067225 -308.322026) (xy 435.119386 -308.335662) (xy 435.169006 -308.356749)
			(xy 435.215027 -308.384835) (xy 435.256469 -308.419323) (xy 435.292447 -308.459477) (xy 435.322195 -308.504441)
			(xy 435.34508 -308.553258) (xy 435.360612 -308.604887) (xy 435.368462 -308.658227) (xy 435.368954 -308.685184)
			(xy 442.174899 -308.685184) (xy 442.178834 -308.631413) (xy 442.190557 -308.578789) (xy 442.209817 -308.528432)
			(xy 442.236203 -308.481415) (xy 442.269155 -308.438742) (xy 442.307968 -308.401321) (xy 442.351816 -308.369951)
			(xy 442.399764 -308.345299) (xy 442.450791 -308.327891) (xy 442.503809 -308.318098) (xy 442.557688 -308.316129)
			(xy 442.611279 -308.322026) (xy 442.66344 -308.335662) (xy 442.71306 -308.356749) (xy 442.759081 -308.384835)
			(xy 442.800523 -308.419323) (xy 442.836501 -308.459477) (xy 442.866249 -308.504441) (xy 442.889134 -308.553258)
			(xy 442.904666 -308.604887) (xy 442.912516 -308.658227) (xy 442.913008 -308.685184) (xy 449.718699 -308.685184)
			(xy 449.722634 -308.631413) (xy 449.734357 -308.578789) (xy 449.753617 -308.528432) (xy 449.780003 -308.481415)
			(xy 449.812955 -308.438742) (xy 449.851768 -308.401321) (xy 449.895616 -308.369951) (xy 449.943564 -308.345299)
			(xy 449.994591 -308.327891) (xy 450.047609 -308.318098) (xy 450.101488 -308.316129) (xy 450.155079 -308.322026)
			(xy 450.20724 -308.335662) (xy 450.25686 -308.356749) (xy 450.302881 -308.384835) (xy 450.344323 -308.419323)
			(xy 450.380301 -308.459477) (xy 450.410049 -308.504441) (xy 450.432934 -308.553258) (xy 450.448466 -308.604887)
			(xy 450.456316 -308.658227) (xy 450.456808 -308.685184) (xy 450.456316 -308.712141) (xy 450.448466 -308.765481)
			(xy 450.432934 -308.81711) (xy 450.410049 -308.865927) (xy 450.380301 -308.910891) (xy 450.344323 -308.951045)
			(xy 450.302881 -308.985533) (xy 450.25686 -309.013619) (xy 450.20724 -309.034706) (xy 450.155079 -309.048342)
			(xy 450.101488 -309.054239) (xy 450.047609 -309.05227) (xy 449.994591 -309.042477) (xy 449.943564 -309.025069)
			(xy 449.895616 -309.000417) (xy 449.851768 -308.969047) (xy 449.812955 -308.931626) (xy 449.780003 -308.888953)
			(xy 449.753617 -308.841936) (xy 449.734357 -308.791579) (xy 449.722634 -308.738955) (xy 449.718699 -308.685184)
			(xy 442.913008 -308.685184) (xy 442.912516 -308.712141) (xy 442.904666 -308.765481) (xy 442.889134 -308.81711)
			(xy 442.866249 -308.865927) (xy 442.836501 -308.910891) (xy 442.800523 -308.951045) (xy 442.759081 -308.985533)
			(xy 442.71306 -309.013619) (xy 442.66344 -309.034706) (xy 442.611279 -309.048342) (xy 442.557688 -309.054239)
			(xy 442.503809 -309.05227) (xy 442.450791 -309.042477) (xy 442.399764 -309.025069) (xy 442.351816 -309.000417)
			(xy 442.307968 -308.969047) (xy 442.269155 -308.931626) (xy 442.236203 -308.888953) (xy 442.209817 -308.841936)
			(xy 442.190557 -308.791579) (xy 442.178834 -308.738955) (xy 442.174899 -308.685184) (xy 435.368954 -308.685184)
			(xy 435.368462 -308.712141) (xy 435.360612 -308.765481) (xy 435.34508 -308.81711) (xy 435.322195 -308.865927)
			(xy 435.292447 -308.910891) (xy 435.256469 -308.951045) (xy 435.215027 -308.985533) (xy 435.169006 -309.013619)
			(xy 435.119386 -309.034706) (xy 435.067225 -309.048342) (xy 435.013634 -309.054239) (xy 434.959755 -309.05227)
			(xy 434.906737 -309.042477) (xy 434.85571 -309.025069) (xy 434.807762 -309.000417) (xy 434.763914 -308.969047)
			(xy 434.725101 -308.931626) (xy 434.692149 -308.888953) (xy 434.665763 -308.841936) (xy 434.646503 -308.791579)
			(xy 434.63478 -308.738955) (xy 434.630845 -308.685184) (xy 427.8249 -308.685184) (xy 427.824408 -308.712141)
			(xy 427.816558 -308.765481) (xy 427.801026 -308.81711) (xy 427.778141 -308.865927) (xy 427.748393 -308.910891)
			(xy 427.712415 -308.951045) (xy 427.670973 -308.985533) (xy 427.624952 -309.013619) (xy 427.575332 -309.034706)
			(xy 427.523171 -309.048342) (xy 427.46958 -309.054239) (xy 427.415701 -309.05227) (xy 427.362683 -309.042477)
			(xy 427.311656 -309.025069) (xy 427.263708 -309.000417) (xy 427.21986 -308.969047) (xy 427.181047 -308.931626)
			(xy 427.148095 -308.888953) (xy 427.121709 -308.841936) (xy 427.102449 -308.791579) (xy 427.090726 -308.738955)
			(xy 427.086791 -308.685184) (xy 425.985178 -308.685184) (xy 425.985178 -309.535068) (xy 431.186859 -309.535068)
			(xy 431.190794 -309.481297) (xy 431.202517 -309.428673) (xy 431.221777 -309.378316) (xy 431.248163 -309.331299)
			(xy 431.281115 -309.288626) (xy 431.319928 -309.251205) (xy 431.363776 -309.219835) (xy 431.411724 -309.195183)
			(xy 431.462751 -309.177775) (xy 431.515769 -309.167982) (xy 431.569648 -309.166013) (xy 431.623239 -309.17191)
			(xy 431.6754 -309.185546) (xy 431.72502 -309.206633) (xy 431.771041 -309.234719) (xy 431.812483 -309.269207)
			(xy 431.848461 -309.309361) (xy 431.878209 -309.354325) (xy 431.901094 -309.403142) (xy 431.916626 -309.454771)
			(xy 431.924476 -309.508111) (xy 431.924968 -309.535068) (xy 438.730913 -309.535068) (xy 438.734848 -309.481297)
			(xy 438.746571 -309.428673) (xy 438.765831 -309.378316) (xy 438.792217 -309.331299) (xy 438.825169 -309.288626)
			(xy 438.863982 -309.251205) (xy 438.90783 -309.219835) (xy 438.955778 -309.195183) (xy 439.006805 -309.177775)
			(xy 439.059823 -309.167982) (xy 439.113702 -309.166013) (xy 439.167293 -309.17191) (xy 439.219454 -309.185546)
			(xy 439.269074 -309.206633) (xy 439.315095 -309.234719) (xy 439.356537 -309.269207) (xy 439.392515 -309.309361)
			(xy 439.422263 -309.354325) (xy 439.445148 -309.403142) (xy 439.46068 -309.454771) (xy 439.46853 -309.508111)
			(xy 439.469022 -309.535068) (xy 446.274967 -309.535068) (xy 446.278902 -309.481297) (xy 446.290625 -309.428673)
			(xy 446.309885 -309.378316) (xy 446.336271 -309.331299) (xy 446.369223 -309.288626) (xy 446.408036 -309.251205)
			(xy 446.451884 -309.219835) (xy 446.499832 -309.195183) (xy 446.550859 -309.177775) (xy 446.603877 -309.167982)
			(xy 446.657756 -309.166013) (xy 446.711347 -309.17191) (xy 446.763508 -309.185546) (xy 446.813128 -309.206633)
			(xy 446.859149 -309.234719) (xy 446.900591 -309.269207) (xy 446.936569 -309.309361) (xy 446.966317 -309.354325)
			(xy 446.989202 -309.403142) (xy 447.004734 -309.454771) (xy 447.012584 -309.508111) (xy 447.013076 -309.535068)
			(xy 453.818767 -309.535068) (xy 453.822702 -309.481297) (xy 453.834425 -309.428673) (xy 453.853685 -309.378316)
			(xy 453.880071 -309.331299) (xy 453.913023 -309.288626) (xy 453.951836 -309.251205) (xy 453.995684 -309.219835)
			(xy 454.043632 -309.195183) (xy 454.094659 -309.177775) (xy 454.147677 -309.167982) (xy 454.201556 -309.166013)
			(xy 454.255147 -309.17191) (xy 454.307308 -309.185546) (xy 454.356928 -309.206633) (xy 454.402949 -309.234719)
			(xy 454.444391 -309.269207) (xy 454.480369 -309.309361) (xy 454.510117 -309.354325) (xy 454.533002 -309.403142)
			(xy 454.548534 -309.454771) (xy 454.556384 -309.508111) (xy 454.556876 -309.535068) (xy 454.556384 -309.562025)
			(xy 454.548534 -309.615365) (xy 454.533002 -309.666994) (xy 454.510117 -309.715811) (xy 454.480369 -309.760775)
			(xy 454.444391 -309.800929) (xy 454.402949 -309.835417) (xy 454.356928 -309.863503) (xy 454.307308 -309.88459)
			(xy 454.255147 -309.898226) (xy 454.201556 -309.904123) (xy 454.147677 -309.902154) (xy 454.094659 -309.892361)
			(xy 454.043632 -309.874953) (xy 453.995684 -309.850301) (xy 453.951836 -309.818931) (xy 453.913023 -309.78151)
			(xy 453.880071 -309.738837) (xy 453.853685 -309.69182) (xy 453.834425 -309.641463) (xy 453.822702 -309.588839)
			(xy 453.818767 -309.535068) (xy 447.013076 -309.535068) (xy 447.012584 -309.562025) (xy 447.004734 -309.615365)
			(xy 446.989202 -309.666994) (xy 446.966317 -309.715811) (xy 446.936569 -309.760775) (xy 446.900591 -309.800929)
			(xy 446.859149 -309.835417) (xy 446.813128 -309.863503) (xy 446.763508 -309.88459) (xy 446.711347 -309.898226)
			(xy 446.657756 -309.904123) (xy 446.603877 -309.902154) (xy 446.550859 -309.892361) (xy 446.499832 -309.874953)
			(xy 446.451884 -309.850301) (xy 446.408036 -309.818931) (xy 446.369223 -309.78151) (xy 446.336271 -309.738837)
			(xy 446.309885 -309.69182) (xy 446.290625 -309.641463) (xy 446.278902 -309.588839) (xy 446.274967 -309.535068)
			(xy 439.469022 -309.535068) (xy 439.46853 -309.562025) (xy 439.46068 -309.615365) (xy 439.445148 -309.666994)
			(xy 439.422263 -309.715811) (xy 439.392515 -309.760775) (xy 439.356537 -309.800929) (xy 439.315095 -309.835417)
			(xy 439.269074 -309.863503) (xy 439.219454 -309.88459) (xy 439.167293 -309.898226) (xy 439.113702 -309.904123)
			(xy 439.059823 -309.902154) (xy 439.006805 -309.892361) (xy 438.955778 -309.874953) (xy 438.90783 -309.850301)
			(xy 438.863982 -309.818931) (xy 438.825169 -309.78151) (xy 438.792217 -309.738837) (xy 438.765831 -309.69182)
			(xy 438.746571 -309.641463) (xy 438.734848 -309.588839) (xy 438.730913 -309.535068) (xy 431.924968 -309.535068)
			(xy 431.924476 -309.562025) (xy 431.916626 -309.615365) (xy 431.901094 -309.666994) (xy 431.878209 -309.715811)
			(xy 431.848461 -309.760775) (xy 431.812483 -309.800929) (xy 431.771041 -309.835417) (xy 431.72502 -309.863503)
			(xy 431.6754 -309.88459) (xy 431.623239 -309.898226) (xy 431.569648 -309.904123) (xy 431.515769 -309.902154)
			(xy 431.462751 -309.892361) (xy 431.411724 -309.874953) (xy 431.363776 -309.850301) (xy 431.319928 -309.818931)
			(xy 431.281115 -309.78151) (xy 431.248163 -309.738837) (xy 431.221777 -309.69182) (xy 431.202517 -309.641463)
			(xy 431.190794 -309.588839) (xy 431.186859 -309.535068) (xy 425.985178 -309.535068) (xy 425.985178 -310.384952)
			(xy 427.086791 -310.384952) (xy 427.090726 -310.331181) (xy 427.102449 -310.278557) (xy 427.121709 -310.2282)
			(xy 427.148095 -310.181183) (xy 427.181047 -310.13851) (xy 427.21986 -310.101089) (xy 427.263708 -310.069719)
			(xy 427.311656 -310.045067) (xy 427.362683 -310.027659) (xy 427.415701 -310.017866) (xy 427.46958 -310.015897)
			(xy 427.523171 -310.021794) (xy 427.575332 -310.03543) (xy 427.624952 -310.056517) (xy 427.670973 -310.084603)
			(xy 427.712415 -310.119091) (xy 427.748393 -310.159245) (xy 427.778141 -310.204209) (xy 427.801026 -310.253026)
			(xy 427.816558 -310.304655) (xy 427.824408 -310.357995) (xy 427.8249 -310.384952) (xy 434.630845 -310.384952)
			(xy 434.63478 -310.331181) (xy 434.646503 -310.278557) (xy 434.665763 -310.2282) (xy 434.692149 -310.181183)
			(xy 434.725101 -310.13851) (xy 434.763914 -310.101089) (xy 434.807762 -310.069719) (xy 434.85571 -310.045067)
			(xy 434.906737 -310.027659) (xy 434.959755 -310.017866) (xy 435.013634 -310.015897) (xy 435.067225 -310.021794)
			(xy 435.119386 -310.03543) (xy 435.169006 -310.056517) (xy 435.215027 -310.084603) (xy 435.256469 -310.119091)
			(xy 435.292447 -310.159245) (xy 435.322195 -310.204209) (xy 435.34508 -310.253026) (xy 435.360612 -310.304655)
			(xy 435.368462 -310.357995) (xy 435.368954 -310.384952) (xy 442.174899 -310.384952) (xy 442.178834 -310.331181)
			(xy 442.190557 -310.278557) (xy 442.209817 -310.2282) (xy 442.236203 -310.181183) (xy 442.269155 -310.13851)
			(xy 442.307968 -310.101089) (xy 442.351816 -310.069719) (xy 442.399764 -310.045067) (xy 442.450791 -310.027659)
			(xy 442.503809 -310.017866) (xy 442.557688 -310.015897) (xy 442.611279 -310.021794) (xy 442.66344 -310.03543)
			(xy 442.71306 -310.056517) (xy 442.759081 -310.084603) (xy 442.800523 -310.119091) (xy 442.836501 -310.159245)
			(xy 442.866249 -310.204209) (xy 442.889134 -310.253026) (xy 442.904666 -310.304655) (xy 442.912516 -310.357995)
			(xy 442.913008 -310.384952) (xy 449.718699 -310.384952) (xy 449.722634 -310.331181) (xy 449.734357 -310.278557)
			(xy 449.753617 -310.2282) (xy 449.780003 -310.181183) (xy 449.812955 -310.13851) (xy 449.851768 -310.101089)
			(xy 449.895616 -310.069719) (xy 449.943564 -310.045067) (xy 449.994591 -310.027659) (xy 450.047609 -310.017866)
			(xy 450.101488 -310.015897) (xy 450.155079 -310.021794) (xy 450.20724 -310.03543) (xy 450.25686 -310.056517)
			(xy 450.302881 -310.084603) (xy 450.344323 -310.119091) (xy 450.380301 -310.159245) (xy 450.410049 -310.204209)
			(xy 450.432934 -310.253026) (xy 450.448466 -310.304655) (xy 450.456316 -310.357995) (xy 450.456808 -310.384952)
			(xy 450.456316 -310.411909) (xy 450.448466 -310.465249) (xy 450.432934 -310.516878) (xy 450.410049 -310.565695)
			(xy 450.380301 -310.610659) (xy 450.344323 -310.650813) (xy 450.302881 -310.685301) (xy 450.25686 -310.713387)
			(xy 450.20724 -310.734474) (xy 450.155079 -310.74811) (xy 450.101488 -310.754007) (xy 450.047609 -310.752038)
			(xy 449.994591 -310.742245) (xy 449.943564 -310.724837) (xy 449.895616 -310.700185) (xy 449.851768 -310.668815)
			(xy 449.812955 -310.631394) (xy 449.780003 -310.588721) (xy 449.753617 -310.541704) (xy 449.734357 -310.491347)
			(xy 449.722634 -310.438723) (xy 449.718699 -310.384952) (xy 442.913008 -310.384952) (xy 442.912516 -310.411909)
			(xy 442.904666 -310.465249) (xy 442.889134 -310.516878) (xy 442.866249 -310.565695) (xy 442.836501 -310.610659)
			(xy 442.800523 -310.650813) (xy 442.759081 -310.685301) (xy 442.71306 -310.713387) (xy 442.66344 -310.734474)
			(xy 442.611279 -310.74811) (xy 442.557688 -310.754007) (xy 442.503809 -310.752038) (xy 442.450791 -310.742245)
			(xy 442.399764 -310.724837) (xy 442.351816 -310.700185) (xy 442.307968 -310.668815) (xy 442.269155 -310.631394)
			(xy 442.236203 -310.588721) (xy 442.209817 -310.541704) (xy 442.190557 -310.491347) (xy 442.178834 -310.438723)
			(xy 442.174899 -310.384952) (xy 435.368954 -310.384952) (xy 435.368462 -310.411909) (xy 435.360612 -310.465249)
			(xy 435.34508 -310.516878) (xy 435.322195 -310.565695) (xy 435.292447 -310.610659) (xy 435.256469 -310.650813)
			(xy 435.215027 -310.685301) (xy 435.169006 -310.713387) (xy 435.119386 -310.734474) (xy 435.067225 -310.74811)
			(xy 435.013634 -310.754007) (xy 434.959755 -310.752038) (xy 434.906737 -310.742245) (xy 434.85571 -310.724837)
			(xy 434.807762 -310.700185) (xy 434.763914 -310.668815) (xy 434.725101 -310.631394) (xy 434.692149 -310.588721)
			(xy 434.665763 -310.541704) (xy 434.646503 -310.491347) (xy 434.63478 -310.438723) (xy 434.630845 -310.384952)
			(xy 427.8249 -310.384952) (xy 427.824408 -310.411909) (xy 427.816558 -310.465249) (xy 427.801026 -310.516878)
			(xy 427.778141 -310.565695) (xy 427.748393 -310.610659) (xy 427.712415 -310.650813) (xy 427.670973 -310.685301)
			(xy 427.624952 -310.713387) (xy 427.575332 -310.734474) (xy 427.523171 -310.74811) (xy 427.46958 -310.754007)
			(xy 427.415701 -310.752038) (xy 427.362683 -310.742245) (xy 427.311656 -310.724837) (xy 427.263708 -310.700185)
			(xy 427.21986 -310.668815) (xy 427.181047 -310.631394) (xy 427.148095 -310.588721) (xy 427.121709 -310.541704)
			(xy 427.102449 -310.491347) (xy 427.090726 -310.438723) (xy 427.086791 -310.384952) (xy 425.985178 -310.384952)
			(xy 425.985178 -311.23509) (xy 431.186859 -311.23509) (xy 431.190794 -311.181319) (xy 431.202517 -311.128695)
			(xy 431.221777 -311.078338) (xy 431.248163 -311.031321) (xy 431.281115 -310.988648) (xy 431.319928 -310.951227)
			(xy 431.363776 -310.919857) (xy 431.411724 -310.895205) (xy 431.462751 -310.877797) (xy 431.515769 -310.868004)
			(xy 431.569648 -310.866035) (xy 431.623239 -310.871932) (xy 431.6754 -310.885568) (xy 431.72502 -310.906655)
			(xy 431.771041 -310.934741) (xy 431.812483 -310.969229) (xy 431.848461 -311.009383) (xy 431.878209 -311.054347)
			(xy 431.901094 -311.103164) (xy 431.916626 -311.154793) (xy 431.924476 -311.208133) (xy 431.924968 -311.23509)
			(xy 438.730913 -311.23509) (xy 438.734848 -311.181319) (xy 438.746571 -311.128695) (xy 438.765831 -311.078338)
			(xy 438.792217 -311.031321) (xy 438.825169 -310.988648) (xy 438.863982 -310.951227) (xy 438.90783 -310.919857)
			(xy 438.955778 -310.895205) (xy 439.006805 -310.877797) (xy 439.059823 -310.868004) (xy 439.113702 -310.866035)
			(xy 439.167293 -310.871932) (xy 439.219454 -310.885568) (xy 439.269074 -310.906655) (xy 439.315095 -310.934741)
			(xy 439.356537 -310.969229) (xy 439.392515 -311.009383) (xy 439.422263 -311.054347) (xy 439.445148 -311.103164)
			(xy 439.46068 -311.154793) (xy 439.46853 -311.208133) (xy 439.469022 -311.23509) (xy 446.274967 -311.23509)
			(xy 446.278902 -311.181319) (xy 446.290625 -311.128695) (xy 446.309885 -311.078338) (xy 446.336271 -311.031321)
			(xy 446.369223 -310.988648) (xy 446.408036 -310.951227) (xy 446.451884 -310.919857) (xy 446.499832 -310.895205)
			(xy 446.550859 -310.877797) (xy 446.603877 -310.868004) (xy 446.657756 -310.866035) (xy 446.711347 -310.871932)
			(xy 446.763508 -310.885568) (xy 446.813128 -310.906655) (xy 446.859149 -310.934741) (xy 446.900591 -310.969229)
			(xy 446.936569 -311.009383) (xy 446.966317 -311.054347) (xy 446.989202 -311.103164) (xy 447.004734 -311.154793)
			(xy 447.012584 -311.208133) (xy 447.013076 -311.23509) (xy 453.818767 -311.23509) (xy 453.822702 -311.181319)
			(xy 453.834425 -311.128695) (xy 453.853685 -311.078338) (xy 453.880071 -311.031321) (xy 453.913023 -310.988648)
			(xy 453.951836 -310.951227) (xy 453.995684 -310.919857) (xy 454.043632 -310.895205) (xy 454.094659 -310.877797)
			(xy 454.147677 -310.868004) (xy 454.201556 -310.866035) (xy 454.255147 -310.871932) (xy 454.307308 -310.885568)
			(xy 454.356928 -310.906655) (xy 454.402949 -310.934741) (xy 454.444391 -310.969229) (xy 454.480369 -311.009383)
			(xy 454.510117 -311.054347) (xy 454.533002 -311.103164) (xy 454.548534 -311.154793) (xy 454.556384 -311.208133)
			(xy 454.556876 -311.23509) (xy 454.556384 -311.262047) (xy 454.548534 -311.315387) (xy 454.533002 -311.367016)
			(xy 454.510117 -311.415833) (xy 454.480369 -311.460797) (xy 454.444391 -311.500951) (xy 454.402949 -311.535439)
			(xy 454.356928 -311.563525) (xy 454.307308 -311.584612) (xy 454.255147 -311.598248) (xy 454.201556 -311.604145)
			(xy 454.147677 -311.602176) (xy 454.094659 -311.592383) (xy 454.043632 -311.574975) (xy 453.995684 -311.550323)
			(xy 453.951836 -311.518953) (xy 453.913023 -311.481532) (xy 453.880071 -311.438859) (xy 453.853685 -311.391842)
			(xy 453.834425 -311.341485) (xy 453.822702 -311.288861) (xy 453.818767 -311.23509) (xy 447.013076 -311.23509)
			(xy 447.012584 -311.262047) (xy 447.004734 -311.315387) (xy 446.989202 -311.367016) (xy 446.966317 -311.415833)
			(xy 446.936569 -311.460797) (xy 446.900591 -311.500951) (xy 446.859149 -311.535439) (xy 446.813128 -311.563525)
			(xy 446.763508 -311.584612) (xy 446.711347 -311.598248) (xy 446.657756 -311.604145) (xy 446.603877 -311.602176)
			(xy 446.550859 -311.592383) (xy 446.499832 -311.574975) (xy 446.451884 -311.550323) (xy 446.408036 -311.518953)
			(xy 446.369223 -311.481532) (xy 446.336271 -311.438859) (xy 446.309885 -311.391842) (xy 446.290625 -311.341485)
			(xy 446.278902 -311.288861) (xy 446.274967 -311.23509) (xy 439.469022 -311.23509) (xy 439.46853 -311.262047)
			(xy 439.46068 -311.315387) (xy 439.445148 -311.367016) (xy 439.422263 -311.415833) (xy 439.392515 -311.460797)
			(xy 439.356537 -311.500951) (xy 439.315095 -311.535439) (xy 439.269074 -311.563525) (xy 439.219454 -311.584612)
			(xy 439.167293 -311.598248) (xy 439.113702 -311.604145) (xy 439.059823 -311.602176) (xy 439.006805 -311.592383)
			(xy 438.955778 -311.574975) (xy 438.90783 -311.550323) (xy 438.863982 -311.518953) (xy 438.825169 -311.481532)
			(xy 438.792217 -311.438859) (xy 438.765831 -311.391842) (xy 438.746571 -311.341485) (xy 438.734848 -311.288861)
			(xy 438.730913 -311.23509) (xy 431.924968 -311.23509) (xy 431.924476 -311.262047) (xy 431.916626 -311.315387)
			(xy 431.901094 -311.367016) (xy 431.878209 -311.415833) (xy 431.848461 -311.460797) (xy 431.812483 -311.500951)
			(xy 431.771041 -311.535439) (xy 431.72502 -311.563525) (xy 431.6754 -311.584612) (xy 431.623239 -311.598248)
			(xy 431.569648 -311.604145) (xy 431.515769 -311.602176) (xy 431.462751 -311.592383) (xy 431.411724 -311.574975)
			(xy 431.363776 -311.550323) (xy 431.319928 -311.518953) (xy 431.281115 -311.481532) (xy 431.248163 -311.438859)
			(xy 431.221777 -311.391842) (xy 431.202517 -311.341485) (xy 431.190794 -311.288861) (xy 431.186859 -311.23509)
			(xy 425.985178 -311.23509) (xy 425.985178 -312.084974) (xy 427.086791 -312.084974) (xy 427.090726 -312.031203)
			(xy 427.102449 -311.978579) (xy 427.121709 -311.928222) (xy 427.148095 -311.881205) (xy 427.181047 -311.838532)
			(xy 427.21986 -311.801111) (xy 427.263708 -311.769741) (xy 427.311656 -311.745089) (xy 427.362683 -311.727681)
			(xy 427.415701 -311.717888) (xy 427.46958 -311.715919) (xy 427.523171 -311.721816) (xy 427.575332 -311.735452)
			(xy 427.624952 -311.756539) (xy 427.670973 -311.784625) (xy 427.712415 -311.819113) (xy 427.748393 -311.859267)
			(xy 427.778141 -311.904231) (xy 427.801026 -311.953048) (xy 427.816558 -312.004677) (xy 427.824408 -312.058017)
			(xy 427.8249 -312.084974) (xy 434.630845 -312.084974) (xy 434.63478 -312.031203) (xy 434.646503 -311.978579)
			(xy 434.665763 -311.928222) (xy 434.692149 -311.881205) (xy 434.725101 -311.838532) (xy 434.763914 -311.801111)
			(xy 434.807762 -311.769741) (xy 434.85571 -311.745089) (xy 434.906737 -311.727681) (xy 434.959755 -311.717888)
			(xy 435.013634 -311.715919) (xy 435.067225 -311.721816) (xy 435.119386 -311.735452) (xy 435.169006 -311.756539)
			(xy 435.215027 -311.784625) (xy 435.256469 -311.819113) (xy 435.292447 -311.859267) (xy 435.322195 -311.904231)
			(xy 435.34508 -311.953048) (xy 435.360612 -312.004677) (xy 435.368462 -312.058017) (xy 435.368954 -312.084974)
			(xy 442.174899 -312.084974) (xy 442.178834 -312.031203) (xy 442.190557 -311.978579) (xy 442.209817 -311.928222)
			(xy 442.236203 -311.881205) (xy 442.269155 -311.838532) (xy 442.307968 -311.801111) (xy 442.351816 -311.769741)
			(xy 442.399764 -311.745089) (xy 442.450791 -311.727681) (xy 442.503809 -311.717888) (xy 442.557688 -311.715919)
			(xy 442.611279 -311.721816) (xy 442.66344 -311.735452) (xy 442.71306 -311.756539) (xy 442.759081 -311.784625)
			(xy 442.800523 -311.819113) (xy 442.836501 -311.859267) (xy 442.866249 -311.904231) (xy 442.889134 -311.953048)
			(xy 442.904666 -312.004677) (xy 442.912516 -312.058017) (xy 442.913008 -312.084974) (xy 449.718699 -312.084974)
			(xy 449.722634 -312.031203) (xy 449.734357 -311.978579) (xy 449.753617 -311.928222) (xy 449.780003 -311.881205)
			(xy 449.812955 -311.838532) (xy 449.851768 -311.801111) (xy 449.895616 -311.769741) (xy 449.943564 -311.745089)
			(xy 449.994591 -311.727681) (xy 450.047609 -311.717888) (xy 450.101488 -311.715919) (xy 450.155079 -311.721816)
			(xy 450.20724 -311.735452) (xy 450.25686 -311.756539) (xy 450.302881 -311.784625) (xy 450.344323 -311.819113)
			(xy 450.380301 -311.859267) (xy 450.410049 -311.904231) (xy 450.432934 -311.953048) (xy 450.448466 -312.004677)
			(xy 450.456316 -312.058017) (xy 450.456808 -312.084974) (xy 450.456316 -312.111931) (xy 450.448466 -312.165271)
			(xy 450.432934 -312.2169) (xy 450.410049 -312.265717) (xy 450.380301 -312.310681) (xy 450.344323 -312.350835)
			(xy 450.302881 -312.385323) (xy 450.25686 -312.413409) (xy 450.20724 -312.434496) (xy 450.155079 -312.448132)
			(xy 450.101488 -312.454029) (xy 450.047609 -312.45206) (xy 449.994591 -312.442267) (xy 449.943564 -312.424859)
			(xy 449.895616 -312.400207) (xy 449.851768 -312.368837) (xy 449.812955 -312.331416) (xy 449.780003 -312.288743)
			(xy 449.753617 -312.241726) (xy 449.734357 -312.191369) (xy 449.722634 -312.138745) (xy 449.718699 -312.084974)
			(xy 442.913008 -312.084974) (xy 442.912516 -312.111931) (xy 442.904666 -312.165271) (xy 442.889134 -312.2169)
			(xy 442.866249 -312.265717) (xy 442.836501 -312.310681) (xy 442.800523 -312.350835) (xy 442.759081 -312.385323)
			(xy 442.71306 -312.413409) (xy 442.66344 -312.434496) (xy 442.611279 -312.448132) (xy 442.557688 -312.454029)
			(xy 442.503809 -312.45206) (xy 442.450791 -312.442267) (xy 442.399764 -312.424859) (xy 442.351816 -312.400207)
			(xy 442.307968 -312.368837) (xy 442.269155 -312.331416) (xy 442.236203 -312.288743) (xy 442.209817 -312.241726)
			(xy 442.190557 -312.191369) (xy 442.178834 -312.138745) (xy 442.174899 -312.084974) (xy 435.368954 -312.084974)
			(xy 435.368462 -312.111931) (xy 435.360612 -312.165271) (xy 435.34508 -312.2169) (xy 435.322195 -312.265717)
			(xy 435.292447 -312.310681) (xy 435.256469 -312.350835) (xy 435.215027 -312.385323) (xy 435.169006 -312.413409)
			(xy 435.119386 -312.434496) (xy 435.067225 -312.448132) (xy 435.013634 -312.454029) (xy 434.959755 -312.45206)
			(xy 434.906737 -312.442267) (xy 434.85571 -312.424859) (xy 434.807762 -312.400207) (xy 434.763914 -312.368837)
			(xy 434.725101 -312.331416) (xy 434.692149 -312.288743) (xy 434.665763 -312.241726) (xy 434.646503 -312.191369)
			(xy 434.63478 -312.138745) (xy 434.630845 -312.084974) (xy 427.8249 -312.084974) (xy 427.824408 -312.111931)
			(xy 427.816558 -312.165271) (xy 427.801026 -312.2169) (xy 427.778141 -312.265717) (xy 427.748393 -312.310681)
			(xy 427.712415 -312.350835) (xy 427.670973 -312.385323) (xy 427.624952 -312.413409) (xy 427.575332 -312.434496)
			(xy 427.523171 -312.448132) (xy 427.46958 -312.454029) (xy 427.415701 -312.45206) (xy 427.362683 -312.442267)
			(xy 427.311656 -312.424859) (xy 427.263708 -312.400207) (xy 427.21986 -312.368837) (xy 427.181047 -312.331416)
			(xy 427.148095 -312.288743) (xy 427.121709 -312.241726) (xy 427.102449 -312.191369) (xy 427.090726 -312.138745)
			(xy 427.086791 -312.084974) (xy 425.985178 -312.084974) (xy 425.985178 -312.935112) (xy 431.186859 -312.935112)
			(xy 431.190794 -312.881341) (xy 431.202517 -312.828717) (xy 431.221777 -312.77836) (xy 431.248163 -312.731343)
			(xy 431.281115 -312.68867) (xy 431.319928 -312.651249) (xy 431.363776 -312.619879) (xy 431.411724 -312.595227)
			(xy 431.462751 -312.577819) (xy 431.515769 -312.568026) (xy 431.569648 -312.566057) (xy 431.623239 -312.571954)
			(xy 431.6754 -312.58559) (xy 431.72502 -312.606677) (xy 431.771041 -312.634763) (xy 431.812483 -312.669251)
			(xy 431.848461 -312.709405) (xy 431.878209 -312.754369) (xy 431.901094 -312.803186) (xy 431.916626 -312.854815)
			(xy 431.924476 -312.908155) (xy 431.924968 -312.935112) (xy 438.730913 -312.935112) (xy 438.734848 -312.881341)
			(xy 438.746571 -312.828717) (xy 438.765831 -312.77836) (xy 438.792217 -312.731343) (xy 438.825169 -312.68867)
			(xy 438.863982 -312.651249) (xy 438.90783 -312.619879) (xy 438.955778 -312.595227) (xy 439.006805 -312.577819)
			(xy 439.059823 -312.568026) (xy 439.113702 -312.566057) (xy 439.167293 -312.571954) (xy 439.219454 -312.58559)
			(xy 439.269074 -312.606677) (xy 439.315095 -312.634763) (xy 439.356537 -312.669251) (xy 439.392515 -312.709405)
			(xy 439.422263 -312.754369) (xy 439.445148 -312.803186) (xy 439.46068 -312.854815) (xy 439.46853 -312.908155)
			(xy 439.469022 -312.935112) (xy 446.274967 -312.935112) (xy 446.278902 -312.881341) (xy 446.290625 -312.828717)
			(xy 446.309885 -312.77836) (xy 446.336271 -312.731343) (xy 446.369223 -312.68867) (xy 446.408036 -312.651249)
			(xy 446.451884 -312.619879) (xy 446.499832 -312.595227) (xy 446.550859 -312.577819) (xy 446.603877 -312.568026)
			(xy 446.657756 -312.566057) (xy 446.711347 -312.571954) (xy 446.763508 -312.58559) (xy 446.813128 -312.606677)
			(xy 446.859149 -312.634763) (xy 446.900591 -312.669251) (xy 446.936569 -312.709405) (xy 446.966317 -312.754369)
			(xy 446.989202 -312.803186) (xy 447.004734 -312.854815) (xy 447.012584 -312.908155) (xy 447.013076 -312.935112)
			(xy 453.818767 -312.935112) (xy 453.822702 -312.881341) (xy 453.834425 -312.828717) (xy 453.853685 -312.77836)
			(xy 453.880071 -312.731343) (xy 453.913023 -312.68867) (xy 453.951836 -312.651249) (xy 453.995684 -312.619879)
			(xy 454.043632 -312.595227) (xy 454.094659 -312.577819) (xy 454.147677 -312.568026) (xy 454.201556 -312.566057)
			(xy 454.255147 -312.571954) (xy 454.307308 -312.58559) (xy 454.356928 -312.606677) (xy 454.402949 -312.634763)
			(xy 454.444391 -312.669251) (xy 454.480369 -312.709405) (xy 454.510117 -312.754369) (xy 454.533002 -312.803186)
			(xy 454.548534 -312.854815) (xy 454.556384 -312.908155) (xy 454.556876 -312.935112) (xy 454.556384 -312.962069)
			(xy 454.548534 -313.015409) (xy 454.533002 -313.067038) (xy 454.510117 -313.115855) (xy 454.480369 -313.160819)
			(xy 454.444391 -313.200973) (xy 454.402949 -313.235461) (xy 454.356928 -313.263547) (xy 454.307308 -313.284634)
			(xy 454.255147 -313.29827) (xy 454.201556 -313.304167) (xy 454.147677 -313.302198) (xy 454.094659 -313.292405)
			(xy 454.043632 -313.274997) (xy 453.995684 -313.250345) (xy 453.951836 -313.218975) (xy 453.913023 -313.181554)
			(xy 453.880071 -313.138881) (xy 453.853685 -313.091864) (xy 453.834425 -313.041507) (xy 453.822702 -312.988883)
			(xy 453.818767 -312.935112) (xy 447.013076 -312.935112) (xy 447.012584 -312.962069) (xy 447.004734 -313.015409)
			(xy 446.989202 -313.067038) (xy 446.966317 -313.115855) (xy 446.936569 -313.160819) (xy 446.900591 -313.200973)
			(xy 446.859149 -313.235461) (xy 446.813128 -313.263547) (xy 446.763508 -313.284634) (xy 446.711347 -313.29827)
			(xy 446.657756 -313.304167) (xy 446.603877 -313.302198) (xy 446.550859 -313.292405) (xy 446.499832 -313.274997)
			(xy 446.451884 -313.250345) (xy 446.408036 -313.218975) (xy 446.369223 -313.181554) (xy 446.336271 -313.138881)
			(xy 446.309885 -313.091864) (xy 446.290625 -313.041507) (xy 446.278902 -312.988883) (xy 446.274967 -312.935112)
			(xy 439.469022 -312.935112) (xy 439.46853 -312.962069) (xy 439.46068 -313.015409) (xy 439.445148 -313.067038)
			(xy 439.422263 -313.115855) (xy 439.392515 -313.160819) (xy 439.356537 -313.200973) (xy 439.315095 -313.235461)
			(xy 439.269074 -313.263547) (xy 439.219454 -313.284634) (xy 439.167293 -313.29827) (xy 439.113702 -313.304167)
			(xy 439.059823 -313.302198) (xy 439.006805 -313.292405) (xy 438.955778 -313.274997) (xy 438.90783 -313.250345)
			(xy 438.863982 -313.218975) (xy 438.825169 -313.181554) (xy 438.792217 -313.138881) (xy 438.765831 -313.091864)
			(xy 438.746571 -313.041507) (xy 438.734848 -312.988883) (xy 438.730913 -312.935112) (xy 431.924968 -312.935112)
			(xy 431.924476 -312.962069) (xy 431.916626 -313.015409) (xy 431.901094 -313.067038) (xy 431.878209 -313.115855)
			(xy 431.848461 -313.160819) (xy 431.812483 -313.200973) (xy 431.771041 -313.235461) (xy 431.72502 -313.263547)
			(xy 431.6754 -313.284634) (xy 431.623239 -313.29827) (xy 431.569648 -313.304167) (xy 431.515769 -313.302198)
			(xy 431.462751 -313.292405) (xy 431.411724 -313.274997) (xy 431.363776 -313.250345) (xy 431.319928 -313.218975)
			(xy 431.281115 -313.181554) (xy 431.248163 -313.138881) (xy 431.221777 -313.091864) (xy 431.202517 -313.041507)
			(xy 431.190794 -312.988883) (xy 431.186859 -312.935112) (xy 425.985178 -312.935112) (xy 425.985178 -313.784996)
			(xy 427.086791 -313.784996) (xy 427.090726 -313.731225) (xy 427.102449 -313.678601) (xy 427.121709 -313.628244)
			(xy 427.148095 -313.581227) (xy 427.181047 -313.538554) (xy 427.21986 -313.501133) (xy 427.263708 -313.469763)
			(xy 427.311656 -313.445111) (xy 427.362683 -313.427703) (xy 427.415701 -313.41791) (xy 427.46958 -313.415941)
			(xy 427.523171 -313.421838) (xy 427.575332 -313.435474) (xy 427.624952 -313.456561) (xy 427.670973 -313.484647)
			(xy 427.712415 -313.519135) (xy 427.748393 -313.559289) (xy 427.778141 -313.604253) (xy 427.801026 -313.65307)
			(xy 427.816558 -313.704699) (xy 427.824408 -313.758039) (xy 427.8249 -313.784996) (xy 431.186859 -313.784996)
			(xy 431.190794 -313.731225) (xy 431.202517 -313.678601) (xy 431.221777 -313.628244) (xy 431.248163 -313.581227)
			(xy 431.281115 -313.538554) (xy 431.319928 -313.501133) (xy 431.363776 -313.469763) (xy 431.411724 -313.445111)
			(xy 431.462751 -313.427703) (xy 431.515769 -313.41791) (xy 431.569648 -313.415941) (xy 431.623239 -313.421838)
			(xy 431.6754 -313.435474) (xy 431.72502 -313.456561) (xy 431.771041 -313.484647) (xy 431.812483 -313.519135)
			(xy 431.848461 -313.559289) (xy 431.878209 -313.604253) (xy 431.901094 -313.65307) (xy 431.916626 -313.704699)
			(xy 431.924476 -313.758039) (xy 431.924968 -313.784996) (xy 434.630845 -313.784996) (xy 434.63478 -313.731225)
			(xy 434.646503 -313.678601) (xy 434.665763 -313.628244) (xy 434.692149 -313.581227) (xy 434.725101 -313.538554)
			(xy 434.763914 -313.501133) (xy 434.807762 -313.469763) (xy 434.85571 -313.445111) (xy 434.906737 -313.427703)
			(xy 434.959755 -313.41791) (xy 435.013634 -313.415941) (xy 435.067225 -313.421838) (xy 435.119386 -313.435474)
			(xy 435.169006 -313.456561) (xy 435.215027 -313.484647) (xy 435.256469 -313.519135) (xy 435.292447 -313.559289)
			(xy 435.322195 -313.604253) (xy 435.34508 -313.65307) (xy 435.360612 -313.704699) (xy 435.368462 -313.758039)
			(xy 435.368954 -313.784996) (xy 438.730913 -313.784996) (xy 438.734848 -313.731225) (xy 438.746571 -313.678601)
			(xy 438.765831 -313.628244) (xy 438.792217 -313.581227) (xy 438.825169 -313.538554) (xy 438.863982 -313.501133)
			(xy 438.90783 -313.469763) (xy 438.955778 -313.445111) (xy 439.006805 -313.427703) (xy 439.059823 -313.41791)
			(xy 439.113702 -313.415941) (xy 439.167293 -313.421838) (xy 439.219454 -313.435474) (xy 439.269074 -313.456561)
			(xy 439.315095 -313.484647) (xy 439.356537 -313.519135) (xy 439.392515 -313.559289) (xy 439.422263 -313.604253)
			(xy 439.445148 -313.65307) (xy 439.46068 -313.704699) (xy 439.46853 -313.758039) (xy 439.469022 -313.784996)
			(xy 442.174899 -313.784996) (xy 442.178834 -313.731225) (xy 442.190557 -313.678601) (xy 442.209817 -313.628244)
			(xy 442.236203 -313.581227) (xy 442.269155 -313.538554) (xy 442.307968 -313.501133) (xy 442.351816 -313.469763)
			(xy 442.399764 -313.445111) (xy 442.450791 -313.427703) (xy 442.503809 -313.41791) (xy 442.557688 -313.415941)
			(xy 442.611279 -313.421838) (xy 442.66344 -313.435474) (xy 442.71306 -313.456561) (xy 442.759081 -313.484647)
			(xy 442.800523 -313.519135) (xy 442.836501 -313.559289) (xy 442.866249 -313.604253) (xy 442.889134 -313.65307)
			(xy 442.904666 -313.704699) (xy 442.912516 -313.758039) (xy 442.913008 -313.784996) (xy 446.274967 -313.784996)
			(xy 446.278902 -313.731225) (xy 446.290625 -313.678601) (xy 446.309885 -313.628244) (xy 446.336271 -313.581227)
			(xy 446.369223 -313.538554) (xy 446.408036 -313.501133) (xy 446.451884 -313.469763) (xy 446.499832 -313.445111)
			(xy 446.550859 -313.427703) (xy 446.603877 -313.41791) (xy 446.657756 -313.415941) (xy 446.711347 -313.421838)
			(xy 446.763508 -313.435474) (xy 446.813128 -313.456561) (xy 446.859149 -313.484647) (xy 446.900591 -313.519135)
			(xy 446.936569 -313.559289) (xy 446.966317 -313.604253) (xy 446.989202 -313.65307) (xy 447.004734 -313.704699)
			(xy 447.012584 -313.758039) (xy 447.013076 -313.784996) (xy 449.718699 -313.784996) (xy 449.722634 -313.731225)
			(xy 449.734357 -313.678601) (xy 449.753617 -313.628244) (xy 449.780003 -313.581227) (xy 449.812955 -313.538554)
			(xy 449.851768 -313.501133) (xy 449.895616 -313.469763) (xy 449.943564 -313.445111) (xy 449.994591 -313.427703)
			(xy 450.047609 -313.41791) (xy 450.101488 -313.415941) (xy 450.155079 -313.421838) (xy 450.20724 -313.435474)
			(xy 450.25686 -313.456561) (xy 450.302881 -313.484647) (xy 450.344323 -313.519135) (xy 450.380301 -313.559289)
			(xy 450.410049 -313.604253) (xy 450.432934 -313.65307) (xy 450.448466 -313.704699) (xy 450.456316 -313.758039)
			(xy 450.456808 -313.784996) (xy 453.818767 -313.784996) (xy 453.822702 -313.731225) (xy 453.834425 -313.678601)
			(xy 453.853685 -313.628244) (xy 453.880071 -313.581227) (xy 453.913023 -313.538554) (xy 453.951836 -313.501133)
			(xy 453.995684 -313.469763) (xy 454.043632 -313.445111) (xy 454.094659 -313.427703) (xy 454.147677 -313.41791)
			(xy 454.201556 -313.415941) (xy 454.255147 -313.421838) (xy 454.307308 -313.435474) (xy 454.356928 -313.456561)
			(xy 454.402949 -313.484647) (xy 454.444391 -313.519135) (xy 454.480369 -313.559289) (xy 454.510117 -313.604253)
			(xy 454.533002 -313.65307) (xy 454.548534 -313.704699) (xy 454.556384 -313.758039) (xy 454.556876 -313.784996)
			(xy 454.556384 -313.811953) (xy 454.548534 -313.865293) (xy 454.533002 -313.916922) (xy 454.510117 -313.965739)
			(xy 454.480369 -314.010703) (xy 454.444391 -314.050857) (xy 454.402949 -314.085345) (xy 454.356928 -314.113431)
			(xy 454.307308 -314.134518) (xy 454.255147 -314.148154) (xy 454.201556 -314.154051) (xy 454.147677 -314.152082)
			(xy 454.094659 -314.142289) (xy 454.043632 -314.124881) (xy 453.995684 -314.100229) (xy 453.951836 -314.068859)
			(xy 453.913023 -314.031438) (xy 453.880071 -313.988765) (xy 453.853685 -313.941748) (xy 453.834425 -313.891391)
			(xy 453.822702 -313.838767) (xy 453.818767 -313.784996) (xy 450.456808 -313.784996) (xy 450.456316 -313.811953)
			(xy 450.448466 -313.865293) (xy 450.432934 -313.916922) (xy 450.410049 -313.965739) (xy 450.380301 -314.010703)
			(xy 450.344323 -314.050857) (xy 450.302881 -314.085345) (xy 450.25686 -314.113431) (xy 450.20724 -314.134518)
			(xy 450.155079 -314.148154) (xy 450.101488 -314.154051) (xy 450.047609 -314.152082) (xy 449.994591 -314.142289)
			(xy 449.943564 -314.124881) (xy 449.895616 -314.100229) (xy 449.851768 -314.068859) (xy 449.812955 -314.031438)
			(xy 449.780003 -313.988765) (xy 449.753617 -313.941748) (xy 449.734357 -313.891391) (xy 449.722634 -313.838767)
			(xy 449.718699 -313.784996) (xy 447.013076 -313.784996) (xy 447.012584 -313.811953) (xy 447.004734 -313.865293)
			(xy 446.989202 -313.916922) (xy 446.966317 -313.965739) (xy 446.936569 -314.010703) (xy 446.900591 -314.050857)
			(xy 446.859149 -314.085345) (xy 446.813128 -314.113431) (xy 446.763508 -314.134518) (xy 446.711347 -314.148154)
			(xy 446.657756 -314.154051) (xy 446.603877 -314.152082) (xy 446.550859 -314.142289) (xy 446.499832 -314.124881)
			(xy 446.451884 -314.100229) (xy 446.408036 -314.068859) (xy 446.369223 -314.031438) (xy 446.336271 -313.988765)
			(xy 446.309885 -313.941748) (xy 446.290625 -313.891391) (xy 446.278902 -313.838767) (xy 446.274967 -313.784996)
			(xy 442.913008 -313.784996) (xy 442.912516 -313.811953) (xy 442.904666 -313.865293) (xy 442.889134 -313.916922)
			(xy 442.866249 -313.965739) (xy 442.836501 -314.010703) (xy 442.800523 -314.050857) (xy 442.759081 -314.085345)
			(xy 442.71306 -314.113431) (xy 442.66344 -314.134518) (xy 442.611279 -314.148154) (xy 442.557688 -314.154051)
			(xy 442.503809 -314.152082) (xy 442.450791 -314.142289) (xy 442.399764 -314.124881) (xy 442.351816 -314.100229)
			(xy 442.307968 -314.068859) (xy 442.269155 -314.031438) (xy 442.236203 -313.988765) (xy 442.209817 -313.941748)
			(xy 442.190557 -313.891391) (xy 442.178834 -313.838767) (xy 442.174899 -313.784996) (xy 439.469022 -313.784996)
			(xy 439.46853 -313.811953) (xy 439.46068 -313.865293) (xy 439.445148 -313.916922) (xy 439.422263 -313.965739)
			(xy 439.392515 -314.010703) (xy 439.356537 -314.050857) (xy 439.315095 -314.085345) (xy 439.269074 -314.113431)
			(xy 439.219454 -314.134518) (xy 439.167293 -314.148154) (xy 439.113702 -314.154051) (xy 439.059823 -314.152082)
			(xy 439.006805 -314.142289) (xy 438.955778 -314.124881) (xy 438.90783 -314.100229) (xy 438.863982 -314.068859)
			(xy 438.825169 -314.031438) (xy 438.792217 -313.988765) (xy 438.765831 -313.941748) (xy 438.746571 -313.891391)
			(xy 438.734848 -313.838767) (xy 438.730913 -313.784996) (xy 435.368954 -313.784996) (xy 435.368462 -313.811953)
			(xy 435.360612 -313.865293) (xy 435.34508 -313.916922) (xy 435.322195 -313.965739) (xy 435.292447 -314.010703)
			(xy 435.256469 -314.050857) (xy 435.215027 -314.085345) (xy 435.169006 -314.113431) (xy 435.119386 -314.134518)
			(xy 435.067225 -314.148154) (xy 435.013634 -314.154051) (xy 434.959755 -314.152082) (xy 434.906737 -314.142289)
			(xy 434.85571 -314.124881) (xy 434.807762 -314.100229) (xy 434.763914 -314.068859) (xy 434.725101 -314.031438)
			(xy 434.692149 -313.988765) (xy 434.665763 -313.941748) (xy 434.646503 -313.891391) (xy 434.63478 -313.838767)
			(xy 434.630845 -313.784996) (xy 431.924968 -313.784996) (xy 431.924476 -313.811953) (xy 431.916626 -313.865293)
			(xy 431.901094 -313.916922) (xy 431.878209 -313.965739) (xy 431.848461 -314.010703) (xy 431.812483 -314.050857)
			(xy 431.771041 -314.085345) (xy 431.72502 -314.113431) (xy 431.6754 -314.134518) (xy 431.623239 -314.148154)
			(xy 431.569648 -314.154051) (xy 431.515769 -314.152082) (xy 431.462751 -314.142289) (xy 431.411724 -314.124881)
			(xy 431.363776 -314.100229) (xy 431.319928 -314.068859) (xy 431.281115 -314.031438) (xy 431.248163 -313.988765)
			(xy 431.221777 -313.941748) (xy 431.202517 -313.891391) (xy 431.190794 -313.838767) (xy 431.186859 -313.784996)
			(xy 427.8249 -313.784996) (xy 427.824408 -313.811953) (xy 427.816558 -313.865293) (xy 427.801026 -313.916922)
			(xy 427.778141 -313.965739) (xy 427.748393 -314.010703) (xy 427.712415 -314.050857) (xy 427.670973 -314.085345)
			(xy 427.624952 -314.113431) (xy 427.575332 -314.134518) (xy 427.523171 -314.148154) (xy 427.46958 -314.154051)
			(xy 427.415701 -314.152082) (xy 427.362683 -314.142289) (xy 427.311656 -314.124881) (xy 427.263708 -314.100229)
			(xy 427.21986 -314.068859) (xy 427.181047 -314.031438) (xy 427.148095 -313.988765) (xy 427.121709 -313.941748)
			(xy 427.102449 -313.891391) (xy 427.090726 -313.838767) (xy 427.086791 -313.784996) (xy 425.985178 -313.784996)
			(xy 425.985178 -314.635134) (xy 427.086791 -314.635134) (xy 427.090726 -314.581363) (xy 427.102449 -314.528739)
			(xy 427.121709 -314.478382) (xy 427.148095 -314.431365) (xy 427.181047 -314.388692) (xy 427.21986 -314.351271)
			(xy 427.263708 -314.319901) (xy 427.311656 -314.295249) (xy 427.362683 -314.277841) (xy 427.415701 -314.268048)
			(xy 427.46958 -314.266079) (xy 427.523171 -314.271976) (xy 427.575332 -314.285612) (xy 427.624952 -314.306699)
			(xy 427.670973 -314.334785) (xy 427.712415 -314.369273) (xy 427.748393 -314.409427) (xy 427.778141 -314.454391)
			(xy 427.801026 -314.503208) (xy 427.816558 -314.554837) (xy 427.824408 -314.608177) (xy 427.8249 -314.635134)
			(xy 434.630845 -314.635134) (xy 434.63478 -314.581363) (xy 434.646503 -314.528739) (xy 434.665763 -314.478382)
			(xy 434.692149 -314.431365) (xy 434.725101 -314.388692) (xy 434.763914 -314.351271) (xy 434.807762 -314.319901)
			(xy 434.85571 -314.295249) (xy 434.906737 -314.277841) (xy 434.959755 -314.268048) (xy 435.013634 -314.266079)
			(xy 435.067225 -314.271976) (xy 435.119386 -314.285612) (xy 435.169006 -314.306699) (xy 435.215027 -314.334785)
			(xy 435.256469 -314.369273) (xy 435.292447 -314.409427) (xy 435.322195 -314.454391) (xy 435.34508 -314.503208)
			(xy 435.360612 -314.554837) (xy 435.368462 -314.608177) (xy 435.368954 -314.635134) (xy 442.174899 -314.635134)
			(xy 442.178834 -314.581363) (xy 442.190557 -314.528739) (xy 442.209817 -314.478382) (xy 442.236203 -314.431365)
			(xy 442.269155 -314.388692) (xy 442.307968 -314.351271) (xy 442.351816 -314.319901) (xy 442.399764 -314.295249)
			(xy 442.450791 -314.277841) (xy 442.503809 -314.268048) (xy 442.557688 -314.266079) (xy 442.611279 -314.271976)
			(xy 442.66344 -314.285612) (xy 442.71306 -314.306699) (xy 442.759081 -314.334785) (xy 442.800523 -314.369273)
			(xy 442.836501 -314.409427) (xy 442.866249 -314.454391) (xy 442.889134 -314.503208) (xy 442.904666 -314.554837)
			(xy 442.912516 -314.608177) (xy 442.913008 -314.635134) (xy 449.718699 -314.635134) (xy 449.722634 -314.581363)
			(xy 449.734357 -314.528739) (xy 449.753617 -314.478382) (xy 449.780003 -314.431365) (xy 449.812955 -314.388692)
			(xy 449.851768 -314.351271) (xy 449.895616 -314.319901) (xy 449.943564 -314.295249) (xy 449.994591 -314.277841)
			(xy 450.047609 -314.268048) (xy 450.101488 -314.266079) (xy 450.155079 -314.271976) (xy 450.20724 -314.285612)
			(xy 450.25686 -314.306699) (xy 450.302881 -314.334785) (xy 450.344323 -314.369273) (xy 450.380301 -314.409427)
			(xy 450.410049 -314.454391) (xy 450.432934 -314.503208) (xy 450.448466 -314.554837) (xy 450.456316 -314.608177)
			(xy 450.456808 -314.635134) (xy 450.456316 -314.662091) (xy 450.448466 -314.715431) (xy 450.432934 -314.76706)
			(xy 450.410049 -314.815877) (xy 450.380301 -314.860841) (xy 450.344323 -314.900995) (xy 450.302881 -314.935483)
			(xy 450.25686 -314.963569) (xy 450.20724 -314.984656) (xy 450.155079 -314.998292) (xy 450.101488 -315.004189)
			(xy 450.047609 -315.00222) (xy 449.994591 -314.992427) (xy 449.943564 -314.975019) (xy 449.895616 -314.950367)
			(xy 449.851768 -314.918997) (xy 449.812955 -314.881576) (xy 449.780003 -314.838903) (xy 449.753617 -314.791886)
			(xy 449.734357 -314.741529) (xy 449.722634 -314.688905) (xy 449.718699 -314.635134) (xy 442.913008 -314.635134)
			(xy 442.912516 -314.662091) (xy 442.904666 -314.715431) (xy 442.889134 -314.76706) (xy 442.866249 -314.815877)
			(xy 442.836501 -314.860841) (xy 442.800523 -314.900995) (xy 442.759081 -314.935483) (xy 442.71306 -314.963569)
			(xy 442.66344 -314.984656) (xy 442.611279 -314.998292) (xy 442.557688 -315.004189) (xy 442.503809 -315.00222)
			(xy 442.450791 -314.992427) (xy 442.399764 -314.975019) (xy 442.351816 -314.950367) (xy 442.307968 -314.918997)
			(xy 442.269155 -314.881576) (xy 442.236203 -314.838903) (xy 442.209817 -314.791886) (xy 442.190557 -314.741529)
			(xy 442.178834 -314.688905) (xy 442.174899 -314.635134) (xy 435.368954 -314.635134) (xy 435.368462 -314.662091)
			(xy 435.360612 -314.715431) (xy 435.34508 -314.76706) (xy 435.322195 -314.815877) (xy 435.292447 -314.860841)
			(xy 435.256469 -314.900995) (xy 435.215027 -314.935483) (xy 435.169006 -314.963569) (xy 435.119386 -314.984656)
			(xy 435.067225 -314.998292) (xy 435.013634 -315.004189) (xy 434.959755 -315.00222) (xy 434.906737 -314.992427)
			(xy 434.85571 -314.975019) (xy 434.807762 -314.950367) (xy 434.763914 -314.918997) (xy 434.725101 -314.881576)
			(xy 434.692149 -314.838903) (xy 434.665763 -314.791886) (xy 434.646503 -314.741529) (xy 434.63478 -314.688905)
			(xy 434.630845 -314.635134) (xy 427.8249 -314.635134) (xy 427.824408 -314.662091) (xy 427.816558 -314.715431)
			(xy 427.801026 -314.76706) (xy 427.778141 -314.815877) (xy 427.748393 -314.860841) (xy 427.712415 -314.900995)
			(xy 427.670973 -314.935483) (xy 427.624952 -314.963569) (xy 427.575332 -314.984656) (xy 427.523171 -314.998292)
			(xy 427.46958 -315.004189) (xy 427.415701 -315.00222) (xy 427.362683 -314.992427) (xy 427.311656 -314.975019)
			(xy 427.263708 -314.950367) (xy 427.21986 -314.918997) (xy 427.181047 -314.881576) (xy 427.148095 -314.838903)
			(xy 427.121709 -314.791886) (xy 427.102449 -314.741529) (xy 427.090726 -314.688905) (xy 427.086791 -314.635134)
			(xy 425.985178 -314.635134) (xy 425.985178 -315.485018) (xy 431.186859 -315.485018) (xy 431.190794 -315.431247)
			(xy 431.202517 -315.378623) (xy 431.221777 -315.328266) (xy 431.248163 -315.281249) (xy 431.281115 -315.238576)
			(xy 431.319928 -315.201155) (xy 431.363776 -315.169785) (xy 431.411724 -315.145133) (xy 431.462751 -315.127725)
			(xy 431.515769 -315.117932) (xy 431.569648 -315.115963) (xy 431.623239 -315.12186) (xy 431.6754 -315.135496)
			(xy 431.72502 -315.156583) (xy 431.771041 -315.184669) (xy 431.812483 -315.219157) (xy 431.848461 -315.259311)
			(xy 431.878209 -315.304275) (xy 431.901094 -315.353092) (xy 431.916626 -315.404721) (xy 431.924476 -315.458061)
			(xy 431.924968 -315.485018) (xy 438.730913 -315.485018) (xy 438.734848 -315.431247) (xy 438.746571 -315.378623)
			(xy 438.765831 -315.328266) (xy 438.792217 -315.281249) (xy 438.825169 -315.238576) (xy 438.863982 -315.201155)
			(xy 438.90783 -315.169785) (xy 438.955778 -315.145133) (xy 439.006805 -315.127725) (xy 439.059823 -315.117932)
			(xy 439.113702 -315.115963) (xy 439.167293 -315.12186) (xy 439.219454 -315.135496) (xy 439.269074 -315.156583)
			(xy 439.315095 -315.184669) (xy 439.356537 -315.219157) (xy 439.392515 -315.259311) (xy 439.422263 -315.304275)
			(xy 439.445148 -315.353092) (xy 439.46068 -315.404721) (xy 439.46853 -315.458061) (xy 439.469022 -315.485018)
			(xy 446.274967 -315.485018) (xy 446.278902 -315.431247) (xy 446.290625 -315.378623) (xy 446.309885 -315.328266)
			(xy 446.336271 -315.281249) (xy 446.369223 -315.238576) (xy 446.408036 -315.201155) (xy 446.451884 -315.169785)
			(xy 446.499832 -315.145133) (xy 446.550859 -315.127725) (xy 446.603877 -315.117932) (xy 446.657756 -315.115963)
			(xy 446.711347 -315.12186) (xy 446.763508 -315.135496) (xy 446.813128 -315.156583) (xy 446.859149 -315.184669)
			(xy 446.900591 -315.219157) (xy 446.936569 -315.259311) (xy 446.966317 -315.304275) (xy 446.989202 -315.353092)
			(xy 447.004734 -315.404721) (xy 447.012584 -315.458061) (xy 447.013076 -315.485018) (xy 453.818767 -315.485018)
			(xy 453.822702 -315.431247) (xy 453.834425 -315.378623) (xy 453.853685 -315.328266) (xy 453.880071 -315.281249)
			(xy 453.913023 -315.238576) (xy 453.951836 -315.201155) (xy 453.995684 -315.169785) (xy 454.043632 -315.145133)
			(xy 454.094659 -315.127725) (xy 454.147677 -315.117932) (xy 454.201556 -315.115963) (xy 454.255147 -315.12186)
			(xy 454.307308 -315.135496) (xy 454.356928 -315.156583) (xy 454.402949 -315.184669) (xy 454.444391 -315.219157)
			(xy 454.480369 -315.259311) (xy 454.510117 -315.304275) (xy 454.533002 -315.353092) (xy 454.548534 -315.404721)
			(xy 454.556384 -315.458061) (xy 454.556876 -315.485018) (xy 454.556384 -315.511975) (xy 454.548534 -315.565315)
			(xy 454.533002 -315.616944) (xy 454.510117 -315.665761) (xy 454.480369 -315.710725) (xy 454.444391 -315.750879)
			(xy 454.402949 -315.785367) (xy 454.356928 -315.813453) (xy 454.307308 -315.83454) (xy 454.255147 -315.848176)
			(xy 454.201556 -315.854073) (xy 454.147677 -315.852104) (xy 454.094659 -315.842311) (xy 454.043632 -315.824903)
			(xy 453.995684 -315.800251) (xy 453.951836 -315.768881) (xy 453.913023 -315.73146) (xy 453.880071 -315.688787)
			(xy 453.853685 -315.64177) (xy 453.834425 -315.591413) (xy 453.822702 -315.538789) (xy 453.818767 -315.485018)
			(xy 447.013076 -315.485018) (xy 447.012584 -315.511975) (xy 447.004734 -315.565315) (xy 446.989202 -315.616944)
			(xy 446.966317 -315.665761) (xy 446.936569 -315.710725) (xy 446.900591 -315.750879) (xy 446.859149 -315.785367)
			(xy 446.813128 -315.813453) (xy 446.763508 -315.83454) (xy 446.711347 -315.848176) (xy 446.657756 -315.854073)
			(xy 446.603877 -315.852104) (xy 446.550859 -315.842311) (xy 446.499832 -315.824903) (xy 446.451884 -315.800251)
			(xy 446.408036 -315.768881) (xy 446.369223 -315.73146) (xy 446.336271 -315.688787) (xy 446.309885 -315.64177)
			(xy 446.290625 -315.591413) (xy 446.278902 -315.538789) (xy 446.274967 -315.485018) (xy 439.469022 -315.485018)
			(xy 439.46853 -315.511975) (xy 439.46068 -315.565315) (xy 439.445148 -315.616944) (xy 439.422263 -315.665761)
			(xy 439.392515 -315.710725) (xy 439.356537 -315.750879) (xy 439.315095 -315.785367) (xy 439.269074 -315.813453)
			(xy 439.219454 -315.83454) (xy 439.167293 -315.848176) (xy 439.113702 -315.854073) (xy 439.059823 -315.852104)
			(xy 439.006805 -315.842311) (xy 438.955778 -315.824903) (xy 438.90783 -315.800251) (xy 438.863982 -315.768881)
			(xy 438.825169 -315.73146) (xy 438.792217 -315.688787) (xy 438.765831 -315.64177) (xy 438.746571 -315.591413)
			(xy 438.734848 -315.538789) (xy 438.730913 -315.485018) (xy 431.924968 -315.485018) (xy 431.924476 -315.511975)
			(xy 431.916626 -315.565315) (xy 431.901094 -315.616944) (xy 431.878209 -315.665761) (xy 431.848461 -315.710725)
			(xy 431.812483 -315.750879) (xy 431.771041 -315.785367) (xy 431.72502 -315.813453) (xy 431.6754 -315.83454)
			(xy 431.623239 -315.848176) (xy 431.569648 -315.854073) (xy 431.515769 -315.852104) (xy 431.462751 -315.842311)
			(xy 431.411724 -315.824903) (xy 431.363776 -315.800251) (xy 431.319928 -315.768881) (xy 431.281115 -315.73146)
			(xy 431.248163 -315.688787) (xy 431.221777 -315.64177) (xy 431.202517 -315.591413) (xy 431.190794 -315.538789)
			(xy 431.186859 -315.485018) (xy 425.985178 -315.485018) (xy 425.985178 -316.335156) (xy 427.086791 -316.335156)
			(xy 427.090726 -316.281385) (xy 427.102449 -316.228761) (xy 427.121709 -316.178404) (xy 427.148095 -316.131387)
			(xy 427.181047 -316.088714) (xy 427.21986 -316.051293) (xy 427.263708 -316.019923) (xy 427.311656 -315.995271)
			(xy 427.362683 -315.977863) (xy 427.415701 -315.96807) (xy 427.46958 -315.966101) (xy 427.523171 -315.971998)
			(xy 427.575332 -315.985634) (xy 427.624952 -316.006721) (xy 427.670973 -316.034807) (xy 427.712415 -316.069295)
			(xy 427.748393 -316.109449) (xy 427.778141 -316.154413) (xy 427.801026 -316.20323) (xy 427.816558 -316.254859)
			(xy 427.824408 -316.308199) (xy 427.8249 -316.335156) (xy 434.630845 -316.335156) (xy 434.63478 -316.281385)
			(xy 434.646503 -316.228761) (xy 434.665763 -316.178404) (xy 434.692149 -316.131387) (xy 434.725101 -316.088714)
			(xy 434.763914 -316.051293) (xy 434.807762 -316.019923) (xy 434.85571 -315.995271) (xy 434.906737 -315.977863)
			(xy 434.959755 -315.96807) (xy 435.013634 -315.966101) (xy 435.067225 -315.971998) (xy 435.119386 -315.985634)
			(xy 435.169006 -316.006721) (xy 435.215027 -316.034807) (xy 435.256469 -316.069295) (xy 435.292447 -316.109449)
			(xy 435.322195 -316.154413) (xy 435.34508 -316.20323) (xy 435.360612 -316.254859) (xy 435.368462 -316.308199)
			(xy 435.368954 -316.335156) (xy 442.174899 -316.335156) (xy 442.178834 -316.281385) (xy 442.190557 -316.228761)
			(xy 442.209817 -316.178404) (xy 442.236203 -316.131387) (xy 442.269155 -316.088714) (xy 442.307968 -316.051293)
			(xy 442.351816 -316.019923) (xy 442.399764 -315.995271) (xy 442.450791 -315.977863) (xy 442.503809 -315.96807)
			(xy 442.557688 -315.966101) (xy 442.611279 -315.971998) (xy 442.66344 -315.985634) (xy 442.71306 -316.006721)
			(xy 442.759081 -316.034807) (xy 442.800523 -316.069295) (xy 442.836501 -316.109449) (xy 442.866249 -316.154413)
			(xy 442.889134 -316.20323) (xy 442.904666 -316.254859) (xy 442.912516 -316.308199) (xy 442.913008 -316.335156)
			(xy 449.718699 -316.335156) (xy 449.722634 -316.281385) (xy 449.734357 -316.228761) (xy 449.753617 -316.178404)
			(xy 449.780003 -316.131387) (xy 449.812955 -316.088714) (xy 449.851768 -316.051293) (xy 449.895616 -316.019923)
			(xy 449.943564 -315.995271) (xy 449.994591 -315.977863) (xy 450.047609 -315.96807) (xy 450.101488 -315.966101)
			(xy 450.155079 -315.971998) (xy 450.20724 -315.985634) (xy 450.25686 -316.006721) (xy 450.302881 -316.034807)
			(xy 450.344323 -316.069295) (xy 450.380301 -316.109449) (xy 450.410049 -316.154413) (xy 450.432934 -316.20323)
			(xy 450.448466 -316.254859) (xy 450.456316 -316.308199) (xy 450.456808 -316.335156) (xy 450.456316 -316.362113)
			(xy 450.448466 -316.415453) (xy 450.432934 -316.467082) (xy 450.410049 -316.515899) (xy 450.380301 -316.560863)
			(xy 450.344323 -316.601017) (xy 450.302881 -316.635505) (xy 450.25686 -316.663591) (xy 450.20724 -316.684678)
			(xy 450.155079 -316.698314) (xy 450.101488 -316.704211) (xy 450.047609 -316.702242) (xy 449.994591 -316.692449)
			(xy 449.943564 -316.675041) (xy 449.895616 -316.650389) (xy 449.851768 -316.619019) (xy 449.812955 -316.581598)
			(xy 449.780003 -316.538925) (xy 449.753617 -316.491908) (xy 449.734357 -316.441551) (xy 449.722634 -316.388927)
			(xy 449.718699 -316.335156) (xy 442.913008 -316.335156) (xy 442.912516 -316.362113) (xy 442.904666 -316.415453)
			(xy 442.889134 -316.467082) (xy 442.866249 -316.515899) (xy 442.836501 -316.560863) (xy 442.800523 -316.601017)
			(xy 442.759081 -316.635505) (xy 442.71306 -316.663591) (xy 442.66344 -316.684678) (xy 442.611279 -316.698314)
			(xy 442.557688 -316.704211) (xy 442.503809 -316.702242) (xy 442.450791 -316.692449) (xy 442.399764 -316.675041)
			(xy 442.351816 -316.650389) (xy 442.307968 -316.619019) (xy 442.269155 -316.581598) (xy 442.236203 -316.538925)
			(xy 442.209817 -316.491908) (xy 442.190557 -316.441551) (xy 442.178834 -316.388927) (xy 442.174899 -316.335156)
			(xy 435.368954 -316.335156) (xy 435.368462 -316.362113) (xy 435.360612 -316.415453) (xy 435.34508 -316.467082)
			(xy 435.322195 -316.515899) (xy 435.292447 -316.560863) (xy 435.256469 -316.601017) (xy 435.215027 -316.635505)
			(xy 435.169006 -316.663591) (xy 435.119386 -316.684678) (xy 435.067225 -316.698314) (xy 435.013634 -316.704211)
			(xy 434.959755 -316.702242) (xy 434.906737 -316.692449) (xy 434.85571 -316.675041) (xy 434.807762 -316.650389)
			(xy 434.763914 -316.619019) (xy 434.725101 -316.581598) (xy 434.692149 -316.538925) (xy 434.665763 -316.491908)
			(xy 434.646503 -316.441551) (xy 434.63478 -316.388927) (xy 434.630845 -316.335156) (xy 427.8249 -316.335156)
			(xy 427.824408 -316.362113) (xy 427.816558 -316.415453) (xy 427.801026 -316.467082) (xy 427.778141 -316.515899)
			(xy 427.748393 -316.560863) (xy 427.712415 -316.601017) (xy 427.670973 -316.635505) (xy 427.624952 -316.663591)
			(xy 427.575332 -316.684678) (xy 427.523171 -316.698314) (xy 427.46958 -316.704211) (xy 427.415701 -316.702242)
			(xy 427.362683 -316.692449) (xy 427.311656 -316.675041) (xy 427.263708 -316.650389) (xy 427.21986 -316.619019)
			(xy 427.181047 -316.581598) (xy 427.148095 -316.538925) (xy 427.121709 -316.491908) (xy 427.102449 -316.441551)
			(xy 427.090726 -316.388927) (xy 427.086791 -316.335156) (xy 425.985178 -316.335156) (xy 425.985178 -317.18504)
			(xy 431.186859 -317.18504) (xy 431.190794 -317.131269) (xy 431.202517 -317.078645) (xy 431.221777 -317.028288)
			(xy 431.248163 -316.981271) (xy 431.281115 -316.938598) (xy 431.319928 -316.901177) (xy 431.363776 -316.869807)
			(xy 431.411724 -316.845155) (xy 431.462751 -316.827747) (xy 431.515769 -316.817954) (xy 431.569648 -316.815985)
			(xy 431.623239 -316.821882) (xy 431.6754 -316.835518) (xy 431.72502 -316.856605) (xy 431.771041 -316.884691)
			(xy 431.812483 -316.919179) (xy 431.848461 -316.959333) (xy 431.878209 -317.004297) (xy 431.901094 -317.053114)
			(xy 431.916626 -317.104743) (xy 431.924476 -317.158083) (xy 431.924968 -317.18504) (xy 438.730913 -317.18504)
			(xy 438.734848 -317.131269) (xy 438.746571 -317.078645) (xy 438.765831 -317.028288) (xy 438.792217 -316.981271)
			(xy 438.825169 -316.938598) (xy 438.863982 -316.901177) (xy 438.90783 -316.869807) (xy 438.955778 -316.845155)
			(xy 439.006805 -316.827747) (xy 439.059823 -316.817954) (xy 439.113702 -316.815985) (xy 439.167293 -316.821882)
			(xy 439.219454 -316.835518) (xy 439.269074 -316.856605) (xy 439.315095 -316.884691) (xy 439.356537 -316.919179)
			(xy 439.392515 -316.959333) (xy 439.422263 -317.004297) (xy 439.445148 -317.053114) (xy 439.46068 -317.104743)
			(xy 439.46853 -317.158083) (xy 439.469022 -317.18504) (xy 446.274967 -317.18504) (xy 446.278902 -317.131269)
			(xy 446.290625 -317.078645) (xy 446.309885 -317.028288) (xy 446.336271 -316.981271) (xy 446.369223 -316.938598)
			(xy 446.408036 -316.901177) (xy 446.451884 -316.869807) (xy 446.499832 -316.845155) (xy 446.550859 -316.827747)
			(xy 446.603877 -316.817954) (xy 446.657756 -316.815985) (xy 446.711347 -316.821882) (xy 446.763508 -316.835518)
			(xy 446.813128 -316.856605) (xy 446.859149 -316.884691) (xy 446.900591 -316.919179) (xy 446.936569 -316.959333)
			(xy 446.966317 -317.004297) (xy 446.989202 -317.053114) (xy 447.004734 -317.104743) (xy 447.012584 -317.158083)
			(xy 447.013076 -317.18504) (xy 453.818767 -317.18504) (xy 453.822702 -317.131269) (xy 453.834425 -317.078645)
			(xy 453.853685 -317.028288) (xy 453.880071 -316.981271) (xy 453.913023 -316.938598) (xy 453.951836 -316.901177)
			(xy 453.995684 -316.869807) (xy 454.043632 -316.845155) (xy 454.094659 -316.827747) (xy 454.147677 -316.817954)
			(xy 454.201556 -316.815985) (xy 454.255147 -316.821882) (xy 454.307308 -316.835518) (xy 454.356928 -316.856605)
			(xy 454.402949 -316.884691) (xy 454.444391 -316.919179) (xy 454.480369 -316.959333) (xy 454.510117 -317.004297)
			(xy 454.533002 -317.053114) (xy 454.548534 -317.104743) (xy 454.556384 -317.158083) (xy 454.556876 -317.18504)
			(xy 454.556384 -317.211997) (xy 454.548534 -317.265337) (xy 454.533002 -317.316966) (xy 454.510117 -317.365783)
			(xy 454.480369 -317.410747) (xy 454.444391 -317.450901) (xy 454.402949 -317.485389) (xy 454.356928 -317.513475)
			(xy 454.307308 -317.534562) (xy 454.255147 -317.548198) (xy 454.201556 -317.554095) (xy 454.147677 -317.552126)
			(xy 454.094659 -317.542333) (xy 454.043632 -317.524925) (xy 453.995684 -317.500273) (xy 453.951836 -317.468903)
			(xy 453.913023 -317.431482) (xy 453.880071 -317.388809) (xy 453.853685 -317.341792) (xy 453.834425 -317.291435)
			(xy 453.822702 -317.238811) (xy 453.818767 -317.18504) (xy 447.013076 -317.18504) (xy 447.012584 -317.211997)
			(xy 447.004734 -317.265337) (xy 446.989202 -317.316966) (xy 446.966317 -317.365783) (xy 446.936569 -317.410747)
			(xy 446.900591 -317.450901) (xy 446.859149 -317.485389) (xy 446.813128 -317.513475) (xy 446.763508 -317.534562)
			(xy 446.711347 -317.548198) (xy 446.657756 -317.554095) (xy 446.603877 -317.552126) (xy 446.550859 -317.542333)
			(xy 446.499832 -317.524925) (xy 446.451884 -317.500273) (xy 446.408036 -317.468903) (xy 446.369223 -317.431482)
			(xy 446.336271 -317.388809) (xy 446.309885 -317.341792) (xy 446.290625 -317.291435) (xy 446.278902 -317.238811)
			(xy 446.274967 -317.18504) (xy 439.469022 -317.18504) (xy 439.46853 -317.211997) (xy 439.46068 -317.265337)
			(xy 439.445148 -317.316966) (xy 439.422263 -317.365783) (xy 439.392515 -317.410747) (xy 439.356537 -317.450901)
			(xy 439.315095 -317.485389) (xy 439.269074 -317.513475) (xy 439.219454 -317.534562) (xy 439.167293 -317.548198)
			(xy 439.113702 -317.554095) (xy 439.059823 -317.552126) (xy 439.006805 -317.542333) (xy 438.955778 -317.524925)
			(xy 438.90783 -317.500273) (xy 438.863982 -317.468903) (xy 438.825169 -317.431482) (xy 438.792217 -317.388809)
			(xy 438.765831 -317.341792) (xy 438.746571 -317.291435) (xy 438.734848 -317.238811) (xy 438.730913 -317.18504)
			(xy 431.924968 -317.18504) (xy 431.924476 -317.211997) (xy 431.916626 -317.265337) (xy 431.901094 -317.316966)
			(xy 431.878209 -317.365783) (xy 431.848461 -317.410747) (xy 431.812483 -317.450901) (xy 431.771041 -317.485389)
			(xy 431.72502 -317.513475) (xy 431.6754 -317.534562) (xy 431.623239 -317.548198) (xy 431.569648 -317.554095)
			(xy 431.515769 -317.552126) (xy 431.462751 -317.542333) (xy 431.411724 -317.524925) (xy 431.363776 -317.500273)
			(xy 431.319928 -317.468903) (xy 431.281115 -317.431482) (xy 431.248163 -317.388809) (xy 431.221777 -317.341792)
			(xy 431.202517 -317.291435) (xy 431.190794 -317.238811) (xy 431.186859 -317.18504) (xy 425.985178 -317.18504)
			(xy 425.985178 -318.035178) (xy 427.086791 -318.035178) (xy 427.090726 -317.981407) (xy 427.102449 -317.928783)
			(xy 427.121709 -317.878426) (xy 427.148095 -317.831409) (xy 427.181047 -317.788736) (xy 427.21986 -317.751315)
			(xy 427.263708 -317.719945) (xy 427.311656 -317.695293) (xy 427.362683 -317.677885) (xy 427.415701 -317.668092)
			(xy 427.46958 -317.666123) (xy 427.523171 -317.67202) (xy 427.575332 -317.685656) (xy 427.624952 -317.706743)
			(xy 427.670973 -317.734829) (xy 427.712415 -317.769317) (xy 427.748393 -317.809471) (xy 427.778141 -317.854435)
			(xy 427.801026 -317.903252) (xy 427.816558 -317.954881) (xy 427.824408 -318.008221) (xy 427.8249 -318.035178)
			(xy 434.630845 -318.035178) (xy 434.63478 -317.981407) (xy 434.646503 -317.928783) (xy 434.665763 -317.878426)
			(xy 434.692149 -317.831409) (xy 434.725101 -317.788736) (xy 434.763914 -317.751315) (xy 434.807762 -317.719945)
			(xy 434.85571 -317.695293) (xy 434.906737 -317.677885) (xy 434.959755 -317.668092) (xy 435.013634 -317.666123)
			(xy 435.067225 -317.67202) (xy 435.119386 -317.685656) (xy 435.169006 -317.706743) (xy 435.215027 -317.734829)
			(xy 435.256469 -317.769317) (xy 435.292447 -317.809471) (xy 435.322195 -317.854435) (xy 435.34508 -317.903252)
			(xy 435.360612 -317.954881) (xy 435.368462 -318.008221) (xy 435.368954 -318.035178) (xy 442.174899 -318.035178)
			(xy 442.178834 -317.981407) (xy 442.190557 -317.928783) (xy 442.209817 -317.878426) (xy 442.236203 -317.831409)
			(xy 442.269155 -317.788736) (xy 442.307968 -317.751315) (xy 442.351816 -317.719945) (xy 442.399764 -317.695293)
			(xy 442.450791 -317.677885) (xy 442.503809 -317.668092) (xy 442.557688 -317.666123) (xy 442.611279 -317.67202)
			(xy 442.66344 -317.685656) (xy 442.71306 -317.706743) (xy 442.759081 -317.734829) (xy 442.800523 -317.769317)
			(xy 442.836501 -317.809471) (xy 442.866249 -317.854435) (xy 442.889134 -317.903252) (xy 442.904666 -317.954881)
			(xy 442.912516 -318.008221) (xy 442.913008 -318.035178) (xy 449.718699 -318.035178) (xy 449.722634 -317.981407)
			(xy 449.734357 -317.928783) (xy 449.753617 -317.878426) (xy 449.780003 -317.831409) (xy 449.812955 -317.788736)
			(xy 449.851768 -317.751315) (xy 449.895616 -317.719945) (xy 449.943564 -317.695293) (xy 449.994591 -317.677885)
			(xy 450.047609 -317.668092) (xy 450.101488 -317.666123) (xy 450.155079 -317.67202) (xy 450.20724 -317.685656)
			(xy 450.25686 -317.706743) (xy 450.302881 -317.734829) (xy 450.344323 -317.769317) (xy 450.380301 -317.809471)
			(xy 450.410049 -317.854435) (xy 450.432934 -317.903252) (xy 450.448466 -317.954881) (xy 450.456316 -318.008221)
			(xy 450.456808 -318.035178) (xy 450.456316 -318.062135) (xy 450.448466 -318.115475) (xy 450.432934 -318.167104)
			(xy 450.410049 -318.215921) (xy 450.380301 -318.260885) (xy 450.344323 -318.301039) (xy 450.302881 -318.335527)
			(xy 450.25686 -318.363613) (xy 450.20724 -318.3847) (xy 450.155079 -318.398336) (xy 450.101488 -318.404233)
			(xy 450.047609 -318.402264) (xy 449.994591 -318.392471) (xy 449.943564 -318.375063) (xy 449.895616 -318.350411)
			(xy 449.851768 -318.319041) (xy 449.812955 -318.28162) (xy 449.780003 -318.238947) (xy 449.753617 -318.19193)
			(xy 449.734357 -318.141573) (xy 449.722634 -318.088949) (xy 449.718699 -318.035178) (xy 442.913008 -318.035178)
			(xy 442.912516 -318.062135) (xy 442.904666 -318.115475) (xy 442.889134 -318.167104) (xy 442.866249 -318.215921)
			(xy 442.836501 -318.260885) (xy 442.800523 -318.301039) (xy 442.759081 -318.335527) (xy 442.71306 -318.363613)
			(xy 442.66344 -318.3847) (xy 442.611279 -318.398336) (xy 442.557688 -318.404233) (xy 442.503809 -318.402264)
			(xy 442.450791 -318.392471) (xy 442.399764 -318.375063) (xy 442.351816 -318.350411) (xy 442.307968 -318.319041)
			(xy 442.269155 -318.28162) (xy 442.236203 -318.238947) (xy 442.209817 -318.19193) (xy 442.190557 -318.141573)
			(xy 442.178834 -318.088949) (xy 442.174899 -318.035178) (xy 435.368954 -318.035178) (xy 435.368462 -318.062135)
			(xy 435.360612 -318.115475) (xy 435.34508 -318.167104) (xy 435.322195 -318.215921) (xy 435.292447 -318.260885)
			(xy 435.256469 -318.301039) (xy 435.215027 -318.335527) (xy 435.169006 -318.363613) (xy 435.119386 -318.3847)
			(xy 435.067225 -318.398336) (xy 435.013634 -318.404233) (xy 434.959755 -318.402264) (xy 434.906737 -318.392471)
			(xy 434.85571 -318.375063) (xy 434.807762 -318.350411) (xy 434.763914 -318.319041) (xy 434.725101 -318.28162)
			(xy 434.692149 -318.238947) (xy 434.665763 -318.19193) (xy 434.646503 -318.141573) (xy 434.63478 -318.088949)
			(xy 434.630845 -318.035178) (xy 427.8249 -318.035178) (xy 427.824408 -318.062135) (xy 427.816558 -318.115475)
			(xy 427.801026 -318.167104) (xy 427.778141 -318.215921) (xy 427.748393 -318.260885) (xy 427.712415 -318.301039)
			(xy 427.670973 -318.335527) (xy 427.624952 -318.363613) (xy 427.575332 -318.3847) (xy 427.523171 -318.398336)
			(xy 427.46958 -318.404233) (xy 427.415701 -318.402264) (xy 427.362683 -318.392471) (xy 427.311656 -318.375063)
			(xy 427.263708 -318.350411) (xy 427.21986 -318.319041) (xy 427.181047 -318.28162) (xy 427.148095 -318.238947)
			(xy 427.121709 -318.19193) (xy 427.102449 -318.141573) (xy 427.090726 -318.088949) (xy 427.086791 -318.035178)
			(xy 425.985178 -318.035178) (xy 425.985178 -318.64427) (xy 425.985613 -318.654335) (xy 425.993343 -318.672923)
			(xy 426.000164 -318.680338) (xy 426.440092 -319.120266) (xy 426.447489 -319.127117) (xy 426.466087 -319.13486)
			(xy 426.47616 -319.135252)
		)
		(stroke
			(width 0)
			(type solid)
		)
		(fill yes)
		(layer "B.Cu")
		(net "GND")
	)
	(gr_poly
		(pts
			(xy 293.017194 -319.070482) (xy 293.027264 -319.07006) (xy 293.045869 -319.062345) (xy 293.053262 -319.055496)
			(xy 293.704772 -318.403986) (xy 293.711619 -318.396588) (xy 293.719353 -318.37799) (xy 293.719758 -318.367918)
			(xy 293.719758 -244.512592) (xy 293.719395 -244.502681) (xy 293.711894 -244.484338) (xy 293.697924 -244.470281)
			(xy 293.679629 -244.462665) (xy 293.66972 -244.4623) (xy 293.58971 -244.4623) (xy 293.579839 -244.461827)
			(xy 293.561559 -244.454365) (xy 293.55415 -244.447822) (xy 293.535354 -244.42928) (xy 293.53255 -244.426655)
			(xy 293.526301 -244.422191) (xy 293.522908 -244.42039) (xy 293.511986 -244.414802) (xy 293.511732 -244.414548)
			(xy 293.504874 -244.411246) (xy 293.499794 -244.408706) (xy 293.482268 -244.404134) (xy 293.469314 -244.402356)
			(xy 293.064438 -244.402356) (xy 293.054584 -244.402888) (xy 293.036409 -244.410527) (xy 293.02254 -244.424537)
			(xy 293.015088 -244.442789) (xy 293.014654 -244.452648) (xy 293.014654 -244.4623) (xy 292.746938 -244.4623)
			(xy 292.72744 -244.461868) (xy 292.689029 -244.455132) (xy 292.652344 -244.441906) (xy 292.618472 -244.422581)
			(xy 292.603174 -244.410484) (xy 292.59657 -244.40515) (xy 292.57244 -244.396006) (xy 292.568092 -244.394465)
			(xy 292.559018 -244.392811) (xy 292.554406 -244.392704) (xy 292.49116 -244.392704) (xy 292.477952 -244.396514)
			(xy 292.471856 -244.40007) (xy 292.450088 -244.412812) (xy 292.403832 -244.432923) (xy 292.35527 -244.446555)
			(xy 292.305305 -244.453455) (xy 292.280086 -244.453918) (xy 292.253742 -244.453447) (xy 292.201591 -244.445947)
			(xy 292.151039 -244.431102) (xy 292.103113 -244.409214) (xy 292.05879 -244.380729) (xy 292.018972 -244.346225)
			(xy 291.984469 -244.306407) (xy 291.955984 -244.262083) (xy 291.934096 -244.214158) (xy 291.919252 -244.163605)
			(xy 291.911753 -244.111454) (xy 291.911278 -244.08511) (xy 291.911747 -244.058765) (xy 291.919244 -244.006611)
			(xy 291.934087 -243.956056) (xy 291.955974 -243.908127) (xy 291.984459 -243.8638) (xy 292.018962 -243.823979)
			(xy 292.058781 -243.789473) (xy 292.103106 -243.760985) (xy 292.151033 -243.739096) (xy 292.201588 -243.724249)
			(xy 292.253741 -243.716749) (xy 292.280086 -243.716302) (xy 292.30531 -243.716709) (xy 292.355287 -243.723585)
			(xy 292.403856 -243.737223) (xy 292.450107 -243.757367) (xy 292.471856 -243.77015) (xy 292.477952 -243.773706)
			(xy 292.49116 -243.777516) (xy 292.554406 -243.777516) (xy 292.559018 -243.777416) (xy 292.568093 -243.775758)
			(xy 292.57244 -243.774214) (xy 292.59657 -243.76507) (xy 292.603174 -243.759736) (xy 292.618464 -243.747629)
			(xy 292.65234 -243.72831) (xy 292.689028 -243.715087) (xy 292.72744 -243.708353) (xy 292.746938 -243.70792)
			(xy 292.964362 -243.70792) (xy 292.964616 -243.70792) (xy 292.974258 -243.708363) (xy 292.992133 -243.715602)
			(xy 293.005988 -243.729018) (xy 293.010336 -243.737638) (xy 293.016432 -243.751608) (xy 293.041578 -243.767864)
			(xy 293.469314 -243.767864) (xy 293.482268 -243.766086) (xy 293.499794 -243.761514) (xy 293.504874 -243.758974)
			(xy 293.511224 -243.755926) (xy 293.517828 -243.752624) (xy 293.528242 -243.742972) (xy 293.536116 -243.730272)
			(xy 293.543736 -243.72062) (xy 293.54907 -243.715286) (xy 293.567358 -243.70792) (xy 293.66972 -243.70792)
			(xy 293.679618 -243.707496) (xy 293.697896 -243.69989) (xy 293.711854 -243.685851) (xy 293.719353 -243.667529)
			(xy 293.719758 -243.657628) (xy 293.719758 -198.689468) (xy 293.719332 -198.679454) (xy 293.711655 -198.660955)
			(xy 293.697483 -198.646803) (xy 293.678973 -198.639153) (xy 293.668958 -198.638668) (xy 292.646608 -198.638668)
			(xy 292.632303 -198.639164) (xy 292.604819 -198.647115) (xy 292.580614 -198.66237) (xy 292.561582 -198.683734)
			(xy 292.549215 -198.709534) (xy 292.544479 -198.73775) (xy 292.547747 -198.766174) (xy 292.558761 -198.792581)
			(xy 292.56736 -198.804022) (xy 292.582719 -198.823747) (xy 292.608532 -198.866559) (xy 292.628317 -198.912469)
			(xy 292.64171 -198.960633) (xy 292.648464 -199.010166) (xy 292.648894 -199.035162) (xy 292.648378 -199.062762)
			(xy 292.640151 -199.117345) (xy 292.623881 -199.170092) (xy 292.599931 -199.219825) (xy 292.568836 -199.265432)
			(xy 292.531291 -199.305896) (xy 292.488134 -199.340313) (xy 292.44033 -199.367912) (xy 292.388946 -199.388079)
			(xy 292.335131 -199.400362) (xy 292.280086 -199.404487) (xy 292.225041 -199.400362) (xy 292.171226 -199.388079)
			(xy 292.119842 -199.367912) (xy 292.072038 -199.340313) (xy 292.028881 -199.305896) (xy 291.991336 -199.265432)
			(xy 291.960241 -199.219825) (xy 291.936291 -199.170092) (xy 291.920021 -199.117345) (xy 291.911794 -199.062762)
			(xy 291.911278 -199.035162) (xy 291.911715 -199.010168) (xy 291.918501 -198.960643) (xy 291.931903 -198.912486)
			(xy 291.951677 -198.866575) (xy 291.977461 -198.82375) (xy 291.992812 -198.804022) (xy 292.001412 -198.792571)
			(xy 292.012474 -198.76617) (xy 292.015774 -198.737735) (xy 292.011051 -198.709502) (xy 291.998676 -198.68369)
			(xy 291.979623 -198.662327) (xy 291.955388 -198.647092) (xy 291.927877 -198.639183) (xy 291.913564 -198.638668)
			(xy 285.102554 -198.638668) (xy 285.088244 -198.639158) (xy 285.060748 -198.647102) (xy 285.036531 -198.662355)
			(xy 285.01749 -198.683723) (xy 285.005116 -198.70953) (xy 285.000379 -198.737756) (xy 285.00365 -198.766189)
			(xy 285.014673 -198.792601) (xy 285.023306 -198.804022) (xy 285.038666 -198.823747) (xy 285.064483 -198.866557)
			(xy 285.084271 -198.912467) (xy 285.097666 -198.960631) (xy 285.104421 -199.010166) (xy 285.10484 -199.035162)
			(xy 285.104324 -199.062762) (xy 285.096097 -199.117345) (xy 285.079827 -199.170092) (xy 285.055877 -199.219825)
			(xy 285.024782 -199.265432) (xy 284.987237 -199.305896) (xy 284.94408 -199.340313) (xy 284.896276 -199.367912)
			(xy 284.844892 -199.388079) (xy 284.791077 -199.400362) (xy 284.736032 -199.404487) (xy 284.680987 -199.400362)
			(xy 284.627172 -199.388079) (xy 284.575788 -199.367912) (xy 284.527984 -199.340313) (xy 284.484827 -199.305896)
			(xy 284.447282 -199.265432) (xy 284.416187 -199.219825) (xy 284.392237 -199.170092) (xy 284.375967 -199.117345)
			(xy 284.36774 -199.062762) (xy 284.367224 -199.035162) (xy 284.367661 -199.010169) (xy 284.374448 -198.960644)
			(xy 284.387851 -198.912487) (xy 284.407627 -198.866578) (xy 284.433414 -198.823755) (xy 284.448758 -198.804022)
			(xy 284.457355 -198.792568) (xy 284.468413 -198.766164) (xy 284.471709 -198.737729) (xy 284.466986 -198.709495)
			(xy 284.454613 -198.683681) (xy 284.435563 -198.662314) (xy 284.411332 -198.647073) (xy 284.383823 -198.639153)
			(xy 284.36951 -198.638668) (xy 277.558754 -198.638668) (xy 277.544444 -198.639158) (xy 277.516948 -198.647102)
			(xy 277.492731 -198.662355) (xy 277.47369 -198.683723) (xy 277.461316 -198.70953) (xy 277.456579 -198.737756)
			(xy 277.45985 -198.766189) (xy 277.470873 -198.792601) (xy 277.479506 -198.804022) (xy 277.494866 -198.823747)
			(xy 277.520683 -198.866557) (xy 277.540471 -198.912467) (xy 277.553866 -198.960631) (xy 277.560621 -199.010166)
			(xy 277.56104 -199.035162) (xy 277.560524 -199.062762) (xy 277.552297 -199.117345) (xy 277.536027 -199.170092)
			(xy 277.512077 -199.219825) (xy 277.480982 -199.265432) (xy 277.443437 -199.305896) (xy 277.40028 -199.340313)
			(xy 277.352476 -199.367912) (xy 277.301092 -199.388079) (xy 277.247277 -199.400362) (xy 277.192232 -199.404487)
			(xy 277.137187 -199.400362) (xy 277.083372 -199.388079) (xy 277.031988 -199.367912) (xy 276.984184 -199.340313)
			(xy 276.941027 -199.305896) (xy 276.903482 -199.265432) (xy 276.872387 -199.219825) (xy 276.848437 -199.170092)
			(xy 276.832167 -199.117345) (xy 276.82394 -199.062762) (xy 276.823424 -199.035162) (xy 276.823861 -199.010169)
			(xy 276.830648 -198.960644) (xy 276.844051 -198.912487) (xy 276.863827 -198.866578) (xy 276.889614 -198.823755)
			(xy 276.904958 -198.804022) (xy 276.913555 -198.792568) (xy 276.924613 -198.766164) (xy 276.927909 -198.737729)
			(xy 276.923186 -198.709495) (xy 276.910813 -198.683681) (xy 276.891763 -198.662314) (xy 276.867532 -198.647073)
			(xy 276.840023 -198.639153) (xy 276.82571 -198.638668) (xy 270.0147 -198.638668) (xy 270.000396 -198.639165)
			(xy 269.972914 -198.647117) (xy 269.948711 -198.662373) (xy 269.929681 -198.683736) (xy 269.917315 -198.709534)
			(xy 269.912579 -198.737749) (xy 269.915846 -198.766172) (xy 269.926859 -198.792577) (xy 269.935452 -198.804022)
			(xy 269.950811 -198.823747) (xy 269.976625 -198.866558) (xy 269.99641 -198.912468) (xy 270.009803 -198.960633)
			(xy 270.016558 -199.010166) (xy 270.016986 -199.035162) (xy 270.01647 -199.062762) (xy 270.008243 -199.117345)
			(xy 269.991973 -199.170092) (xy 269.968023 -199.219825) (xy 269.936928 -199.265432) (xy 269.899383 -199.305896)
			(xy 269.856226 -199.340313) (xy 269.808422 -199.367912) (xy 269.757038 -199.388079) (xy 269.703223 -199.400362)
			(xy 269.648178 -199.404487) (xy 269.593133 -199.400362) (xy 269.539318 -199.388079) (xy 269.487934 -199.367912)
			(xy 269.44013 -199.340313) (xy 269.396973 -199.305896) (xy 269.359428 -199.265432) (xy 269.328333 -199.219825)
			(xy 269.304383 -199.170092) (xy 269.288113 -199.117345) (xy 269.279886 -199.062762) (xy 269.27937 -199.035162)
			(xy 269.279807 -199.010168) (xy 269.286593 -198.960643) (xy 269.299995 -198.912485) (xy 269.319768 -198.866575)
			(xy 269.345552 -198.823749) (xy 269.360904 -198.804022) (xy 269.369504 -198.792571) (xy 269.380568 -198.766171)
			(xy 269.383868 -198.737736) (xy 269.379144 -198.709503) (xy 269.36677 -198.683691) (xy 269.347716 -198.662329)
			(xy 269.323481 -198.647095) (xy 269.295969 -198.639188) (xy 269.281656 -198.638668) (xy 264.194798 -198.638668)
			(xy 264.184788 -198.639156) (xy 264.166292 -198.646815) (xy 264.152131 -198.660966) (xy 264.144462 -198.679459)
			(xy 264.143998 -198.689468) (xy 264.143998 -199.885046) (xy 265.178809 -199.885046) (xy 265.182744 -199.831275)
			(xy 265.194467 -199.778651) (xy 265.213727 -199.728294) (xy 265.240113 -199.681277) (xy 265.273065 -199.638604)
			(xy 265.311878 -199.601183) (xy 265.355726 -199.569813) (xy 265.403674 -199.545161) (xy 265.454701 -199.527753)
			(xy 265.507719 -199.51796) (xy 265.561598 -199.515991) (xy 265.615189 -199.521888) (xy 265.66735 -199.535524)
			(xy 265.71697 -199.556611) (xy 265.762991 -199.584697) (xy 265.804433 -199.619185) (xy 265.840411 -199.659339)
			(xy 265.870159 -199.704303) (xy 265.893044 -199.75312) (xy 265.908576 -199.804749) (xy 265.916426 -199.858089)
			(xy 265.916918 -199.885046) (xy 272.722863 -199.885046) (xy 272.726798 -199.831275) (xy 272.738521 -199.778651)
			(xy 272.757781 -199.728294) (xy 272.784167 -199.681277) (xy 272.817119 -199.638604) (xy 272.855932 -199.601183)
			(xy 272.89978 -199.569813) (xy 272.947728 -199.545161) (xy 272.998755 -199.527753) (xy 273.051773 -199.51796)
			(xy 273.105652 -199.515991) (xy 273.159243 -199.521888) (xy 273.211404 -199.535524) (xy 273.261024 -199.556611)
			(xy 273.307045 -199.584697) (xy 273.348487 -199.619185) (xy 273.384465 -199.659339) (xy 273.414213 -199.704303)
			(xy 273.437098 -199.75312) (xy 273.45263 -199.804749) (xy 273.46048 -199.858089) (xy 273.460972 -199.885046)
			(xy 280.266663 -199.885046) (xy 280.270598 -199.831275) (xy 280.282321 -199.778651) (xy 280.301581 -199.728294)
			(xy 280.327967 -199.681277) (xy 280.360919 -199.638604) (xy 280.399732 -199.601183) (xy 280.44358 -199.569813)
			(xy 280.491528 -199.545161) (xy 280.542555 -199.527753) (xy 280.595573 -199.51796) (xy 280.649452 -199.515991)
			(xy 280.703043 -199.521888) (xy 280.755204 -199.535524) (xy 280.804824 -199.556611) (xy 280.850845 -199.584697)
			(xy 280.892287 -199.619185) (xy 280.928265 -199.659339) (xy 280.958013 -199.704303) (xy 280.980898 -199.75312)
			(xy 280.99643 -199.804749) (xy 281.00428 -199.858089) (xy 281.004772 -199.885046) (xy 287.810717 -199.885046)
			(xy 287.814652 -199.831275) (xy 287.826375 -199.778651) (xy 287.845635 -199.728294) (xy 287.872021 -199.681277)
			(xy 287.904973 -199.638604) (xy 287.943786 -199.601183) (xy 287.987634 -199.569813) (xy 288.035582 -199.545161)
			(xy 288.086609 -199.527753) (xy 288.139627 -199.51796) (xy 288.193506 -199.515991) (xy 288.247097 -199.521888)
			(xy 288.299258 -199.535524) (xy 288.348878 -199.556611) (xy 288.394899 -199.584697) (xy 288.436341 -199.619185)
			(xy 288.472319 -199.659339) (xy 288.502067 -199.704303) (xy 288.524952 -199.75312) (xy 288.540484 -199.804749)
			(xy 288.548334 -199.858089) (xy 288.548826 -199.885046) (xy 288.548334 -199.912003) (xy 288.540484 -199.965343)
			(xy 288.524952 -200.016972) (xy 288.502067 -200.065789) (xy 288.472319 -200.110753) (xy 288.436341 -200.150907)
			(xy 288.394899 -200.185395) (xy 288.348878 -200.213481) (xy 288.299258 -200.234568) (xy 288.247097 -200.248204)
			(xy 288.193506 -200.254101) (xy 288.139627 -200.252132) (xy 288.086609 -200.242339) (xy 288.035582 -200.224931)
			(xy 287.987634 -200.200279) (xy 287.943786 -200.168909) (xy 287.904973 -200.131488) (xy 287.872021 -200.088815)
			(xy 287.845635 -200.041798) (xy 287.826375 -199.991441) (xy 287.814652 -199.938817) (xy 287.810717 -199.885046)
			(xy 281.004772 -199.885046) (xy 281.00428 -199.912003) (xy 280.99643 -199.965343) (xy 280.980898 -200.016972)
			(xy 280.958013 -200.065789) (xy 280.928265 -200.110753) (xy 280.892287 -200.150907) (xy 280.850845 -200.185395)
			(xy 280.804824 -200.213481) (xy 280.755204 -200.234568) (xy 280.703043 -200.248204) (xy 280.649452 -200.254101)
			(xy 280.595573 -200.252132) (xy 280.542555 -200.242339) (xy 280.491528 -200.224931) (xy 280.44358 -200.200279)
			(xy 280.399732 -200.168909) (xy 280.360919 -200.131488) (xy 280.327967 -200.088815) (xy 280.301581 -200.041798)
			(xy 280.282321 -199.991441) (xy 280.270598 -199.938817) (xy 280.266663 -199.885046) (xy 273.460972 -199.885046)
			(xy 273.46048 -199.912003) (xy 273.45263 -199.965343) (xy 273.437098 -200.016972) (xy 273.414213 -200.065789)
			(xy 273.384465 -200.110753) (xy 273.348487 -200.150907) (xy 273.307045 -200.185395) (xy 273.261024 -200.213481)
			(xy 273.211404 -200.234568) (xy 273.159243 -200.248204) (xy 273.105652 -200.254101) (xy 273.051773 -200.252132)
			(xy 272.998755 -200.242339) (xy 272.947728 -200.224931) (xy 272.89978 -200.200279) (xy 272.855932 -200.168909)
			(xy 272.817119 -200.131488) (xy 272.784167 -200.088815) (xy 272.757781 -200.041798) (xy 272.738521 -199.991441)
			(xy 272.726798 -199.938817) (xy 272.722863 -199.885046) (xy 265.916918 -199.885046) (xy 265.916426 -199.912003)
			(xy 265.908576 -199.965343) (xy 265.893044 -200.016972) (xy 265.870159 -200.065789) (xy 265.840411 -200.110753)
			(xy 265.804433 -200.150907) (xy 265.762991 -200.185395) (xy 265.71697 -200.213481) (xy 265.66735 -200.234568)
			(xy 265.615189 -200.248204) (xy 265.561598 -200.254101) (xy 265.507719 -200.252132) (xy 265.454701 -200.242339)
			(xy 265.403674 -200.224931) (xy 265.355726 -200.200279) (xy 265.311878 -200.168909) (xy 265.273065 -200.131488)
			(xy 265.240113 -200.088815) (xy 265.213727 -200.041798) (xy 265.194467 -199.991441) (xy 265.182744 -199.938817)
			(xy 265.178809 -199.885046) (xy 264.143998 -199.885046) (xy 264.143998 -200.735184) (xy 269.278877 -200.735184)
			(xy 269.282812 -200.681413) (xy 269.294535 -200.628789) (xy 269.313795 -200.578432) (xy 269.340181 -200.531415)
			(xy 269.373133 -200.488742) (xy 269.411946 -200.451321) (xy 269.455794 -200.419951) (xy 269.503742 -200.395299)
			(xy 269.554769 -200.377891) (xy 269.607787 -200.368098) (xy 269.661666 -200.366129) (xy 269.715257 -200.372026)
			(xy 269.767418 -200.385662) (xy 269.817038 -200.406749) (xy 269.863059 -200.434835) (xy 269.904501 -200.469323)
			(xy 269.940479 -200.509477) (xy 269.970227 -200.554441) (xy 269.993112 -200.603258) (xy 270.008644 -200.654887)
			(xy 270.016494 -200.708227) (xy 270.016986 -200.735184) (xy 276.822931 -200.735184) (xy 276.826866 -200.681413)
			(xy 276.838589 -200.628789) (xy 276.857849 -200.578432) (xy 276.884235 -200.531415) (xy 276.917187 -200.488742)
			(xy 276.956 -200.451321) (xy 276.999848 -200.419951) (xy 277.047796 -200.395299) (xy 277.098823 -200.377891)
			(xy 277.151841 -200.368098) (xy 277.20572 -200.366129) (xy 277.259311 -200.372026) (xy 277.311472 -200.385662)
			(xy 277.361092 -200.406749) (xy 277.407113 -200.434835) (xy 277.448555 -200.469323) (xy 277.484533 -200.509477)
			(xy 277.514281 -200.554441) (xy 277.537166 -200.603258) (xy 277.552698 -200.654887) (xy 277.560548 -200.708227)
			(xy 277.56104 -200.735184) (xy 284.366731 -200.735184) (xy 284.370666 -200.681413) (xy 284.382389 -200.628789)
			(xy 284.401649 -200.578432) (xy 284.428035 -200.531415) (xy 284.460987 -200.488742) (xy 284.4998 -200.451321)
			(xy 284.543648 -200.419951) (xy 284.591596 -200.395299) (xy 284.642623 -200.377891) (xy 284.695641 -200.368098)
			(xy 284.74952 -200.366129) (xy 284.803111 -200.372026) (xy 284.855272 -200.385662) (xy 284.904892 -200.406749)
			(xy 284.950913 -200.434835) (xy 284.992355 -200.469323) (xy 285.028333 -200.509477) (xy 285.058081 -200.554441)
			(xy 285.080966 -200.603258) (xy 285.096498 -200.654887) (xy 285.104348 -200.708227) (xy 285.10484 -200.735184)
			(xy 291.910785 -200.735184) (xy 291.91472 -200.681413) (xy 291.926443 -200.628789) (xy 291.945703 -200.578432)
			(xy 291.972089 -200.531415) (xy 292.005041 -200.488742) (xy 292.043854 -200.451321) (xy 292.087702 -200.419951)
			(xy 292.13565 -200.395299) (xy 292.186677 -200.377891) (xy 292.239695 -200.368098) (xy 292.293574 -200.366129)
			(xy 292.347165 -200.372026) (xy 292.399326 -200.385662) (xy 292.448946 -200.406749) (xy 292.494967 -200.434835)
			(xy 292.536409 -200.469323) (xy 292.572387 -200.509477) (xy 292.602135 -200.554441) (xy 292.62502 -200.603258)
			(xy 292.640552 -200.654887) (xy 292.648402 -200.708227) (xy 292.648894 -200.735184) (xy 292.648402 -200.762141)
			(xy 292.640552 -200.815481) (xy 292.62502 -200.86711) (xy 292.602135 -200.915927) (xy 292.572387 -200.960891)
			(xy 292.536409 -201.001045) (xy 292.494967 -201.035533) (xy 292.448946 -201.063619) (xy 292.399326 -201.084706)
			(xy 292.347165 -201.098342) (xy 292.293574 -201.104239) (xy 292.239695 -201.10227) (xy 292.186677 -201.092477)
			(xy 292.13565 -201.075069) (xy 292.087702 -201.050417) (xy 292.043854 -201.019047) (xy 292.005041 -200.981626)
			(xy 291.972089 -200.938953) (xy 291.945703 -200.891936) (xy 291.926443 -200.841579) (xy 291.91472 -200.788955)
			(xy 291.910785 -200.735184) (xy 285.10484 -200.735184) (xy 285.104348 -200.762141) (xy 285.096498 -200.815481)
			(xy 285.080966 -200.86711) (xy 285.058081 -200.915927) (xy 285.028333 -200.960891) (xy 284.992355 -201.001045)
			(xy 284.950913 -201.035533) (xy 284.904892 -201.063619) (xy 284.855272 -201.084706) (xy 284.803111 -201.098342)
			(xy 284.74952 -201.104239) (xy 284.695641 -201.10227) (xy 284.642623 -201.092477) (xy 284.591596 -201.075069)
			(xy 284.543648 -201.050417) (xy 284.4998 -201.019047) (xy 284.460987 -200.981626) (xy 284.428035 -200.938953)
			(xy 284.401649 -200.891936) (xy 284.382389 -200.841579) (xy 284.370666 -200.788955) (xy 284.366731 -200.735184)
			(xy 277.56104 -200.735184) (xy 277.560548 -200.762141) (xy 277.552698 -200.815481) (xy 277.537166 -200.86711)
			(xy 277.514281 -200.915927) (xy 277.484533 -200.960891) (xy 277.448555 -201.001045) (xy 277.407113 -201.035533)
			(xy 277.361092 -201.063619) (xy 277.311472 -201.084706) (xy 277.259311 -201.098342) (xy 277.20572 -201.104239)
			(xy 277.151841 -201.10227) (xy 277.098823 -201.092477) (xy 277.047796 -201.075069) (xy 276.999848 -201.050417)
			(xy 276.956 -201.019047) (xy 276.917187 -200.981626) (xy 276.884235 -200.938953) (xy 276.857849 -200.891936)
			(xy 276.838589 -200.841579) (xy 276.826866 -200.788955) (xy 276.822931 -200.735184) (xy 270.016986 -200.735184)
			(xy 270.016494 -200.762141) (xy 270.008644 -200.815481) (xy 269.993112 -200.86711) (xy 269.970227 -200.915927)
			(xy 269.940479 -200.960891) (xy 269.904501 -201.001045) (xy 269.863059 -201.035533) (xy 269.817038 -201.063619)
			(xy 269.767418 -201.084706) (xy 269.715257 -201.098342) (xy 269.661666 -201.104239) (xy 269.607787 -201.10227)
			(xy 269.554769 -201.092477) (xy 269.503742 -201.075069) (xy 269.455794 -201.050417) (xy 269.411946 -201.019047)
			(xy 269.373133 -200.981626) (xy 269.340181 -200.938953) (xy 269.313795 -200.891936) (xy 269.294535 -200.841579)
			(xy 269.282812 -200.788955) (xy 269.278877 -200.735184) (xy 264.143998 -200.735184) (xy 264.143998 -201.585068)
			(xy 265.178809 -201.585068) (xy 265.182744 -201.531297) (xy 265.194467 -201.478673) (xy 265.213727 -201.428316)
			(xy 265.240113 -201.381299) (xy 265.273065 -201.338626) (xy 265.311878 -201.301205) (xy 265.355726 -201.269835)
			(xy 265.403674 -201.245183) (xy 265.454701 -201.227775) (xy 265.507719 -201.217982) (xy 265.561598 -201.216013)
			(xy 265.615189 -201.22191) (xy 265.66735 -201.235546) (xy 265.71697 -201.256633) (xy 265.762991 -201.284719)
			(xy 265.804433 -201.319207) (xy 265.840411 -201.359361) (xy 265.870159 -201.404325) (xy 265.893044 -201.453142)
			(xy 265.908576 -201.504771) (xy 265.916426 -201.558111) (xy 265.916918 -201.585068) (xy 269.278877 -201.585068)
			(xy 269.282812 -201.531297) (xy 269.294535 -201.478673) (xy 269.313795 -201.428316) (xy 269.340181 -201.381299)
			(xy 269.373133 -201.338626) (xy 269.411946 -201.301205) (xy 269.455794 -201.269835) (xy 269.503742 -201.245183)
			(xy 269.554769 -201.227775) (xy 269.607787 -201.217982) (xy 269.661666 -201.216013) (xy 269.715257 -201.22191)
			(xy 269.767418 -201.235546) (xy 269.817038 -201.256633) (xy 269.863059 -201.284719) (xy 269.904501 -201.319207)
			(xy 269.940479 -201.359361) (xy 269.970227 -201.404325) (xy 269.993112 -201.453142) (xy 270.008644 -201.504771)
			(xy 270.016494 -201.558111) (xy 270.016986 -201.585068) (xy 272.722863 -201.585068) (xy 272.726798 -201.531297)
			(xy 272.738521 -201.478673) (xy 272.757781 -201.428316) (xy 272.784167 -201.381299) (xy 272.817119 -201.338626)
			(xy 272.855932 -201.301205) (xy 272.89978 -201.269835) (xy 272.947728 -201.245183) (xy 272.998755 -201.227775)
			(xy 273.051773 -201.217982) (xy 273.105652 -201.216013) (xy 273.159243 -201.22191) (xy 273.211404 -201.235546)
			(xy 273.261024 -201.256633) (xy 273.307045 -201.284719) (xy 273.348487 -201.319207) (xy 273.384465 -201.359361)
			(xy 273.414213 -201.404325) (xy 273.437098 -201.453142) (xy 273.45263 -201.504771) (xy 273.46048 -201.558111)
			(xy 273.460972 -201.585068) (xy 276.822931 -201.585068) (xy 276.826866 -201.531297) (xy 276.838589 -201.478673)
			(xy 276.857849 -201.428316) (xy 276.884235 -201.381299) (xy 276.917187 -201.338626) (xy 276.956 -201.301205)
			(xy 276.999848 -201.269835) (xy 277.047796 -201.245183) (xy 277.098823 -201.227775) (xy 277.151841 -201.217982)
			(xy 277.20572 -201.216013) (xy 277.259311 -201.22191) (xy 277.311472 -201.235546) (xy 277.361092 -201.256633)
			(xy 277.407113 -201.284719) (xy 277.448555 -201.319207) (xy 277.484533 -201.359361) (xy 277.514281 -201.404325)
			(xy 277.537166 -201.453142) (xy 277.552698 -201.504771) (xy 277.560548 -201.558111) (xy 277.56104 -201.585068)
			(xy 280.266663 -201.585068) (xy 280.270598 -201.531297) (xy 280.282321 -201.478673) (xy 280.301581 -201.428316)
			(xy 280.327967 -201.381299) (xy 280.360919 -201.338626) (xy 280.399732 -201.301205) (xy 280.44358 -201.269835)
			(xy 280.491528 -201.245183) (xy 280.542555 -201.227775) (xy 280.595573 -201.217982) (xy 280.649452 -201.216013)
			(xy 280.703043 -201.22191) (xy 280.755204 -201.235546) (xy 280.804824 -201.256633) (xy 280.850845 -201.284719)
			(xy 280.892287 -201.319207) (xy 280.928265 -201.359361) (xy 280.958013 -201.404325) (xy 280.980898 -201.453142)
			(xy 280.99643 -201.504771) (xy 281.00428 -201.558111) (xy 281.004772 -201.585068) (xy 284.366731 -201.585068)
			(xy 284.370666 -201.531297) (xy 284.382389 -201.478673) (xy 284.401649 -201.428316) (xy 284.428035 -201.381299)
			(xy 284.460987 -201.338626) (xy 284.4998 -201.301205) (xy 284.543648 -201.269835) (xy 284.591596 -201.245183)
			(xy 284.642623 -201.227775) (xy 284.695641 -201.217982) (xy 284.74952 -201.216013) (xy 284.803111 -201.22191)
			(xy 284.855272 -201.235546) (xy 284.904892 -201.256633) (xy 284.950913 -201.284719) (xy 284.992355 -201.319207)
			(xy 285.028333 -201.359361) (xy 285.058081 -201.404325) (xy 285.080966 -201.453142) (xy 285.096498 -201.504771)
			(xy 285.104348 -201.558111) (xy 285.10484 -201.585068) (xy 287.810717 -201.585068) (xy 287.814652 -201.531297)
			(xy 287.826375 -201.478673) (xy 287.845635 -201.428316) (xy 287.872021 -201.381299) (xy 287.904973 -201.338626)
			(xy 287.943786 -201.301205) (xy 287.987634 -201.269835) (xy 288.035582 -201.245183) (xy 288.086609 -201.227775)
			(xy 288.139627 -201.217982) (xy 288.193506 -201.216013) (xy 288.247097 -201.22191) (xy 288.299258 -201.235546)
			(xy 288.348878 -201.256633) (xy 288.394899 -201.284719) (xy 288.436341 -201.319207) (xy 288.472319 -201.359361)
			(xy 288.502067 -201.404325) (xy 288.524952 -201.453142) (xy 288.540484 -201.504771) (xy 288.548334 -201.558111)
			(xy 288.548826 -201.585068) (xy 291.910785 -201.585068) (xy 291.91472 -201.531297) (xy 291.926443 -201.478673)
			(xy 291.945703 -201.428316) (xy 291.972089 -201.381299) (xy 292.005041 -201.338626) (xy 292.043854 -201.301205)
			(xy 292.087702 -201.269835) (xy 292.13565 -201.245183) (xy 292.186677 -201.227775) (xy 292.239695 -201.217982)
			(xy 292.293574 -201.216013) (xy 292.347165 -201.22191) (xy 292.399326 -201.235546) (xy 292.448946 -201.256633)
			(xy 292.494967 -201.284719) (xy 292.536409 -201.319207) (xy 292.572387 -201.359361) (xy 292.602135 -201.404325)
			(xy 292.62502 -201.453142) (xy 292.640552 -201.504771) (xy 292.648402 -201.558111) (xy 292.648894 -201.585068)
			(xy 292.648402 -201.612025) (xy 292.640552 -201.665365) (xy 292.62502 -201.716994) (xy 292.602135 -201.765811)
			(xy 292.572387 -201.810775) (xy 292.536409 -201.850929) (xy 292.494967 -201.885417) (xy 292.448946 -201.913503)
			(xy 292.399326 -201.93459) (xy 292.347165 -201.948226) (xy 292.293574 -201.954123) (xy 292.239695 -201.952154)
			(xy 292.186677 -201.942361) (xy 292.13565 -201.924953) (xy 292.087702 -201.900301) (xy 292.043854 -201.868931)
			(xy 292.005041 -201.83151) (xy 291.972089 -201.788837) (xy 291.945703 -201.74182) (xy 291.926443 -201.691463)
			(xy 291.91472 -201.638839) (xy 291.910785 -201.585068) (xy 288.548826 -201.585068) (xy 288.548334 -201.612025)
			(xy 288.540484 -201.665365) (xy 288.524952 -201.716994) (xy 288.502067 -201.765811) (xy 288.472319 -201.810775)
			(xy 288.436341 -201.850929) (xy 288.394899 -201.885417) (xy 288.348878 -201.913503) (xy 288.299258 -201.93459)
			(xy 288.247097 -201.948226) (xy 288.193506 -201.954123) (xy 288.139627 -201.952154) (xy 288.086609 -201.942361)
			(xy 288.035582 -201.924953) (xy 287.987634 -201.900301) (xy 287.943786 -201.868931) (xy 287.904973 -201.83151)
			(xy 287.872021 -201.788837) (xy 287.845635 -201.74182) (xy 287.826375 -201.691463) (xy 287.814652 -201.638839)
			(xy 287.810717 -201.585068) (xy 285.10484 -201.585068) (xy 285.104348 -201.612025) (xy 285.096498 -201.665365)
			(xy 285.080966 -201.716994) (xy 285.058081 -201.765811) (xy 285.028333 -201.810775) (xy 284.992355 -201.850929)
			(xy 284.950913 -201.885417) (xy 284.904892 -201.913503) (xy 284.855272 -201.93459) (xy 284.803111 -201.948226)
			(xy 284.74952 -201.954123) (xy 284.695641 -201.952154) (xy 284.642623 -201.942361) (xy 284.591596 -201.924953)
			(xy 284.543648 -201.900301) (xy 284.4998 -201.868931) (xy 284.460987 -201.83151) (xy 284.428035 -201.788837)
			(xy 284.401649 -201.74182) (xy 284.382389 -201.691463) (xy 284.370666 -201.638839) (xy 284.366731 -201.585068)
			(xy 281.004772 -201.585068) (xy 281.00428 -201.612025) (xy 280.99643 -201.665365) (xy 280.980898 -201.716994)
			(xy 280.958013 -201.765811) (xy 280.928265 -201.810775) (xy 280.892287 -201.850929) (xy 280.850845 -201.885417)
			(xy 280.804824 -201.913503) (xy 280.755204 -201.93459) (xy 280.703043 -201.948226) (xy 280.649452 -201.954123)
			(xy 280.595573 -201.952154) (xy 280.542555 -201.942361) (xy 280.491528 -201.924953) (xy 280.44358 -201.900301)
			(xy 280.399732 -201.868931) (xy 280.360919 -201.83151) (xy 280.327967 -201.788837) (xy 280.301581 -201.74182)
			(xy 280.282321 -201.691463) (xy 280.270598 -201.638839) (xy 280.266663 -201.585068) (xy 277.56104 -201.585068)
			(xy 277.560548 -201.612025) (xy 277.552698 -201.665365) (xy 277.537166 -201.716994) (xy 277.514281 -201.765811)
			(xy 277.484533 -201.810775) (xy 277.448555 -201.850929) (xy 277.407113 -201.885417) (xy 277.361092 -201.913503)
			(xy 277.311472 -201.93459) (xy 277.259311 -201.948226) (xy 277.20572 -201.954123) (xy 277.151841 -201.952154)
			(xy 277.098823 -201.942361) (xy 277.047796 -201.924953) (xy 276.999848 -201.900301) (xy 276.956 -201.868931)
			(xy 276.917187 -201.83151) (xy 276.884235 -201.788837) (xy 276.857849 -201.74182) (xy 276.838589 -201.691463)
			(xy 276.826866 -201.638839) (xy 276.822931 -201.585068) (xy 273.460972 -201.585068) (xy 273.46048 -201.612025)
			(xy 273.45263 -201.665365) (xy 273.437098 -201.716994) (xy 273.414213 -201.765811) (xy 273.384465 -201.810775)
			(xy 273.348487 -201.850929) (xy 273.307045 -201.885417) (xy 273.261024 -201.913503) (xy 273.211404 -201.93459)
			(xy 273.159243 -201.948226) (xy 273.105652 -201.954123) (xy 273.051773 -201.952154) (xy 272.998755 -201.942361)
			(xy 272.947728 -201.924953) (xy 272.89978 -201.900301) (xy 272.855932 -201.868931) (xy 272.817119 -201.83151)
			(xy 272.784167 -201.788837) (xy 272.757781 -201.74182) (xy 272.738521 -201.691463) (xy 272.726798 -201.638839)
			(xy 272.722863 -201.585068) (xy 270.016986 -201.585068) (xy 270.016494 -201.612025) (xy 270.008644 -201.665365)
			(xy 269.993112 -201.716994) (xy 269.970227 -201.765811) (xy 269.940479 -201.810775) (xy 269.904501 -201.850929)
			(xy 269.863059 -201.885417) (xy 269.817038 -201.913503) (xy 269.767418 -201.93459) (xy 269.715257 -201.948226)
			(xy 269.661666 -201.954123) (xy 269.607787 -201.952154) (xy 269.554769 -201.942361) (xy 269.503742 -201.924953)
			(xy 269.455794 -201.900301) (xy 269.411946 -201.868931) (xy 269.373133 -201.83151) (xy 269.340181 -201.788837)
			(xy 269.313795 -201.74182) (xy 269.294535 -201.691463) (xy 269.282812 -201.638839) (xy 269.278877 -201.585068)
			(xy 265.916918 -201.585068) (xy 265.916426 -201.612025) (xy 265.908576 -201.665365) (xy 265.893044 -201.716994)
			(xy 265.870159 -201.765811) (xy 265.840411 -201.810775) (xy 265.804433 -201.850929) (xy 265.762991 -201.885417)
			(xy 265.71697 -201.913503) (xy 265.66735 -201.93459) (xy 265.615189 -201.948226) (xy 265.561598 -201.954123)
			(xy 265.507719 -201.952154) (xy 265.454701 -201.942361) (xy 265.403674 -201.924953) (xy 265.355726 -201.900301)
			(xy 265.311878 -201.868931) (xy 265.273065 -201.83151) (xy 265.240113 -201.788837) (xy 265.213727 -201.74182)
			(xy 265.194467 -201.691463) (xy 265.182744 -201.638839) (xy 265.178809 -201.585068) (xy 264.143998 -201.585068)
			(xy 264.143998 -202.434952) (xy 265.178809 -202.434952) (xy 265.182744 -202.381181) (xy 265.194467 -202.328557)
			(xy 265.213727 -202.2782) (xy 265.240113 -202.231183) (xy 265.273065 -202.18851) (xy 265.311878 -202.151089)
			(xy 265.355726 -202.119719) (xy 265.403674 -202.095067) (xy 265.454701 -202.077659) (xy 265.507719 -202.067866)
			(xy 265.561598 -202.065897) (xy 265.615189 -202.071794) (xy 265.66735 -202.08543) (xy 265.71697 -202.106517)
			(xy 265.762991 -202.134603) (xy 265.804433 -202.169091) (xy 265.840411 -202.209245) (xy 265.870159 -202.254209)
			(xy 265.893044 -202.303026) (xy 265.908576 -202.354655) (xy 265.916426 -202.407995) (xy 265.916918 -202.434952)
			(xy 272.722863 -202.434952) (xy 272.726798 -202.381181) (xy 272.738521 -202.328557) (xy 272.757781 -202.2782)
			(xy 272.784167 -202.231183) (xy 272.817119 -202.18851) (xy 272.855932 -202.151089) (xy 272.89978 -202.119719)
			(xy 272.947728 -202.095067) (xy 272.998755 -202.077659) (xy 273.051773 -202.067866) (xy 273.105652 -202.065897)
			(xy 273.159243 -202.071794) (xy 273.211404 -202.08543) (xy 273.261024 -202.106517) (xy 273.307045 -202.134603)
			(xy 273.348487 -202.169091) (xy 273.384465 -202.209245) (xy 273.414213 -202.254209) (xy 273.437098 -202.303026)
			(xy 273.45263 -202.354655) (xy 273.46048 -202.407995) (xy 273.460972 -202.434952) (xy 280.266663 -202.434952)
			(xy 280.270598 -202.381181) (xy 280.282321 -202.328557) (xy 280.301581 -202.2782) (xy 280.327967 -202.231183)
			(xy 280.360919 -202.18851) (xy 280.399732 -202.151089) (xy 280.44358 -202.119719) (xy 280.491528 -202.095067)
			(xy 280.542555 -202.077659) (xy 280.595573 -202.067866) (xy 280.649452 -202.065897) (xy 280.703043 -202.071794)
			(xy 280.755204 -202.08543) (xy 280.804824 -202.106517) (xy 280.850845 -202.134603) (xy 280.892287 -202.169091)
			(xy 280.928265 -202.209245) (xy 280.958013 -202.254209) (xy 280.980898 -202.303026) (xy 280.99643 -202.354655)
			(xy 281.00428 -202.407995) (xy 281.004772 -202.434952) (xy 287.810717 -202.434952) (xy 287.814652 -202.381181)
			(xy 287.826375 -202.328557) (xy 287.845635 -202.2782) (xy 287.872021 -202.231183) (xy 287.904973 -202.18851)
			(xy 287.943786 -202.151089) (xy 287.987634 -202.119719) (xy 288.035582 -202.095067) (xy 288.086609 -202.077659)
			(xy 288.139627 -202.067866) (xy 288.193506 -202.065897) (xy 288.247097 -202.071794) (xy 288.299258 -202.08543)
			(xy 288.348878 -202.106517) (xy 288.394899 -202.134603) (xy 288.436341 -202.169091) (xy 288.472319 -202.209245)
			(xy 288.502067 -202.254209) (xy 288.524952 -202.303026) (xy 288.540484 -202.354655) (xy 288.548334 -202.407995)
			(xy 288.548826 -202.434952) (xy 288.548334 -202.461909) (xy 288.540484 -202.515249) (xy 288.524952 -202.566878)
			(xy 288.502067 -202.615695) (xy 288.472319 -202.660659) (xy 288.436341 -202.700813) (xy 288.394899 -202.735301)
			(xy 288.348878 -202.763387) (xy 288.299258 -202.784474) (xy 288.247097 -202.79811) (xy 288.193506 -202.804007)
			(xy 288.139627 -202.802038) (xy 288.086609 -202.792245) (xy 288.035582 -202.774837) (xy 287.987634 -202.750185)
			(xy 287.943786 -202.718815) (xy 287.904973 -202.681394) (xy 287.872021 -202.638721) (xy 287.845635 -202.591704)
			(xy 287.826375 -202.541347) (xy 287.814652 -202.488723) (xy 287.810717 -202.434952) (xy 281.004772 -202.434952)
			(xy 281.00428 -202.461909) (xy 280.99643 -202.515249) (xy 280.980898 -202.566878) (xy 280.958013 -202.615695)
			(xy 280.928265 -202.660659) (xy 280.892287 -202.700813) (xy 280.850845 -202.735301) (xy 280.804824 -202.763387)
			(xy 280.755204 -202.784474) (xy 280.703043 -202.79811) (xy 280.649452 -202.804007) (xy 280.595573 -202.802038)
			(xy 280.542555 -202.792245) (xy 280.491528 -202.774837) (xy 280.44358 -202.750185) (xy 280.399732 -202.718815)
			(xy 280.360919 -202.681394) (xy 280.327967 -202.638721) (xy 280.301581 -202.591704) (xy 280.282321 -202.541347)
			(xy 280.270598 -202.488723) (xy 280.266663 -202.434952) (xy 273.460972 -202.434952) (xy 273.46048 -202.461909)
			(xy 273.45263 -202.515249) (xy 273.437098 -202.566878) (xy 273.414213 -202.615695) (xy 273.384465 -202.660659)
			(xy 273.348487 -202.700813) (xy 273.307045 -202.735301) (xy 273.261024 -202.763387) (xy 273.211404 -202.784474)
			(xy 273.159243 -202.79811) (xy 273.105652 -202.804007) (xy 273.051773 -202.802038) (xy 272.998755 -202.792245)
			(xy 272.947728 -202.774837) (xy 272.89978 -202.750185) (xy 272.855932 -202.718815) (xy 272.817119 -202.681394)
			(xy 272.784167 -202.638721) (xy 272.757781 -202.591704) (xy 272.738521 -202.541347) (xy 272.726798 -202.488723)
			(xy 272.722863 -202.434952) (xy 265.916918 -202.434952) (xy 265.916426 -202.461909) (xy 265.908576 -202.515249)
			(xy 265.893044 -202.566878) (xy 265.870159 -202.615695) (xy 265.840411 -202.660659) (xy 265.804433 -202.700813)
			(xy 265.762991 -202.735301) (xy 265.71697 -202.763387) (xy 265.66735 -202.784474) (xy 265.615189 -202.79811)
			(xy 265.561598 -202.804007) (xy 265.507719 -202.802038) (xy 265.454701 -202.792245) (xy 265.403674 -202.774837)
			(xy 265.355726 -202.750185) (xy 265.311878 -202.718815) (xy 265.273065 -202.681394) (xy 265.240113 -202.638721)
			(xy 265.213727 -202.591704) (xy 265.194467 -202.541347) (xy 265.182744 -202.488723) (xy 265.178809 -202.434952)
			(xy 264.143998 -202.434952) (xy 264.143998 -203.28509) (xy 269.278877 -203.28509) (xy 269.282812 -203.231319)
			(xy 269.294535 -203.178695) (xy 269.313795 -203.128338) (xy 269.340181 -203.081321) (xy 269.373133 -203.038648)
			(xy 269.411946 -203.001227) (xy 269.455794 -202.969857) (xy 269.503742 -202.945205) (xy 269.554769 -202.927797)
			(xy 269.607787 -202.918004) (xy 269.661666 -202.916035) (xy 269.715257 -202.921932) (xy 269.767418 -202.935568)
			(xy 269.817038 -202.956655) (xy 269.863059 -202.984741) (xy 269.904501 -203.019229) (xy 269.940479 -203.059383)
			(xy 269.970227 -203.104347) (xy 269.993112 -203.153164) (xy 270.008644 -203.204793) (xy 270.016494 -203.258133)
			(xy 270.016986 -203.28509) (xy 276.822931 -203.28509) (xy 276.826866 -203.231319) (xy 276.838589 -203.178695)
			(xy 276.857849 -203.128338) (xy 276.884235 -203.081321) (xy 276.917187 -203.038648) (xy 276.956 -203.001227)
			(xy 276.999848 -202.969857) (xy 277.047796 -202.945205) (xy 277.098823 -202.927797) (xy 277.151841 -202.918004)
			(xy 277.20572 -202.916035) (xy 277.259311 -202.921932) (xy 277.311472 -202.935568) (xy 277.361092 -202.956655)
			(xy 277.407113 -202.984741) (xy 277.448555 -203.019229) (xy 277.484533 -203.059383) (xy 277.514281 -203.104347)
			(xy 277.537166 -203.153164) (xy 277.552698 -203.204793) (xy 277.560548 -203.258133) (xy 277.56104 -203.28509)
			(xy 284.366731 -203.28509) (xy 284.370666 -203.231319) (xy 284.382389 -203.178695) (xy 284.401649 -203.128338)
			(xy 284.428035 -203.081321) (xy 284.460987 -203.038648) (xy 284.4998 -203.001227) (xy 284.543648 -202.969857)
			(xy 284.591596 -202.945205) (xy 284.642623 -202.927797) (xy 284.695641 -202.918004) (xy 284.74952 -202.916035)
			(xy 284.803111 -202.921932) (xy 284.855272 -202.935568) (xy 284.904892 -202.956655) (xy 284.950913 -202.984741)
			(xy 284.992355 -203.019229) (xy 285.028333 -203.059383) (xy 285.058081 -203.104347) (xy 285.080966 -203.153164)
			(xy 285.096498 -203.204793) (xy 285.104348 -203.258133) (xy 285.10484 -203.28509) (xy 291.910785 -203.28509)
			(xy 291.91472 -203.231319) (xy 291.926443 -203.178695) (xy 291.945703 -203.128338) (xy 291.972089 -203.081321)
			(xy 292.005041 -203.038648) (xy 292.043854 -203.001227) (xy 292.087702 -202.969857) (xy 292.13565 -202.945205)
			(xy 292.186677 -202.927797) (xy 292.239695 -202.918004) (xy 292.293574 -202.916035) (xy 292.347165 -202.921932)
			(xy 292.399326 -202.935568) (xy 292.448946 -202.956655) (xy 292.494967 -202.984741) (xy 292.536409 -203.019229)
			(xy 292.572387 -203.059383) (xy 292.602135 -203.104347) (xy 292.62502 -203.153164) (xy 292.640552 -203.204793)
			(xy 292.648402 -203.258133) (xy 292.648894 -203.28509) (xy 292.648402 -203.312047) (xy 292.640552 -203.365387)
			(xy 292.62502 -203.417016) (xy 292.602135 -203.465833) (xy 292.572387 -203.510797) (xy 292.536409 -203.550951)
			(xy 292.494967 -203.585439) (xy 292.448946 -203.613525) (xy 292.399326 -203.634612) (xy 292.347165 -203.648248)
			(xy 292.293574 -203.654145) (xy 292.239695 -203.652176) (xy 292.186677 -203.642383) (xy 292.13565 -203.624975)
			(xy 292.087702 -203.600323) (xy 292.043854 -203.568953) (xy 292.005041 -203.531532) (xy 291.972089 -203.488859)
			(xy 291.945703 -203.441842) (xy 291.926443 -203.391485) (xy 291.91472 -203.338861) (xy 291.910785 -203.28509)
			(xy 285.10484 -203.28509) (xy 285.104348 -203.312047) (xy 285.096498 -203.365387) (xy 285.080966 -203.417016)
			(xy 285.058081 -203.465833) (xy 285.028333 -203.510797) (xy 284.992355 -203.550951) (xy 284.950913 -203.585439)
			(xy 284.904892 -203.613525) (xy 284.855272 -203.634612) (xy 284.803111 -203.648248) (xy 284.74952 -203.654145)
			(xy 284.695641 -203.652176) (xy 284.642623 -203.642383) (xy 284.591596 -203.624975) (xy 284.543648 -203.600323)
			(xy 284.4998 -203.568953) (xy 284.460987 -203.531532) (xy 284.428035 -203.488859) (xy 284.401649 -203.441842)
			(xy 284.382389 -203.391485) (xy 284.370666 -203.338861) (xy 284.366731 -203.28509) (xy 277.56104 -203.28509)
			(xy 277.560548 -203.312047) (xy 277.552698 -203.365387) (xy 277.537166 -203.417016) (xy 277.514281 -203.465833)
			(xy 277.484533 -203.510797) (xy 277.448555 -203.550951) (xy 277.407113 -203.585439) (xy 277.361092 -203.613525)
			(xy 277.311472 -203.634612) (xy 277.259311 -203.648248) (xy 277.20572 -203.654145) (xy 277.151841 -203.652176)
			(xy 277.098823 -203.642383) (xy 277.047796 -203.624975) (xy 276.999848 -203.600323) (xy 276.956 -203.568953)
			(xy 276.917187 -203.531532) (xy 276.884235 -203.488859) (xy 276.857849 -203.441842) (xy 276.838589 -203.391485)
			(xy 276.826866 -203.338861) (xy 276.822931 -203.28509) (xy 270.016986 -203.28509) (xy 270.016494 -203.312047)
			(xy 270.008644 -203.365387) (xy 269.993112 -203.417016) (xy 269.970227 -203.465833) (xy 269.940479 -203.510797)
			(xy 269.904501 -203.550951) (xy 269.863059 -203.585439) (xy 269.817038 -203.613525) (xy 269.767418 -203.634612)
			(xy 269.715257 -203.648248) (xy 269.661666 -203.654145) (xy 269.607787 -203.652176) (xy 269.554769 -203.642383)
			(xy 269.503742 -203.624975) (xy 269.455794 -203.600323) (xy 269.411946 -203.568953) (xy 269.373133 -203.531532)
			(xy 269.340181 -203.488859) (xy 269.313795 -203.441842) (xy 269.294535 -203.391485) (xy 269.282812 -203.338861)
			(xy 269.278877 -203.28509) (xy 264.143998 -203.28509) (xy 264.143998 -204.134974) (xy 265.178809 -204.134974)
			(xy 265.182744 -204.081203) (xy 265.194467 -204.028579) (xy 265.213727 -203.978222) (xy 265.240113 -203.931205)
			(xy 265.273065 -203.888532) (xy 265.311878 -203.851111) (xy 265.355726 -203.819741) (xy 265.403674 -203.795089)
			(xy 265.454701 -203.777681) (xy 265.507719 -203.767888) (xy 265.561598 -203.765919) (xy 265.615189 -203.771816)
			(xy 265.66735 -203.785452) (xy 265.71697 -203.806539) (xy 265.762991 -203.834625) (xy 265.804433 -203.869113)
			(xy 265.840411 -203.909267) (xy 265.870159 -203.954231) (xy 265.893044 -204.003048) (xy 265.908576 -204.054677)
			(xy 265.916426 -204.108017) (xy 265.916918 -204.134974) (xy 272.722863 -204.134974) (xy 272.726798 -204.081203)
			(xy 272.738521 -204.028579) (xy 272.757781 -203.978222) (xy 272.784167 -203.931205) (xy 272.817119 -203.888532)
			(xy 272.855932 -203.851111) (xy 272.89978 -203.819741) (xy 272.947728 -203.795089) (xy 272.998755 -203.777681)
			(xy 273.051773 -203.767888) (xy 273.105652 -203.765919) (xy 273.159243 -203.771816) (xy 273.211404 -203.785452)
			(xy 273.261024 -203.806539) (xy 273.307045 -203.834625) (xy 273.348487 -203.869113) (xy 273.384465 -203.909267)
			(xy 273.414213 -203.954231) (xy 273.437098 -204.003048) (xy 273.45263 -204.054677) (xy 273.46048 -204.108017)
			(xy 273.460972 -204.134974) (xy 280.266663 -204.134974) (xy 280.270598 -204.081203) (xy 280.282321 -204.028579)
			(xy 280.301581 -203.978222) (xy 280.327967 -203.931205) (xy 280.360919 -203.888532) (xy 280.399732 -203.851111)
			(xy 280.44358 -203.819741) (xy 280.491528 -203.795089) (xy 280.542555 -203.777681) (xy 280.595573 -203.767888)
			(xy 280.649452 -203.765919) (xy 280.703043 -203.771816) (xy 280.755204 -203.785452) (xy 280.804824 -203.806539)
			(xy 280.850845 -203.834625) (xy 280.892287 -203.869113) (xy 280.928265 -203.909267) (xy 280.958013 -203.954231)
			(xy 280.980898 -204.003048) (xy 280.99643 -204.054677) (xy 281.00428 -204.108017) (xy 281.004772 -204.134974)
			(xy 287.810717 -204.134974) (xy 287.814652 -204.081203) (xy 287.826375 -204.028579) (xy 287.845635 -203.978222)
			(xy 287.872021 -203.931205) (xy 287.904973 -203.888532) (xy 287.943786 -203.851111) (xy 287.987634 -203.819741)
			(xy 288.035582 -203.795089) (xy 288.086609 -203.777681) (xy 288.139627 -203.767888) (xy 288.193506 -203.765919)
			(xy 288.247097 -203.771816) (xy 288.299258 -203.785452) (xy 288.348878 -203.806539) (xy 288.394899 -203.834625)
			(xy 288.436341 -203.869113) (xy 288.472319 -203.909267) (xy 288.502067 -203.954231) (xy 288.524952 -204.003048)
			(xy 288.540484 -204.054677) (xy 288.548334 -204.108017) (xy 288.548826 -204.134974) (xy 288.548334 -204.161931)
			(xy 288.540484 -204.215271) (xy 288.524952 -204.2669) (xy 288.502067 -204.315717) (xy 288.472319 -204.360681)
			(xy 288.436341 -204.400835) (xy 288.394899 -204.435323) (xy 288.348878 -204.463409) (xy 288.299258 -204.484496)
			(xy 288.247097 -204.498132) (xy 288.193506 -204.504029) (xy 288.139627 -204.50206) (xy 288.086609 -204.492267)
			(xy 288.035582 -204.474859) (xy 287.987634 -204.450207) (xy 287.943786 -204.418837) (xy 287.904973 -204.381416)
			(xy 287.872021 -204.338743) (xy 287.845635 -204.291726) (xy 287.826375 -204.241369) (xy 287.814652 -204.188745)
			(xy 287.810717 -204.134974) (xy 281.004772 -204.134974) (xy 281.00428 -204.161931) (xy 280.99643 -204.215271)
			(xy 280.980898 -204.2669) (xy 280.958013 -204.315717) (xy 280.928265 -204.360681) (xy 280.892287 -204.400835)
			(xy 280.850845 -204.435323) (xy 280.804824 -204.463409) (xy 280.755204 -204.484496) (xy 280.703043 -204.498132)
			(xy 280.649452 -204.504029) (xy 280.595573 -204.50206) (xy 280.542555 -204.492267) (xy 280.491528 -204.474859)
			(xy 280.44358 -204.450207) (xy 280.399732 -204.418837) (xy 280.360919 -204.381416) (xy 280.327967 -204.338743)
			(xy 280.301581 -204.291726) (xy 280.282321 -204.241369) (xy 280.270598 -204.188745) (xy 280.266663 -204.134974)
			(xy 273.460972 -204.134974) (xy 273.46048 -204.161931) (xy 273.45263 -204.215271) (xy 273.437098 -204.2669)
			(xy 273.414213 -204.315717) (xy 273.384465 -204.360681) (xy 273.348487 -204.400835) (xy 273.307045 -204.435323)
			(xy 273.261024 -204.463409) (xy 273.211404 -204.484496) (xy 273.159243 -204.498132) (xy 273.105652 -204.504029)
			(xy 273.051773 -204.50206) (xy 272.998755 -204.492267) (xy 272.947728 -204.474859) (xy 272.89978 -204.450207)
			(xy 272.855932 -204.418837) (xy 272.817119 -204.381416) (xy 272.784167 -204.338743) (xy 272.757781 -204.291726)
			(xy 272.738521 -204.241369) (xy 272.726798 -204.188745) (xy 272.722863 -204.134974) (xy 265.916918 -204.134974)
			(xy 265.916426 -204.161931) (xy 265.908576 -204.215271) (xy 265.893044 -204.2669) (xy 265.870159 -204.315717)
			(xy 265.840411 -204.360681) (xy 265.804433 -204.400835) (xy 265.762991 -204.435323) (xy 265.71697 -204.463409)
			(xy 265.66735 -204.484496) (xy 265.615189 -204.498132) (xy 265.561598 -204.504029) (xy 265.507719 -204.50206)
			(xy 265.454701 -204.492267) (xy 265.403674 -204.474859) (xy 265.355726 -204.450207) (xy 265.311878 -204.418837)
			(xy 265.273065 -204.381416) (xy 265.240113 -204.338743) (xy 265.213727 -204.291726) (xy 265.194467 -204.241369)
			(xy 265.182744 -204.188745) (xy 265.178809 -204.134974) (xy 264.143998 -204.134974) (xy 264.143998 -204.985112)
			(xy 269.278877 -204.985112) (xy 269.282812 -204.931341) (xy 269.294535 -204.878717) (xy 269.313795 -204.82836)
			(xy 269.340181 -204.781343) (xy 269.373133 -204.73867) (xy 269.411946 -204.701249) (xy 269.455794 -204.669879)
			(xy 269.503742 -204.645227) (xy 269.554769 -204.627819) (xy 269.607787 -204.618026) (xy 269.661666 -204.616057)
			(xy 269.715257 -204.621954) (xy 269.767418 -204.63559) (xy 269.817038 -204.656677) (xy 269.863059 -204.684763)
			(xy 269.904501 -204.719251) (xy 269.940479 -204.759405) (xy 269.970227 -204.804369) (xy 269.993112 -204.853186)
			(xy 270.008644 -204.904815) (xy 270.016494 -204.958155) (xy 270.016986 -204.985112) (xy 276.822931 -204.985112)
			(xy 276.826866 -204.931341) (xy 276.838589 -204.878717) (xy 276.857849 -204.82836) (xy 276.884235 -204.781343)
			(xy 276.917187 -204.73867) (xy 276.956 -204.701249) (xy 276.999848 -204.669879) (xy 277.047796 -204.645227)
			(xy 277.098823 -204.627819) (xy 277.151841 -204.618026) (xy 277.20572 -204.616057) (xy 277.259311 -204.621954)
			(xy 277.311472 -204.63559) (xy 277.361092 -204.656677) (xy 277.407113 -204.684763) (xy 277.448555 -204.719251)
			(xy 277.484533 -204.759405) (xy 277.514281 -204.804369) (xy 277.537166 -204.853186) (xy 277.552698 -204.904815)
			(xy 277.560548 -204.958155) (xy 277.56104 -204.985112) (xy 284.366731 -204.985112) (xy 284.370666 -204.931341)
			(xy 284.382389 -204.878717) (xy 284.401649 -204.82836) (xy 284.428035 -204.781343) (xy 284.460987 -204.73867)
			(xy 284.4998 -204.701249) (xy 284.543648 -204.669879) (xy 284.591596 -204.645227) (xy 284.642623 -204.627819)
			(xy 284.695641 -204.618026) (xy 284.74952 -204.616057) (xy 284.803111 -204.621954) (xy 284.855272 -204.63559)
			(xy 284.904892 -204.656677) (xy 284.950913 -204.684763) (xy 284.992355 -204.719251) (xy 285.028333 -204.759405)
			(xy 285.058081 -204.804369) (xy 285.080966 -204.853186) (xy 285.096498 -204.904815) (xy 285.104348 -204.958155)
			(xy 285.10484 -204.985112) (xy 291.910785 -204.985112) (xy 291.91472 -204.931341) (xy 291.926443 -204.878717)
			(xy 291.945703 -204.82836) (xy 291.972089 -204.781343) (xy 292.005041 -204.73867) (xy 292.043854 -204.701249)
			(xy 292.087702 -204.669879) (xy 292.13565 -204.645227) (xy 292.186677 -204.627819) (xy 292.239695 -204.618026)
			(xy 292.293574 -204.616057) (xy 292.347165 -204.621954) (xy 292.399326 -204.63559) (xy 292.448946 -204.656677)
			(xy 292.494967 -204.684763) (xy 292.536409 -204.719251) (xy 292.572387 -204.759405) (xy 292.602135 -204.804369)
			(xy 292.62502 -204.853186) (xy 292.640552 -204.904815) (xy 292.648402 -204.958155) (xy 292.648894 -204.985112)
			(xy 292.648402 -205.012069) (xy 292.640552 -205.065409) (xy 292.62502 -205.117038) (xy 292.602135 -205.165855)
			(xy 292.572387 -205.210819) (xy 292.536409 -205.250973) (xy 292.494967 -205.285461) (xy 292.448946 -205.313547)
			(xy 292.399326 -205.334634) (xy 292.347165 -205.34827) (xy 292.293574 -205.354167) (xy 292.239695 -205.352198)
			(xy 292.186677 -205.342405) (xy 292.13565 -205.324997) (xy 292.087702 -205.300345) (xy 292.043854 -205.268975)
			(xy 292.005041 -205.231554) (xy 291.972089 -205.188881) (xy 291.945703 -205.141864) (xy 291.926443 -205.091507)
			(xy 291.91472 -205.038883) (xy 291.910785 -204.985112) (xy 285.10484 -204.985112) (xy 285.104348 -205.012069)
			(xy 285.096498 -205.065409) (xy 285.080966 -205.117038) (xy 285.058081 -205.165855) (xy 285.028333 -205.210819)
			(xy 284.992355 -205.250973) (xy 284.950913 -205.285461) (xy 284.904892 -205.313547) (xy 284.855272 -205.334634)
			(xy 284.803111 -205.34827) (xy 284.74952 -205.354167) (xy 284.695641 -205.352198) (xy 284.642623 -205.342405)
			(xy 284.591596 -205.324997) (xy 284.543648 -205.300345) (xy 284.4998 -205.268975) (xy 284.460987 -205.231554)
			(xy 284.428035 -205.188881) (xy 284.401649 -205.141864) (xy 284.382389 -205.091507) (xy 284.370666 -205.038883)
			(xy 284.366731 -204.985112) (xy 277.56104 -204.985112) (xy 277.560548 -205.012069) (xy 277.552698 -205.065409)
			(xy 277.537166 -205.117038) (xy 277.514281 -205.165855) (xy 277.484533 -205.210819) (xy 277.448555 -205.250973)
			(xy 277.407113 -205.285461) (xy 277.361092 -205.313547) (xy 277.311472 -205.334634) (xy 277.259311 -205.34827)
			(xy 277.20572 -205.354167) (xy 277.151841 -205.352198) (xy 277.098823 -205.342405) (xy 277.047796 -205.324997)
			(xy 276.999848 -205.300345) (xy 276.956 -205.268975) (xy 276.917187 -205.231554) (xy 276.884235 -205.188881)
			(xy 276.857849 -205.141864) (xy 276.838589 -205.091507) (xy 276.826866 -205.038883) (xy 276.822931 -204.985112)
			(xy 270.016986 -204.985112) (xy 270.016494 -205.012069) (xy 270.008644 -205.065409) (xy 269.993112 -205.117038)
			(xy 269.970227 -205.165855) (xy 269.940479 -205.210819) (xy 269.904501 -205.250973) (xy 269.863059 -205.285461)
			(xy 269.817038 -205.313547) (xy 269.767418 -205.334634) (xy 269.715257 -205.34827) (xy 269.661666 -205.354167)
			(xy 269.607787 -205.352198) (xy 269.554769 -205.342405) (xy 269.503742 -205.324997) (xy 269.455794 -205.300345)
			(xy 269.411946 -205.268975) (xy 269.373133 -205.231554) (xy 269.340181 -205.188881) (xy 269.313795 -205.141864)
			(xy 269.294535 -205.091507) (xy 269.282812 -205.038883) (xy 269.278877 -204.985112) (xy 264.143998 -204.985112)
			(xy 264.143998 -205.834996) (xy 265.178809 -205.834996) (xy 265.182744 -205.781225) (xy 265.194467 -205.728601)
			(xy 265.213727 -205.678244) (xy 265.240113 -205.631227) (xy 265.273065 -205.588554) (xy 265.311878 -205.551133)
			(xy 265.355726 -205.519763) (xy 265.403674 -205.495111) (xy 265.454701 -205.477703) (xy 265.507719 -205.46791)
			(xy 265.561598 -205.465941) (xy 265.615189 -205.471838) (xy 265.66735 -205.485474) (xy 265.71697 -205.506561)
			(xy 265.762991 -205.534647) (xy 265.804433 -205.569135) (xy 265.840411 -205.609289) (xy 265.870159 -205.654253)
			(xy 265.893044 -205.70307) (xy 265.908576 -205.754699) (xy 265.916426 -205.808039) (xy 265.916918 -205.834996)
			(xy 272.722863 -205.834996) (xy 272.726798 -205.781225) (xy 272.738521 -205.728601) (xy 272.757781 -205.678244)
			(xy 272.784167 -205.631227) (xy 272.817119 -205.588554) (xy 272.855932 -205.551133) (xy 272.89978 -205.519763)
			(xy 272.947728 -205.495111) (xy 272.998755 -205.477703) (xy 273.051773 -205.46791) (xy 273.105652 -205.465941)
			(xy 273.159243 -205.471838) (xy 273.211404 -205.485474) (xy 273.261024 -205.506561) (xy 273.307045 -205.534647)
			(xy 273.348487 -205.569135) (xy 273.384465 -205.609289) (xy 273.414213 -205.654253) (xy 273.437098 -205.70307)
			(xy 273.45263 -205.754699) (xy 273.46048 -205.808039) (xy 273.460972 -205.834996) (xy 280.266663 -205.834996)
			(xy 280.270598 -205.781225) (xy 280.282321 -205.728601) (xy 280.301581 -205.678244) (xy 280.327967 -205.631227)
			(xy 280.360919 -205.588554) (xy 280.399732 -205.551133) (xy 280.44358 -205.519763) (xy 280.491528 -205.495111)
			(xy 280.542555 -205.477703) (xy 280.595573 -205.46791) (xy 280.649452 -205.465941) (xy 280.703043 -205.471838)
			(xy 280.755204 -205.485474) (xy 280.804824 -205.506561) (xy 280.850845 -205.534647) (xy 280.892287 -205.569135)
			(xy 280.928265 -205.609289) (xy 280.958013 -205.654253) (xy 280.980898 -205.70307) (xy 280.99643 -205.754699)
			(xy 281.00428 -205.808039) (xy 281.004772 -205.834996) (xy 287.810717 -205.834996) (xy 287.814652 -205.781225)
			(xy 287.826375 -205.728601) (xy 287.845635 -205.678244) (xy 287.872021 -205.631227) (xy 287.904973 -205.588554)
			(xy 287.943786 -205.551133) (xy 287.987634 -205.519763) (xy 288.035582 -205.495111) (xy 288.086609 -205.477703)
			(xy 288.139627 -205.46791) (xy 288.193506 -205.465941) (xy 288.247097 -205.471838) (xy 288.299258 -205.485474)
			(xy 288.348878 -205.506561) (xy 288.394899 -205.534647) (xy 288.436341 -205.569135) (xy 288.472319 -205.609289)
			(xy 288.502067 -205.654253) (xy 288.524952 -205.70307) (xy 288.540484 -205.754699) (xy 288.548334 -205.808039)
			(xy 288.548826 -205.834996) (xy 288.548334 -205.861953) (xy 288.540484 -205.915293) (xy 288.524952 -205.966922)
			(xy 288.502067 -206.015739) (xy 288.472319 -206.060703) (xy 288.436341 -206.100857) (xy 288.394899 -206.135345)
			(xy 288.348878 -206.163431) (xy 288.299258 -206.184518) (xy 288.247097 -206.198154) (xy 288.193506 -206.204051)
			(xy 288.139627 -206.202082) (xy 288.086609 -206.192289) (xy 288.035582 -206.174881) (xy 287.987634 -206.150229)
			(xy 287.943786 -206.118859) (xy 287.904973 -206.081438) (xy 287.872021 -206.038765) (xy 287.845635 -205.991748)
			(xy 287.826375 -205.941391) (xy 287.814652 -205.888767) (xy 287.810717 -205.834996) (xy 281.004772 -205.834996)
			(xy 281.00428 -205.861953) (xy 280.99643 -205.915293) (xy 280.980898 -205.966922) (xy 280.958013 -206.015739)
			(xy 280.928265 -206.060703) (xy 280.892287 -206.100857) (xy 280.850845 -206.135345) (xy 280.804824 -206.163431)
			(xy 280.755204 -206.184518) (xy 280.703043 -206.198154) (xy 280.649452 -206.204051) (xy 280.595573 -206.202082)
			(xy 280.542555 -206.192289) (xy 280.491528 -206.174881) (xy 280.44358 -206.150229) (xy 280.399732 -206.118859)
			(xy 280.360919 -206.081438) (xy 280.327967 -206.038765) (xy 280.301581 -205.991748) (xy 280.282321 -205.941391)
			(xy 280.270598 -205.888767) (xy 280.266663 -205.834996) (xy 273.460972 -205.834996) (xy 273.46048 -205.861953)
			(xy 273.45263 -205.915293) (xy 273.437098 -205.966922) (xy 273.414213 -206.015739) (xy 273.384465 -206.060703)
			(xy 273.348487 -206.100857) (xy 273.307045 -206.135345) (xy 273.261024 -206.163431) (xy 273.211404 -206.184518)
			(xy 273.159243 -206.198154) (xy 273.105652 -206.204051) (xy 273.051773 -206.202082) (xy 272.998755 -206.192289)
			(xy 272.947728 -206.174881) (xy 272.89978 -206.150229) (xy 272.855932 -206.118859) (xy 272.817119 -206.081438)
			(xy 272.784167 -206.038765) (xy 272.757781 -205.991748) (xy 272.738521 -205.941391) (xy 272.726798 -205.888767)
			(xy 272.722863 -205.834996) (xy 265.916918 -205.834996) (xy 265.916426 -205.861953) (xy 265.908576 -205.915293)
			(xy 265.893044 -205.966922) (xy 265.870159 -206.015739) (xy 265.840411 -206.060703) (xy 265.804433 -206.100857)
			(xy 265.762991 -206.135345) (xy 265.71697 -206.163431) (xy 265.66735 -206.184518) (xy 265.615189 -206.198154)
			(xy 265.561598 -206.204051) (xy 265.507719 -206.202082) (xy 265.454701 -206.192289) (xy 265.403674 -206.174881)
			(xy 265.355726 -206.150229) (xy 265.311878 -206.118859) (xy 265.273065 -206.081438) (xy 265.240113 -206.038765)
			(xy 265.213727 -205.991748) (xy 265.194467 -205.941391) (xy 265.182744 -205.888767) (xy 265.178809 -205.834996)
			(xy 264.143998 -205.834996) (xy 264.143998 -206.685134) (xy 269.278877 -206.685134) (xy 269.282812 -206.631363)
			(xy 269.294535 -206.578739) (xy 269.313795 -206.528382) (xy 269.340181 -206.481365) (xy 269.373133 -206.438692)
			(xy 269.411946 -206.401271) (xy 269.455794 -206.369901) (xy 269.503742 -206.345249) (xy 269.554769 -206.327841)
			(xy 269.607787 -206.318048) (xy 269.661666 -206.316079) (xy 269.715257 -206.321976) (xy 269.767418 -206.335612)
			(xy 269.817038 -206.356699) (xy 269.863059 -206.384785) (xy 269.904501 -206.419273) (xy 269.940479 -206.459427)
			(xy 269.970227 -206.504391) (xy 269.993112 -206.553208) (xy 270.008644 -206.604837) (xy 270.016494 -206.658177)
			(xy 270.016986 -206.685134) (xy 276.822931 -206.685134) (xy 276.826866 -206.631363) (xy 276.838589 -206.578739)
			(xy 276.857849 -206.528382) (xy 276.884235 -206.481365) (xy 276.917187 -206.438692) (xy 276.956 -206.401271)
			(xy 276.999848 -206.369901) (xy 277.047796 -206.345249) (xy 277.098823 -206.327841) (xy 277.151841 -206.318048)
			(xy 277.20572 -206.316079) (xy 277.259311 -206.321976) (xy 277.311472 -206.335612) (xy 277.361092 -206.356699)
			(xy 277.407113 -206.384785) (xy 277.448555 -206.419273) (xy 277.484533 -206.459427) (xy 277.514281 -206.504391)
			(xy 277.537166 -206.553208) (xy 277.552698 -206.604837) (xy 277.560548 -206.658177) (xy 277.56104 -206.685134)
			(xy 284.366731 -206.685134) (xy 284.370666 -206.631363) (xy 284.382389 -206.578739) (xy 284.401649 -206.528382)
			(xy 284.428035 -206.481365) (xy 284.460987 -206.438692) (xy 284.4998 -206.401271) (xy 284.543648 -206.369901)
			(xy 284.591596 -206.345249) (xy 284.642623 -206.327841) (xy 284.695641 -206.318048) (xy 284.74952 -206.316079)
			(xy 284.803111 -206.321976) (xy 284.855272 -206.335612) (xy 284.904892 -206.356699) (xy 284.950913 -206.384785)
			(xy 284.992355 -206.419273) (xy 285.028333 -206.459427) (xy 285.058081 -206.504391) (xy 285.080966 -206.553208)
			(xy 285.096498 -206.604837) (xy 285.104348 -206.658177) (xy 285.10484 -206.685134) (xy 291.910785 -206.685134)
			(xy 291.91472 -206.631363) (xy 291.926443 -206.578739) (xy 291.945703 -206.528382) (xy 291.972089 -206.481365)
			(xy 292.005041 -206.438692) (xy 292.043854 -206.401271) (xy 292.087702 -206.369901) (xy 292.13565 -206.345249)
			(xy 292.186677 -206.327841) (xy 292.239695 -206.318048) (xy 292.293574 -206.316079) (xy 292.347165 -206.321976)
			(xy 292.399326 -206.335612) (xy 292.448946 -206.356699) (xy 292.494967 -206.384785) (xy 292.536409 -206.419273)
			(xy 292.572387 -206.459427) (xy 292.602135 -206.504391) (xy 292.62502 -206.553208) (xy 292.640552 -206.604837)
			(xy 292.648402 -206.658177) (xy 292.648894 -206.685134) (xy 292.648402 -206.712091) (xy 292.640552 -206.765431)
			(xy 292.62502 -206.81706) (xy 292.602135 -206.865877) (xy 292.572387 -206.910841) (xy 292.536409 -206.950995)
			(xy 292.494967 -206.985483) (xy 292.448946 -207.013569) (xy 292.399326 -207.034656) (xy 292.347165 -207.048292)
			(xy 292.293574 -207.054189) (xy 292.239695 -207.05222) (xy 292.186677 -207.042427) (xy 292.13565 -207.025019)
			(xy 292.087702 -207.000367) (xy 292.043854 -206.968997) (xy 292.005041 -206.931576) (xy 291.972089 -206.888903)
			(xy 291.945703 -206.841886) (xy 291.926443 -206.791529) (xy 291.91472 -206.738905) (xy 291.910785 -206.685134)
			(xy 285.10484 -206.685134) (xy 285.104348 -206.712091) (xy 285.096498 -206.765431) (xy 285.080966 -206.81706)
			(xy 285.058081 -206.865877) (xy 285.028333 -206.910841) (xy 284.992355 -206.950995) (xy 284.950913 -206.985483)
			(xy 284.904892 -207.013569) (xy 284.855272 -207.034656) (xy 284.803111 -207.048292) (xy 284.74952 -207.054189)
			(xy 284.695641 -207.05222) (xy 284.642623 -207.042427) (xy 284.591596 -207.025019) (xy 284.543648 -207.000367)
			(xy 284.4998 -206.968997) (xy 284.460987 -206.931576) (xy 284.428035 -206.888903) (xy 284.401649 -206.841886)
			(xy 284.382389 -206.791529) (xy 284.370666 -206.738905) (xy 284.366731 -206.685134) (xy 277.56104 -206.685134)
			(xy 277.560548 -206.712091) (xy 277.552698 -206.765431) (xy 277.537166 -206.81706) (xy 277.514281 -206.865877)
			(xy 277.484533 -206.910841) (xy 277.448555 -206.950995) (xy 277.407113 -206.985483) (xy 277.361092 -207.013569)
			(xy 277.311472 -207.034656) (xy 277.259311 -207.048292) (xy 277.20572 -207.054189) (xy 277.151841 -207.05222)
			(xy 277.098823 -207.042427) (xy 277.047796 -207.025019) (xy 276.999848 -207.000367) (xy 276.956 -206.968997)
			(xy 276.917187 -206.931576) (xy 276.884235 -206.888903) (xy 276.857849 -206.841886) (xy 276.838589 -206.791529)
			(xy 276.826866 -206.738905) (xy 276.822931 -206.685134) (xy 270.016986 -206.685134) (xy 270.016494 -206.712091)
			(xy 270.008644 -206.765431) (xy 269.993112 -206.81706) (xy 269.970227 -206.865877) (xy 269.940479 -206.910841)
			(xy 269.904501 -206.950995) (xy 269.863059 -206.985483) (xy 269.817038 -207.013569) (xy 269.767418 -207.034656)
			(xy 269.715257 -207.048292) (xy 269.661666 -207.054189) (xy 269.607787 -207.05222) (xy 269.554769 -207.042427)
			(xy 269.503742 -207.025019) (xy 269.455794 -207.000367) (xy 269.411946 -206.968997) (xy 269.373133 -206.931576)
			(xy 269.340181 -206.888903) (xy 269.313795 -206.841886) (xy 269.294535 -206.791529) (xy 269.282812 -206.738905)
			(xy 269.278877 -206.685134) (xy 264.143998 -206.685134) (xy 264.143998 -207.535018) (xy 265.178809 -207.535018)
			(xy 265.182744 -207.481247) (xy 265.194467 -207.428623) (xy 265.213727 -207.378266) (xy 265.240113 -207.331249)
			(xy 265.273065 -207.288576) (xy 265.311878 -207.251155) (xy 265.355726 -207.219785) (xy 265.403674 -207.195133)
			(xy 265.454701 -207.177725) (xy 265.507719 -207.167932) (xy 265.561598 -207.165963) (xy 265.615189 -207.17186)
			(xy 265.66735 -207.185496) (xy 265.71697 -207.206583) (xy 265.762991 -207.234669) (xy 265.804433 -207.269157)
			(xy 265.840411 -207.309311) (xy 265.870159 -207.354275) (xy 265.893044 -207.403092) (xy 265.908576 -207.454721)
			(xy 265.916426 -207.508061) (xy 265.916918 -207.535018) (xy 272.722863 -207.535018) (xy 272.726798 -207.481247)
			(xy 272.738521 -207.428623) (xy 272.757781 -207.378266) (xy 272.784167 -207.331249) (xy 272.817119 -207.288576)
			(xy 272.855932 -207.251155) (xy 272.89978 -207.219785) (xy 272.947728 -207.195133) (xy 272.998755 -207.177725)
			(xy 273.051773 -207.167932) (xy 273.105652 -207.165963) (xy 273.159243 -207.17186) (xy 273.211404 -207.185496)
			(xy 273.261024 -207.206583) (xy 273.307045 -207.234669) (xy 273.348487 -207.269157) (xy 273.384465 -207.309311)
			(xy 273.414213 -207.354275) (xy 273.437098 -207.403092) (xy 273.45263 -207.454721) (xy 273.46048 -207.508061)
			(xy 273.460972 -207.535018) (xy 280.266663 -207.535018) (xy 280.270598 -207.481247) (xy 280.282321 -207.428623)
			(xy 280.301581 -207.378266) (xy 280.327967 -207.331249) (xy 280.360919 -207.288576) (xy 280.399732 -207.251155)
			(xy 280.44358 -207.219785) (xy 280.491528 -207.195133) (xy 280.542555 -207.177725) (xy 280.595573 -207.167932)
			(xy 280.649452 -207.165963) (xy 280.703043 -207.17186) (xy 280.755204 -207.185496) (xy 280.804824 -207.206583)
			(xy 280.850845 -207.234669) (xy 280.892287 -207.269157) (xy 280.928265 -207.309311) (xy 280.958013 -207.354275)
			(xy 280.980898 -207.403092) (xy 280.99643 -207.454721) (xy 281.00428 -207.508061) (xy 281.004772 -207.535018)
			(xy 287.810717 -207.535018) (xy 287.814652 -207.481247) (xy 287.826375 -207.428623) (xy 287.845635 -207.378266)
			(xy 287.872021 -207.331249) (xy 287.904973 -207.288576) (xy 287.943786 -207.251155) (xy 287.987634 -207.219785)
			(xy 288.035582 -207.195133) (xy 288.086609 -207.177725) (xy 288.139627 -207.167932) (xy 288.193506 -207.165963)
			(xy 288.247097 -207.17186) (xy 288.299258 -207.185496) (xy 288.348878 -207.206583) (xy 288.394899 -207.234669)
			(xy 288.436341 -207.269157) (xy 288.472319 -207.309311) (xy 288.502067 -207.354275) (xy 288.524952 -207.403092)
			(xy 288.540484 -207.454721) (xy 288.548334 -207.508061) (xy 288.548826 -207.535018) (xy 288.548334 -207.561975)
			(xy 288.540484 -207.615315) (xy 288.524952 -207.666944) (xy 288.502067 -207.715761) (xy 288.472319 -207.760725)
			(xy 288.436341 -207.800879) (xy 288.394899 -207.835367) (xy 288.348878 -207.863453) (xy 288.299258 -207.88454)
			(xy 288.247097 -207.898176) (xy 288.193506 -207.904073) (xy 288.139627 -207.902104) (xy 288.086609 -207.892311)
			(xy 288.035582 -207.874903) (xy 287.987634 -207.850251) (xy 287.943786 -207.818881) (xy 287.904973 -207.78146)
			(xy 287.872021 -207.738787) (xy 287.845635 -207.69177) (xy 287.826375 -207.641413) (xy 287.814652 -207.588789)
			(xy 287.810717 -207.535018) (xy 281.004772 -207.535018) (xy 281.00428 -207.561975) (xy 280.99643 -207.615315)
			(xy 280.980898 -207.666944) (xy 280.958013 -207.715761) (xy 280.928265 -207.760725) (xy 280.892287 -207.800879)
			(xy 280.850845 -207.835367) (xy 280.804824 -207.863453) (xy 280.755204 -207.88454) (xy 280.703043 -207.898176)
			(xy 280.649452 -207.904073) (xy 280.595573 -207.902104) (xy 280.542555 -207.892311) (xy 280.491528 -207.874903)
			(xy 280.44358 -207.850251) (xy 280.399732 -207.818881) (xy 280.360919 -207.78146) (xy 280.327967 -207.738787)
			(xy 280.301581 -207.69177) (xy 280.282321 -207.641413) (xy 280.270598 -207.588789) (xy 280.266663 -207.535018)
			(xy 273.460972 -207.535018) (xy 273.46048 -207.561975) (xy 273.45263 -207.615315) (xy 273.437098 -207.666944)
			(xy 273.414213 -207.715761) (xy 273.384465 -207.760725) (xy 273.348487 -207.800879) (xy 273.307045 -207.835367)
			(xy 273.261024 -207.863453) (xy 273.211404 -207.88454) (xy 273.159243 -207.898176) (xy 273.105652 -207.904073)
			(xy 273.051773 -207.902104) (xy 272.998755 -207.892311) (xy 272.947728 -207.874903) (xy 272.89978 -207.850251)
			(xy 272.855932 -207.818881) (xy 272.817119 -207.78146) (xy 272.784167 -207.738787) (xy 272.757781 -207.69177)
			(xy 272.738521 -207.641413) (xy 272.726798 -207.588789) (xy 272.722863 -207.535018) (xy 265.916918 -207.535018)
			(xy 265.916426 -207.561975) (xy 265.908576 -207.615315) (xy 265.893044 -207.666944) (xy 265.870159 -207.715761)
			(xy 265.840411 -207.760725) (xy 265.804433 -207.800879) (xy 265.762991 -207.835367) (xy 265.71697 -207.863453)
			(xy 265.66735 -207.88454) (xy 265.615189 -207.898176) (xy 265.561598 -207.904073) (xy 265.507719 -207.902104)
			(xy 265.454701 -207.892311) (xy 265.403674 -207.874903) (xy 265.355726 -207.850251) (xy 265.311878 -207.818881)
			(xy 265.273065 -207.78146) (xy 265.240113 -207.738787) (xy 265.213727 -207.69177) (xy 265.194467 -207.641413)
			(xy 265.182744 -207.588789) (xy 265.178809 -207.535018) (xy 264.143998 -207.535018) (xy 264.143998 -208.385156)
			(xy 269.278877 -208.385156) (xy 269.282812 -208.331385) (xy 269.294535 -208.278761) (xy 269.313795 -208.228404)
			(xy 269.340181 -208.181387) (xy 269.373133 -208.138714) (xy 269.411946 -208.101293) (xy 269.455794 -208.069923)
			(xy 269.503742 -208.045271) (xy 269.554769 -208.027863) (xy 269.607787 -208.01807) (xy 269.661666 -208.016101)
			(xy 269.715257 -208.021998) (xy 269.767418 -208.035634) (xy 269.817038 -208.056721) (xy 269.863059 -208.084807)
			(xy 269.904501 -208.119295) (xy 269.940479 -208.159449) (xy 269.970227 -208.204413) (xy 269.993112 -208.25323)
			(xy 270.008644 -208.304859) (xy 270.016494 -208.358199) (xy 270.016986 -208.385156) (xy 276.822931 -208.385156)
			(xy 276.826866 -208.331385) (xy 276.838589 -208.278761) (xy 276.857849 -208.228404) (xy 276.884235 -208.181387)
			(xy 276.917187 -208.138714) (xy 276.956 -208.101293) (xy 276.999848 -208.069923) (xy 277.047796 -208.045271)
			(xy 277.098823 -208.027863) (xy 277.151841 -208.01807) (xy 277.20572 -208.016101) (xy 277.259311 -208.021998)
			(xy 277.311472 -208.035634) (xy 277.361092 -208.056721) (xy 277.407113 -208.084807) (xy 277.448555 -208.119295)
			(xy 277.484533 -208.159449) (xy 277.514281 -208.204413) (xy 277.537166 -208.25323) (xy 277.552698 -208.304859)
			(xy 277.560548 -208.358199) (xy 277.56104 -208.385156) (xy 284.366731 -208.385156) (xy 284.370666 -208.331385)
			(xy 284.382389 -208.278761) (xy 284.401649 -208.228404) (xy 284.428035 -208.181387) (xy 284.460987 -208.138714)
			(xy 284.4998 -208.101293) (xy 284.543648 -208.069923) (xy 284.591596 -208.045271) (xy 284.642623 -208.027863)
			(xy 284.695641 -208.01807) (xy 284.74952 -208.016101) (xy 284.803111 -208.021998) (xy 284.855272 -208.035634)
			(xy 284.904892 -208.056721) (xy 284.950913 -208.084807) (xy 284.992355 -208.119295) (xy 285.028333 -208.159449)
			(xy 285.058081 -208.204413) (xy 285.080966 -208.25323) (xy 285.096498 -208.304859) (xy 285.104348 -208.358199)
			(xy 285.10484 -208.385156) (xy 291.910785 -208.385156) (xy 291.91472 -208.331385) (xy 291.926443 -208.278761)
			(xy 291.945703 -208.228404) (xy 291.972089 -208.181387) (xy 292.005041 -208.138714) (xy 292.043854 -208.101293)
			(xy 292.087702 -208.069923) (xy 292.13565 -208.045271) (xy 292.186677 -208.027863) (xy 292.239695 -208.01807)
			(xy 292.293574 -208.016101) (xy 292.347165 -208.021998) (xy 292.399326 -208.035634) (xy 292.448946 -208.056721)
			(xy 292.494967 -208.084807) (xy 292.536409 -208.119295) (xy 292.572387 -208.159449) (xy 292.602135 -208.204413)
			(xy 292.62502 -208.25323) (xy 292.640552 -208.304859) (xy 292.648402 -208.358199) (xy 292.648894 -208.385156)
			(xy 292.648402 -208.412113) (xy 292.640552 -208.465453) (xy 292.62502 -208.517082) (xy 292.602135 -208.565899)
			(xy 292.572387 -208.610863) (xy 292.536409 -208.651017) (xy 292.494967 -208.685505) (xy 292.448946 -208.713591)
			(xy 292.399326 -208.734678) (xy 292.347165 -208.748314) (xy 292.293574 -208.754211) (xy 292.239695 -208.752242)
			(xy 292.186677 -208.742449) (xy 292.13565 -208.725041) (xy 292.087702 -208.700389) (xy 292.043854 -208.669019)
			(xy 292.005041 -208.631598) (xy 291.972089 -208.588925) (xy 291.945703 -208.541908) (xy 291.926443 -208.491551)
			(xy 291.91472 -208.438927) (xy 291.910785 -208.385156) (xy 285.10484 -208.385156) (xy 285.104348 -208.412113)
			(xy 285.096498 -208.465453) (xy 285.080966 -208.517082) (xy 285.058081 -208.565899) (xy 285.028333 -208.610863)
			(xy 284.992355 -208.651017) (xy 284.950913 -208.685505) (xy 284.904892 -208.713591) (xy 284.855272 -208.734678)
			(xy 284.803111 -208.748314) (xy 284.74952 -208.754211) (xy 284.695641 -208.752242) (xy 284.642623 -208.742449)
			(xy 284.591596 -208.725041) (xy 284.543648 -208.700389) (xy 284.4998 -208.669019) (xy 284.460987 -208.631598)
			(xy 284.428035 -208.588925) (xy 284.401649 -208.541908) (xy 284.382389 -208.491551) (xy 284.370666 -208.438927)
			(xy 284.366731 -208.385156) (xy 277.56104 -208.385156) (xy 277.560548 -208.412113) (xy 277.552698 -208.465453)
			(xy 277.537166 -208.517082) (xy 277.514281 -208.565899) (xy 277.484533 -208.610863) (xy 277.448555 -208.651017)
			(xy 277.407113 -208.685505) (xy 277.361092 -208.713591) (xy 277.311472 -208.734678) (xy 277.259311 -208.748314)
			(xy 277.20572 -208.754211) (xy 277.151841 -208.752242) (xy 277.098823 -208.742449) (xy 277.047796 -208.725041)
			(xy 276.999848 -208.700389) (xy 276.956 -208.669019) (xy 276.917187 -208.631598) (xy 276.884235 -208.588925)
			(xy 276.857849 -208.541908) (xy 276.838589 -208.491551) (xy 276.826866 -208.438927) (xy 276.822931 -208.385156)
			(xy 270.016986 -208.385156) (xy 270.016494 -208.412113) (xy 270.008644 -208.465453) (xy 269.993112 -208.517082)
			(xy 269.970227 -208.565899) (xy 269.940479 -208.610863) (xy 269.904501 -208.651017) (xy 269.863059 -208.685505)
			(xy 269.817038 -208.713591) (xy 269.767418 -208.734678) (xy 269.715257 -208.748314) (xy 269.661666 -208.754211)
			(xy 269.607787 -208.752242) (xy 269.554769 -208.742449) (xy 269.503742 -208.725041) (xy 269.455794 -208.700389)
			(xy 269.411946 -208.669019) (xy 269.373133 -208.631598) (xy 269.340181 -208.588925) (xy 269.313795 -208.541908)
			(xy 269.294535 -208.491551) (xy 269.282812 -208.438927) (xy 269.278877 -208.385156) (xy 264.143998 -208.385156)
			(xy 264.143998 -209.23504) (xy 265.178809 -209.23504) (xy 265.182744 -209.181269) (xy 265.194467 -209.128645)
			(xy 265.213727 -209.078288) (xy 265.240113 -209.031271) (xy 265.273065 -208.988598) (xy 265.311878 -208.951177)
			(xy 265.355726 -208.919807) (xy 265.403674 -208.895155) (xy 265.454701 -208.877747) (xy 265.507719 -208.867954)
			(xy 265.561598 -208.865985) (xy 265.615189 -208.871882) (xy 265.66735 -208.885518) (xy 265.71697 -208.906605)
			(xy 265.762991 -208.934691) (xy 265.804433 -208.969179) (xy 265.840411 -209.009333) (xy 265.870159 -209.054297)
			(xy 265.893044 -209.103114) (xy 265.908576 -209.154743) (xy 265.916426 -209.208083) (xy 265.916918 -209.23504)
			(xy 272.722863 -209.23504) (xy 272.726798 -209.181269) (xy 272.738521 -209.128645) (xy 272.757781 -209.078288)
			(xy 272.784167 -209.031271) (xy 272.817119 -208.988598) (xy 272.855932 -208.951177) (xy 272.89978 -208.919807)
			(xy 272.947728 -208.895155) (xy 272.998755 -208.877747) (xy 273.051773 -208.867954) (xy 273.105652 -208.865985)
			(xy 273.159243 -208.871882) (xy 273.211404 -208.885518) (xy 273.261024 -208.906605) (xy 273.307045 -208.934691)
			(xy 273.348487 -208.969179) (xy 273.384465 -209.009333) (xy 273.414213 -209.054297) (xy 273.437098 -209.103114)
			(xy 273.45263 -209.154743) (xy 273.46048 -209.208083) (xy 273.460972 -209.23504) (xy 280.266663 -209.23504)
			(xy 280.270598 -209.181269) (xy 280.282321 -209.128645) (xy 280.301581 -209.078288) (xy 280.327967 -209.031271)
			(xy 280.360919 -208.988598) (xy 280.399732 -208.951177) (xy 280.44358 -208.919807) (xy 280.491528 -208.895155)
			(xy 280.542555 -208.877747) (xy 280.595573 -208.867954) (xy 280.649452 -208.865985) (xy 280.703043 -208.871882)
			(xy 280.755204 -208.885518) (xy 280.804824 -208.906605) (xy 280.850845 -208.934691) (xy 280.892287 -208.969179)
			(xy 280.928265 -209.009333) (xy 280.958013 -209.054297) (xy 280.980898 -209.103114) (xy 280.99643 -209.154743)
			(xy 281.00428 -209.208083) (xy 281.004772 -209.23504) (xy 287.810717 -209.23504) (xy 287.814652 -209.181269)
			(xy 287.826375 -209.128645) (xy 287.845635 -209.078288) (xy 287.872021 -209.031271) (xy 287.904973 -208.988598)
			(xy 287.943786 -208.951177) (xy 287.987634 -208.919807) (xy 288.035582 -208.895155) (xy 288.086609 -208.877747)
			(xy 288.139627 -208.867954) (xy 288.193506 -208.865985) (xy 288.247097 -208.871882) (xy 288.299258 -208.885518)
			(xy 288.348878 -208.906605) (xy 288.394899 -208.934691) (xy 288.436341 -208.969179) (xy 288.472319 -209.009333)
			(xy 288.502067 -209.054297) (xy 288.524952 -209.103114) (xy 288.540484 -209.154743) (xy 288.548334 -209.208083)
			(xy 288.548826 -209.23504) (xy 288.548334 -209.261997) (xy 288.540484 -209.315337) (xy 288.524952 -209.366966)
			(xy 288.502067 -209.415783) (xy 288.472319 -209.460747) (xy 288.436341 -209.500901) (xy 288.394899 -209.535389)
			(xy 288.348878 -209.563475) (xy 288.299258 -209.584562) (xy 288.247097 -209.598198) (xy 288.193506 -209.604095)
			(xy 288.139627 -209.602126) (xy 288.086609 -209.592333) (xy 288.035582 -209.574925) (xy 287.987634 -209.550273)
			(xy 287.943786 -209.518903) (xy 287.904973 -209.481482) (xy 287.872021 -209.438809) (xy 287.845635 -209.391792)
			(xy 287.826375 -209.341435) (xy 287.814652 -209.288811) (xy 287.810717 -209.23504) (xy 281.004772 -209.23504)
			(xy 281.00428 -209.261997) (xy 280.99643 -209.315337) (xy 280.980898 -209.366966) (xy 280.958013 -209.415783)
			(xy 280.928265 -209.460747) (xy 280.892287 -209.500901) (xy 280.850845 -209.535389) (xy 280.804824 -209.563475)
			(xy 280.755204 -209.584562) (xy 280.703043 -209.598198) (xy 280.649452 -209.604095) (xy 280.595573 -209.602126)
			(xy 280.542555 -209.592333) (xy 280.491528 -209.574925) (xy 280.44358 -209.550273) (xy 280.399732 -209.518903)
			(xy 280.360919 -209.481482) (xy 280.327967 -209.438809) (xy 280.301581 -209.391792) (xy 280.282321 -209.341435)
			(xy 280.270598 -209.288811) (xy 280.266663 -209.23504) (xy 273.460972 -209.23504) (xy 273.46048 -209.261997)
			(xy 273.45263 -209.315337) (xy 273.437098 -209.366966) (xy 273.414213 -209.415783) (xy 273.384465 -209.460747)
			(xy 273.348487 -209.500901) (xy 273.307045 -209.535389) (xy 273.261024 -209.563475) (xy 273.211404 -209.584562)
			(xy 273.159243 -209.598198) (xy 273.105652 -209.604095) (xy 273.051773 -209.602126) (xy 272.998755 -209.592333)
			(xy 272.947728 -209.574925) (xy 272.89978 -209.550273) (xy 272.855932 -209.518903) (xy 272.817119 -209.481482)
			(xy 272.784167 -209.438809) (xy 272.757781 -209.391792) (xy 272.738521 -209.341435) (xy 272.726798 -209.288811)
			(xy 272.722863 -209.23504) (xy 265.916918 -209.23504) (xy 265.916426 -209.261997) (xy 265.908576 -209.315337)
			(xy 265.893044 -209.366966) (xy 265.870159 -209.415783) (xy 265.840411 -209.460747) (xy 265.804433 -209.500901)
			(xy 265.762991 -209.535389) (xy 265.71697 -209.563475) (xy 265.66735 -209.584562) (xy 265.615189 -209.598198)
			(xy 265.561598 -209.604095) (xy 265.507719 -209.602126) (xy 265.454701 -209.592333) (xy 265.403674 -209.574925)
			(xy 265.355726 -209.550273) (xy 265.311878 -209.518903) (xy 265.273065 -209.481482) (xy 265.240113 -209.438809)
			(xy 265.213727 -209.391792) (xy 265.194467 -209.341435) (xy 265.182744 -209.288811) (xy 265.178809 -209.23504)
			(xy 264.143998 -209.23504) (xy 264.143998 -210.085178) (xy 269.278877 -210.085178) (xy 269.282812 -210.031407)
			(xy 269.294535 -209.978783) (xy 269.313795 -209.928426) (xy 269.340181 -209.881409) (xy 269.373133 -209.838736)
			(xy 269.411946 -209.801315) (xy 269.455794 -209.769945) (xy 269.503742 -209.745293) (xy 269.554769 -209.727885)
			(xy 269.607787 -209.718092) (xy 269.661666 -209.716123) (xy 269.715257 -209.72202) (xy 269.767418 -209.735656)
			(xy 269.817038 -209.756743) (xy 269.863059 -209.784829) (xy 269.904501 -209.819317) (xy 269.940479 -209.859471)
			(xy 269.970227 -209.904435) (xy 269.993112 -209.953252) (xy 270.008644 -210.004881) (xy 270.016494 -210.058221)
			(xy 270.016986 -210.085178) (xy 276.822931 -210.085178) (xy 276.826866 -210.031407) (xy 276.838589 -209.978783)
			(xy 276.857849 -209.928426) (xy 276.884235 -209.881409) (xy 276.917187 -209.838736) (xy 276.956 -209.801315)
			(xy 276.999848 -209.769945) (xy 277.047796 -209.745293) (xy 277.098823 -209.727885) (xy 277.151841 -209.718092)
			(xy 277.20572 -209.716123) (xy 277.259311 -209.72202) (xy 277.311472 -209.735656) (xy 277.361092 -209.756743)
			(xy 277.407113 -209.784829) (xy 277.448555 -209.819317) (xy 277.484533 -209.859471) (xy 277.514281 -209.904435)
			(xy 277.537166 -209.953252) (xy 277.552698 -210.004881) (xy 277.560548 -210.058221) (xy 277.56104 -210.085178)
			(xy 284.366731 -210.085178) (xy 284.370666 -210.031407) (xy 284.382389 -209.978783) (xy 284.401649 -209.928426)
			(xy 284.428035 -209.881409) (xy 284.460987 -209.838736) (xy 284.4998 -209.801315) (xy 284.543648 -209.769945)
			(xy 284.591596 -209.745293) (xy 284.642623 -209.727885) (xy 284.695641 -209.718092) (xy 284.74952 -209.716123)
			(xy 284.803111 -209.72202) (xy 284.855272 -209.735656) (xy 284.904892 -209.756743) (xy 284.950913 -209.784829)
			(xy 284.992355 -209.819317) (xy 285.028333 -209.859471) (xy 285.058081 -209.904435) (xy 285.080966 -209.953252)
			(xy 285.096498 -210.004881) (xy 285.104348 -210.058221) (xy 285.10484 -210.085178) (xy 291.910785 -210.085178)
			(xy 291.91472 -210.031407) (xy 291.926443 -209.978783) (xy 291.945703 -209.928426) (xy 291.972089 -209.881409)
			(xy 292.005041 -209.838736) (xy 292.043854 -209.801315) (xy 292.087702 -209.769945) (xy 292.13565 -209.745293)
			(xy 292.186677 -209.727885) (xy 292.239695 -209.718092) (xy 292.293574 -209.716123) (xy 292.347165 -209.72202)
			(xy 292.399326 -209.735656) (xy 292.448946 -209.756743) (xy 292.494967 -209.784829) (xy 292.536409 -209.819317)
			(xy 292.572387 -209.859471) (xy 292.602135 -209.904435) (xy 292.62502 -209.953252) (xy 292.640552 -210.004881)
			(xy 292.648402 -210.058221) (xy 292.648894 -210.085178) (xy 292.648402 -210.112135) (xy 292.640552 -210.165475)
			(xy 292.62502 -210.217104) (xy 292.602135 -210.265921) (xy 292.572387 -210.310885) (xy 292.536409 -210.351039)
			(xy 292.494967 -210.385527) (xy 292.448946 -210.413613) (xy 292.399326 -210.4347) (xy 292.347165 -210.448336)
			(xy 292.293574 -210.454233) (xy 292.239695 -210.452264) (xy 292.186677 -210.442471) (xy 292.13565 -210.425063)
			(xy 292.087702 -210.400411) (xy 292.043854 -210.369041) (xy 292.005041 -210.33162) (xy 291.972089 -210.288947)
			(xy 291.945703 -210.24193) (xy 291.926443 -210.191573) (xy 291.91472 -210.138949) (xy 291.910785 -210.085178)
			(xy 285.10484 -210.085178) (xy 285.104348 -210.112135) (xy 285.096498 -210.165475) (xy 285.080966 -210.217104)
			(xy 285.058081 -210.265921) (xy 285.028333 -210.310885) (xy 284.992355 -210.351039) (xy 284.950913 -210.385527)
			(xy 284.904892 -210.413613) (xy 284.855272 -210.4347) (xy 284.803111 -210.448336) (xy 284.74952 -210.454233)
			(xy 284.695641 -210.452264) (xy 284.642623 -210.442471) (xy 284.591596 -210.425063) (xy 284.543648 -210.400411)
			(xy 284.4998 -210.369041) (xy 284.460987 -210.33162) (xy 284.428035 -210.288947) (xy 284.401649 -210.24193)
			(xy 284.382389 -210.191573) (xy 284.370666 -210.138949) (xy 284.366731 -210.085178) (xy 277.56104 -210.085178)
			(xy 277.560548 -210.112135) (xy 277.552698 -210.165475) (xy 277.537166 -210.217104) (xy 277.514281 -210.265921)
			(xy 277.484533 -210.310885) (xy 277.448555 -210.351039) (xy 277.407113 -210.385527) (xy 277.361092 -210.413613)
			(xy 277.311472 -210.4347) (xy 277.259311 -210.448336) (xy 277.20572 -210.454233) (xy 277.151841 -210.452264)
			(xy 277.098823 -210.442471) (xy 277.047796 -210.425063) (xy 276.999848 -210.400411) (xy 276.956 -210.369041)
			(xy 276.917187 -210.33162) (xy 276.884235 -210.288947) (xy 276.857849 -210.24193) (xy 276.838589 -210.191573)
			(xy 276.826866 -210.138949) (xy 276.822931 -210.085178) (xy 270.016986 -210.085178) (xy 270.016494 -210.112135)
			(xy 270.008644 -210.165475) (xy 269.993112 -210.217104) (xy 269.970227 -210.265921) (xy 269.940479 -210.310885)
			(xy 269.904501 -210.351039) (xy 269.863059 -210.385527) (xy 269.817038 -210.413613) (xy 269.767418 -210.4347)
			(xy 269.715257 -210.448336) (xy 269.661666 -210.454233) (xy 269.607787 -210.452264) (xy 269.554769 -210.442471)
			(xy 269.503742 -210.425063) (xy 269.455794 -210.400411) (xy 269.411946 -210.369041) (xy 269.373133 -210.33162)
			(xy 269.340181 -210.288947) (xy 269.313795 -210.24193) (xy 269.294535 -210.191573) (xy 269.282812 -210.138949)
			(xy 269.278877 -210.085178) (xy 264.143998 -210.085178) (xy 264.143998 -210.935062) (xy 265.178809 -210.935062)
			(xy 265.182744 -210.881291) (xy 265.194467 -210.828667) (xy 265.213727 -210.77831) (xy 265.240113 -210.731293)
			(xy 265.273065 -210.68862) (xy 265.311878 -210.651199) (xy 265.355726 -210.619829) (xy 265.403674 -210.595177)
			(xy 265.454701 -210.577769) (xy 265.507719 -210.567976) (xy 265.561598 -210.566007) (xy 265.615189 -210.571904)
			(xy 265.66735 -210.58554) (xy 265.71697 -210.606627) (xy 265.762991 -210.634713) (xy 265.804433 -210.669201)
			(xy 265.840411 -210.709355) (xy 265.870159 -210.754319) (xy 265.893044 -210.803136) (xy 265.908576 -210.854765)
			(xy 265.916426 -210.908105) (xy 265.916918 -210.935062) (xy 269.278877 -210.935062) (xy 269.282812 -210.881291)
			(xy 269.294535 -210.828667) (xy 269.313795 -210.77831) (xy 269.340181 -210.731293) (xy 269.373133 -210.68862)
			(xy 269.411946 -210.651199) (xy 269.455794 -210.619829) (xy 269.503742 -210.595177) (xy 269.554769 -210.577769)
			(xy 269.607787 -210.567976) (xy 269.661666 -210.566007) (xy 269.715257 -210.571904) (xy 269.767418 -210.58554)
			(xy 269.817038 -210.606627) (xy 269.863059 -210.634713) (xy 269.904501 -210.669201) (xy 269.940479 -210.709355)
			(xy 269.970227 -210.754319) (xy 269.993112 -210.803136) (xy 270.008644 -210.854765) (xy 270.016494 -210.908105)
			(xy 270.016986 -210.935062) (xy 272.722863 -210.935062) (xy 272.726798 -210.881291) (xy 272.738521 -210.828667)
			(xy 272.757781 -210.77831) (xy 272.784167 -210.731293) (xy 272.817119 -210.68862) (xy 272.855932 -210.651199)
			(xy 272.89978 -210.619829) (xy 272.947728 -210.595177) (xy 272.998755 -210.577769) (xy 273.051773 -210.567976)
			(xy 273.105652 -210.566007) (xy 273.159243 -210.571904) (xy 273.211404 -210.58554) (xy 273.261024 -210.606627)
			(xy 273.307045 -210.634713) (xy 273.348487 -210.669201) (xy 273.384465 -210.709355) (xy 273.414213 -210.754319)
			(xy 273.437098 -210.803136) (xy 273.45263 -210.854765) (xy 273.46048 -210.908105) (xy 273.460972 -210.935062)
			(xy 276.822931 -210.935062) (xy 276.826866 -210.881291) (xy 276.838589 -210.828667) (xy 276.857849 -210.77831)
			(xy 276.884235 -210.731293) (xy 276.917187 -210.68862) (xy 276.956 -210.651199) (xy 276.999848 -210.619829)
			(xy 277.047796 -210.595177) (xy 277.098823 -210.577769) (xy 277.151841 -210.567976) (xy 277.20572 -210.566007)
			(xy 277.259311 -210.571904) (xy 277.311472 -210.58554) (xy 277.361092 -210.606627) (xy 277.407113 -210.634713)
			(xy 277.448555 -210.669201) (xy 277.484533 -210.709355) (xy 277.514281 -210.754319) (xy 277.537166 -210.803136)
			(xy 277.552698 -210.854765) (xy 277.560548 -210.908105) (xy 277.56104 -210.935062) (xy 280.266663 -210.935062)
			(xy 280.270598 -210.881291) (xy 280.282321 -210.828667) (xy 280.301581 -210.77831) (xy 280.327967 -210.731293)
			(xy 280.360919 -210.68862) (xy 280.399732 -210.651199) (xy 280.44358 -210.619829) (xy 280.491528 -210.595177)
			(xy 280.542555 -210.577769) (xy 280.595573 -210.567976) (xy 280.649452 -210.566007) (xy 280.703043 -210.571904)
			(xy 280.755204 -210.58554) (xy 280.804824 -210.606627) (xy 280.850845 -210.634713) (xy 280.892287 -210.669201)
			(xy 280.928265 -210.709355) (xy 280.958013 -210.754319) (xy 280.980898 -210.803136) (xy 280.99643 -210.854765)
			(xy 281.00428 -210.908105) (xy 281.004772 -210.935062) (xy 284.366731 -210.935062) (xy 284.370666 -210.881291)
			(xy 284.382389 -210.828667) (xy 284.401649 -210.77831) (xy 284.428035 -210.731293) (xy 284.460987 -210.68862)
			(xy 284.4998 -210.651199) (xy 284.543648 -210.619829) (xy 284.591596 -210.595177) (xy 284.642623 -210.577769)
			(xy 284.695641 -210.567976) (xy 284.74952 -210.566007) (xy 284.803111 -210.571904) (xy 284.855272 -210.58554)
			(xy 284.904892 -210.606627) (xy 284.950913 -210.634713) (xy 284.992355 -210.669201) (xy 285.028333 -210.709355)
			(xy 285.058081 -210.754319) (xy 285.080966 -210.803136) (xy 285.096498 -210.854765) (xy 285.104348 -210.908105)
			(xy 285.10484 -210.935062) (xy 287.810717 -210.935062) (xy 287.814652 -210.881291) (xy 287.826375 -210.828667)
			(xy 287.845635 -210.77831) (xy 287.872021 -210.731293) (xy 287.904973 -210.68862) (xy 287.943786 -210.651199)
			(xy 287.987634 -210.619829) (xy 288.035582 -210.595177) (xy 288.086609 -210.577769) (xy 288.139627 -210.567976)
			(xy 288.193506 -210.566007) (xy 288.247097 -210.571904) (xy 288.299258 -210.58554) (xy 288.348878 -210.606627)
			(xy 288.394899 -210.634713) (xy 288.436341 -210.669201) (xy 288.472319 -210.709355) (xy 288.502067 -210.754319)
			(xy 288.524952 -210.803136) (xy 288.540484 -210.854765) (xy 288.548334 -210.908105) (xy 288.548826 -210.935062)
			(xy 291.910785 -210.935062) (xy 291.91472 -210.881291) (xy 291.926443 -210.828667) (xy 291.945703 -210.77831)
			(xy 291.972089 -210.731293) (xy 292.005041 -210.68862) (xy 292.043854 -210.651199) (xy 292.087702 -210.619829)
			(xy 292.13565 -210.595177) (xy 292.186677 -210.577769) (xy 292.239695 -210.567976) (xy 292.293574 -210.566007)
			(xy 292.347165 -210.571904) (xy 292.399326 -210.58554) (xy 292.448946 -210.606627) (xy 292.494967 -210.634713)
			(xy 292.536409 -210.669201) (xy 292.572387 -210.709355) (xy 292.602135 -210.754319) (xy 292.62502 -210.803136)
			(xy 292.640552 -210.854765) (xy 292.648402 -210.908105) (xy 292.648894 -210.935062) (xy 292.648402 -210.962019)
			(xy 292.640552 -211.015359) (xy 292.62502 -211.066988) (xy 292.602135 -211.115805) (xy 292.572387 -211.160769)
			(xy 292.536409 -211.200923) (xy 292.494967 -211.235411) (xy 292.448946 -211.263497) (xy 292.399326 -211.284584)
			(xy 292.347165 -211.29822) (xy 292.293574 -211.304117) (xy 292.239695 -211.302148) (xy 292.186677 -211.292355)
			(xy 292.13565 -211.274947) (xy 292.087702 -211.250295) (xy 292.043854 -211.218925) (xy 292.005041 -211.181504)
			(xy 291.972089 -211.138831) (xy 291.945703 -211.091814) (xy 291.926443 -211.041457) (xy 291.91472 -210.988833)
			(xy 291.910785 -210.935062) (xy 288.548826 -210.935062) (xy 288.548334 -210.962019) (xy 288.540484 -211.015359)
			(xy 288.524952 -211.066988) (xy 288.502067 -211.115805) (xy 288.472319 -211.160769) (xy 288.436341 -211.200923)
			(xy 288.394899 -211.235411) (xy 288.348878 -211.263497) (xy 288.299258 -211.284584) (xy 288.247097 -211.29822)
			(xy 288.193506 -211.304117) (xy 288.139627 -211.302148) (xy 288.086609 -211.292355) (xy 288.035582 -211.274947)
			(xy 287.987634 -211.250295) (xy 287.943786 -211.218925) (xy 287.904973 -211.181504) (xy 287.872021 -211.138831)
			(xy 287.845635 -211.091814) (xy 287.826375 -211.041457) (xy 287.814652 -210.988833) (xy 287.810717 -210.935062)
			(xy 285.10484 -210.935062) (xy 285.104348 -210.962019) (xy 285.096498 -211.015359) (xy 285.080966 -211.066988)
			(xy 285.058081 -211.115805) (xy 285.028333 -211.160769) (xy 284.992355 -211.200923) (xy 284.950913 -211.235411)
			(xy 284.904892 -211.263497) (xy 284.855272 -211.284584) (xy 284.803111 -211.29822) (xy 284.74952 -211.304117)
			(xy 284.695641 -211.302148) (xy 284.642623 -211.292355) (xy 284.591596 -211.274947) (xy 284.543648 -211.250295)
			(xy 284.4998 -211.218925) (xy 284.460987 -211.181504) (xy 284.428035 -211.138831) (xy 284.401649 -211.091814)
			(xy 284.382389 -211.041457) (xy 284.370666 -210.988833) (xy 284.366731 -210.935062) (xy 281.004772 -210.935062)
			(xy 281.00428 -210.962019) (xy 280.99643 -211.015359) (xy 280.980898 -211.066988) (xy 280.958013 -211.115805)
			(xy 280.928265 -211.160769) (xy 280.892287 -211.200923) (xy 280.850845 -211.235411) (xy 280.804824 -211.263497)
			(xy 280.755204 -211.284584) (xy 280.703043 -211.29822) (xy 280.649452 -211.304117) (xy 280.595573 -211.302148)
			(xy 280.542555 -211.292355) (xy 280.491528 -211.274947) (xy 280.44358 -211.250295) (xy 280.399732 -211.218925)
			(xy 280.360919 -211.181504) (xy 280.327967 -211.138831) (xy 280.301581 -211.091814) (xy 280.282321 -211.041457)
			(xy 280.270598 -210.988833) (xy 280.266663 -210.935062) (xy 277.56104 -210.935062) (xy 277.560548 -210.962019)
			(xy 277.552698 -211.015359) (xy 277.537166 -211.066988) (xy 277.514281 -211.115805) (xy 277.484533 -211.160769)
			(xy 277.448555 -211.200923) (xy 277.407113 -211.235411) (xy 277.361092 -211.263497) (xy 277.311472 -211.284584)
			(xy 277.259311 -211.29822) (xy 277.20572 -211.304117) (xy 277.151841 -211.302148) (xy 277.098823 -211.292355)
			(xy 277.047796 -211.274947) (xy 276.999848 -211.250295) (xy 276.956 -211.218925) (xy 276.917187 -211.181504)
			(xy 276.884235 -211.138831) (xy 276.857849 -211.091814) (xy 276.838589 -211.041457) (xy 276.826866 -210.988833)
			(xy 276.822931 -210.935062) (xy 273.460972 -210.935062) (xy 273.46048 -210.962019) (xy 273.45263 -211.015359)
			(xy 273.437098 -211.066988) (xy 273.414213 -211.115805) (xy 273.384465 -211.160769) (xy 273.348487 -211.200923)
			(xy 273.307045 -211.235411) (xy 273.261024 -211.263497) (xy 273.211404 -211.284584) (xy 273.159243 -211.29822)
			(xy 273.105652 -211.304117) (xy 273.051773 -211.302148) (xy 272.998755 -211.292355) (xy 272.947728 -211.274947)
			(xy 272.89978 -211.250295) (xy 272.855932 -211.218925) (xy 272.817119 -211.181504) (xy 272.784167 -211.138831)
			(xy 272.757781 -211.091814) (xy 272.738521 -211.041457) (xy 272.726798 -210.988833) (xy 272.722863 -210.935062)
			(xy 270.016986 -210.935062) (xy 270.016494 -210.962019) (xy 270.008644 -211.015359) (xy 269.993112 -211.066988)
			(xy 269.970227 -211.115805) (xy 269.940479 -211.160769) (xy 269.904501 -211.200923) (xy 269.863059 -211.235411)
			(xy 269.817038 -211.263497) (xy 269.767418 -211.284584) (xy 269.715257 -211.29822) (xy 269.661666 -211.304117)
			(xy 269.607787 -211.302148) (xy 269.554769 -211.292355) (xy 269.503742 -211.274947) (xy 269.455794 -211.250295)
			(xy 269.411946 -211.218925) (xy 269.373133 -211.181504) (xy 269.340181 -211.138831) (xy 269.313795 -211.091814)
			(xy 269.294535 -211.041457) (xy 269.282812 -210.988833) (xy 269.278877 -210.935062) (xy 265.916918 -210.935062)
			(xy 265.916426 -210.962019) (xy 265.908576 -211.015359) (xy 265.893044 -211.066988) (xy 265.870159 -211.115805)
			(xy 265.840411 -211.160769) (xy 265.804433 -211.200923) (xy 265.762991 -211.235411) (xy 265.71697 -211.263497)
			(xy 265.66735 -211.284584) (xy 265.615189 -211.29822) (xy 265.561598 -211.304117) (xy 265.507719 -211.302148)
			(xy 265.454701 -211.292355) (xy 265.403674 -211.274947) (xy 265.355726 -211.250295) (xy 265.311878 -211.218925)
			(xy 265.273065 -211.181504) (xy 265.240113 -211.138831) (xy 265.213727 -211.091814) (xy 265.194467 -211.041457)
			(xy 265.182744 -210.988833) (xy 265.178809 -210.935062) (xy 264.143998 -210.935062) (xy 264.143998 -211.784946)
			(xy 265.178809 -211.784946) (xy 265.182744 -211.731175) (xy 265.194467 -211.678551) (xy 265.213727 -211.628194)
			(xy 265.240113 -211.581177) (xy 265.273065 -211.538504) (xy 265.311878 -211.501083) (xy 265.355726 -211.469713)
			(xy 265.403674 -211.445061) (xy 265.454701 -211.427653) (xy 265.507719 -211.41786) (xy 265.561598 -211.415891)
			(xy 265.615189 -211.421788) (xy 265.66735 -211.435424) (xy 265.71697 -211.456511) (xy 265.762991 -211.484597)
			(xy 265.804433 -211.519085) (xy 265.840411 -211.559239) (xy 265.870159 -211.604203) (xy 265.893044 -211.65302)
			(xy 265.908576 -211.704649) (xy 265.916426 -211.757989) (xy 265.916918 -211.784946) (xy 272.722863 -211.784946)
			(xy 272.726798 -211.731175) (xy 272.738521 -211.678551) (xy 272.757781 -211.628194) (xy 272.784167 -211.581177)
			(xy 272.817119 -211.538504) (xy 272.855932 -211.501083) (xy 272.89978 -211.469713) (xy 272.947728 -211.445061)
			(xy 272.998755 -211.427653) (xy 273.051773 -211.41786) (xy 273.105652 -211.415891) (xy 273.159243 -211.421788)
			(xy 273.211404 -211.435424) (xy 273.261024 -211.456511) (xy 273.307045 -211.484597) (xy 273.348487 -211.519085)
			(xy 273.384465 -211.559239) (xy 273.414213 -211.604203) (xy 273.437098 -211.65302) (xy 273.45263 -211.704649)
			(xy 273.46048 -211.757989) (xy 273.460972 -211.784946) (xy 280.266663 -211.784946) (xy 280.270598 -211.731175)
			(xy 280.282321 -211.678551) (xy 280.301581 -211.628194) (xy 280.327967 -211.581177) (xy 280.360919 -211.538504)
			(xy 280.399732 -211.501083) (xy 280.44358 -211.469713) (xy 280.491528 -211.445061) (xy 280.542555 -211.427653)
			(xy 280.595573 -211.41786) (xy 280.649452 -211.415891) (xy 280.703043 -211.421788) (xy 280.755204 -211.435424)
			(xy 280.804824 -211.456511) (xy 280.850845 -211.484597) (xy 280.892287 -211.519085) (xy 280.928265 -211.559239)
			(xy 280.958013 -211.604203) (xy 280.980898 -211.65302) (xy 280.99643 -211.704649) (xy 281.00428 -211.757989)
			(xy 281.004772 -211.784946) (xy 287.810717 -211.784946) (xy 287.814652 -211.731175) (xy 287.826375 -211.678551)
			(xy 287.845635 -211.628194) (xy 287.872021 -211.581177) (xy 287.904973 -211.538504) (xy 287.943786 -211.501083)
			(xy 287.987634 -211.469713) (xy 288.035582 -211.445061) (xy 288.086609 -211.427653) (xy 288.139627 -211.41786)
			(xy 288.193506 -211.415891) (xy 288.247097 -211.421788) (xy 288.299258 -211.435424) (xy 288.348878 -211.456511)
			(xy 288.394899 -211.484597) (xy 288.436341 -211.519085) (xy 288.472319 -211.559239) (xy 288.502067 -211.604203)
			(xy 288.524952 -211.65302) (xy 288.540484 -211.704649) (xy 288.548334 -211.757989) (xy 288.548826 -211.784946)
			(xy 288.548334 -211.811903) (xy 288.540484 -211.865243) (xy 288.524952 -211.916872) (xy 288.502067 -211.965689)
			(xy 288.472319 -212.010653) (xy 288.436341 -212.050807) (xy 288.394899 -212.085295) (xy 288.348878 -212.113381)
			(xy 288.299258 -212.134468) (xy 288.247097 -212.148104) (xy 288.193506 -212.154001) (xy 288.139627 -212.152032)
			(xy 288.086609 -212.142239) (xy 288.035582 -212.124831) (xy 287.987634 -212.100179) (xy 287.943786 -212.068809)
			(xy 287.904973 -212.031388) (xy 287.872021 -211.988715) (xy 287.845635 -211.941698) (xy 287.826375 -211.891341)
			(xy 287.814652 -211.838717) (xy 287.810717 -211.784946) (xy 281.004772 -211.784946) (xy 281.00428 -211.811903)
			(xy 280.99643 -211.865243) (xy 280.980898 -211.916872) (xy 280.958013 -211.965689) (xy 280.928265 -212.010653)
			(xy 280.892287 -212.050807) (xy 280.850845 -212.085295) (xy 280.804824 -212.113381) (xy 280.755204 -212.134468)
			(xy 280.703043 -212.148104) (xy 280.649452 -212.154001) (xy 280.595573 -212.152032) (xy 280.542555 -212.142239)
			(xy 280.491528 -212.124831) (xy 280.44358 -212.100179) (xy 280.399732 -212.068809) (xy 280.360919 -212.031388)
			(xy 280.327967 -211.988715) (xy 280.301581 -211.941698) (xy 280.282321 -211.891341) (xy 280.270598 -211.838717)
			(xy 280.266663 -211.784946) (xy 273.460972 -211.784946) (xy 273.46048 -211.811903) (xy 273.45263 -211.865243)
			(xy 273.437098 -211.916872) (xy 273.414213 -211.965689) (xy 273.384465 -212.010653) (xy 273.348487 -212.050807)
			(xy 273.307045 -212.085295) (xy 273.261024 -212.113381) (xy 273.211404 -212.134468) (xy 273.159243 -212.148104)
			(xy 273.105652 -212.154001) (xy 273.051773 -212.152032) (xy 272.998755 -212.142239) (xy 272.947728 -212.124831)
			(xy 272.89978 -212.100179) (xy 272.855932 -212.068809) (xy 272.817119 -212.031388) (xy 272.784167 -211.988715)
			(xy 272.757781 -211.941698) (xy 272.738521 -211.891341) (xy 272.726798 -211.838717) (xy 272.722863 -211.784946)
			(xy 265.916918 -211.784946) (xy 265.916426 -211.811903) (xy 265.908576 -211.865243) (xy 265.893044 -211.916872)
			(xy 265.870159 -211.965689) (xy 265.840411 -212.010653) (xy 265.804433 -212.050807) (xy 265.762991 -212.085295)
			(xy 265.71697 -212.113381) (xy 265.66735 -212.134468) (xy 265.615189 -212.148104) (xy 265.561598 -212.154001)
			(xy 265.507719 -212.152032) (xy 265.454701 -212.142239) (xy 265.403674 -212.124831) (xy 265.355726 -212.100179)
			(xy 265.311878 -212.068809) (xy 265.273065 -212.031388) (xy 265.240113 -211.988715) (xy 265.213727 -211.941698)
			(xy 265.194467 -211.891341) (xy 265.182744 -211.838717) (xy 265.178809 -211.784946) (xy 264.143998 -211.784946)
			(xy 264.143998 -212.635084) (xy 269.278877 -212.635084) (xy 269.282812 -212.581313) (xy 269.294535 -212.528689)
			(xy 269.313795 -212.478332) (xy 269.340181 -212.431315) (xy 269.373133 -212.388642) (xy 269.411946 -212.351221)
			(xy 269.455794 -212.319851) (xy 269.503742 -212.295199) (xy 269.554769 -212.277791) (xy 269.607787 -212.267998)
			(xy 269.661666 -212.266029) (xy 269.715257 -212.271926) (xy 269.767418 -212.285562) (xy 269.817038 -212.306649)
			(xy 269.863059 -212.334735) (xy 269.904501 -212.369223) (xy 269.940479 -212.409377) (xy 269.970227 -212.454341)
			(xy 269.993112 -212.503158) (xy 270.008644 -212.554787) (xy 270.016494 -212.608127) (xy 270.016986 -212.635084)
			(xy 276.822931 -212.635084) (xy 276.826866 -212.581313) (xy 276.838589 -212.528689) (xy 276.857849 -212.478332)
			(xy 276.884235 -212.431315) (xy 276.917187 -212.388642) (xy 276.956 -212.351221) (xy 276.999848 -212.319851)
			(xy 277.047796 -212.295199) (xy 277.098823 -212.277791) (xy 277.151841 -212.267998) (xy 277.20572 -212.266029)
			(xy 277.259311 -212.271926) (xy 277.311472 -212.285562) (xy 277.361092 -212.306649) (xy 277.407113 -212.334735)
			(xy 277.448555 -212.369223) (xy 277.484533 -212.409377) (xy 277.514281 -212.454341) (xy 277.537166 -212.503158)
			(xy 277.552698 -212.554787) (xy 277.560548 -212.608127) (xy 277.56104 -212.635084) (xy 284.366731 -212.635084)
			(xy 284.370666 -212.581313) (xy 284.382389 -212.528689) (xy 284.401649 -212.478332) (xy 284.428035 -212.431315)
			(xy 284.460987 -212.388642) (xy 284.4998 -212.351221) (xy 284.543648 -212.319851) (xy 284.591596 -212.295199)
			(xy 284.642623 -212.277791) (xy 284.695641 -212.267998) (xy 284.74952 -212.266029) (xy 284.803111 -212.271926)
			(xy 284.855272 -212.285562) (xy 284.904892 -212.306649) (xy 284.950913 -212.334735) (xy 284.992355 -212.369223)
			(xy 285.028333 -212.409377) (xy 285.058081 -212.454341) (xy 285.080966 -212.503158) (xy 285.096498 -212.554787)
			(xy 285.104348 -212.608127) (xy 285.10484 -212.635084) (xy 291.910785 -212.635084) (xy 291.91472 -212.581313)
			(xy 291.926443 -212.528689) (xy 291.945703 -212.478332) (xy 291.972089 -212.431315) (xy 292.005041 -212.388642)
			(xy 292.043854 -212.351221) (xy 292.087702 -212.319851) (xy 292.13565 -212.295199) (xy 292.186677 -212.277791)
			(xy 292.239695 -212.267998) (xy 292.293574 -212.266029) (xy 292.347165 -212.271926) (xy 292.399326 -212.285562)
			(xy 292.448946 -212.306649) (xy 292.494967 -212.334735) (xy 292.536409 -212.369223) (xy 292.572387 -212.409377)
			(xy 292.602135 -212.454341) (xy 292.62502 -212.503158) (xy 292.640552 -212.554787) (xy 292.648402 -212.608127)
			(xy 292.648894 -212.635084) (xy 292.648402 -212.662041) (xy 292.640552 -212.715381) (xy 292.62502 -212.76701)
			(xy 292.602135 -212.815827) (xy 292.572387 -212.860791) (xy 292.536409 -212.900945) (xy 292.494967 -212.935433)
			(xy 292.448946 -212.963519) (xy 292.399326 -212.984606) (xy 292.347165 -212.998242) (xy 292.293574 -213.004139)
			(xy 292.239695 -213.00217) (xy 292.186677 -212.992377) (xy 292.13565 -212.974969) (xy 292.087702 -212.950317)
			(xy 292.043854 -212.918947) (xy 292.005041 -212.881526) (xy 291.972089 -212.838853) (xy 291.945703 -212.791836)
			(xy 291.926443 -212.741479) (xy 291.91472 -212.688855) (xy 291.910785 -212.635084) (xy 285.10484 -212.635084)
			(xy 285.104348 -212.662041) (xy 285.096498 -212.715381) (xy 285.080966 -212.76701) (xy 285.058081 -212.815827)
			(xy 285.028333 -212.860791) (xy 284.992355 -212.900945) (xy 284.950913 -212.935433) (xy 284.904892 -212.963519)
			(xy 284.855272 -212.984606) (xy 284.803111 -212.998242) (xy 284.74952 -213.004139) (xy 284.695641 -213.00217)
			(xy 284.642623 -212.992377) (xy 284.591596 -212.974969) (xy 284.543648 -212.950317) (xy 284.4998 -212.918947)
			(xy 284.460987 -212.881526) (xy 284.428035 -212.838853) (xy 284.401649 -212.791836) (xy 284.382389 -212.741479)
			(xy 284.370666 -212.688855) (xy 284.366731 -212.635084) (xy 277.56104 -212.635084) (xy 277.560548 -212.662041)
			(xy 277.552698 -212.715381) (xy 277.537166 -212.76701) (xy 277.514281 -212.815827) (xy 277.484533 -212.860791)
			(xy 277.448555 -212.900945) (xy 277.407113 -212.935433) (xy 277.361092 -212.963519) (xy 277.311472 -212.984606)
			(xy 277.259311 -212.998242) (xy 277.20572 -213.004139) (xy 277.151841 -213.00217) (xy 277.098823 -212.992377)
			(xy 277.047796 -212.974969) (xy 276.999848 -212.950317) (xy 276.956 -212.918947) (xy 276.917187 -212.881526)
			(xy 276.884235 -212.838853) (xy 276.857849 -212.791836) (xy 276.838589 -212.741479) (xy 276.826866 -212.688855)
			(xy 276.822931 -212.635084) (xy 270.016986 -212.635084) (xy 270.016494 -212.662041) (xy 270.008644 -212.715381)
			(xy 269.993112 -212.76701) (xy 269.970227 -212.815827) (xy 269.940479 -212.860791) (xy 269.904501 -212.900945)
			(xy 269.863059 -212.935433) (xy 269.817038 -212.963519) (xy 269.767418 -212.984606) (xy 269.715257 -212.998242)
			(xy 269.661666 -213.004139) (xy 269.607787 -213.00217) (xy 269.554769 -212.992377) (xy 269.503742 -212.974969)
			(xy 269.455794 -212.950317) (xy 269.411946 -212.918947) (xy 269.373133 -212.881526) (xy 269.340181 -212.838853)
			(xy 269.313795 -212.791836) (xy 269.294535 -212.741479) (xy 269.282812 -212.688855) (xy 269.278877 -212.635084)
			(xy 264.143998 -212.635084) (xy 264.143998 -213.484968) (xy 265.178809 -213.484968) (xy 265.182744 -213.431197)
			(xy 265.194467 -213.378573) (xy 265.213727 -213.328216) (xy 265.240113 -213.281199) (xy 265.273065 -213.238526)
			(xy 265.311878 -213.201105) (xy 265.355726 -213.169735) (xy 265.403674 -213.145083) (xy 265.454701 -213.127675)
			(xy 265.507719 -213.117882) (xy 265.561598 -213.115913) (xy 265.615189 -213.12181) (xy 265.66735 -213.135446)
			(xy 265.71697 -213.156533) (xy 265.762991 -213.184619) (xy 265.804433 -213.219107) (xy 265.840411 -213.259261)
			(xy 265.870159 -213.304225) (xy 265.893044 -213.353042) (xy 265.908576 -213.404671) (xy 265.916426 -213.458011)
			(xy 265.916918 -213.484968) (xy 272.722863 -213.484968) (xy 272.726798 -213.431197) (xy 272.738521 -213.378573)
			(xy 272.757781 -213.328216) (xy 272.784167 -213.281199) (xy 272.817119 -213.238526) (xy 272.855932 -213.201105)
			(xy 272.89978 -213.169735) (xy 272.947728 -213.145083) (xy 272.998755 -213.127675) (xy 273.051773 -213.117882)
			(xy 273.105652 -213.115913) (xy 273.159243 -213.12181) (xy 273.211404 -213.135446) (xy 273.261024 -213.156533)
			(xy 273.307045 -213.184619) (xy 273.348487 -213.219107) (xy 273.384465 -213.259261) (xy 273.414213 -213.304225)
			(xy 273.437098 -213.353042) (xy 273.45263 -213.404671) (xy 273.46048 -213.458011) (xy 273.460972 -213.484968)
			(xy 280.266663 -213.484968) (xy 280.270598 -213.431197) (xy 280.282321 -213.378573) (xy 280.301581 -213.328216)
			(xy 280.327967 -213.281199) (xy 280.360919 -213.238526) (xy 280.399732 -213.201105) (xy 280.44358 -213.169735)
			(xy 280.491528 -213.145083) (xy 280.542555 -213.127675) (xy 280.595573 -213.117882) (xy 280.649452 -213.115913)
			(xy 280.703043 -213.12181) (xy 280.755204 -213.135446) (xy 280.804824 -213.156533) (xy 280.850845 -213.184619)
			(xy 280.892287 -213.219107) (xy 280.928265 -213.259261) (xy 280.958013 -213.304225) (xy 280.980898 -213.353042)
			(xy 280.99643 -213.404671) (xy 281.00428 -213.458011) (xy 281.004772 -213.484968) (xy 287.810717 -213.484968)
			(xy 287.814652 -213.431197) (xy 287.826375 -213.378573) (xy 287.845635 -213.328216) (xy 287.872021 -213.281199)
			(xy 287.904973 -213.238526) (xy 287.943786 -213.201105) (xy 287.987634 -213.169735) (xy 288.035582 -213.145083)
			(xy 288.086609 -213.127675) (xy 288.139627 -213.117882) (xy 288.193506 -213.115913) (xy 288.247097 -213.12181)
			(xy 288.299258 -213.135446) (xy 288.348878 -213.156533) (xy 288.394899 -213.184619) (xy 288.436341 -213.219107)
			(xy 288.472319 -213.259261) (xy 288.502067 -213.304225) (xy 288.524952 -213.353042) (xy 288.540484 -213.404671)
			(xy 288.548334 -213.458011) (xy 288.548826 -213.484968) (xy 288.548334 -213.511925) (xy 288.540484 -213.565265)
			(xy 288.524952 -213.616894) (xy 288.502067 -213.665711) (xy 288.472319 -213.710675) (xy 288.436341 -213.750829)
			(xy 288.394899 -213.785317) (xy 288.348878 -213.813403) (xy 288.299258 -213.83449) (xy 288.247097 -213.848126)
			(xy 288.193506 -213.854023) (xy 288.139627 -213.852054) (xy 288.086609 -213.842261) (xy 288.035582 -213.824853)
			(xy 287.987634 -213.800201) (xy 287.943786 -213.768831) (xy 287.904973 -213.73141) (xy 287.872021 -213.688737)
			(xy 287.845635 -213.64172) (xy 287.826375 -213.591363) (xy 287.814652 -213.538739) (xy 287.810717 -213.484968)
			(xy 281.004772 -213.484968) (xy 281.00428 -213.511925) (xy 280.99643 -213.565265) (xy 280.980898 -213.616894)
			(xy 280.958013 -213.665711) (xy 280.928265 -213.710675) (xy 280.892287 -213.750829) (xy 280.850845 -213.785317)
			(xy 280.804824 -213.813403) (xy 280.755204 -213.83449) (xy 280.703043 -213.848126) (xy 280.649452 -213.854023)
			(xy 280.595573 -213.852054) (xy 280.542555 -213.842261) (xy 280.491528 -213.824853) (xy 280.44358 -213.800201)
			(xy 280.399732 -213.768831) (xy 280.360919 -213.73141) (xy 280.327967 -213.688737) (xy 280.301581 -213.64172)
			(xy 280.282321 -213.591363) (xy 280.270598 -213.538739) (xy 280.266663 -213.484968) (xy 273.460972 -213.484968)
			(xy 273.46048 -213.511925) (xy 273.45263 -213.565265) (xy 273.437098 -213.616894) (xy 273.414213 -213.665711)
			(xy 273.384465 -213.710675) (xy 273.348487 -213.750829) (xy 273.307045 -213.785317) (xy 273.261024 -213.813403)
			(xy 273.211404 -213.83449) (xy 273.159243 -213.848126) (xy 273.105652 -213.854023) (xy 273.051773 -213.852054)
			(xy 272.998755 -213.842261) (xy 272.947728 -213.824853) (xy 272.89978 -213.800201) (xy 272.855932 -213.768831)
			(xy 272.817119 -213.73141) (xy 272.784167 -213.688737) (xy 272.757781 -213.64172) (xy 272.738521 -213.591363)
			(xy 272.726798 -213.538739) (xy 272.722863 -213.484968) (xy 265.916918 -213.484968) (xy 265.916426 -213.511925)
			(xy 265.908576 -213.565265) (xy 265.893044 -213.616894) (xy 265.870159 -213.665711) (xy 265.840411 -213.710675)
			(xy 265.804433 -213.750829) (xy 265.762991 -213.785317) (xy 265.71697 -213.813403) (xy 265.66735 -213.83449)
			(xy 265.615189 -213.848126) (xy 265.561598 -213.854023) (xy 265.507719 -213.852054) (xy 265.454701 -213.842261)
			(xy 265.403674 -213.824853) (xy 265.355726 -213.800201) (xy 265.311878 -213.768831) (xy 265.273065 -213.73141)
			(xy 265.240113 -213.688737) (xy 265.213727 -213.64172) (xy 265.194467 -213.591363) (xy 265.182744 -213.538739)
			(xy 265.178809 -213.484968) (xy 264.143998 -213.484968) (xy 264.143998 -214.335106) (xy 269.278877 -214.335106)
			(xy 269.282812 -214.281335) (xy 269.294535 -214.228711) (xy 269.313795 -214.178354) (xy 269.340181 -214.131337)
			(xy 269.373133 -214.088664) (xy 269.411946 -214.051243) (xy 269.455794 -214.019873) (xy 269.503742 -213.995221)
			(xy 269.554769 -213.977813) (xy 269.607787 -213.96802) (xy 269.661666 -213.966051) (xy 269.715257 -213.971948)
			(xy 269.767418 -213.985584) (xy 269.817038 -214.006671) (xy 269.863059 -214.034757) (xy 269.904501 -214.069245)
			(xy 269.940479 -214.109399) (xy 269.970227 -214.154363) (xy 269.993112 -214.20318) (xy 270.008644 -214.254809)
			(xy 270.016494 -214.308149) (xy 270.016986 -214.335106) (xy 276.822931 -214.335106) (xy 276.826866 -214.281335)
			(xy 276.838589 -214.228711) (xy 276.857849 -214.178354) (xy 276.884235 -214.131337) (xy 276.917187 -214.088664)
			(xy 276.956 -214.051243) (xy 276.999848 -214.019873) (xy 277.047796 -213.995221) (xy 277.098823 -213.977813)
			(xy 277.151841 -213.96802) (xy 277.20572 -213.966051) (xy 277.259311 -213.971948) (xy 277.311472 -213.985584)
			(xy 277.361092 -214.006671) (xy 277.407113 -214.034757) (xy 277.448555 -214.069245) (xy 277.484533 -214.109399)
			(xy 277.514281 -214.154363) (xy 277.537166 -214.20318) (xy 277.552698 -214.254809) (xy 277.560548 -214.308149)
			(xy 277.56104 -214.335106) (xy 284.366731 -214.335106) (xy 284.370666 -214.281335) (xy 284.382389 -214.228711)
			(xy 284.401649 -214.178354) (xy 284.428035 -214.131337) (xy 284.460987 -214.088664) (xy 284.4998 -214.051243)
			(xy 284.543648 -214.019873) (xy 284.591596 -213.995221) (xy 284.642623 -213.977813) (xy 284.695641 -213.96802)
			(xy 284.74952 -213.966051) (xy 284.803111 -213.971948) (xy 284.855272 -213.985584) (xy 284.904892 -214.006671)
			(xy 284.950913 -214.034757) (xy 284.992355 -214.069245) (xy 285.028333 -214.109399) (xy 285.058081 -214.154363)
			(xy 285.080966 -214.20318) (xy 285.096498 -214.254809) (xy 285.104348 -214.308149) (xy 285.10484 -214.335106)
			(xy 291.910785 -214.335106) (xy 291.91472 -214.281335) (xy 291.926443 -214.228711) (xy 291.945703 -214.178354)
			(xy 291.972089 -214.131337) (xy 292.005041 -214.088664) (xy 292.043854 -214.051243) (xy 292.087702 -214.019873)
			(xy 292.13565 -213.995221) (xy 292.186677 -213.977813) (xy 292.239695 -213.96802) (xy 292.293574 -213.966051)
			(xy 292.347165 -213.971948) (xy 292.399326 -213.985584) (xy 292.448946 -214.006671) (xy 292.494967 -214.034757)
			(xy 292.536409 -214.069245) (xy 292.572387 -214.109399) (xy 292.602135 -214.154363) (xy 292.62502 -214.20318)
			(xy 292.640552 -214.254809) (xy 292.648402 -214.308149) (xy 292.648894 -214.335106) (xy 292.648402 -214.362063)
			(xy 292.640552 -214.415403) (xy 292.62502 -214.467032) (xy 292.602135 -214.515849) (xy 292.572387 -214.560813)
			(xy 292.536409 -214.600967) (xy 292.494967 -214.635455) (xy 292.448946 -214.663541) (xy 292.399326 -214.684628)
			(xy 292.347165 -214.698264) (xy 292.293574 -214.704161) (xy 292.239695 -214.702192) (xy 292.186677 -214.692399)
			(xy 292.13565 -214.674991) (xy 292.087702 -214.650339) (xy 292.043854 -214.618969) (xy 292.005041 -214.581548)
			(xy 291.972089 -214.538875) (xy 291.945703 -214.491858) (xy 291.926443 -214.441501) (xy 291.91472 -214.388877)
			(xy 291.910785 -214.335106) (xy 285.10484 -214.335106) (xy 285.104348 -214.362063) (xy 285.096498 -214.415403)
			(xy 285.080966 -214.467032) (xy 285.058081 -214.515849) (xy 285.028333 -214.560813) (xy 284.992355 -214.600967)
			(xy 284.950913 -214.635455) (xy 284.904892 -214.663541) (xy 284.855272 -214.684628) (xy 284.803111 -214.698264)
			(xy 284.74952 -214.704161) (xy 284.695641 -214.702192) (xy 284.642623 -214.692399) (xy 284.591596 -214.674991)
			(xy 284.543648 -214.650339) (xy 284.4998 -214.618969) (xy 284.460987 -214.581548) (xy 284.428035 -214.538875)
			(xy 284.401649 -214.491858) (xy 284.382389 -214.441501) (xy 284.370666 -214.388877) (xy 284.366731 -214.335106)
			(xy 277.56104 -214.335106) (xy 277.560548 -214.362063) (xy 277.552698 -214.415403) (xy 277.537166 -214.467032)
			(xy 277.514281 -214.515849) (xy 277.484533 -214.560813) (xy 277.448555 -214.600967) (xy 277.407113 -214.635455)
			(xy 277.361092 -214.663541) (xy 277.311472 -214.684628) (xy 277.259311 -214.698264) (xy 277.20572 -214.704161)
			(xy 277.151841 -214.702192) (xy 277.098823 -214.692399) (xy 277.047796 -214.674991) (xy 276.999848 -214.650339)
			(xy 276.956 -214.618969) (xy 276.917187 -214.581548) (xy 276.884235 -214.538875) (xy 276.857849 -214.491858)
			(xy 276.838589 -214.441501) (xy 276.826866 -214.388877) (xy 276.822931 -214.335106) (xy 270.016986 -214.335106)
			(xy 270.016494 -214.362063) (xy 270.008644 -214.415403) (xy 269.993112 -214.467032) (xy 269.970227 -214.515849)
			(xy 269.940479 -214.560813) (xy 269.904501 -214.600967) (xy 269.863059 -214.635455) (xy 269.817038 -214.663541)
			(xy 269.767418 -214.684628) (xy 269.715257 -214.698264) (xy 269.661666 -214.704161) (xy 269.607787 -214.702192)
			(xy 269.554769 -214.692399) (xy 269.503742 -214.674991) (xy 269.455794 -214.650339) (xy 269.411946 -214.618969)
			(xy 269.373133 -214.581548) (xy 269.340181 -214.538875) (xy 269.313795 -214.491858) (xy 269.294535 -214.441501)
			(xy 269.282812 -214.388877) (xy 269.278877 -214.335106) (xy 264.143998 -214.335106) (xy 264.143998 -215.18499)
			(xy 265.178809 -215.18499) (xy 265.182744 -215.131219) (xy 265.194467 -215.078595) (xy 265.213727 -215.028238)
			(xy 265.240113 -214.981221) (xy 265.273065 -214.938548) (xy 265.311878 -214.901127) (xy 265.355726 -214.869757)
			(xy 265.403674 -214.845105) (xy 265.454701 -214.827697) (xy 265.507719 -214.817904) (xy 265.561598 -214.815935)
			(xy 265.615189 -214.821832) (xy 265.66735 -214.835468) (xy 265.71697 -214.856555) (xy 265.762991 -214.884641)
			(xy 265.804433 -214.919129) (xy 265.840411 -214.959283) (xy 265.870159 -215.004247) (xy 265.893044 -215.053064)
			(xy 265.908576 -215.104693) (xy 265.916426 -215.158033) (xy 265.916918 -215.18499) (xy 272.722863 -215.18499)
			(xy 272.726798 -215.131219) (xy 272.738521 -215.078595) (xy 272.757781 -215.028238) (xy 272.784167 -214.981221)
			(xy 272.817119 -214.938548) (xy 272.855932 -214.901127) (xy 272.89978 -214.869757) (xy 272.947728 -214.845105)
			(xy 272.998755 -214.827697) (xy 273.051773 -214.817904) (xy 273.105652 -214.815935) (xy 273.159243 -214.821832)
			(xy 273.211404 -214.835468) (xy 273.261024 -214.856555) (xy 273.307045 -214.884641) (xy 273.348487 -214.919129)
			(xy 273.384465 -214.959283) (xy 273.414213 -215.004247) (xy 273.437098 -215.053064) (xy 273.45263 -215.104693)
			(xy 273.46048 -215.158033) (xy 273.460972 -215.18499) (xy 280.266663 -215.18499) (xy 280.270598 -215.131219)
			(xy 280.282321 -215.078595) (xy 280.301581 -215.028238) (xy 280.327967 -214.981221) (xy 280.360919 -214.938548)
			(xy 280.399732 -214.901127) (xy 280.44358 -214.869757) (xy 280.491528 -214.845105) (xy 280.542555 -214.827697)
			(xy 280.595573 -214.817904) (xy 280.649452 -214.815935) (xy 280.703043 -214.821832) (xy 280.755204 -214.835468)
			(xy 280.804824 -214.856555) (xy 280.850845 -214.884641) (xy 280.892287 -214.919129) (xy 280.928265 -214.959283)
			(xy 280.958013 -215.004247) (xy 280.980898 -215.053064) (xy 280.99643 -215.104693) (xy 281.00428 -215.158033)
			(xy 281.004772 -215.18499) (xy 287.810717 -215.18499) (xy 287.814652 -215.131219) (xy 287.826375 -215.078595)
			(xy 287.845635 -215.028238) (xy 287.872021 -214.981221) (xy 287.904973 -214.938548) (xy 287.943786 -214.901127)
			(xy 287.987634 -214.869757) (xy 288.035582 -214.845105) (xy 288.086609 -214.827697) (xy 288.139627 -214.817904)
			(xy 288.193506 -214.815935) (xy 288.247097 -214.821832) (xy 288.299258 -214.835468) (xy 288.348878 -214.856555)
			(xy 288.394899 -214.884641) (xy 288.436341 -214.919129) (xy 288.472319 -214.959283) (xy 288.502067 -215.004247)
			(xy 288.524952 -215.053064) (xy 288.540484 -215.104693) (xy 288.548334 -215.158033) (xy 288.548826 -215.18499)
			(xy 288.548334 -215.211947) (xy 288.540484 -215.265287) (xy 288.524952 -215.316916) (xy 288.502067 -215.365733)
			(xy 288.472319 -215.410697) (xy 288.436341 -215.450851) (xy 288.394899 -215.485339) (xy 288.348878 -215.513425)
			(xy 288.299258 -215.534512) (xy 288.247097 -215.548148) (xy 288.193506 -215.554045) (xy 288.139627 -215.552076)
			(xy 288.086609 -215.542283) (xy 288.035582 -215.524875) (xy 287.987634 -215.500223) (xy 287.943786 -215.468853)
			(xy 287.904973 -215.431432) (xy 287.872021 -215.388759) (xy 287.845635 -215.341742) (xy 287.826375 -215.291385)
			(xy 287.814652 -215.238761) (xy 287.810717 -215.18499) (xy 281.004772 -215.18499) (xy 281.00428 -215.211947)
			(xy 280.99643 -215.265287) (xy 280.980898 -215.316916) (xy 280.958013 -215.365733) (xy 280.928265 -215.410697)
			(xy 280.892287 -215.450851) (xy 280.850845 -215.485339) (xy 280.804824 -215.513425) (xy 280.755204 -215.534512)
			(xy 280.703043 -215.548148) (xy 280.649452 -215.554045) (xy 280.595573 -215.552076) (xy 280.542555 -215.542283)
			(xy 280.491528 -215.524875) (xy 280.44358 -215.500223) (xy 280.399732 -215.468853) (xy 280.360919 -215.431432)
			(xy 280.327967 -215.388759) (xy 280.301581 -215.341742) (xy 280.282321 -215.291385) (xy 280.270598 -215.238761)
			(xy 280.266663 -215.18499) (xy 273.460972 -215.18499) (xy 273.46048 -215.211947) (xy 273.45263 -215.265287)
			(xy 273.437098 -215.316916) (xy 273.414213 -215.365733) (xy 273.384465 -215.410697) (xy 273.348487 -215.450851)
			(xy 273.307045 -215.485339) (xy 273.261024 -215.513425) (xy 273.211404 -215.534512) (xy 273.159243 -215.548148)
			(xy 273.105652 -215.554045) (xy 273.051773 -215.552076) (xy 272.998755 -215.542283) (xy 272.947728 -215.524875)
			(xy 272.89978 -215.500223) (xy 272.855932 -215.468853) (xy 272.817119 -215.431432) (xy 272.784167 -215.388759)
			(xy 272.757781 -215.341742) (xy 272.738521 -215.291385) (xy 272.726798 -215.238761) (xy 272.722863 -215.18499)
			(xy 265.916918 -215.18499) (xy 265.916426 -215.211947) (xy 265.908576 -215.265287) (xy 265.893044 -215.316916)
			(xy 265.870159 -215.365733) (xy 265.840411 -215.410697) (xy 265.804433 -215.450851) (xy 265.762991 -215.485339)
			(xy 265.71697 -215.513425) (xy 265.66735 -215.534512) (xy 265.615189 -215.548148) (xy 265.561598 -215.554045)
			(xy 265.507719 -215.552076) (xy 265.454701 -215.542283) (xy 265.403674 -215.524875) (xy 265.355726 -215.500223)
			(xy 265.311878 -215.468853) (xy 265.273065 -215.431432) (xy 265.240113 -215.388759) (xy 265.213727 -215.341742)
			(xy 265.194467 -215.291385) (xy 265.182744 -215.238761) (xy 265.178809 -215.18499) (xy 264.143998 -215.18499)
			(xy 264.143998 -216.035128) (xy 269.278877 -216.035128) (xy 269.282812 -215.981357) (xy 269.294535 -215.928733)
			(xy 269.313795 -215.878376) (xy 269.340181 -215.831359) (xy 269.373133 -215.788686) (xy 269.411946 -215.751265)
			(xy 269.455794 -215.719895) (xy 269.503742 -215.695243) (xy 269.554769 -215.677835) (xy 269.607787 -215.668042)
			(xy 269.661666 -215.666073) (xy 269.715257 -215.67197) (xy 269.767418 -215.685606) (xy 269.817038 -215.706693)
			(xy 269.863059 -215.734779) (xy 269.904501 -215.769267) (xy 269.940479 -215.809421) (xy 269.970227 -215.854385)
			(xy 269.993112 -215.903202) (xy 270.008644 -215.954831) (xy 270.016494 -216.008171) (xy 270.016986 -216.035128)
			(xy 276.822931 -216.035128) (xy 276.826866 -215.981357) (xy 276.838589 -215.928733) (xy 276.857849 -215.878376)
			(xy 276.884235 -215.831359) (xy 276.917187 -215.788686) (xy 276.956 -215.751265) (xy 276.999848 -215.719895)
			(xy 277.047796 -215.695243) (xy 277.098823 -215.677835) (xy 277.151841 -215.668042) (xy 277.20572 -215.666073)
			(xy 277.259311 -215.67197) (xy 277.311472 -215.685606) (xy 277.361092 -215.706693) (xy 277.407113 -215.734779)
			(xy 277.448555 -215.769267) (xy 277.484533 -215.809421) (xy 277.514281 -215.854385) (xy 277.537166 -215.903202)
			(xy 277.552698 -215.954831) (xy 277.560548 -216.008171) (xy 277.56104 -216.035128) (xy 284.366731 -216.035128)
			(xy 284.370666 -215.981357) (xy 284.382389 -215.928733) (xy 284.401649 -215.878376) (xy 284.428035 -215.831359)
			(xy 284.460987 -215.788686) (xy 284.4998 -215.751265) (xy 284.543648 -215.719895) (xy 284.591596 -215.695243)
			(xy 284.642623 -215.677835) (xy 284.695641 -215.668042) (xy 284.74952 -215.666073) (xy 284.803111 -215.67197)
			(xy 284.855272 -215.685606) (xy 284.904892 -215.706693) (xy 284.950913 -215.734779) (xy 284.992355 -215.769267)
			(xy 285.028333 -215.809421) (xy 285.058081 -215.854385) (xy 285.080966 -215.903202) (xy 285.096498 -215.954831)
			(xy 285.104348 -216.008171) (xy 285.10484 -216.035128) (xy 291.910785 -216.035128) (xy 291.91472 -215.981357)
			(xy 291.926443 -215.928733) (xy 291.945703 -215.878376) (xy 291.972089 -215.831359) (xy 292.005041 -215.788686)
			(xy 292.043854 -215.751265) (xy 292.087702 -215.719895) (xy 292.13565 -215.695243) (xy 292.186677 -215.677835)
			(xy 292.239695 -215.668042) (xy 292.293574 -215.666073) (xy 292.347165 -215.67197) (xy 292.399326 -215.685606)
			(xy 292.448946 -215.706693) (xy 292.494967 -215.734779) (xy 292.536409 -215.769267) (xy 292.572387 -215.809421)
			(xy 292.602135 -215.854385) (xy 292.62502 -215.903202) (xy 292.640552 -215.954831) (xy 292.648402 -216.008171)
			(xy 292.648894 -216.035128) (xy 292.648402 -216.062085) (xy 292.640552 -216.115425) (xy 292.62502 -216.167054)
			(xy 292.602135 -216.215871) (xy 292.572387 -216.260835) (xy 292.536409 -216.300989) (xy 292.494967 -216.335477)
			(xy 292.448946 -216.363563) (xy 292.399326 -216.38465) (xy 292.347165 -216.398286) (xy 292.293574 -216.404183)
			(xy 292.239695 -216.402214) (xy 292.186677 -216.392421) (xy 292.13565 -216.375013) (xy 292.087702 -216.350361)
			(xy 292.043854 -216.318991) (xy 292.005041 -216.28157) (xy 291.972089 -216.238897) (xy 291.945703 -216.19188)
			(xy 291.926443 -216.141523) (xy 291.91472 -216.088899) (xy 291.910785 -216.035128) (xy 285.10484 -216.035128)
			(xy 285.104348 -216.062085) (xy 285.096498 -216.115425) (xy 285.080966 -216.167054) (xy 285.058081 -216.215871)
			(xy 285.028333 -216.260835) (xy 284.992355 -216.300989) (xy 284.950913 -216.335477) (xy 284.904892 -216.363563)
			(xy 284.855272 -216.38465) (xy 284.803111 -216.398286) (xy 284.74952 -216.404183) (xy 284.695641 -216.402214)
			(xy 284.642623 -216.392421) (xy 284.591596 -216.375013) (xy 284.543648 -216.350361) (xy 284.4998 -216.318991)
			(xy 284.460987 -216.28157) (xy 284.428035 -216.238897) (xy 284.401649 -216.19188) (xy 284.382389 -216.141523)
			(xy 284.370666 -216.088899) (xy 284.366731 -216.035128) (xy 277.56104 -216.035128) (xy 277.560548 -216.062085)
			(xy 277.552698 -216.115425) (xy 277.537166 -216.167054) (xy 277.514281 -216.215871) (xy 277.484533 -216.260835)
			(xy 277.448555 -216.300989) (xy 277.407113 -216.335477) (xy 277.361092 -216.363563) (xy 277.311472 -216.38465)
			(xy 277.259311 -216.398286) (xy 277.20572 -216.404183) (xy 277.151841 -216.402214) (xy 277.098823 -216.392421)
			(xy 277.047796 -216.375013) (xy 276.999848 -216.350361) (xy 276.956 -216.318991) (xy 276.917187 -216.28157)
			(xy 276.884235 -216.238897) (xy 276.857849 -216.19188) (xy 276.838589 -216.141523) (xy 276.826866 -216.088899)
			(xy 276.822931 -216.035128) (xy 270.016986 -216.035128) (xy 270.016494 -216.062085) (xy 270.008644 -216.115425)
			(xy 269.993112 -216.167054) (xy 269.970227 -216.215871) (xy 269.940479 -216.260835) (xy 269.904501 -216.300989)
			(xy 269.863059 -216.335477) (xy 269.817038 -216.363563) (xy 269.767418 -216.38465) (xy 269.715257 -216.398286)
			(xy 269.661666 -216.404183) (xy 269.607787 -216.402214) (xy 269.554769 -216.392421) (xy 269.503742 -216.375013)
			(xy 269.455794 -216.350361) (xy 269.411946 -216.318991) (xy 269.373133 -216.28157) (xy 269.340181 -216.238897)
			(xy 269.313795 -216.19188) (xy 269.294535 -216.141523) (xy 269.282812 -216.088899) (xy 269.278877 -216.035128)
			(xy 264.143998 -216.035128) (xy 264.143998 -216.885012) (xy 265.178809 -216.885012) (xy 265.182744 -216.831241)
			(xy 265.194467 -216.778617) (xy 265.213727 -216.72826) (xy 265.240113 -216.681243) (xy 265.273065 -216.63857)
			(xy 265.311878 -216.601149) (xy 265.355726 -216.569779) (xy 265.403674 -216.545127) (xy 265.454701 -216.527719)
			(xy 265.507719 -216.517926) (xy 265.561598 -216.515957) (xy 265.615189 -216.521854) (xy 265.66735 -216.53549)
			(xy 265.71697 -216.556577) (xy 265.762991 -216.584663) (xy 265.804433 -216.619151) (xy 265.840411 -216.659305)
			(xy 265.870159 -216.704269) (xy 265.893044 -216.753086) (xy 265.908576 -216.804715) (xy 265.916426 -216.858055)
			(xy 265.916918 -216.885012) (xy 272.722863 -216.885012) (xy 272.726798 -216.831241) (xy 272.738521 -216.778617)
			(xy 272.757781 -216.72826) (xy 272.784167 -216.681243) (xy 272.817119 -216.63857) (xy 272.855932 -216.601149)
			(xy 272.89978 -216.569779) (xy 272.947728 -216.545127) (xy 272.998755 -216.527719) (xy 273.051773 -216.517926)
			(xy 273.105652 -216.515957) (xy 273.159243 -216.521854) (xy 273.211404 -216.53549) (xy 273.261024 -216.556577)
			(xy 273.307045 -216.584663) (xy 273.348487 -216.619151) (xy 273.384465 -216.659305) (xy 273.414213 -216.704269)
			(xy 273.437098 -216.753086) (xy 273.45263 -216.804715) (xy 273.46048 -216.858055) (xy 273.460972 -216.885012)
			(xy 280.266663 -216.885012) (xy 280.270598 -216.831241) (xy 280.282321 -216.778617) (xy 280.301581 -216.72826)
			(xy 280.327967 -216.681243) (xy 280.360919 -216.63857) (xy 280.399732 -216.601149) (xy 280.44358 -216.569779)
			(xy 280.491528 -216.545127) (xy 280.542555 -216.527719) (xy 280.595573 -216.517926) (xy 280.649452 -216.515957)
			(xy 280.703043 -216.521854) (xy 280.755204 -216.53549) (xy 280.804824 -216.556577) (xy 280.850845 -216.584663)
			(xy 280.892287 -216.619151) (xy 280.928265 -216.659305) (xy 280.958013 -216.704269) (xy 280.980898 -216.753086)
			(xy 280.99643 -216.804715) (xy 281.00428 -216.858055) (xy 281.004772 -216.885012) (xy 287.810717 -216.885012)
			(xy 287.814652 -216.831241) (xy 287.826375 -216.778617) (xy 287.845635 -216.72826) (xy 287.872021 -216.681243)
			(xy 287.904973 -216.63857) (xy 287.943786 -216.601149) (xy 287.987634 -216.569779) (xy 288.035582 -216.545127)
			(xy 288.086609 -216.527719) (xy 288.139627 -216.517926) (xy 288.193506 -216.515957) (xy 288.247097 -216.521854)
			(xy 288.299258 -216.53549) (xy 288.348878 -216.556577) (xy 288.394899 -216.584663) (xy 288.436341 -216.619151)
			(xy 288.472319 -216.659305) (xy 288.502067 -216.704269) (xy 288.524952 -216.753086) (xy 288.540484 -216.804715)
			(xy 288.548334 -216.858055) (xy 288.548826 -216.885012) (xy 288.548334 -216.911969) (xy 288.540484 -216.965309)
			(xy 288.524952 -217.016938) (xy 288.502067 -217.065755) (xy 288.472319 -217.110719) (xy 288.436341 -217.150873)
			(xy 288.394899 -217.185361) (xy 288.348878 -217.213447) (xy 288.299258 -217.234534) (xy 288.247097 -217.24817)
			(xy 288.193506 -217.254067) (xy 288.139627 -217.252098) (xy 288.086609 -217.242305) (xy 288.035582 -217.224897)
			(xy 287.987634 -217.200245) (xy 287.943786 -217.168875) (xy 287.904973 -217.131454) (xy 287.872021 -217.088781)
			(xy 287.845635 -217.041764) (xy 287.826375 -216.991407) (xy 287.814652 -216.938783) (xy 287.810717 -216.885012)
			(xy 281.004772 -216.885012) (xy 281.00428 -216.911969) (xy 280.99643 -216.965309) (xy 280.980898 -217.016938)
			(xy 280.958013 -217.065755) (xy 280.928265 -217.110719) (xy 280.892287 -217.150873) (xy 280.850845 -217.185361)
			(xy 280.804824 -217.213447) (xy 280.755204 -217.234534) (xy 280.703043 -217.24817) (xy 280.649452 -217.254067)
			(xy 280.595573 -217.252098) (xy 280.542555 -217.242305) (xy 280.491528 -217.224897) (xy 280.44358 -217.200245)
			(xy 280.399732 -217.168875) (xy 280.360919 -217.131454) (xy 280.327967 -217.088781) (xy 280.301581 -217.041764)
			(xy 280.282321 -216.991407) (xy 280.270598 -216.938783) (xy 280.266663 -216.885012) (xy 273.460972 -216.885012)
			(xy 273.46048 -216.911969) (xy 273.45263 -216.965309) (xy 273.437098 -217.016938) (xy 273.414213 -217.065755)
			(xy 273.384465 -217.110719) (xy 273.348487 -217.150873) (xy 273.307045 -217.185361) (xy 273.261024 -217.213447)
			(xy 273.211404 -217.234534) (xy 273.159243 -217.24817) (xy 273.105652 -217.254067) (xy 273.051773 -217.252098)
			(xy 272.998755 -217.242305) (xy 272.947728 -217.224897) (xy 272.89978 -217.200245) (xy 272.855932 -217.168875)
			(xy 272.817119 -217.131454) (xy 272.784167 -217.088781) (xy 272.757781 -217.041764) (xy 272.738521 -216.991407)
			(xy 272.726798 -216.938783) (xy 272.722863 -216.885012) (xy 265.916918 -216.885012) (xy 265.916426 -216.911969)
			(xy 265.908576 -216.965309) (xy 265.893044 -217.016938) (xy 265.870159 -217.065755) (xy 265.840411 -217.110719)
			(xy 265.804433 -217.150873) (xy 265.762991 -217.185361) (xy 265.71697 -217.213447) (xy 265.66735 -217.234534)
			(xy 265.615189 -217.24817) (xy 265.561598 -217.254067) (xy 265.507719 -217.252098) (xy 265.454701 -217.242305)
			(xy 265.403674 -217.224897) (xy 265.355726 -217.200245) (xy 265.311878 -217.168875) (xy 265.273065 -217.131454)
			(xy 265.240113 -217.088781) (xy 265.213727 -217.041764) (xy 265.194467 -216.991407) (xy 265.182744 -216.938783)
			(xy 265.178809 -216.885012) (xy 264.143998 -216.885012) (xy 264.143998 -217.73515) (xy 269.278877 -217.73515)
			(xy 269.282812 -217.681379) (xy 269.294535 -217.628755) (xy 269.313795 -217.578398) (xy 269.340181 -217.531381)
			(xy 269.373133 -217.488708) (xy 269.411946 -217.451287) (xy 269.455794 -217.419917) (xy 269.503742 -217.395265)
			(xy 269.554769 -217.377857) (xy 269.607787 -217.368064) (xy 269.661666 -217.366095) (xy 269.715257 -217.371992)
			(xy 269.767418 -217.385628) (xy 269.817038 -217.406715) (xy 269.863059 -217.434801) (xy 269.904501 -217.469289)
			(xy 269.940479 -217.509443) (xy 269.970227 -217.554407) (xy 269.993112 -217.603224) (xy 270.008644 -217.654853)
			(xy 270.016494 -217.708193) (xy 270.016986 -217.73515) (xy 276.822931 -217.73515) (xy 276.826866 -217.681379)
			(xy 276.838589 -217.628755) (xy 276.857849 -217.578398) (xy 276.884235 -217.531381) (xy 276.917187 -217.488708)
			(xy 276.956 -217.451287) (xy 276.999848 -217.419917) (xy 277.047796 -217.395265) (xy 277.098823 -217.377857)
			(xy 277.151841 -217.368064) (xy 277.20572 -217.366095) (xy 277.259311 -217.371992) (xy 277.311472 -217.385628)
			(xy 277.361092 -217.406715) (xy 277.407113 -217.434801) (xy 277.448555 -217.469289) (xy 277.484533 -217.509443)
			(xy 277.514281 -217.554407) (xy 277.537166 -217.603224) (xy 277.552698 -217.654853) (xy 277.560548 -217.708193)
			(xy 277.56104 -217.73515) (xy 284.366731 -217.73515) (xy 284.370666 -217.681379) (xy 284.382389 -217.628755)
			(xy 284.401649 -217.578398) (xy 284.428035 -217.531381) (xy 284.460987 -217.488708) (xy 284.4998 -217.451287)
			(xy 284.543648 -217.419917) (xy 284.591596 -217.395265) (xy 284.642623 -217.377857) (xy 284.695641 -217.368064)
			(xy 284.74952 -217.366095) (xy 284.803111 -217.371992) (xy 284.855272 -217.385628) (xy 284.904892 -217.406715)
			(xy 284.950913 -217.434801) (xy 284.992355 -217.469289) (xy 285.028333 -217.509443) (xy 285.058081 -217.554407)
			(xy 285.080966 -217.603224) (xy 285.096498 -217.654853) (xy 285.104348 -217.708193) (xy 285.10484 -217.73515)
			(xy 291.910785 -217.73515) (xy 291.91472 -217.681379) (xy 291.926443 -217.628755) (xy 291.945703 -217.578398)
			(xy 291.972089 -217.531381) (xy 292.005041 -217.488708) (xy 292.043854 -217.451287) (xy 292.087702 -217.419917)
			(xy 292.13565 -217.395265) (xy 292.186677 -217.377857) (xy 292.239695 -217.368064) (xy 292.293574 -217.366095)
			(xy 292.347165 -217.371992) (xy 292.399326 -217.385628) (xy 292.448946 -217.406715) (xy 292.494967 -217.434801)
			(xy 292.536409 -217.469289) (xy 292.572387 -217.509443) (xy 292.602135 -217.554407) (xy 292.62502 -217.603224)
			(xy 292.640552 -217.654853) (xy 292.648402 -217.708193) (xy 292.648894 -217.73515) (xy 292.648402 -217.762107)
			(xy 292.640552 -217.815447) (xy 292.62502 -217.867076) (xy 292.602135 -217.915893) (xy 292.572387 -217.960857)
			(xy 292.536409 -218.001011) (xy 292.494967 -218.035499) (xy 292.448946 -218.063585) (xy 292.399326 -218.084672)
			(xy 292.347165 -218.098308) (xy 292.293574 -218.104205) (xy 292.239695 -218.102236) (xy 292.186677 -218.092443)
			(xy 292.13565 -218.075035) (xy 292.087702 -218.050383) (xy 292.043854 -218.019013) (xy 292.005041 -217.981592)
			(xy 291.972089 -217.938919) (xy 291.945703 -217.891902) (xy 291.926443 -217.841545) (xy 291.91472 -217.788921)
			(xy 291.910785 -217.73515) (xy 285.10484 -217.73515) (xy 285.104348 -217.762107) (xy 285.096498 -217.815447)
			(xy 285.080966 -217.867076) (xy 285.058081 -217.915893) (xy 285.028333 -217.960857) (xy 284.992355 -218.001011)
			(xy 284.950913 -218.035499) (xy 284.904892 -218.063585) (xy 284.855272 -218.084672) (xy 284.803111 -218.098308)
			(xy 284.74952 -218.104205) (xy 284.695641 -218.102236) (xy 284.642623 -218.092443) (xy 284.591596 -218.075035)
			(xy 284.543648 -218.050383) (xy 284.4998 -218.019013) (xy 284.460987 -217.981592) (xy 284.428035 -217.938919)
			(xy 284.401649 -217.891902) (xy 284.382389 -217.841545) (xy 284.370666 -217.788921) (xy 284.366731 -217.73515)
			(xy 277.56104 -217.73515) (xy 277.560548 -217.762107) (xy 277.552698 -217.815447) (xy 277.537166 -217.867076)
			(xy 277.514281 -217.915893) (xy 277.484533 -217.960857) (xy 277.448555 -218.001011) (xy 277.407113 -218.035499)
			(xy 277.361092 -218.063585) (xy 277.311472 -218.084672) (xy 277.259311 -218.098308) (xy 277.20572 -218.104205)
			(xy 277.151841 -218.102236) (xy 277.098823 -218.092443) (xy 277.047796 -218.075035) (xy 276.999848 -218.050383)
			(xy 276.956 -218.019013) (xy 276.917187 -217.981592) (xy 276.884235 -217.938919) (xy 276.857849 -217.891902)
			(xy 276.838589 -217.841545) (xy 276.826866 -217.788921) (xy 276.822931 -217.73515) (xy 270.016986 -217.73515)
			(xy 270.016494 -217.762107) (xy 270.008644 -217.815447) (xy 269.993112 -217.867076) (xy 269.970227 -217.915893)
			(xy 269.940479 -217.960857) (xy 269.904501 -218.001011) (xy 269.863059 -218.035499) (xy 269.817038 -218.063585)
			(xy 269.767418 -218.084672) (xy 269.715257 -218.098308) (xy 269.661666 -218.104205) (xy 269.607787 -218.102236)
			(xy 269.554769 -218.092443) (xy 269.503742 -218.075035) (xy 269.455794 -218.050383) (xy 269.411946 -218.019013)
			(xy 269.373133 -217.981592) (xy 269.340181 -217.938919) (xy 269.313795 -217.891902) (xy 269.294535 -217.841545)
			(xy 269.282812 -217.788921) (xy 269.278877 -217.73515) (xy 264.143998 -217.73515) (xy 264.143998 -218.585034)
			(xy 265.178809 -218.585034) (xy 265.182744 -218.531263) (xy 265.194467 -218.478639) (xy 265.213727 -218.428282)
			(xy 265.240113 -218.381265) (xy 265.273065 -218.338592) (xy 265.311878 -218.301171) (xy 265.355726 -218.269801)
			(xy 265.403674 -218.245149) (xy 265.454701 -218.227741) (xy 265.507719 -218.217948) (xy 265.561598 -218.215979)
			(xy 265.615189 -218.221876) (xy 265.66735 -218.235512) (xy 265.71697 -218.256599) (xy 265.762991 -218.284685)
			(xy 265.804433 -218.319173) (xy 265.840411 -218.359327) (xy 265.870159 -218.404291) (xy 265.893044 -218.453108)
			(xy 265.908576 -218.504737) (xy 265.916426 -218.558077) (xy 265.916918 -218.585034) (xy 272.722863 -218.585034)
			(xy 272.726798 -218.531263) (xy 272.738521 -218.478639) (xy 272.757781 -218.428282) (xy 272.784167 -218.381265)
			(xy 272.817119 -218.338592) (xy 272.855932 -218.301171) (xy 272.89978 -218.269801) (xy 272.947728 -218.245149)
			(xy 272.998755 -218.227741) (xy 273.051773 -218.217948) (xy 273.105652 -218.215979) (xy 273.159243 -218.221876)
			(xy 273.211404 -218.235512) (xy 273.261024 -218.256599) (xy 273.307045 -218.284685) (xy 273.348487 -218.319173)
			(xy 273.384465 -218.359327) (xy 273.414213 -218.404291) (xy 273.437098 -218.453108) (xy 273.45263 -218.504737)
			(xy 273.46048 -218.558077) (xy 273.460972 -218.585034) (xy 280.266663 -218.585034) (xy 280.270598 -218.531263)
			(xy 280.282321 -218.478639) (xy 280.301581 -218.428282) (xy 280.327967 -218.381265) (xy 280.360919 -218.338592)
			(xy 280.399732 -218.301171) (xy 280.44358 -218.269801) (xy 280.491528 -218.245149) (xy 280.542555 -218.227741)
			(xy 280.595573 -218.217948) (xy 280.649452 -218.215979) (xy 280.703043 -218.221876) (xy 280.755204 -218.235512)
			(xy 280.804824 -218.256599) (xy 280.850845 -218.284685) (xy 280.892287 -218.319173) (xy 280.928265 -218.359327)
			(xy 280.958013 -218.404291) (xy 280.980898 -218.453108) (xy 280.99643 -218.504737) (xy 281.00428 -218.558077)
			(xy 281.004772 -218.585034) (xy 287.810717 -218.585034) (xy 287.814652 -218.531263) (xy 287.826375 -218.478639)
			(xy 287.845635 -218.428282) (xy 287.872021 -218.381265) (xy 287.904973 -218.338592) (xy 287.943786 -218.301171)
			(xy 287.987634 -218.269801) (xy 288.035582 -218.245149) (xy 288.086609 -218.227741) (xy 288.139627 -218.217948)
			(xy 288.193506 -218.215979) (xy 288.247097 -218.221876) (xy 288.299258 -218.235512) (xy 288.348878 -218.256599)
			(xy 288.394899 -218.284685) (xy 288.436341 -218.319173) (xy 288.472319 -218.359327) (xy 288.502067 -218.404291)
			(xy 288.524952 -218.453108) (xy 288.540484 -218.504737) (xy 288.548334 -218.558077) (xy 288.548826 -218.585034)
			(xy 288.548334 -218.611991) (xy 288.540484 -218.665331) (xy 288.524952 -218.71696) (xy 288.502067 -218.765777)
			(xy 288.472319 -218.810741) (xy 288.436341 -218.850895) (xy 288.394899 -218.885383) (xy 288.348878 -218.913469)
			(xy 288.299258 -218.934556) (xy 288.247097 -218.948192) (xy 288.193506 -218.954089) (xy 288.139627 -218.95212)
			(xy 288.086609 -218.942327) (xy 288.035582 -218.924919) (xy 287.987634 -218.900267) (xy 287.943786 -218.868897)
			(xy 287.904973 -218.831476) (xy 287.872021 -218.788803) (xy 287.845635 -218.741786) (xy 287.826375 -218.691429)
			(xy 287.814652 -218.638805) (xy 287.810717 -218.585034) (xy 281.004772 -218.585034) (xy 281.00428 -218.611991)
			(xy 280.99643 -218.665331) (xy 280.980898 -218.71696) (xy 280.958013 -218.765777) (xy 280.928265 -218.810741)
			(xy 280.892287 -218.850895) (xy 280.850845 -218.885383) (xy 280.804824 -218.913469) (xy 280.755204 -218.934556)
			(xy 280.703043 -218.948192) (xy 280.649452 -218.954089) (xy 280.595573 -218.95212) (xy 280.542555 -218.942327)
			(xy 280.491528 -218.924919) (xy 280.44358 -218.900267) (xy 280.399732 -218.868897) (xy 280.360919 -218.831476)
			(xy 280.327967 -218.788803) (xy 280.301581 -218.741786) (xy 280.282321 -218.691429) (xy 280.270598 -218.638805)
			(xy 280.266663 -218.585034) (xy 273.460972 -218.585034) (xy 273.46048 -218.611991) (xy 273.45263 -218.665331)
			(xy 273.437098 -218.71696) (xy 273.414213 -218.765777) (xy 273.384465 -218.810741) (xy 273.348487 -218.850895)
			(xy 273.307045 -218.885383) (xy 273.261024 -218.913469) (xy 273.211404 -218.934556) (xy 273.159243 -218.948192)
			(xy 273.105652 -218.954089) (xy 273.051773 -218.95212) (xy 272.998755 -218.942327) (xy 272.947728 -218.924919)
			(xy 272.89978 -218.900267) (xy 272.855932 -218.868897) (xy 272.817119 -218.831476) (xy 272.784167 -218.788803)
			(xy 272.757781 -218.741786) (xy 272.738521 -218.691429) (xy 272.726798 -218.638805) (xy 272.722863 -218.585034)
			(xy 265.916918 -218.585034) (xy 265.916426 -218.611991) (xy 265.908576 -218.665331) (xy 265.893044 -218.71696)
			(xy 265.870159 -218.765777) (xy 265.840411 -218.810741) (xy 265.804433 -218.850895) (xy 265.762991 -218.885383)
			(xy 265.71697 -218.913469) (xy 265.66735 -218.934556) (xy 265.615189 -218.948192) (xy 265.561598 -218.954089)
			(xy 265.507719 -218.95212) (xy 265.454701 -218.942327) (xy 265.403674 -218.924919) (xy 265.355726 -218.900267)
			(xy 265.311878 -218.868897) (xy 265.273065 -218.831476) (xy 265.240113 -218.788803) (xy 265.213727 -218.741786)
			(xy 265.194467 -218.691429) (xy 265.182744 -218.638805) (xy 265.178809 -218.585034) (xy 264.143998 -218.585034)
			(xy 264.143998 -219.435172) (xy 269.278877 -219.435172) (xy 269.282812 -219.381401) (xy 269.294535 -219.328777)
			(xy 269.313795 -219.27842) (xy 269.340181 -219.231403) (xy 269.373133 -219.18873) (xy 269.411946 -219.151309)
			(xy 269.455794 -219.119939) (xy 269.503742 -219.095287) (xy 269.554769 -219.077879) (xy 269.607787 -219.068086)
			(xy 269.661666 -219.066117) (xy 269.715257 -219.072014) (xy 269.767418 -219.08565) (xy 269.817038 -219.106737)
			(xy 269.863059 -219.134823) (xy 269.904501 -219.169311) (xy 269.940479 -219.209465) (xy 269.970227 -219.254429)
			(xy 269.993112 -219.303246) (xy 270.008644 -219.354875) (xy 270.016494 -219.408215) (xy 270.016986 -219.435172)
			(xy 276.822931 -219.435172) (xy 276.826866 -219.381401) (xy 276.838589 -219.328777) (xy 276.857849 -219.27842)
			(xy 276.884235 -219.231403) (xy 276.917187 -219.18873) (xy 276.956 -219.151309) (xy 276.999848 -219.119939)
			(xy 277.047796 -219.095287) (xy 277.098823 -219.077879) (xy 277.151841 -219.068086) (xy 277.20572 -219.066117)
			(xy 277.259311 -219.072014) (xy 277.311472 -219.08565) (xy 277.361092 -219.106737) (xy 277.407113 -219.134823)
			(xy 277.448555 -219.169311) (xy 277.484533 -219.209465) (xy 277.514281 -219.254429) (xy 277.537166 -219.303246)
			(xy 277.552698 -219.354875) (xy 277.560548 -219.408215) (xy 277.56104 -219.435172) (xy 284.366731 -219.435172)
			(xy 284.370666 -219.381401) (xy 284.382389 -219.328777) (xy 284.401649 -219.27842) (xy 284.428035 -219.231403)
			(xy 284.460987 -219.18873) (xy 284.4998 -219.151309) (xy 284.543648 -219.119939) (xy 284.591596 -219.095287)
			(xy 284.642623 -219.077879) (xy 284.695641 -219.068086) (xy 284.74952 -219.066117) (xy 284.803111 -219.072014)
			(xy 284.855272 -219.08565) (xy 284.904892 -219.106737) (xy 284.950913 -219.134823) (xy 284.992355 -219.169311)
			(xy 285.028333 -219.209465) (xy 285.058081 -219.254429) (xy 285.080966 -219.303246) (xy 285.096498 -219.354875)
			(xy 285.104348 -219.408215) (xy 285.10484 -219.435172) (xy 291.910785 -219.435172) (xy 291.91472 -219.381401)
			(xy 291.926443 -219.328777) (xy 291.945703 -219.27842) (xy 291.972089 -219.231403) (xy 292.005041 -219.18873)
			(xy 292.043854 -219.151309) (xy 292.087702 -219.119939) (xy 292.13565 -219.095287) (xy 292.186677 -219.077879)
			(xy 292.239695 -219.068086) (xy 292.293574 -219.066117) (xy 292.347165 -219.072014) (xy 292.399326 -219.08565)
			(xy 292.448946 -219.106737) (xy 292.494967 -219.134823) (xy 292.536409 -219.169311) (xy 292.572387 -219.209465)
			(xy 292.602135 -219.254429) (xy 292.62502 -219.303246) (xy 292.640552 -219.354875) (xy 292.648402 -219.408215)
			(xy 292.648894 -219.435172) (xy 292.648402 -219.462129) (xy 292.640552 -219.515469) (xy 292.62502 -219.567098)
			(xy 292.602135 -219.615915) (xy 292.572387 -219.660879) (xy 292.536409 -219.701033) (xy 292.494967 -219.735521)
			(xy 292.448946 -219.763607) (xy 292.399326 -219.784694) (xy 292.347165 -219.79833) (xy 292.293574 -219.804227)
			(xy 292.239695 -219.802258) (xy 292.186677 -219.792465) (xy 292.13565 -219.775057) (xy 292.087702 -219.750405)
			(xy 292.043854 -219.719035) (xy 292.005041 -219.681614) (xy 291.972089 -219.638941) (xy 291.945703 -219.591924)
			(xy 291.926443 -219.541567) (xy 291.91472 -219.488943) (xy 291.910785 -219.435172) (xy 285.10484 -219.435172)
			(xy 285.104348 -219.462129) (xy 285.096498 -219.515469) (xy 285.080966 -219.567098) (xy 285.058081 -219.615915)
			(xy 285.028333 -219.660879) (xy 284.992355 -219.701033) (xy 284.950913 -219.735521) (xy 284.904892 -219.763607)
			(xy 284.855272 -219.784694) (xy 284.803111 -219.79833) (xy 284.74952 -219.804227) (xy 284.695641 -219.802258)
			(xy 284.642623 -219.792465) (xy 284.591596 -219.775057) (xy 284.543648 -219.750405) (xy 284.4998 -219.719035)
			(xy 284.460987 -219.681614) (xy 284.428035 -219.638941) (xy 284.401649 -219.591924) (xy 284.382389 -219.541567)
			(xy 284.370666 -219.488943) (xy 284.366731 -219.435172) (xy 277.56104 -219.435172) (xy 277.560548 -219.462129)
			(xy 277.552698 -219.515469) (xy 277.537166 -219.567098) (xy 277.514281 -219.615915) (xy 277.484533 -219.660879)
			(xy 277.448555 -219.701033) (xy 277.407113 -219.735521) (xy 277.361092 -219.763607) (xy 277.311472 -219.784694)
			(xy 277.259311 -219.79833) (xy 277.20572 -219.804227) (xy 277.151841 -219.802258) (xy 277.098823 -219.792465)
			(xy 277.047796 -219.775057) (xy 276.999848 -219.750405) (xy 276.956 -219.719035) (xy 276.917187 -219.681614)
			(xy 276.884235 -219.638941) (xy 276.857849 -219.591924) (xy 276.838589 -219.541567) (xy 276.826866 -219.488943)
			(xy 276.822931 -219.435172) (xy 270.016986 -219.435172) (xy 270.016494 -219.462129) (xy 270.008644 -219.515469)
			(xy 269.993112 -219.567098) (xy 269.970227 -219.615915) (xy 269.940479 -219.660879) (xy 269.904501 -219.701033)
			(xy 269.863059 -219.735521) (xy 269.817038 -219.763607) (xy 269.767418 -219.784694) (xy 269.715257 -219.79833)
			(xy 269.661666 -219.804227) (xy 269.607787 -219.802258) (xy 269.554769 -219.792465) (xy 269.503742 -219.775057)
			(xy 269.455794 -219.750405) (xy 269.411946 -219.719035) (xy 269.373133 -219.681614) (xy 269.340181 -219.638941)
			(xy 269.313795 -219.591924) (xy 269.294535 -219.541567) (xy 269.282812 -219.488943) (xy 269.278877 -219.435172)
			(xy 264.143998 -219.435172) (xy 264.143998 -220.285056) (xy 265.178809 -220.285056) (xy 265.182744 -220.231285)
			(xy 265.194467 -220.178661) (xy 265.213727 -220.128304) (xy 265.240113 -220.081287) (xy 265.273065 -220.038614)
			(xy 265.311878 -220.001193) (xy 265.355726 -219.969823) (xy 265.403674 -219.945171) (xy 265.454701 -219.927763)
			(xy 265.507719 -219.91797) (xy 265.561598 -219.916001) (xy 265.615189 -219.921898) (xy 265.66735 -219.935534)
			(xy 265.71697 -219.956621) (xy 265.762991 -219.984707) (xy 265.804433 -220.019195) (xy 265.840411 -220.059349)
			(xy 265.870159 -220.104313) (xy 265.893044 -220.15313) (xy 265.908576 -220.204759) (xy 265.916426 -220.258099)
			(xy 265.916918 -220.285056) (xy 269.278877 -220.285056) (xy 269.282812 -220.231285) (xy 269.294535 -220.178661)
			(xy 269.313795 -220.128304) (xy 269.340181 -220.081287) (xy 269.373133 -220.038614) (xy 269.411946 -220.001193)
			(xy 269.455794 -219.969823) (xy 269.503742 -219.945171) (xy 269.554769 -219.927763) (xy 269.607787 -219.91797)
			(xy 269.661666 -219.916001) (xy 269.715257 -219.921898) (xy 269.767418 -219.935534) (xy 269.817038 -219.956621)
			(xy 269.863059 -219.984707) (xy 269.904501 -220.019195) (xy 269.940479 -220.059349) (xy 269.970227 -220.104313)
			(xy 269.993112 -220.15313) (xy 270.008644 -220.204759) (xy 270.016494 -220.258099) (xy 270.016986 -220.285056)
			(xy 272.722863 -220.285056) (xy 272.726798 -220.231285) (xy 272.738521 -220.178661) (xy 272.757781 -220.128304)
			(xy 272.784167 -220.081287) (xy 272.817119 -220.038614) (xy 272.855932 -220.001193) (xy 272.89978 -219.969823)
			(xy 272.947728 -219.945171) (xy 272.998755 -219.927763) (xy 273.051773 -219.91797) (xy 273.105652 -219.916001)
			(xy 273.159243 -219.921898) (xy 273.211404 -219.935534) (xy 273.261024 -219.956621) (xy 273.307045 -219.984707)
			(xy 273.348487 -220.019195) (xy 273.384465 -220.059349) (xy 273.414213 -220.104313) (xy 273.437098 -220.15313)
			(xy 273.45263 -220.204759) (xy 273.46048 -220.258099) (xy 273.460972 -220.285056) (xy 276.822931 -220.285056)
			(xy 276.826866 -220.231285) (xy 276.838589 -220.178661) (xy 276.857849 -220.128304) (xy 276.884235 -220.081287)
			(xy 276.917187 -220.038614) (xy 276.956 -220.001193) (xy 276.999848 -219.969823) (xy 277.047796 -219.945171)
			(xy 277.098823 -219.927763) (xy 277.151841 -219.91797) (xy 277.20572 -219.916001) (xy 277.259311 -219.921898)
			(xy 277.311472 -219.935534) (xy 277.361092 -219.956621) (xy 277.407113 -219.984707) (xy 277.448555 -220.019195)
			(xy 277.484533 -220.059349) (xy 277.514281 -220.104313) (xy 277.537166 -220.15313) (xy 277.552698 -220.204759)
			(xy 277.560548 -220.258099) (xy 277.56104 -220.285056) (xy 280.266663 -220.285056) (xy 280.270598 -220.231285)
			(xy 280.282321 -220.178661) (xy 280.301581 -220.128304) (xy 280.327967 -220.081287) (xy 280.360919 -220.038614)
			(xy 280.399732 -220.001193) (xy 280.44358 -219.969823) (xy 280.491528 -219.945171) (xy 280.542555 -219.927763)
			(xy 280.595573 -219.91797) (xy 280.649452 -219.916001) (xy 280.703043 -219.921898) (xy 280.755204 -219.935534)
			(xy 280.804824 -219.956621) (xy 280.850845 -219.984707) (xy 280.892287 -220.019195) (xy 280.928265 -220.059349)
			(xy 280.958013 -220.104313) (xy 280.980898 -220.15313) (xy 280.99643 -220.204759) (xy 281.00428 -220.258099)
			(xy 281.004772 -220.285056) (xy 284.366731 -220.285056) (xy 284.370666 -220.231285) (xy 284.382389 -220.178661)
			(xy 284.401649 -220.128304) (xy 284.428035 -220.081287) (xy 284.460987 -220.038614) (xy 284.4998 -220.001193)
			(xy 284.543648 -219.969823) (xy 284.591596 -219.945171) (xy 284.642623 -219.927763) (xy 284.695641 -219.91797)
			(xy 284.74952 -219.916001) (xy 284.803111 -219.921898) (xy 284.855272 -219.935534) (xy 284.904892 -219.956621)
			(xy 284.950913 -219.984707) (xy 284.992355 -220.019195) (xy 285.028333 -220.059349) (xy 285.058081 -220.104313)
			(xy 285.080966 -220.15313) (xy 285.096498 -220.204759) (xy 285.104348 -220.258099) (xy 285.10484 -220.285056)
			(xy 287.810717 -220.285056) (xy 287.814652 -220.231285) (xy 287.826375 -220.178661) (xy 287.845635 -220.128304)
			(xy 287.872021 -220.081287) (xy 287.904973 -220.038614) (xy 287.943786 -220.001193) (xy 287.987634 -219.969823)
			(xy 288.035582 -219.945171) (xy 288.086609 -219.927763) (xy 288.139627 -219.91797) (xy 288.193506 -219.916001)
			(xy 288.247097 -219.921898) (xy 288.299258 -219.935534) (xy 288.348878 -219.956621) (xy 288.394899 -219.984707)
			(xy 288.436341 -220.019195) (xy 288.472319 -220.059349) (xy 288.502067 -220.104313) (xy 288.524952 -220.15313)
			(xy 288.540484 -220.204759) (xy 288.548334 -220.258099) (xy 288.548826 -220.285056) (xy 291.910785 -220.285056)
			(xy 291.91472 -220.231285) (xy 291.926443 -220.178661) (xy 291.945703 -220.128304) (xy 291.972089 -220.081287)
			(xy 292.005041 -220.038614) (xy 292.043854 -220.001193) (xy 292.087702 -219.969823) (xy 292.13565 -219.945171)
			(xy 292.186677 -219.927763) (xy 292.239695 -219.91797) (xy 292.293574 -219.916001) (xy 292.347165 -219.921898)
			(xy 292.399326 -219.935534) (xy 292.448946 -219.956621) (xy 292.494967 -219.984707) (xy 292.536409 -220.019195)
			(xy 292.572387 -220.059349) (xy 292.602135 -220.104313) (xy 292.62502 -220.15313) (xy 292.640552 -220.204759)
			(xy 292.648402 -220.258099) (xy 292.648894 -220.285056) (xy 292.648402 -220.312013) (xy 292.640552 -220.365353)
			(xy 292.62502 -220.416982) (xy 292.602135 -220.465799) (xy 292.572387 -220.510763) (xy 292.536409 -220.550917)
			(xy 292.494967 -220.585405) (xy 292.448946 -220.613491) (xy 292.399326 -220.634578) (xy 292.347165 -220.648214)
			(xy 292.293574 -220.654111) (xy 292.239695 -220.652142) (xy 292.186677 -220.642349) (xy 292.13565 -220.624941)
			(xy 292.087702 -220.600289) (xy 292.043854 -220.568919) (xy 292.005041 -220.531498) (xy 291.972089 -220.488825)
			(xy 291.945703 -220.441808) (xy 291.926443 -220.391451) (xy 291.91472 -220.338827) (xy 291.910785 -220.285056)
			(xy 288.548826 -220.285056) (xy 288.548334 -220.312013) (xy 288.540484 -220.365353) (xy 288.524952 -220.416982)
			(xy 288.502067 -220.465799) (xy 288.472319 -220.510763) (xy 288.436341 -220.550917) (xy 288.394899 -220.585405)
			(xy 288.348878 -220.613491) (xy 288.299258 -220.634578) (xy 288.247097 -220.648214) (xy 288.193506 -220.654111)
			(xy 288.139627 -220.652142) (xy 288.086609 -220.642349) (xy 288.035582 -220.624941) (xy 287.987634 -220.600289)
			(xy 287.943786 -220.568919) (xy 287.904973 -220.531498) (xy 287.872021 -220.488825) (xy 287.845635 -220.441808)
			(xy 287.826375 -220.391451) (xy 287.814652 -220.338827) (xy 287.810717 -220.285056) (xy 285.10484 -220.285056)
			(xy 285.104348 -220.312013) (xy 285.096498 -220.365353) (xy 285.080966 -220.416982) (xy 285.058081 -220.465799)
			(xy 285.028333 -220.510763) (xy 284.992355 -220.550917) (xy 284.950913 -220.585405) (xy 284.904892 -220.613491)
			(xy 284.855272 -220.634578) (xy 284.803111 -220.648214) (xy 284.74952 -220.654111) (xy 284.695641 -220.652142)
			(xy 284.642623 -220.642349) (xy 284.591596 -220.624941) (xy 284.543648 -220.600289) (xy 284.4998 -220.568919)
			(xy 284.460987 -220.531498) (xy 284.428035 -220.488825) (xy 284.401649 -220.441808) (xy 284.382389 -220.391451)
			(xy 284.370666 -220.338827) (xy 284.366731 -220.285056) (xy 281.004772 -220.285056) (xy 281.00428 -220.312013)
			(xy 280.99643 -220.365353) (xy 280.980898 -220.416982) (xy 280.958013 -220.465799) (xy 280.928265 -220.510763)
			(xy 280.892287 -220.550917) (xy 280.850845 -220.585405) (xy 280.804824 -220.613491) (xy 280.755204 -220.634578)
			(xy 280.703043 -220.648214) (xy 280.649452 -220.654111) (xy 280.595573 -220.652142) (xy 280.542555 -220.642349)
			(xy 280.491528 -220.624941) (xy 280.44358 -220.600289) (xy 280.399732 -220.568919) (xy 280.360919 -220.531498)
			(xy 280.327967 -220.488825) (xy 280.301581 -220.441808) (xy 280.282321 -220.391451) (xy 280.270598 -220.338827)
			(xy 280.266663 -220.285056) (xy 277.56104 -220.285056) (xy 277.560548 -220.312013) (xy 277.552698 -220.365353)
			(xy 277.537166 -220.416982) (xy 277.514281 -220.465799) (xy 277.484533 -220.510763) (xy 277.448555 -220.550917)
			(xy 277.407113 -220.585405) (xy 277.361092 -220.613491) (xy 277.311472 -220.634578) (xy 277.259311 -220.648214)
			(xy 277.20572 -220.654111) (xy 277.151841 -220.652142) (xy 277.098823 -220.642349) (xy 277.047796 -220.624941)
			(xy 276.999848 -220.600289) (xy 276.956 -220.568919) (xy 276.917187 -220.531498) (xy 276.884235 -220.488825)
			(xy 276.857849 -220.441808) (xy 276.838589 -220.391451) (xy 276.826866 -220.338827) (xy 276.822931 -220.285056)
			(xy 273.460972 -220.285056) (xy 273.46048 -220.312013) (xy 273.45263 -220.365353) (xy 273.437098 -220.416982)
			(xy 273.414213 -220.465799) (xy 273.384465 -220.510763) (xy 273.348487 -220.550917) (xy 273.307045 -220.585405)
			(xy 273.261024 -220.613491) (xy 273.211404 -220.634578) (xy 273.159243 -220.648214) (xy 273.105652 -220.654111)
			(xy 273.051773 -220.652142) (xy 272.998755 -220.642349) (xy 272.947728 -220.624941) (xy 272.89978 -220.600289)
			(xy 272.855932 -220.568919) (xy 272.817119 -220.531498) (xy 272.784167 -220.488825) (xy 272.757781 -220.441808)
			(xy 272.738521 -220.391451) (xy 272.726798 -220.338827) (xy 272.722863 -220.285056) (xy 270.016986 -220.285056)
			(xy 270.016494 -220.312013) (xy 270.008644 -220.365353) (xy 269.993112 -220.416982) (xy 269.970227 -220.465799)
			(xy 269.940479 -220.510763) (xy 269.904501 -220.550917) (xy 269.863059 -220.585405) (xy 269.817038 -220.613491)
			(xy 269.767418 -220.634578) (xy 269.715257 -220.648214) (xy 269.661666 -220.654111) (xy 269.607787 -220.652142)
			(xy 269.554769 -220.642349) (xy 269.503742 -220.624941) (xy 269.455794 -220.600289) (xy 269.411946 -220.568919)
			(xy 269.373133 -220.531498) (xy 269.340181 -220.488825) (xy 269.313795 -220.441808) (xy 269.294535 -220.391451)
			(xy 269.282812 -220.338827) (xy 269.278877 -220.285056) (xy 265.916918 -220.285056) (xy 265.916426 -220.312013)
			(xy 265.908576 -220.365353) (xy 265.893044 -220.416982) (xy 265.870159 -220.465799) (xy 265.840411 -220.510763)
			(xy 265.804433 -220.550917) (xy 265.762991 -220.585405) (xy 265.71697 -220.613491) (xy 265.66735 -220.634578)
			(xy 265.615189 -220.648214) (xy 265.561598 -220.654111) (xy 265.507719 -220.652142) (xy 265.454701 -220.642349)
			(xy 265.403674 -220.624941) (xy 265.355726 -220.600289) (xy 265.311878 -220.568919) (xy 265.273065 -220.531498)
			(xy 265.240113 -220.488825) (xy 265.213727 -220.441808) (xy 265.194467 -220.391451) (xy 265.182744 -220.338827)
			(xy 265.178809 -220.285056) (xy 264.143998 -220.285056) (xy 264.143998 -221.13494) (xy 265.178809 -221.13494)
			(xy 265.182744 -221.081169) (xy 265.194467 -221.028545) (xy 265.213727 -220.978188) (xy 265.240113 -220.931171)
			(xy 265.273065 -220.888498) (xy 265.311878 -220.851077) (xy 265.355726 -220.819707) (xy 265.403674 -220.795055)
			(xy 265.454701 -220.777647) (xy 265.507719 -220.767854) (xy 265.561598 -220.765885) (xy 265.615189 -220.771782)
			(xy 265.66735 -220.785418) (xy 265.71697 -220.806505) (xy 265.762991 -220.834591) (xy 265.804433 -220.869079)
			(xy 265.840411 -220.909233) (xy 265.870159 -220.954197) (xy 265.893044 -221.003014) (xy 265.908576 -221.054643)
			(xy 265.916426 -221.107983) (xy 265.916918 -221.13494) (xy 272.722863 -221.13494) (xy 272.726798 -221.081169)
			(xy 272.738521 -221.028545) (xy 272.757781 -220.978188) (xy 272.784167 -220.931171) (xy 272.817119 -220.888498)
			(xy 272.855932 -220.851077) (xy 272.89978 -220.819707) (xy 272.947728 -220.795055) (xy 272.998755 -220.777647)
			(xy 273.051773 -220.767854) (xy 273.105652 -220.765885) (xy 273.159243 -220.771782) (xy 273.211404 -220.785418)
			(xy 273.261024 -220.806505) (xy 273.307045 -220.834591) (xy 273.348487 -220.869079) (xy 273.384465 -220.909233)
			(xy 273.414213 -220.954197) (xy 273.437098 -221.003014) (xy 273.45263 -221.054643) (xy 273.46048 -221.107983)
			(xy 273.460972 -221.13494) (xy 280.266663 -221.13494) (xy 280.270598 -221.081169) (xy 280.282321 -221.028545)
			(xy 280.301581 -220.978188) (xy 280.327967 -220.931171) (xy 280.360919 -220.888498) (xy 280.399732 -220.851077)
			(xy 280.44358 -220.819707) (xy 280.491528 -220.795055) (xy 280.542555 -220.777647) (xy 280.595573 -220.767854)
			(xy 280.649452 -220.765885) (xy 280.703043 -220.771782) (xy 280.755204 -220.785418) (xy 280.804824 -220.806505)
			(xy 280.850845 -220.834591) (xy 280.892287 -220.869079) (xy 280.928265 -220.909233) (xy 280.958013 -220.954197)
			(xy 280.980898 -221.003014) (xy 280.99643 -221.054643) (xy 281.00428 -221.107983) (xy 281.004772 -221.13494)
			(xy 287.810717 -221.13494) (xy 287.814652 -221.081169) (xy 287.826375 -221.028545) (xy 287.845635 -220.978188)
			(xy 287.872021 -220.931171) (xy 287.904973 -220.888498) (xy 287.943786 -220.851077) (xy 287.987634 -220.819707)
			(xy 288.035582 -220.795055) (xy 288.086609 -220.777647) (xy 288.139627 -220.767854) (xy 288.193506 -220.765885)
			(xy 288.247097 -220.771782) (xy 288.299258 -220.785418) (xy 288.348878 -220.806505) (xy 288.394899 -220.834591)
			(xy 288.436341 -220.869079) (xy 288.472319 -220.909233) (xy 288.502067 -220.954197) (xy 288.524952 -221.003014)
			(xy 288.540484 -221.054643) (xy 288.548334 -221.107983) (xy 288.548826 -221.13494) (xy 288.548334 -221.161897)
			(xy 288.540484 -221.215237) (xy 288.524952 -221.266866) (xy 288.502067 -221.315683) (xy 288.472319 -221.360647)
			(xy 288.436341 -221.400801) (xy 288.394899 -221.435289) (xy 288.348878 -221.463375) (xy 288.299258 -221.484462)
			(xy 288.247097 -221.498098) (xy 288.193506 -221.503995) (xy 288.139627 -221.502026) (xy 288.086609 -221.492233)
			(xy 288.035582 -221.474825) (xy 287.987634 -221.450173) (xy 287.943786 -221.418803) (xy 287.904973 -221.381382)
			(xy 287.872021 -221.338709) (xy 287.845635 -221.291692) (xy 287.826375 -221.241335) (xy 287.814652 -221.188711)
			(xy 287.810717 -221.13494) (xy 281.004772 -221.13494) (xy 281.00428 -221.161897) (xy 280.99643 -221.215237)
			(xy 280.980898 -221.266866) (xy 280.958013 -221.315683) (xy 280.928265 -221.360647) (xy 280.892287 -221.400801)
			(xy 280.850845 -221.435289) (xy 280.804824 -221.463375) (xy 280.755204 -221.484462) (xy 280.703043 -221.498098)
			(xy 280.649452 -221.503995) (xy 280.595573 -221.502026) (xy 280.542555 -221.492233) (xy 280.491528 -221.474825)
			(xy 280.44358 -221.450173) (xy 280.399732 -221.418803) (xy 280.360919 -221.381382) (xy 280.327967 -221.338709)
			(xy 280.301581 -221.291692) (xy 280.282321 -221.241335) (xy 280.270598 -221.188711) (xy 280.266663 -221.13494)
			(xy 273.460972 -221.13494) (xy 273.46048 -221.161897) (xy 273.45263 -221.215237) (xy 273.437098 -221.266866)
			(xy 273.414213 -221.315683) (xy 273.384465 -221.360647) (xy 273.348487 -221.400801) (xy 273.307045 -221.435289)
			(xy 273.261024 -221.463375) (xy 273.211404 -221.484462) (xy 273.159243 -221.498098) (xy 273.105652 -221.503995)
			(xy 273.051773 -221.502026) (xy 272.998755 -221.492233) (xy 272.947728 -221.474825) (xy 272.89978 -221.450173)
			(xy 272.855932 -221.418803) (xy 272.817119 -221.381382) (xy 272.784167 -221.338709) (xy 272.757781 -221.291692)
			(xy 272.738521 -221.241335) (xy 272.726798 -221.188711) (xy 272.722863 -221.13494) (xy 265.916918 -221.13494)
			(xy 265.916426 -221.161897) (xy 265.908576 -221.215237) (xy 265.893044 -221.266866) (xy 265.870159 -221.315683)
			(xy 265.840411 -221.360647) (xy 265.804433 -221.400801) (xy 265.762991 -221.435289) (xy 265.71697 -221.463375)
			(xy 265.66735 -221.484462) (xy 265.615189 -221.498098) (xy 265.561598 -221.503995) (xy 265.507719 -221.502026)
			(xy 265.454701 -221.492233) (xy 265.403674 -221.474825) (xy 265.355726 -221.450173) (xy 265.311878 -221.418803)
			(xy 265.273065 -221.381382) (xy 265.240113 -221.338709) (xy 265.213727 -221.291692) (xy 265.194467 -221.241335)
			(xy 265.182744 -221.188711) (xy 265.178809 -221.13494) (xy 264.143998 -221.13494) (xy 264.143998 -221.985078)
			(xy 269.278877 -221.985078) (xy 269.282812 -221.931307) (xy 269.294535 -221.878683) (xy 269.313795 -221.828326)
			(xy 269.340181 -221.781309) (xy 269.373133 -221.738636) (xy 269.411946 -221.701215) (xy 269.455794 -221.669845)
			(xy 269.503742 -221.645193) (xy 269.554769 -221.627785) (xy 269.607787 -221.617992) (xy 269.661666 -221.616023)
			(xy 269.715257 -221.62192) (xy 269.767418 -221.635556) (xy 269.817038 -221.656643) (xy 269.863059 -221.684729)
			(xy 269.904501 -221.719217) (xy 269.940479 -221.759371) (xy 269.970227 -221.804335) (xy 269.993112 -221.853152)
			(xy 270.008644 -221.904781) (xy 270.016494 -221.958121) (xy 270.016986 -221.985078) (xy 276.822931 -221.985078)
			(xy 276.826866 -221.931307) (xy 276.838589 -221.878683) (xy 276.857849 -221.828326) (xy 276.884235 -221.781309)
			(xy 276.917187 -221.738636) (xy 276.956 -221.701215) (xy 276.999848 -221.669845) (xy 277.047796 -221.645193)
			(xy 277.098823 -221.627785) (xy 277.151841 -221.617992) (xy 277.20572 -221.616023) (xy 277.259311 -221.62192)
			(xy 277.311472 -221.635556) (xy 277.361092 -221.656643) (xy 277.407113 -221.684729) (xy 277.448555 -221.719217)
			(xy 277.484533 -221.759371) (xy 277.514281 -221.804335) (xy 277.537166 -221.853152) (xy 277.552698 -221.904781)
			(xy 277.560548 -221.958121) (xy 277.56104 -221.985078) (xy 284.366731 -221.985078) (xy 284.370666 -221.931307)
			(xy 284.382389 -221.878683) (xy 284.401649 -221.828326) (xy 284.428035 -221.781309) (xy 284.460987 -221.738636)
			(xy 284.4998 -221.701215) (xy 284.543648 -221.669845) (xy 284.591596 -221.645193) (xy 284.642623 -221.627785)
			(xy 284.695641 -221.617992) (xy 284.74952 -221.616023) (xy 284.803111 -221.62192) (xy 284.855272 -221.635556)
			(xy 284.904892 -221.656643) (xy 284.950913 -221.684729) (xy 284.992355 -221.719217) (xy 285.028333 -221.759371)
			(xy 285.058081 -221.804335) (xy 285.080966 -221.853152) (xy 285.096498 -221.904781) (xy 285.104348 -221.958121)
			(xy 285.10484 -221.985078) (xy 291.910785 -221.985078) (xy 291.91472 -221.931307) (xy 291.926443 -221.878683)
			(xy 291.945703 -221.828326) (xy 291.972089 -221.781309) (xy 292.005041 -221.738636) (xy 292.043854 -221.701215)
			(xy 292.087702 -221.669845) (xy 292.13565 -221.645193) (xy 292.186677 -221.627785) (xy 292.239695 -221.617992)
			(xy 292.293574 -221.616023) (xy 292.347165 -221.62192) (xy 292.399326 -221.635556) (xy 292.448946 -221.656643)
			(xy 292.494967 -221.684729) (xy 292.536409 -221.719217) (xy 292.572387 -221.759371) (xy 292.602135 -221.804335)
			(xy 292.62502 -221.853152) (xy 292.640552 -221.904781) (xy 292.648402 -221.958121) (xy 292.648894 -221.985078)
			(xy 292.648402 -222.012035) (xy 292.640552 -222.065375) (xy 292.62502 -222.117004) (xy 292.602135 -222.165821)
			(xy 292.572387 -222.210785) (xy 292.536409 -222.250939) (xy 292.494967 -222.285427) (xy 292.448946 -222.313513)
			(xy 292.399326 -222.3346) (xy 292.347165 -222.348236) (xy 292.293574 -222.354133) (xy 292.239695 -222.352164)
			(xy 292.186677 -222.342371) (xy 292.13565 -222.324963) (xy 292.087702 -222.300311) (xy 292.043854 -222.268941)
			(xy 292.005041 -222.23152) (xy 291.972089 -222.188847) (xy 291.945703 -222.14183) (xy 291.926443 -222.091473)
			(xy 291.91472 -222.038849) (xy 291.910785 -221.985078) (xy 285.10484 -221.985078) (xy 285.104348 -222.012035)
			(xy 285.096498 -222.065375) (xy 285.080966 -222.117004) (xy 285.058081 -222.165821) (xy 285.028333 -222.210785)
			(xy 284.992355 -222.250939) (xy 284.950913 -222.285427) (xy 284.904892 -222.313513) (xy 284.855272 -222.3346)
			(xy 284.803111 -222.348236) (xy 284.74952 -222.354133) (xy 284.695641 -222.352164) (xy 284.642623 -222.342371)
			(xy 284.591596 -222.324963) (xy 284.543648 -222.300311) (xy 284.4998 -222.268941) (xy 284.460987 -222.23152)
			(xy 284.428035 -222.188847) (xy 284.401649 -222.14183) (xy 284.382389 -222.091473) (xy 284.370666 -222.038849)
			(xy 284.366731 -221.985078) (xy 277.56104 -221.985078) (xy 277.560548 -222.012035) (xy 277.552698 -222.065375)
			(xy 277.537166 -222.117004) (xy 277.514281 -222.165821) (xy 277.484533 -222.210785) (xy 277.448555 -222.250939)
			(xy 277.407113 -222.285427) (xy 277.361092 -222.313513) (xy 277.311472 -222.3346) (xy 277.259311 -222.348236)
			(xy 277.20572 -222.354133) (xy 277.151841 -222.352164) (xy 277.098823 -222.342371) (xy 277.047796 -222.324963)
			(xy 276.999848 -222.300311) (xy 276.956 -222.268941) (xy 276.917187 -222.23152) (xy 276.884235 -222.188847)
			(xy 276.857849 -222.14183) (xy 276.838589 -222.091473) (xy 276.826866 -222.038849) (xy 276.822931 -221.985078)
			(xy 270.016986 -221.985078) (xy 270.016494 -222.012035) (xy 270.008644 -222.065375) (xy 269.993112 -222.117004)
			(xy 269.970227 -222.165821) (xy 269.940479 -222.210785) (xy 269.904501 -222.250939) (xy 269.863059 -222.285427)
			(xy 269.817038 -222.313513) (xy 269.767418 -222.3346) (xy 269.715257 -222.348236) (xy 269.661666 -222.354133)
			(xy 269.607787 -222.352164) (xy 269.554769 -222.342371) (xy 269.503742 -222.324963) (xy 269.455794 -222.300311)
			(xy 269.411946 -222.268941) (xy 269.373133 -222.23152) (xy 269.340181 -222.188847) (xy 269.313795 -222.14183)
			(xy 269.294535 -222.091473) (xy 269.282812 -222.038849) (xy 269.278877 -221.985078) (xy 264.143998 -221.985078)
			(xy 264.143998 -222.834962) (xy 265.178809 -222.834962) (xy 265.182744 -222.781191) (xy 265.194467 -222.728567)
			(xy 265.213727 -222.67821) (xy 265.240113 -222.631193) (xy 265.273065 -222.58852) (xy 265.311878 -222.551099)
			(xy 265.355726 -222.519729) (xy 265.403674 -222.495077) (xy 265.454701 -222.477669) (xy 265.507719 -222.467876)
			(xy 265.561598 -222.465907) (xy 265.615189 -222.471804) (xy 265.66735 -222.48544) (xy 265.71697 -222.506527)
			(xy 265.762991 -222.534613) (xy 265.804433 -222.569101) (xy 265.840411 -222.609255) (xy 265.870159 -222.654219)
			(xy 265.893044 -222.703036) (xy 265.908576 -222.754665) (xy 265.916426 -222.808005) (xy 265.916918 -222.834962)
			(xy 272.722863 -222.834962) (xy 272.726798 -222.781191) (xy 272.738521 -222.728567) (xy 272.757781 -222.67821)
			(xy 272.784167 -222.631193) (xy 272.817119 -222.58852) (xy 272.855932 -222.551099) (xy 272.89978 -222.519729)
			(xy 272.947728 -222.495077) (xy 272.998755 -222.477669) (xy 273.051773 -222.467876) (xy 273.105652 -222.465907)
			(xy 273.159243 -222.471804) (xy 273.211404 -222.48544) (xy 273.261024 -222.506527) (xy 273.307045 -222.534613)
			(xy 273.348487 -222.569101) (xy 273.384465 -222.609255) (xy 273.414213 -222.654219) (xy 273.437098 -222.703036)
			(xy 273.45263 -222.754665) (xy 273.46048 -222.808005) (xy 273.460972 -222.834962) (xy 280.266663 -222.834962)
			(xy 280.270598 -222.781191) (xy 280.282321 -222.728567) (xy 280.301581 -222.67821) (xy 280.327967 -222.631193)
			(xy 280.360919 -222.58852) (xy 280.399732 -222.551099) (xy 280.44358 -222.519729) (xy 280.491528 -222.495077)
			(xy 280.542555 -222.477669) (xy 280.595573 -222.467876) (xy 280.649452 -222.465907) (xy 280.703043 -222.471804)
			(xy 280.755204 -222.48544) (xy 280.804824 -222.506527) (xy 280.850845 -222.534613) (xy 280.892287 -222.569101)
			(xy 280.928265 -222.609255) (xy 280.958013 -222.654219) (xy 280.980898 -222.703036) (xy 280.99643 -222.754665)
			(xy 281.00428 -222.808005) (xy 281.004772 -222.834962) (xy 287.810717 -222.834962) (xy 287.814652 -222.781191)
			(xy 287.826375 -222.728567) (xy 287.845635 -222.67821) (xy 287.872021 -222.631193) (xy 287.904973 -222.58852)
			(xy 287.943786 -222.551099) (xy 287.987634 -222.519729) (xy 288.035582 -222.495077) (xy 288.086609 -222.477669)
			(xy 288.139627 -222.467876) (xy 288.193506 -222.465907) (xy 288.247097 -222.471804) (xy 288.299258 -222.48544)
			(xy 288.348878 -222.506527) (xy 288.394899 -222.534613) (xy 288.436341 -222.569101) (xy 288.472319 -222.609255)
			(xy 288.502067 -222.654219) (xy 288.524952 -222.703036) (xy 288.540484 -222.754665) (xy 288.548334 -222.808005)
			(xy 288.548826 -222.834962) (xy 288.548334 -222.861919) (xy 288.540484 -222.915259) (xy 288.524952 -222.966888)
			(xy 288.502067 -223.015705) (xy 288.472319 -223.060669) (xy 288.436341 -223.100823) (xy 288.394899 -223.135311)
			(xy 288.348878 -223.163397) (xy 288.299258 -223.184484) (xy 288.247097 -223.19812) (xy 288.193506 -223.204017)
			(xy 288.139627 -223.202048) (xy 288.086609 -223.192255) (xy 288.035582 -223.174847) (xy 287.987634 -223.150195)
			(xy 287.943786 -223.118825) (xy 287.904973 -223.081404) (xy 287.872021 -223.038731) (xy 287.845635 -222.991714)
			(xy 287.826375 -222.941357) (xy 287.814652 -222.888733) (xy 287.810717 -222.834962) (xy 281.004772 -222.834962)
			(xy 281.00428 -222.861919) (xy 280.99643 -222.915259) (xy 280.980898 -222.966888) (xy 280.958013 -223.015705)
			(xy 280.928265 -223.060669) (xy 280.892287 -223.100823) (xy 280.850845 -223.135311) (xy 280.804824 -223.163397)
			(xy 280.755204 -223.184484) (xy 280.703043 -223.19812) (xy 280.649452 -223.204017) (xy 280.595573 -223.202048)
			(xy 280.542555 -223.192255) (xy 280.491528 -223.174847) (xy 280.44358 -223.150195) (xy 280.399732 -223.118825)
			(xy 280.360919 -223.081404) (xy 280.327967 -223.038731) (xy 280.301581 -222.991714) (xy 280.282321 -222.941357)
			(xy 280.270598 -222.888733) (xy 280.266663 -222.834962) (xy 273.460972 -222.834962) (xy 273.46048 -222.861919)
			(xy 273.45263 -222.915259) (xy 273.437098 -222.966888) (xy 273.414213 -223.015705) (xy 273.384465 -223.060669)
			(xy 273.348487 -223.100823) (xy 273.307045 -223.135311) (xy 273.261024 -223.163397) (xy 273.211404 -223.184484)
			(xy 273.159243 -223.19812) (xy 273.105652 -223.204017) (xy 273.051773 -223.202048) (xy 272.998755 -223.192255)
			(xy 272.947728 -223.174847) (xy 272.89978 -223.150195) (xy 272.855932 -223.118825) (xy 272.817119 -223.081404)
			(xy 272.784167 -223.038731) (xy 272.757781 -222.991714) (xy 272.738521 -222.941357) (xy 272.726798 -222.888733)
			(xy 272.722863 -222.834962) (xy 265.916918 -222.834962) (xy 265.916426 -222.861919) (xy 265.908576 -222.915259)
			(xy 265.893044 -222.966888) (xy 265.870159 -223.015705) (xy 265.840411 -223.060669) (xy 265.804433 -223.100823)
			(xy 265.762991 -223.135311) (xy 265.71697 -223.163397) (xy 265.66735 -223.184484) (xy 265.615189 -223.19812)
			(xy 265.561598 -223.204017) (xy 265.507719 -223.202048) (xy 265.454701 -223.192255) (xy 265.403674 -223.174847)
			(xy 265.355726 -223.150195) (xy 265.311878 -223.118825) (xy 265.273065 -223.081404) (xy 265.240113 -223.038731)
			(xy 265.213727 -222.991714) (xy 265.194467 -222.941357) (xy 265.182744 -222.888733) (xy 265.178809 -222.834962)
			(xy 264.143998 -222.834962) (xy 264.143998 -223.6851) (xy 269.278877 -223.6851) (xy 269.282812 -223.631329)
			(xy 269.294535 -223.578705) (xy 269.313795 -223.528348) (xy 269.340181 -223.481331) (xy 269.373133 -223.438658)
			(xy 269.411946 -223.401237) (xy 269.455794 -223.369867) (xy 269.503742 -223.345215) (xy 269.554769 -223.327807)
			(xy 269.607787 -223.318014) (xy 269.661666 -223.316045) (xy 269.715257 -223.321942) (xy 269.767418 -223.335578)
			(xy 269.817038 -223.356665) (xy 269.863059 -223.384751) (xy 269.904501 -223.419239) (xy 269.940479 -223.459393)
			(xy 269.970227 -223.504357) (xy 269.993112 -223.553174) (xy 270.008644 -223.604803) (xy 270.016494 -223.658143)
			(xy 270.016986 -223.6851) (xy 276.822931 -223.6851) (xy 276.826866 -223.631329) (xy 276.838589 -223.578705)
			(xy 276.857849 -223.528348) (xy 276.884235 -223.481331) (xy 276.917187 -223.438658) (xy 276.956 -223.401237)
			(xy 276.999848 -223.369867) (xy 277.047796 -223.345215) (xy 277.098823 -223.327807) (xy 277.151841 -223.318014)
			(xy 277.20572 -223.316045) (xy 277.259311 -223.321942) (xy 277.311472 -223.335578) (xy 277.361092 -223.356665)
			(xy 277.407113 -223.384751) (xy 277.448555 -223.419239) (xy 277.484533 -223.459393) (xy 277.514281 -223.504357)
			(xy 277.537166 -223.553174) (xy 277.552698 -223.604803) (xy 277.560548 -223.658143) (xy 277.56104 -223.6851)
			(xy 284.366731 -223.6851) (xy 284.370666 -223.631329) (xy 284.382389 -223.578705) (xy 284.401649 -223.528348)
			(xy 284.428035 -223.481331) (xy 284.460987 -223.438658) (xy 284.4998 -223.401237) (xy 284.543648 -223.369867)
			(xy 284.591596 -223.345215) (xy 284.642623 -223.327807) (xy 284.695641 -223.318014) (xy 284.74952 -223.316045)
			(xy 284.803111 -223.321942) (xy 284.855272 -223.335578) (xy 284.904892 -223.356665) (xy 284.950913 -223.384751)
			(xy 284.992355 -223.419239) (xy 285.028333 -223.459393) (xy 285.058081 -223.504357) (xy 285.080966 -223.553174)
			(xy 285.096498 -223.604803) (xy 285.104348 -223.658143) (xy 285.10484 -223.6851) (xy 291.910785 -223.6851)
			(xy 291.91472 -223.631329) (xy 291.926443 -223.578705) (xy 291.945703 -223.528348) (xy 291.972089 -223.481331)
			(xy 292.005041 -223.438658) (xy 292.043854 -223.401237) (xy 292.087702 -223.369867) (xy 292.13565 -223.345215)
			(xy 292.186677 -223.327807) (xy 292.239695 -223.318014) (xy 292.293574 -223.316045) (xy 292.347165 -223.321942)
			(xy 292.399326 -223.335578) (xy 292.448946 -223.356665) (xy 292.494967 -223.384751) (xy 292.536409 -223.419239)
			(xy 292.572387 -223.459393) (xy 292.602135 -223.504357) (xy 292.62502 -223.553174) (xy 292.640552 -223.604803)
			(xy 292.648402 -223.658143) (xy 292.648894 -223.6851) (xy 292.648402 -223.712057) (xy 292.640552 -223.765397)
			(xy 292.62502 -223.817026) (xy 292.602135 -223.865843) (xy 292.572387 -223.910807) (xy 292.536409 -223.950961)
			(xy 292.494967 -223.985449) (xy 292.448946 -224.013535) (xy 292.399326 -224.034622) (xy 292.347165 -224.048258)
			(xy 292.293574 -224.054155) (xy 292.239695 -224.052186) (xy 292.186677 -224.042393) (xy 292.13565 -224.024985)
			(xy 292.087702 -224.000333) (xy 292.043854 -223.968963) (xy 292.005041 -223.931542) (xy 291.972089 -223.888869)
			(xy 291.945703 -223.841852) (xy 291.926443 -223.791495) (xy 291.91472 -223.738871) (xy 291.910785 -223.6851)
			(xy 285.10484 -223.6851) (xy 285.104348 -223.712057) (xy 285.096498 -223.765397) (xy 285.080966 -223.817026)
			(xy 285.058081 -223.865843) (xy 285.028333 -223.910807) (xy 284.992355 -223.950961) (xy 284.950913 -223.985449)
			(xy 284.904892 -224.013535) (xy 284.855272 -224.034622) (xy 284.803111 -224.048258) (xy 284.74952 -224.054155)
			(xy 284.695641 -224.052186) (xy 284.642623 -224.042393) (xy 284.591596 -224.024985) (xy 284.543648 -224.000333)
			(xy 284.4998 -223.968963) (xy 284.460987 -223.931542) (xy 284.428035 -223.888869) (xy 284.401649 -223.841852)
			(xy 284.382389 -223.791495) (xy 284.370666 -223.738871) (xy 284.366731 -223.6851) (xy 277.56104 -223.6851)
			(xy 277.560548 -223.712057) (xy 277.552698 -223.765397) (xy 277.537166 -223.817026) (xy 277.514281 -223.865843)
			(xy 277.484533 -223.910807) (xy 277.448555 -223.950961) (xy 277.407113 -223.985449) (xy 277.361092 -224.013535)
			(xy 277.311472 -224.034622) (xy 277.259311 -224.048258) (xy 277.20572 -224.054155) (xy 277.151841 -224.052186)
			(xy 277.098823 -224.042393) (xy 277.047796 -224.024985) (xy 276.999848 -224.000333) (xy 276.956 -223.968963)
			(xy 276.917187 -223.931542) (xy 276.884235 -223.888869) (xy 276.857849 -223.841852) (xy 276.838589 -223.791495)
			(xy 276.826866 -223.738871) (xy 276.822931 -223.6851) (xy 270.016986 -223.6851) (xy 270.016494 -223.712057)
			(xy 270.008644 -223.765397) (xy 269.993112 -223.817026) (xy 269.970227 -223.865843) (xy 269.940479 -223.910807)
			(xy 269.904501 -223.950961) (xy 269.863059 -223.985449) (xy 269.817038 -224.013535) (xy 269.767418 -224.034622)
			(xy 269.715257 -224.048258) (xy 269.661666 -224.054155) (xy 269.607787 -224.052186) (xy 269.554769 -224.042393)
			(xy 269.503742 -224.024985) (xy 269.455794 -224.000333) (xy 269.411946 -223.968963) (xy 269.373133 -223.931542)
			(xy 269.340181 -223.888869) (xy 269.313795 -223.841852) (xy 269.294535 -223.791495) (xy 269.282812 -223.738871)
			(xy 269.278877 -223.6851) (xy 264.143998 -223.6851) (xy 264.143998 -224.534984) (xy 265.178809 -224.534984)
			(xy 265.182744 -224.481213) (xy 265.194467 -224.428589) (xy 265.213727 -224.378232) (xy 265.240113 -224.331215)
			(xy 265.273065 -224.288542) (xy 265.311878 -224.251121) (xy 265.355726 -224.219751) (xy 265.403674 -224.195099)
			(xy 265.454701 -224.177691) (xy 265.507719 -224.167898) (xy 265.561598 -224.165929) (xy 265.615189 -224.171826)
			(xy 265.66735 -224.185462) (xy 265.71697 -224.206549) (xy 265.762991 -224.234635) (xy 265.804433 -224.269123)
			(xy 265.840411 -224.309277) (xy 265.870159 -224.354241) (xy 265.893044 -224.403058) (xy 265.908576 -224.454687)
			(xy 265.916426 -224.508027) (xy 265.916918 -224.534984) (xy 272.722863 -224.534984) (xy 272.726798 -224.481213)
			(xy 272.738521 -224.428589) (xy 272.757781 -224.378232) (xy 272.784167 -224.331215) (xy 272.817119 -224.288542)
			(xy 272.855932 -224.251121) (xy 272.89978 -224.219751) (xy 272.947728 -224.195099) (xy 272.998755 -224.177691)
			(xy 273.051773 -224.167898) (xy 273.105652 -224.165929) (xy 273.159243 -224.171826) (xy 273.211404 -224.185462)
			(xy 273.261024 -224.206549) (xy 273.307045 -224.234635) (xy 273.348487 -224.269123) (xy 273.384465 -224.309277)
			(xy 273.414213 -224.354241) (xy 273.437098 -224.403058) (xy 273.45263 -224.454687) (xy 273.46048 -224.508027)
			(xy 273.460972 -224.534984) (xy 280.266663 -224.534984) (xy 280.270598 -224.481213) (xy 280.282321 -224.428589)
			(xy 280.301581 -224.378232) (xy 280.327967 -224.331215) (xy 280.360919 -224.288542) (xy 280.399732 -224.251121)
			(xy 280.44358 -224.219751) (xy 280.491528 -224.195099) (xy 280.542555 -224.177691) (xy 280.595573 -224.167898)
			(xy 280.649452 -224.165929) (xy 280.703043 -224.171826) (xy 280.755204 -224.185462) (xy 280.804824 -224.206549)
			(xy 280.850845 -224.234635) (xy 280.892287 -224.269123) (xy 280.928265 -224.309277) (xy 280.958013 -224.354241)
			(xy 280.980898 -224.403058) (xy 280.99643 -224.454687) (xy 281.00428 -224.508027) (xy 281.004772 -224.534984)
			(xy 287.810717 -224.534984) (xy 287.814652 -224.481213) (xy 287.826375 -224.428589) (xy 287.845635 -224.378232)
			(xy 287.872021 -224.331215) (xy 287.904973 -224.288542) (xy 287.943786 -224.251121) (xy 287.987634 -224.219751)
			(xy 288.035582 -224.195099) (xy 288.086609 -224.177691) (xy 288.139627 -224.167898) (xy 288.193506 -224.165929)
			(xy 288.247097 -224.171826) (xy 288.299258 -224.185462) (xy 288.348878 -224.206549) (xy 288.394899 -224.234635)
			(xy 288.436341 -224.269123) (xy 288.472319 -224.309277) (xy 288.502067 -224.354241) (xy 288.524952 -224.403058)
			(xy 288.540484 -224.454687) (xy 288.548334 -224.508027) (xy 288.548826 -224.534984) (xy 288.548334 -224.561941)
			(xy 288.540484 -224.615281) (xy 288.524952 -224.66691) (xy 288.502067 -224.715727) (xy 288.472319 -224.760691)
			(xy 288.436341 -224.800845) (xy 288.394899 -224.835333) (xy 288.348878 -224.863419) (xy 288.299258 -224.884506)
			(xy 288.247097 -224.898142) (xy 288.193506 -224.904039) (xy 288.139627 -224.90207) (xy 288.086609 -224.892277)
			(xy 288.035582 -224.874869) (xy 287.987634 -224.850217) (xy 287.943786 -224.818847) (xy 287.904973 -224.781426)
			(xy 287.872021 -224.738753) (xy 287.845635 -224.691736) (xy 287.826375 -224.641379) (xy 287.814652 -224.588755)
			(xy 287.810717 -224.534984) (xy 281.004772 -224.534984) (xy 281.00428 -224.561941) (xy 280.99643 -224.615281)
			(xy 280.980898 -224.66691) (xy 280.958013 -224.715727) (xy 280.928265 -224.760691) (xy 280.892287 -224.800845)
			(xy 280.850845 -224.835333) (xy 280.804824 -224.863419) (xy 280.755204 -224.884506) (xy 280.703043 -224.898142)
			(xy 280.649452 -224.904039) (xy 280.595573 -224.90207) (xy 280.542555 -224.892277) (xy 280.491528 -224.874869)
			(xy 280.44358 -224.850217) (xy 280.399732 -224.818847) (xy 280.360919 -224.781426) (xy 280.327967 -224.738753)
			(xy 280.301581 -224.691736) (xy 280.282321 -224.641379) (xy 280.270598 -224.588755) (xy 280.266663 -224.534984)
			(xy 273.460972 -224.534984) (xy 273.46048 -224.561941) (xy 273.45263 -224.615281) (xy 273.437098 -224.66691)
			(xy 273.414213 -224.715727) (xy 273.384465 -224.760691) (xy 273.348487 -224.800845) (xy 273.307045 -224.835333)
			(xy 273.261024 -224.863419) (xy 273.211404 -224.884506) (xy 273.159243 -224.898142) (xy 273.105652 -224.904039)
			(xy 273.051773 -224.90207) (xy 272.998755 -224.892277) (xy 272.947728 -224.874869) (xy 272.89978 -224.850217)
			(xy 272.855932 -224.818847) (xy 272.817119 -224.781426) (xy 272.784167 -224.738753) (xy 272.757781 -224.691736)
			(xy 272.738521 -224.641379) (xy 272.726798 -224.588755) (xy 272.722863 -224.534984) (xy 265.916918 -224.534984)
			(xy 265.916426 -224.561941) (xy 265.908576 -224.615281) (xy 265.893044 -224.66691) (xy 265.870159 -224.715727)
			(xy 265.840411 -224.760691) (xy 265.804433 -224.800845) (xy 265.762991 -224.835333) (xy 265.71697 -224.863419)
			(xy 265.66735 -224.884506) (xy 265.615189 -224.898142) (xy 265.561598 -224.904039) (xy 265.507719 -224.90207)
			(xy 265.454701 -224.892277) (xy 265.403674 -224.874869) (xy 265.355726 -224.850217) (xy 265.311878 -224.818847)
			(xy 265.273065 -224.781426) (xy 265.240113 -224.738753) (xy 265.213727 -224.691736) (xy 265.194467 -224.641379)
			(xy 265.182744 -224.588755) (xy 265.178809 -224.534984) (xy 264.143998 -224.534984) (xy 264.143998 -225.385122)
			(xy 269.278877 -225.385122) (xy 269.282812 -225.331351) (xy 269.294535 -225.278727) (xy 269.313795 -225.22837)
			(xy 269.340181 -225.181353) (xy 269.373133 -225.13868) (xy 269.411946 -225.101259) (xy 269.455794 -225.069889)
			(xy 269.503742 -225.045237) (xy 269.554769 -225.027829) (xy 269.607787 -225.018036) (xy 269.661666 -225.016067)
			(xy 269.715257 -225.021964) (xy 269.767418 -225.0356) (xy 269.817038 -225.056687) (xy 269.863059 -225.084773)
			(xy 269.904501 -225.119261) (xy 269.940479 -225.159415) (xy 269.970227 -225.204379) (xy 269.993112 -225.253196)
			(xy 270.008644 -225.304825) (xy 270.016494 -225.358165) (xy 270.016986 -225.385122) (xy 276.822931 -225.385122)
			(xy 276.826866 -225.331351) (xy 276.838589 -225.278727) (xy 276.857849 -225.22837) (xy 276.884235 -225.181353)
			(xy 276.917187 -225.13868) (xy 276.956 -225.101259) (xy 276.999848 -225.069889) (xy 277.047796 -225.045237)
			(xy 277.098823 -225.027829) (xy 277.151841 -225.018036) (xy 277.20572 -225.016067) (xy 277.259311 -225.021964)
			(xy 277.311472 -225.0356) (xy 277.361092 -225.056687) (xy 277.407113 -225.084773) (xy 277.448555 -225.119261)
			(xy 277.484533 -225.159415) (xy 277.514281 -225.204379) (xy 277.537166 -225.253196) (xy 277.552698 -225.304825)
			(xy 277.560548 -225.358165) (xy 277.56104 -225.385122) (xy 284.366731 -225.385122) (xy 284.370666 -225.331351)
			(xy 284.382389 -225.278727) (xy 284.401649 -225.22837) (xy 284.428035 -225.181353) (xy 284.460987 -225.13868)
			(xy 284.4998 -225.101259) (xy 284.543648 -225.069889) (xy 284.591596 -225.045237) (xy 284.642623 -225.027829)
			(xy 284.695641 -225.018036) (xy 284.74952 -225.016067) (xy 284.803111 -225.021964) (xy 284.855272 -225.0356)
			(xy 284.904892 -225.056687) (xy 284.950913 -225.084773) (xy 284.992355 -225.119261) (xy 285.028333 -225.159415)
			(xy 285.058081 -225.204379) (xy 285.080966 -225.253196) (xy 285.096498 -225.304825) (xy 285.104348 -225.358165)
			(xy 285.10484 -225.385122) (xy 291.910785 -225.385122) (xy 291.91472 -225.331351) (xy 291.926443 -225.278727)
			(xy 291.945703 -225.22837) (xy 291.972089 -225.181353) (xy 292.005041 -225.13868) (xy 292.043854 -225.101259)
			(xy 292.087702 -225.069889) (xy 292.13565 -225.045237) (xy 292.186677 -225.027829) (xy 292.239695 -225.018036)
			(xy 292.293574 -225.016067) (xy 292.347165 -225.021964) (xy 292.399326 -225.0356) (xy 292.448946 -225.056687)
			(xy 292.494967 -225.084773) (xy 292.536409 -225.119261) (xy 292.572387 -225.159415) (xy 292.602135 -225.204379)
			(xy 292.62502 -225.253196) (xy 292.640552 -225.304825) (xy 292.648402 -225.358165) (xy 292.648894 -225.385122)
			(xy 292.648402 -225.412079) (xy 292.640552 -225.465419) (xy 292.62502 -225.517048) (xy 292.602135 -225.565865)
			(xy 292.572387 -225.610829) (xy 292.536409 -225.650983) (xy 292.494967 -225.685471) (xy 292.448946 -225.713557)
			(xy 292.399326 -225.734644) (xy 292.347165 -225.74828) (xy 292.293574 -225.754177) (xy 292.239695 -225.752208)
			(xy 292.186677 -225.742415) (xy 292.13565 -225.725007) (xy 292.087702 -225.700355) (xy 292.043854 -225.668985)
			(xy 292.005041 -225.631564) (xy 291.972089 -225.588891) (xy 291.945703 -225.541874) (xy 291.926443 -225.491517)
			(xy 291.91472 -225.438893) (xy 291.910785 -225.385122) (xy 285.10484 -225.385122) (xy 285.104348 -225.412079)
			(xy 285.096498 -225.465419) (xy 285.080966 -225.517048) (xy 285.058081 -225.565865) (xy 285.028333 -225.610829)
			(xy 284.992355 -225.650983) (xy 284.950913 -225.685471) (xy 284.904892 -225.713557) (xy 284.855272 -225.734644)
			(xy 284.803111 -225.74828) (xy 284.74952 -225.754177) (xy 284.695641 -225.752208) (xy 284.642623 -225.742415)
			(xy 284.591596 -225.725007) (xy 284.543648 -225.700355) (xy 284.4998 -225.668985) (xy 284.460987 -225.631564)
			(xy 284.428035 -225.588891) (xy 284.401649 -225.541874) (xy 284.382389 -225.491517) (xy 284.370666 -225.438893)
			(xy 284.366731 -225.385122) (xy 277.56104 -225.385122) (xy 277.560548 -225.412079) (xy 277.552698 -225.465419)
			(xy 277.537166 -225.517048) (xy 277.514281 -225.565865) (xy 277.484533 -225.610829) (xy 277.448555 -225.650983)
			(xy 277.407113 -225.685471) (xy 277.361092 -225.713557) (xy 277.311472 -225.734644) (xy 277.259311 -225.74828)
			(xy 277.20572 -225.754177) (xy 277.151841 -225.752208) (xy 277.098823 -225.742415) (xy 277.047796 -225.725007)
			(xy 276.999848 -225.700355) (xy 276.956 -225.668985) (xy 276.917187 -225.631564) (xy 276.884235 -225.588891)
			(xy 276.857849 -225.541874) (xy 276.838589 -225.491517) (xy 276.826866 -225.438893) (xy 276.822931 -225.385122)
			(xy 270.016986 -225.385122) (xy 270.016494 -225.412079) (xy 270.008644 -225.465419) (xy 269.993112 -225.517048)
			(xy 269.970227 -225.565865) (xy 269.940479 -225.610829) (xy 269.904501 -225.650983) (xy 269.863059 -225.685471)
			(xy 269.817038 -225.713557) (xy 269.767418 -225.734644) (xy 269.715257 -225.74828) (xy 269.661666 -225.754177)
			(xy 269.607787 -225.752208) (xy 269.554769 -225.742415) (xy 269.503742 -225.725007) (xy 269.455794 -225.700355)
			(xy 269.411946 -225.668985) (xy 269.373133 -225.631564) (xy 269.340181 -225.588891) (xy 269.313795 -225.541874)
			(xy 269.294535 -225.491517) (xy 269.282812 -225.438893) (xy 269.278877 -225.385122) (xy 264.143998 -225.385122)
			(xy 264.143998 -226.235006) (xy 265.178809 -226.235006) (xy 265.182744 -226.181235) (xy 265.194467 -226.128611)
			(xy 265.213727 -226.078254) (xy 265.240113 -226.031237) (xy 265.273065 -225.988564) (xy 265.311878 -225.951143)
			(xy 265.355726 -225.919773) (xy 265.403674 -225.895121) (xy 265.454701 -225.877713) (xy 265.507719 -225.86792)
			(xy 265.561598 -225.865951) (xy 265.615189 -225.871848) (xy 265.66735 -225.885484) (xy 265.71697 -225.906571)
			(xy 265.762991 -225.934657) (xy 265.804433 -225.969145) (xy 265.840411 -226.009299) (xy 265.870159 -226.054263)
			(xy 265.893044 -226.10308) (xy 265.908576 -226.154709) (xy 265.916426 -226.208049) (xy 265.916918 -226.235006)
			(xy 272.722863 -226.235006) (xy 272.726798 -226.181235) (xy 272.738521 -226.128611) (xy 272.757781 -226.078254)
			(xy 272.784167 -226.031237) (xy 272.817119 -225.988564) (xy 272.855932 -225.951143) (xy 272.89978 -225.919773)
			(xy 272.947728 -225.895121) (xy 272.998755 -225.877713) (xy 273.051773 -225.86792) (xy 273.105652 -225.865951)
			(xy 273.159243 -225.871848) (xy 273.211404 -225.885484) (xy 273.261024 -225.906571) (xy 273.307045 -225.934657)
			(xy 273.348487 -225.969145) (xy 273.384465 -226.009299) (xy 273.414213 -226.054263) (xy 273.437098 -226.10308)
			(xy 273.45263 -226.154709) (xy 273.46048 -226.208049) (xy 273.460972 -226.235006) (xy 280.266663 -226.235006)
			(xy 280.270598 -226.181235) (xy 280.282321 -226.128611) (xy 280.301581 -226.078254) (xy 280.327967 -226.031237)
			(xy 280.360919 -225.988564) (xy 280.399732 -225.951143) (xy 280.44358 -225.919773) (xy 280.491528 -225.895121)
			(xy 280.542555 -225.877713) (xy 280.595573 -225.86792) (xy 280.649452 -225.865951) (xy 280.703043 -225.871848)
			(xy 280.755204 -225.885484) (xy 280.804824 -225.906571) (xy 280.850845 -225.934657) (xy 280.892287 -225.969145)
			(xy 280.928265 -226.009299) (xy 280.958013 -226.054263) (xy 280.980898 -226.10308) (xy 280.99643 -226.154709)
			(xy 281.00428 -226.208049) (xy 281.004772 -226.235006) (xy 287.810717 -226.235006) (xy 287.814652 -226.181235)
			(xy 287.826375 -226.128611) (xy 287.845635 -226.078254) (xy 287.872021 -226.031237) (xy 287.904973 -225.988564)
			(xy 287.943786 -225.951143) (xy 287.987634 -225.919773) (xy 288.035582 -225.895121) (xy 288.086609 -225.877713)
			(xy 288.139627 -225.86792) (xy 288.193506 -225.865951) (xy 288.247097 -225.871848) (xy 288.299258 -225.885484)
			(xy 288.348878 -225.906571) (xy 288.394899 -225.934657) (xy 288.436341 -225.969145) (xy 288.472319 -226.009299)
			(xy 288.502067 -226.054263) (xy 288.524952 -226.10308) (xy 288.540484 -226.154709) (xy 288.548334 -226.208049)
			(xy 288.548826 -226.235006) (xy 288.548334 -226.261963) (xy 288.540484 -226.315303) (xy 288.524952 -226.366932)
			(xy 288.502067 -226.415749) (xy 288.472319 -226.460713) (xy 288.436341 -226.500867) (xy 288.394899 -226.535355)
			(xy 288.348878 -226.563441) (xy 288.299258 -226.584528) (xy 288.247097 -226.598164) (xy 288.193506 -226.604061)
			(xy 288.139627 -226.602092) (xy 288.086609 -226.592299) (xy 288.035582 -226.574891) (xy 287.987634 -226.550239)
			(xy 287.943786 -226.518869) (xy 287.904973 -226.481448) (xy 287.872021 -226.438775) (xy 287.845635 -226.391758)
			(xy 287.826375 -226.341401) (xy 287.814652 -226.288777) (xy 287.810717 -226.235006) (xy 281.004772 -226.235006)
			(xy 281.00428 -226.261963) (xy 280.99643 -226.315303) (xy 280.980898 -226.366932) (xy 280.958013 -226.415749)
			(xy 280.928265 -226.460713) (xy 280.892287 -226.500867) (xy 280.850845 -226.535355) (xy 280.804824 -226.563441)
			(xy 280.755204 -226.584528) (xy 280.703043 -226.598164) (xy 280.649452 -226.604061) (xy 280.595573 -226.602092)
			(xy 280.542555 -226.592299) (xy 280.491528 -226.574891) (xy 280.44358 -226.550239) (xy 280.399732 -226.518869)
			(xy 280.360919 -226.481448) (xy 280.327967 -226.438775) (xy 280.301581 -226.391758) (xy 280.282321 -226.341401)
			(xy 280.270598 -226.288777) (xy 280.266663 -226.235006) (xy 273.460972 -226.235006) (xy 273.46048 -226.261963)
			(xy 273.45263 -226.315303) (xy 273.437098 -226.366932) (xy 273.414213 -226.415749) (xy 273.384465 -226.460713)
			(xy 273.348487 -226.500867) (xy 273.307045 -226.535355) (xy 273.261024 -226.563441) (xy 273.211404 -226.584528)
			(xy 273.159243 -226.598164) (xy 273.105652 -226.604061) (xy 273.051773 -226.602092) (xy 272.998755 -226.592299)
			(xy 272.947728 -226.574891) (xy 272.89978 -226.550239) (xy 272.855932 -226.518869) (xy 272.817119 -226.481448)
			(xy 272.784167 -226.438775) (xy 272.757781 -226.391758) (xy 272.738521 -226.341401) (xy 272.726798 -226.288777)
			(xy 272.722863 -226.235006) (xy 265.916918 -226.235006) (xy 265.916426 -226.261963) (xy 265.908576 -226.315303)
			(xy 265.893044 -226.366932) (xy 265.870159 -226.415749) (xy 265.840411 -226.460713) (xy 265.804433 -226.500867)
			(xy 265.762991 -226.535355) (xy 265.71697 -226.563441) (xy 265.66735 -226.584528) (xy 265.615189 -226.598164)
			(xy 265.561598 -226.604061) (xy 265.507719 -226.602092) (xy 265.454701 -226.592299) (xy 265.403674 -226.574891)
			(xy 265.355726 -226.550239) (xy 265.311878 -226.518869) (xy 265.273065 -226.481448) (xy 265.240113 -226.438775)
			(xy 265.213727 -226.391758) (xy 265.194467 -226.341401) (xy 265.182744 -226.288777) (xy 265.178809 -226.235006)
			(xy 264.143998 -226.235006) (xy 264.143998 -227.085144) (xy 269.278877 -227.085144) (xy 269.282812 -227.031373)
			(xy 269.294535 -226.978749) (xy 269.313795 -226.928392) (xy 269.340181 -226.881375) (xy 269.373133 -226.838702)
			(xy 269.411946 -226.801281) (xy 269.455794 -226.769911) (xy 269.503742 -226.745259) (xy 269.554769 -226.727851)
			(xy 269.607787 -226.718058) (xy 269.661666 -226.716089) (xy 269.715257 -226.721986) (xy 269.767418 -226.735622)
			(xy 269.817038 -226.756709) (xy 269.863059 -226.784795) (xy 269.904501 -226.819283) (xy 269.940479 -226.859437)
			(xy 269.970227 -226.904401) (xy 269.993112 -226.953218) (xy 270.008644 -227.004847) (xy 270.016494 -227.058187)
			(xy 270.016986 -227.085144) (xy 276.822931 -227.085144) (xy 276.826866 -227.031373) (xy 276.838589 -226.978749)
			(xy 276.857849 -226.928392) (xy 276.884235 -226.881375) (xy 276.917187 -226.838702) (xy 276.956 -226.801281)
			(xy 276.999848 -226.769911) (xy 277.047796 -226.745259) (xy 277.098823 -226.727851) (xy 277.151841 -226.718058)
			(xy 277.20572 -226.716089) (xy 277.259311 -226.721986) (xy 277.311472 -226.735622) (xy 277.361092 -226.756709)
			(xy 277.407113 -226.784795) (xy 277.448555 -226.819283) (xy 277.484533 -226.859437) (xy 277.514281 -226.904401)
			(xy 277.537166 -226.953218) (xy 277.552698 -227.004847) (xy 277.560548 -227.058187) (xy 277.56104 -227.085144)
			(xy 284.366731 -227.085144) (xy 284.370666 -227.031373) (xy 284.382389 -226.978749) (xy 284.401649 -226.928392)
			(xy 284.428035 -226.881375) (xy 284.460987 -226.838702) (xy 284.4998 -226.801281) (xy 284.543648 -226.769911)
			(xy 284.591596 -226.745259) (xy 284.642623 -226.727851) (xy 284.695641 -226.718058) (xy 284.74952 -226.716089)
			(xy 284.803111 -226.721986) (xy 284.855272 -226.735622) (xy 284.904892 -226.756709) (xy 284.950913 -226.784795)
			(xy 284.992355 -226.819283) (xy 285.028333 -226.859437) (xy 285.058081 -226.904401) (xy 285.080966 -226.953218)
			(xy 285.096498 -227.004847) (xy 285.104348 -227.058187) (xy 285.10484 -227.085144) (xy 291.910785 -227.085144)
			(xy 291.91472 -227.031373) (xy 291.926443 -226.978749) (xy 291.945703 -226.928392) (xy 291.972089 -226.881375)
			(xy 292.005041 -226.838702) (xy 292.043854 -226.801281) (xy 292.087702 -226.769911) (xy 292.13565 -226.745259)
			(xy 292.186677 -226.727851) (xy 292.239695 -226.718058) (xy 292.293574 -226.716089) (xy 292.347165 -226.721986)
			(xy 292.399326 -226.735622) (xy 292.448946 -226.756709) (xy 292.494967 -226.784795) (xy 292.536409 -226.819283)
			(xy 292.572387 -226.859437) (xy 292.602135 -226.904401) (xy 292.62502 -226.953218) (xy 292.640552 -227.004847)
			(xy 292.648402 -227.058187) (xy 292.648894 -227.085144) (xy 292.648402 -227.112101) (xy 292.640552 -227.165441)
			(xy 292.62502 -227.21707) (xy 292.602135 -227.265887) (xy 292.572387 -227.310851) (xy 292.536409 -227.351005)
			(xy 292.494967 -227.385493) (xy 292.448946 -227.413579) (xy 292.399326 -227.434666) (xy 292.347165 -227.448302)
			(xy 292.293574 -227.454199) (xy 292.239695 -227.45223) (xy 292.186677 -227.442437) (xy 292.13565 -227.425029)
			(xy 292.087702 -227.400377) (xy 292.043854 -227.369007) (xy 292.005041 -227.331586) (xy 291.972089 -227.288913)
			(xy 291.945703 -227.241896) (xy 291.926443 -227.191539) (xy 291.91472 -227.138915) (xy 291.910785 -227.085144)
			(xy 285.10484 -227.085144) (xy 285.104348 -227.112101) (xy 285.096498 -227.165441) (xy 285.080966 -227.21707)
			(xy 285.058081 -227.265887) (xy 285.028333 -227.310851) (xy 284.992355 -227.351005) (xy 284.950913 -227.385493)
			(xy 284.904892 -227.413579) (xy 284.855272 -227.434666) (xy 284.803111 -227.448302) (xy 284.74952 -227.454199)
			(xy 284.695641 -227.45223) (xy 284.642623 -227.442437) (xy 284.591596 -227.425029) (xy 284.543648 -227.400377)
			(xy 284.4998 -227.369007) (xy 284.460987 -227.331586) (xy 284.428035 -227.288913) (xy 284.401649 -227.241896)
			(xy 284.382389 -227.191539) (xy 284.370666 -227.138915) (xy 284.366731 -227.085144) (xy 277.56104 -227.085144)
			(xy 277.560548 -227.112101) (xy 277.552698 -227.165441) (xy 277.537166 -227.21707) (xy 277.514281 -227.265887)
			(xy 277.484533 -227.310851) (xy 277.448555 -227.351005) (xy 277.407113 -227.385493) (xy 277.361092 -227.413579)
			(xy 277.311472 -227.434666) (xy 277.259311 -227.448302) (xy 277.20572 -227.454199) (xy 277.151841 -227.45223)
			(xy 277.098823 -227.442437) (xy 277.047796 -227.425029) (xy 276.999848 -227.400377) (xy 276.956 -227.369007)
			(xy 276.917187 -227.331586) (xy 276.884235 -227.288913) (xy 276.857849 -227.241896) (xy 276.838589 -227.191539)
			(xy 276.826866 -227.138915) (xy 276.822931 -227.085144) (xy 270.016986 -227.085144) (xy 270.016494 -227.112101)
			(xy 270.008644 -227.165441) (xy 269.993112 -227.21707) (xy 269.970227 -227.265887) (xy 269.940479 -227.310851)
			(xy 269.904501 -227.351005) (xy 269.863059 -227.385493) (xy 269.817038 -227.413579) (xy 269.767418 -227.434666)
			(xy 269.715257 -227.448302) (xy 269.661666 -227.454199) (xy 269.607787 -227.45223) (xy 269.554769 -227.442437)
			(xy 269.503742 -227.425029) (xy 269.455794 -227.400377) (xy 269.411946 -227.369007) (xy 269.373133 -227.331586)
			(xy 269.340181 -227.288913) (xy 269.313795 -227.241896) (xy 269.294535 -227.191539) (xy 269.282812 -227.138915)
			(xy 269.278877 -227.085144) (xy 264.143998 -227.085144) (xy 264.143998 -227.935028) (xy 265.178809 -227.935028)
			(xy 265.182744 -227.881257) (xy 265.194467 -227.828633) (xy 265.213727 -227.778276) (xy 265.240113 -227.731259)
			(xy 265.273065 -227.688586) (xy 265.311878 -227.651165) (xy 265.355726 -227.619795) (xy 265.403674 -227.595143)
			(xy 265.454701 -227.577735) (xy 265.507719 -227.567942) (xy 265.561598 -227.565973) (xy 265.615189 -227.57187)
			(xy 265.66735 -227.585506) (xy 265.71697 -227.606593) (xy 265.762991 -227.634679) (xy 265.804433 -227.669167)
			(xy 265.840411 -227.709321) (xy 265.870159 -227.754285) (xy 265.893044 -227.803102) (xy 265.908576 -227.854731)
			(xy 265.916426 -227.908071) (xy 265.916918 -227.935028) (xy 272.722863 -227.935028) (xy 272.726798 -227.881257)
			(xy 272.738521 -227.828633) (xy 272.757781 -227.778276) (xy 272.784167 -227.731259) (xy 272.817119 -227.688586)
			(xy 272.855932 -227.651165) (xy 272.89978 -227.619795) (xy 272.947728 -227.595143) (xy 272.998755 -227.577735)
			(xy 273.051773 -227.567942) (xy 273.105652 -227.565973) (xy 273.159243 -227.57187) (xy 273.211404 -227.585506)
			(xy 273.261024 -227.606593) (xy 273.307045 -227.634679) (xy 273.348487 -227.669167) (xy 273.384465 -227.709321)
			(xy 273.414213 -227.754285) (xy 273.437098 -227.803102) (xy 273.45263 -227.854731) (xy 273.46048 -227.908071)
			(xy 273.460972 -227.935028) (xy 280.266663 -227.935028) (xy 280.270598 -227.881257) (xy 280.282321 -227.828633)
			(xy 280.301581 -227.778276) (xy 280.327967 -227.731259) (xy 280.360919 -227.688586) (xy 280.399732 -227.651165)
			(xy 280.44358 -227.619795) (xy 280.491528 -227.595143) (xy 280.542555 -227.577735) (xy 280.595573 -227.567942)
			(xy 280.649452 -227.565973) (xy 280.703043 -227.57187) (xy 280.755204 -227.585506) (xy 280.804824 -227.606593)
			(xy 280.850845 -227.634679) (xy 280.892287 -227.669167) (xy 280.928265 -227.709321) (xy 280.958013 -227.754285)
			(xy 280.980898 -227.803102) (xy 280.99643 -227.854731) (xy 281.00428 -227.908071) (xy 281.004772 -227.935028)
			(xy 287.810717 -227.935028) (xy 287.814652 -227.881257) (xy 287.826375 -227.828633) (xy 287.845635 -227.778276)
			(xy 287.872021 -227.731259) (xy 287.904973 -227.688586) (xy 287.943786 -227.651165) (xy 287.987634 -227.619795)
			(xy 288.035582 -227.595143) (xy 288.086609 -227.577735) (xy 288.139627 -227.567942) (xy 288.193506 -227.565973)
			(xy 288.247097 -227.57187) (xy 288.299258 -227.585506) (xy 288.348878 -227.606593) (xy 288.394899 -227.634679)
			(xy 288.436341 -227.669167) (xy 288.472319 -227.709321) (xy 288.502067 -227.754285) (xy 288.524952 -227.803102)
			(xy 288.540484 -227.854731) (xy 288.548334 -227.908071) (xy 288.548826 -227.935028) (xy 288.548334 -227.961985)
			(xy 288.540484 -228.015325) (xy 288.524952 -228.066954) (xy 288.502067 -228.115771) (xy 288.472319 -228.160735)
			(xy 288.436341 -228.200889) (xy 288.394899 -228.235377) (xy 288.348878 -228.263463) (xy 288.299258 -228.28455)
			(xy 288.247097 -228.298186) (xy 288.193506 -228.304083) (xy 288.139627 -228.302114) (xy 288.086609 -228.292321)
			(xy 288.035582 -228.274913) (xy 287.987634 -228.250261) (xy 287.943786 -228.218891) (xy 287.904973 -228.18147)
			(xy 287.872021 -228.138797) (xy 287.845635 -228.09178) (xy 287.826375 -228.041423) (xy 287.814652 -227.988799)
			(xy 287.810717 -227.935028) (xy 281.004772 -227.935028) (xy 281.00428 -227.961985) (xy 280.99643 -228.015325)
			(xy 280.980898 -228.066954) (xy 280.958013 -228.115771) (xy 280.928265 -228.160735) (xy 280.892287 -228.200889)
			(xy 280.850845 -228.235377) (xy 280.804824 -228.263463) (xy 280.755204 -228.28455) (xy 280.703043 -228.298186)
			(xy 280.649452 -228.304083) (xy 280.595573 -228.302114) (xy 280.542555 -228.292321) (xy 280.491528 -228.274913)
			(xy 280.44358 -228.250261) (xy 280.399732 -228.218891) (xy 280.360919 -228.18147) (xy 280.327967 -228.138797)
			(xy 280.301581 -228.09178) (xy 280.282321 -228.041423) (xy 280.270598 -227.988799) (xy 280.266663 -227.935028)
			(xy 273.460972 -227.935028) (xy 273.46048 -227.961985) (xy 273.45263 -228.015325) (xy 273.437098 -228.066954)
			(xy 273.414213 -228.115771) (xy 273.384465 -228.160735) (xy 273.348487 -228.200889) (xy 273.307045 -228.235377)
			(xy 273.261024 -228.263463) (xy 273.211404 -228.28455) (xy 273.159243 -228.298186) (xy 273.105652 -228.304083)
			(xy 273.051773 -228.302114) (xy 272.998755 -228.292321) (xy 272.947728 -228.274913) (xy 272.89978 -228.250261)
			(xy 272.855932 -228.218891) (xy 272.817119 -228.18147) (xy 272.784167 -228.138797) (xy 272.757781 -228.09178)
			(xy 272.738521 -228.041423) (xy 272.726798 -227.988799) (xy 272.722863 -227.935028) (xy 265.916918 -227.935028)
			(xy 265.916426 -227.961985) (xy 265.908576 -228.015325) (xy 265.893044 -228.066954) (xy 265.870159 -228.115771)
			(xy 265.840411 -228.160735) (xy 265.804433 -228.200889) (xy 265.762991 -228.235377) (xy 265.71697 -228.263463)
			(xy 265.66735 -228.28455) (xy 265.615189 -228.298186) (xy 265.561598 -228.304083) (xy 265.507719 -228.302114)
			(xy 265.454701 -228.292321) (xy 265.403674 -228.274913) (xy 265.355726 -228.250261) (xy 265.311878 -228.218891)
			(xy 265.273065 -228.18147) (xy 265.240113 -228.138797) (xy 265.213727 -228.09178) (xy 265.194467 -228.041423)
			(xy 265.182744 -227.988799) (xy 265.178809 -227.935028) (xy 264.143998 -227.935028) (xy 264.143998 -228.785166)
			(xy 269.278877 -228.785166) (xy 269.282812 -228.731395) (xy 269.294535 -228.678771) (xy 269.313795 -228.628414)
			(xy 269.340181 -228.581397) (xy 269.373133 -228.538724) (xy 269.411946 -228.501303) (xy 269.455794 -228.469933)
			(xy 269.503742 -228.445281) (xy 269.554769 -228.427873) (xy 269.607787 -228.41808) (xy 269.661666 -228.416111)
			(xy 269.715257 -228.422008) (xy 269.767418 -228.435644) (xy 269.817038 -228.456731) (xy 269.863059 -228.484817)
			(xy 269.904501 -228.519305) (xy 269.940479 -228.559459) (xy 269.970227 -228.604423) (xy 269.993112 -228.65324)
			(xy 270.008644 -228.704869) (xy 270.016494 -228.758209) (xy 270.016986 -228.785166) (xy 276.822931 -228.785166)
			(xy 276.826866 -228.731395) (xy 276.838589 -228.678771) (xy 276.857849 -228.628414) (xy 276.884235 -228.581397)
			(xy 276.917187 -228.538724) (xy 276.956 -228.501303) (xy 276.999848 -228.469933) (xy 277.047796 -228.445281)
			(xy 277.098823 -228.427873) (xy 277.151841 -228.41808) (xy 277.20572 -228.416111) (xy 277.259311 -228.422008)
			(xy 277.311472 -228.435644) (xy 277.361092 -228.456731) (xy 277.407113 -228.484817) (xy 277.448555 -228.519305)
			(xy 277.484533 -228.559459) (xy 277.514281 -228.604423) (xy 277.537166 -228.65324) (xy 277.552698 -228.704869)
			(xy 277.560548 -228.758209) (xy 277.56104 -228.785166) (xy 284.366731 -228.785166) (xy 284.370666 -228.731395)
			(xy 284.382389 -228.678771) (xy 284.401649 -228.628414) (xy 284.428035 -228.581397) (xy 284.460987 -228.538724)
			(xy 284.4998 -228.501303) (xy 284.543648 -228.469933) (xy 284.591596 -228.445281) (xy 284.642623 -228.427873)
			(xy 284.695641 -228.41808) (xy 284.74952 -228.416111) (xy 284.803111 -228.422008) (xy 284.855272 -228.435644)
			(xy 284.904892 -228.456731) (xy 284.950913 -228.484817) (xy 284.992355 -228.519305) (xy 285.028333 -228.559459)
			(xy 285.058081 -228.604423) (xy 285.080966 -228.65324) (xy 285.096498 -228.704869) (xy 285.104348 -228.758209)
			(xy 285.10484 -228.785166) (xy 291.910785 -228.785166) (xy 291.91472 -228.731395) (xy 291.926443 -228.678771)
			(xy 291.945703 -228.628414) (xy 291.972089 -228.581397) (xy 292.005041 -228.538724) (xy 292.043854 -228.501303)
			(xy 292.087702 -228.469933) (xy 292.13565 -228.445281) (xy 292.186677 -228.427873) (xy 292.239695 -228.41808)
			(xy 292.293574 -228.416111) (xy 292.347165 -228.422008) (xy 292.399326 -228.435644) (xy 292.448946 -228.456731)
			(xy 292.494967 -228.484817) (xy 292.536409 -228.519305) (xy 292.572387 -228.559459) (xy 292.602135 -228.604423)
			(xy 292.62502 -228.65324) (xy 292.640552 -228.704869) (xy 292.648402 -228.758209) (xy 292.648894 -228.785166)
			(xy 292.648402 -228.812123) (xy 292.640552 -228.865463) (xy 292.62502 -228.917092) (xy 292.602135 -228.965909)
			(xy 292.572387 -229.010873) (xy 292.536409 -229.051027) (xy 292.494967 -229.085515) (xy 292.448946 -229.113601)
			(xy 292.399326 -229.134688) (xy 292.347165 -229.148324) (xy 292.293574 -229.154221) (xy 292.239695 -229.152252)
			(xy 292.186677 -229.142459) (xy 292.13565 -229.125051) (xy 292.087702 -229.100399) (xy 292.043854 -229.069029)
			(xy 292.005041 -229.031608) (xy 291.972089 -228.988935) (xy 291.945703 -228.941918) (xy 291.926443 -228.891561)
			(xy 291.91472 -228.838937) (xy 291.910785 -228.785166) (xy 285.10484 -228.785166) (xy 285.104348 -228.812123)
			(xy 285.096498 -228.865463) (xy 285.080966 -228.917092) (xy 285.058081 -228.965909) (xy 285.028333 -229.010873)
			(xy 284.992355 -229.051027) (xy 284.950913 -229.085515) (xy 284.904892 -229.113601) (xy 284.855272 -229.134688)
			(xy 284.803111 -229.148324) (xy 284.74952 -229.154221) (xy 284.695641 -229.152252) (xy 284.642623 -229.142459)
			(xy 284.591596 -229.125051) (xy 284.543648 -229.100399) (xy 284.4998 -229.069029) (xy 284.460987 -229.031608)
			(xy 284.428035 -228.988935) (xy 284.401649 -228.941918) (xy 284.382389 -228.891561) (xy 284.370666 -228.838937)
			(xy 284.366731 -228.785166) (xy 277.56104 -228.785166) (xy 277.560548 -228.812123) (xy 277.552698 -228.865463)
			(xy 277.537166 -228.917092) (xy 277.514281 -228.965909) (xy 277.484533 -229.010873) (xy 277.448555 -229.051027)
			(xy 277.407113 -229.085515) (xy 277.361092 -229.113601) (xy 277.311472 -229.134688) (xy 277.259311 -229.148324)
			(xy 277.20572 -229.154221) (xy 277.151841 -229.152252) (xy 277.098823 -229.142459) (xy 277.047796 -229.125051)
			(xy 276.999848 -229.100399) (xy 276.956 -229.069029) (xy 276.917187 -229.031608) (xy 276.884235 -228.988935)
			(xy 276.857849 -228.941918) (xy 276.838589 -228.891561) (xy 276.826866 -228.838937) (xy 276.822931 -228.785166)
			(xy 270.016986 -228.785166) (xy 270.016494 -228.812123) (xy 270.008644 -228.865463) (xy 269.993112 -228.917092)
			(xy 269.970227 -228.965909) (xy 269.940479 -229.010873) (xy 269.904501 -229.051027) (xy 269.863059 -229.085515)
			(xy 269.817038 -229.113601) (xy 269.767418 -229.134688) (xy 269.715257 -229.148324) (xy 269.661666 -229.154221)
			(xy 269.607787 -229.152252) (xy 269.554769 -229.142459) (xy 269.503742 -229.125051) (xy 269.455794 -229.100399)
			(xy 269.411946 -229.069029) (xy 269.373133 -229.031608) (xy 269.340181 -228.988935) (xy 269.313795 -228.941918)
			(xy 269.294535 -228.891561) (xy 269.282812 -228.838937) (xy 269.278877 -228.785166) (xy 264.143998 -228.785166)
			(xy 264.143998 -229.63505) (xy 265.178809 -229.63505) (xy 265.182744 -229.581279) (xy 265.194467 -229.528655)
			(xy 265.213727 -229.478298) (xy 265.240113 -229.431281) (xy 265.273065 -229.388608) (xy 265.311878 -229.351187)
			(xy 265.355726 -229.319817) (xy 265.403674 -229.295165) (xy 265.454701 -229.277757) (xy 265.507719 -229.267964)
			(xy 265.561598 -229.265995) (xy 265.615189 -229.271892) (xy 265.66735 -229.285528) (xy 265.71697 -229.306615)
			(xy 265.762991 -229.334701) (xy 265.804433 -229.369189) (xy 265.840411 -229.409343) (xy 265.870159 -229.454307)
			(xy 265.893044 -229.503124) (xy 265.908576 -229.554753) (xy 265.916426 -229.608093) (xy 265.916918 -229.63505)
			(xy 269.278877 -229.63505) (xy 269.282812 -229.581279) (xy 269.294535 -229.528655) (xy 269.313795 -229.478298)
			(xy 269.340181 -229.431281) (xy 269.373133 -229.388608) (xy 269.411946 -229.351187) (xy 269.455794 -229.319817)
			(xy 269.503742 -229.295165) (xy 269.554769 -229.277757) (xy 269.607787 -229.267964) (xy 269.661666 -229.265995)
			(xy 269.715257 -229.271892) (xy 269.767418 -229.285528) (xy 269.817038 -229.306615) (xy 269.863059 -229.334701)
			(xy 269.904501 -229.369189) (xy 269.940479 -229.409343) (xy 269.970227 -229.454307) (xy 269.993112 -229.503124)
			(xy 270.008644 -229.554753) (xy 270.016494 -229.608093) (xy 270.016986 -229.63505) (xy 272.722863 -229.63505)
			(xy 272.726798 -229.581279) (xy 272.738521 -229.528655) (xy 272.757781 -229.478298) (xy 272.784167 -229.431281)
			(xy 272.817119 -229.388608) (xy 272.855932 -229.351187) (xy 272.89978 -229.319817) (xy 272.947728 -229.295165)
			(xy 272.998755 -229.277757) (xy 273.051773 -229.267964) (xy 273.105652 -229.265995) (xy 273.159243 -229.271892)
			(xy 273.211404 -229.285528) (xy 273.261024 -229.306615) (xy 273.307045 -229.334701) (xy 273.348487 -229.369189)
			(xy 273.384465 -229.409343) (xy 273.414213 -229.454307) (xy 273.437098 -229.503124) (xy 273.45263 -229.554753)
			(xy 273.46048 -229.608093) (xy 273.460972 -229.63505) (xy 276.822931 -229.63505) (xy 276.826866 -229.581279)
			(xy 276.838589 -229.528655) (xy 276.857849 -229.478298) (xy 276.884235 -229.431281) (xy 276.917187 -229.388608)
			(xy 276.956 -229.351187) (xy 276.999848 -229.319817) (xy 277.047796 -229.295165) (xy 277.098823 -229.277757)
			(xy 277.151841 -229.267964) (xy 277.20572 -229.265995) (xy 277.259311 -229.271892) (xy 277.311472 -229.285528)
			(xy 277.361092 -229.306615) (xy 277.407113 -229.334701) (xy 277.448555 -229.369189) (xy 277.484533 -229.409343)
			(xy 277.514281 -229.454307) (xy 277.537166 -229.503124) (xy 277.552698 -229.554753) (xy 277.560548 -229.608093)
			(xy 277.56104 -229.63505) (xy 280.266663 -229.63505) (xy 280.270598 -229.581279) (xy 280.282321 -229.528655)
			(xy 280.301581 -229.478298) (xy 280.327967 -229.431281) (xy 280.360919 -229.388608) (xy 280.399732 -229.351187)
			(xy 280.44358 -229.319817) (xy 280.491528 -229.295165) (xy 280.542555 -229.277757) (xy 280.595573 -229.267964)
			(xy 280.649452 -229.265995) (xy 280.703043 -229.271892) (xy 280.755204 -229.285528) (xy 280.804824 -229.306615)
			(xy 280.850845 -229.334701) (xy 280.892287 -229.369189) (xy 280.928265 -229.409343) (xy 280.958013 -229.454307)
			(xy 280.980898 -229.503124) (xy 280.99643 -229.554753) (xy 281.00428 -229.608093) (xy 281.004772 -229.63505)
			(xy 284.366731 -229.63505) (xy 284.370666 -229.581279) (xy 284.382389 -229.528655) (xy 284.401649 -229.478298)
			(xy 284.428035 -229.431281) (xy 284.460987 -229.388608) (xy 284.4998 -229.351187) (xy 284.543648 -229.319817)
			(xy 284.591596 -229.295165) (xy 284.642623 -229.277757) (xy 284.695641 -229.267964) (xy 284.74952 -229.265995)
			(xy 284.803111 -229.271892) (xy 284.855272 -229.285528) (xy 284.904892 -229.306615) (xy 284.950913 -229.334701)
			(xy 284.992355 -229.369189) (xy 285.028333 -229.409343) (xy 285.058081 -229.454307) (xy 285.080966 -229.503124)
			(xy 285.096498 -229.554753) (xy 285.104348 -229.608093) (xy 285.10484 -229.63505) (xy 287.810717 -229.63505)
			(xy 287.814652 -229.581279) (xy 287.826375 -229.528655) (xy 287.845635 -229.478298) (xy 287.872021 -229.431281)
			(xy 287.904973 -229.388608) (xy 287.943786 -229.351187) (xy 287.987634 -229.319817) (xy 288.035582 -229.295165)
			(xy 288.086609 -229.277757) (xy 288.139627 -229.267964) (xy 288.193506 -229.265995) (xy 288.247097 -229.271892)
			(xy 288.299258 -229.285528) (xy 288.348878 -229.306615) (xy 288.394899 -229.334701) (xy 288.436341 -229.369189)
			(xy 288.472319 -229.409343) (xy 288.502067 -229.454307) (xy 288.524952 -229.503124) (xy 288.540484 -229.554753)
			(xy 288.548334 -229.608093) (xy 288.548826 -229.63505) (xy 291.910785 -229.63505) (xy 291.91472 -229.581279)
			(xy 291.926443 -229.528655) (xy 291.945703 -229.478298) (xy 291.972089 -229.431281) (xy 292.005041 -229.388608)
			(xy 292.043854 -229.351187) (xy 292.087702 -229.319817) (xy 292.13565 -229.295165) (xy 292.186677 -229.277757)
			(xy 292.239695 -229.267964) (xy 292.293574 -229.265995) (xy 292.347165 -229.271892) (xy 292.399326 -229.285528)
			(xy 292.448946 -229.306615) (xy 292.494967 -229.334701) (xy 292.536409 -229.369189) (xy 292.572387 -229.409343)
			(xy 292.602135 -229.454307) (xy 292.62502 -229.503124) (xy 292.640552 -229.554753) (xy 292.648402 -229.608093)
			(xy 292.648894 -229.63505) (xy 292.648402 -229.662007) (xy 292.640552 -229.715347) (xy 292.62502 -229.766976)
			(xy 292.602135 -229.815793) (xy 292.572387 -229.860757) (xy 292.536409 -229.900911) (xy 292.494967 -229.935399)
			(xy 292.448946 -229.963485) (xy 292.399326 -229.984572) (xy 292.347165 -229.998208) (xy 292.293574 -230.004105)
			(xy 292.239695 -230.002136) (xy 292.186677 -229.992343) (xy 292.13565 -229.974935) (xy 292.087702 -229.950283)
			(xy 292.043854 -229.918913) (xy 292.005041 -229.881492) (xy 291.972089 -229.838819) (xy 291.945703 -229.791802)
			(xy 291.926443 -229.741445) (xy 291.91472 -229.688821) (xy 291.910785 -229.63505) (xy 288.548826 -229.63505)
			(xy 288.548334 -229.662007) (xy 288.540484 -229.715347) (xy 288.524952 -229.766976) (xy 288.502067 -229.815793)
			(xy 288.472319 -229.860757) (xy 288.436341 -229.900911) (xy 288.394899 -229.935399) (xy 288.348878 -229.963485)
			(xy 288.299258 -229.984572) (xy 288.247097 -229.998208) (xy 288.193506 -230.004105) (xy 288.139627 -230.002136)
			(xy 288.086609 -229.992343) (xy 288.035582 -229.974935) (xy 287.987634 -229.950283) (xy 287.943786 -229.918913)
			(xy 287.904973 -229.881492) (xy 287.872021 -229.838819) (xy 287.845635 -229.791802) (xy 287.826375 -229.741445)
			(xy 287.814652 -229.688821) (xy 287.810717 -229.63505) (xy 285.10484 -229.63505) (xy 285.104348 -229.662007)
			(xy 285.096498 -229.715347) (xy 285.080966 -229.766976) (xy 285.058081 -229.815793) (xy 285.028333 -229.860757)
			(xy 284.992355 -229.900911) (xy 284.950913 -229.935399) (xy 284.904892 -229.963485) (xy 284.855272 -229.984572)
			(xy 284.803111 -229.998208) (xy 284.74952 -230.004105) (xy 284.695641 -230.002136) (xy 284.642623 -229.992343)
			(xy 284.591596 -229.974935) (xy 284.543648 -229.950283) (xy 284.4998 -229.918913) (xy 284.460987 -229.881492)
			(xy 284.428035 -229.838819) (xy 284.401649 -229.791802) (xy 284.382389 -229.741445) (xy 284.370666 -229.688821)
			(xy 284.366731 -229.63505) (xy 281.004772 -229.63505) (xy 281.00428 -229.662007) (xy 280.99643 -229.715347)
			(xy 280.980898 -229.766976) (xy 280.958013 -229.815793) (xy 280.928265 -229.860757) (xy 280.892287 -229.900911)
			(xy 280.850845 -229.935399) (xy 280.804824 -229.963485) (xy 280.755204 -229.984572) (xy 280.703043 -229.998208)
			(xy 280.649452 -230.004105) (xy 280.595573 -230.002136) (xy 280.542555 -229.992343) (xy 280.491528 -229.974935)
			(xy 280.44358 -229.950283) (xy 280.399732 -229.918913) (xy 280.360919 -229.881492) (xy 280.327967 -229.838819)
			(xy 280.301581 -229.791802) (xy 280.282321 -229.741445) (xy 280.270598 -229.688821) (xy 280.266663 -229.63505)
			(xy 277.56104 -229.63505) (xy 277.560548 -229.662007) (xy 277.552698 -229.715347) (xy 277.537166 -229.766976)
			(xy 277.514281 -229.815793) (xy 277.484533 -229.860757) (xy 277.448555 -229.900911) (xy 277.407113 -229.935399)
			(xy 277.361092 -229.963485) (xy 277.311472 -229.984572) (xy 277.259311 -229.998208) (xy 277.20572 -230.004105)
			(xy 277.151841 -230.002136) (xy 277.098823 -229.992343) (xy 277.047796 -229.974935) (xy 276.999848 -229.950283)
			(xy 276.956 -229.918913) (xy 276.917187 -229.881492) (xy 276.884235 -229.838819) (xy 276.857849 -229.791802)
			(xy 276.838589 -229.741445) (xy 276.826866 -229.688821) (xy 276.822931 -229.63505) (xy 273.460972 -229.63505)
			(xy 273.46048 -229.662007) (xy 273.45263 -229.715347) (xy 273.437098 -229.766976) (xy 273.414213 -229.815793)
			(xy 273.384465 -229.860757) (xy 273.348487 -229.900911) (xy 273.307045 -229.935399) (xy 273.261024 -229.963485)
			(xy 273.211404 -229.984572) (xy 273.159243 -229.998208) (xy 273.105652 -230.004105) (xy 273.051773 -230.002136)
			(xy 272.998755 -229.992343) (xy 272.947728 -229.974935) (xy 272.89978 -229.950283) (xy 272.855932 -229.918913)
			(xy 272.817119 -229.881492) (xy 272.784167 -229.838819) (xy 272.757781 -229.791802) (xy 272.738521 -229.741445)
			(xy 272.726798 -229.688821) (xy 272.722863 -229.63505) (xy 270.016986 -229.63505) (xy 270.016494 -229.662007)
			(xy 270.008644 -229.715347) (xy 269.993112 -229.766976) (xy 269.970227 -229.815793) (xy 269.940479 -229.860757)
			(xy 269.904501 -229.900911) (xy 269.863059 -229.935399) (xy 269.817038 -229.963485) (xy 269.767418 -229.984572)
			(xy 269.715257 -229.998208) (xy 269.661666 -230.004105) (xy 269.607787 -230.002136) (xy 269.554769 -229.992343)
			(xy 269.503742 -229.974935) (xy 269.455794 -229.950283) (xy 269.411946 -229.918913) (xy 269.373133 -229.881492)
			(xy 269.340181 -229.838819) (xy 269.313795 -229.791802) (xy 269.294535 -229.741445) (xy 269.282812 -229.688821)
			(xy 269.278877 -229.63505) (xy 265.916918 -229.63505) (xy 265.916426 -229.662007) (xy 265.908576 -229.715347)
			(xy 265.893044 -229.766976) (xy 265.870159 -229.815793) (xy 265.840411 -229.860757) (xy 265.804433 -229.900911)
			(xy 265.762991 -229.935399) (xy 265.71697 -229.963485) (xy 265.66735 -229.984572) (xy 265.615189 -229.998208)
			(xy 265.561598 -230.004105) (xy 265.507719 -230.002136) (xy 265.454701 -229.992343) (xy 265.403674 -229.974935)
			(xy 265.355726 -229.950283) (xy 265.311878 -229.918913) (xy 265.273065 -229.881492) (xy 265.240113 -229.838819)
			(xy 265.213727 -229.791802) (xy 265.194467 -229.741445) (xy 265.182744 -229.688821) (xy 265.178809 -229.63505)
			(xy 264.143998 -229.63505) (xy 264.143998 -230.485188) (xy 265.178809 -230.485188) (xy 265.182744 -230.431417)
			(xy 265.194467 -230.378793) (xy 265.213727 -230.328436) (xy 265.240113 -230.281419) (xy 265.273065 -230.238746)
			(xy 265.311878 -230.201325) (xy 265.355726 -230.169955) (xy 265.403674 -230.145303) (xy 265.454701 -230.127895)
			(xy 265.507719 -230.118102) (xy 265.561598 -230.116133) (xy 265.615189 -230.12203) (xy 265.66735 -230.135666)
			(xy 265.71697 -230.156753) (xy 265.762991 -230.184839) (xy 265.804433 -230.219327) (xy 265.840411 -230.259481)
			(xy 265.870159 -230.304445) (xy 265.893044 -230.353262) (xy 265.908576 -230.404891) (xy 265.916426 -230.458231)
			(xy 265.916918 -230.485188) (xy 272.722863 -230.485188) (xy 272.726798 -230.431417) (xy 272.738521 -230.378793)
			(xy 272.757781 -230.328436) (xy 272.784167 -230.281419) (xy 272.817119 -230.238746) (xy 272.855932 -230.201325)
			(xy 272.89978 -230.169955) (xy 272.947728 -230.145303) (xy 272.998755 -230.127895) (xy 273.051773 -230.118102)
			(xy 273.105652 -230.116133) (xy 273.159243 -230.12203) (xy 273.211404 -230.135666) (xy 273.261024 -230.156753)
			(xy 273.307045 -230.184839) (xy 273.348487 -230.219327) (xy 273.384465 -230.259481) (xy 273.414213 -230.304445)
			(xy 273.437098 -230.353262) (xy 273.45263 -230.404891) (xy 273.46048 -230.458231) (xy 273.460972 -230.485188)
			(xy 280.266663 -230.485188) (xy 280.270598 -230.431417) (xy 280.282321 -230.378793) (xy 280.301581 -230.328436)
			(xy 280.327967 -230.281419) (xy 280.360919 -230.238746) (xy 280.399732 -230.201325) (xy 280.44358 -230.169955)
			(xy 280.491528 -230.145303) (xy 280.542555 -230.127895) (xy 280.595573 -230.118102) (xy 280.649452 -230.116133)
			(xy 280.703043 -230.12203) (xy 280.755204 -230.135666) (xy 280.804824 -230.156753) (xy 280.850845 -230.184839)
			(xy 280.892287 -230.219327) (xy 280.928265 -230.259481) (xy 280.958013 -230.304445) (xy 280.980898 -230.353262)
			(xy 280.99643 -230.404891) (xy 281.00428 -230.458231) (xy 281.004772 -230.485188) (xy 287.810717 -230.485188)
			(xy 287.814652 -230.431417) (xy 287.826375 -230.378793) (xy 287.845635 -230.328436) (xy 287.872021 -230.281419)
			(xy 287.904973 -230.238746) (xy 287.943786 -230.201325) (xy 287.987634 -230.169955) (xy 288.035582 -230.145303)
			(xy 288.086609 -230.127895) (xy 288.139627 -230.118102) (xy 288.193506 -230.116133) (xy 288.247097 -230.12203)
			(xy 288.299258 -230.135666) (xy 288.348878 -230.156753) (xy 288.394899 -230.184839) (xy 288.436341 -230.219327)
			(xy 288.472319 -230.259481) (xy 288.502067 -230.304445) (xy 288.524952 -230.353262) (xy 288.540484 -230.404891)
			(xy 288.548334 -230.458231) (xy 288.548826 -230.485188) (xy 288.548334 -230.512145) (xy 288.540484 -230.565485)
			(xy 288.524952 -230.617114) (xy 288.502067 -230.665931) (xy 288.472319 -230.710895) (xy 288.436341 -230.751049)
			(xy 288.394899 -230.785537) (xy 288.348878 -230.813623) (xy 288.299258 -230.83471) (xy 288.247097 -230.848346)
			(xy 288.193506 -230.854243) (xy 288.139627 -230.852274) (xy 288.086609 -230.842481) (xy 288.035582 -230.825073)
			(xy 287.987634 -230.800421) (xy 287.943786 -230.769051) (xy 287.904973 -230.73163) (xy 287.872021 -230.688957)
			(xy 287.845635 -230.64194) (xy 287.826375 -230.591583) (xy 287.814652 -230.538959) (xy 287.810717 -230.485188)
			(xy 281.004772 -230.485188) (xy 281.00428 -230.512145) (xy 280.99643 -230.565485) (xy 280.980898 -230.617114)
			(xy 280.958013 -230.665931) (xy 280.928265 -230.710895) (xy 280.892287 -230.751049) (xy 280.850845 -230.785537)
			(xy 280.804824 -230.813623) (xy 280.755204 -230.83471) (xy 280.703043 -230.848346) (xy 280.649452 -230.854243)
			(xy 280.595573 -230.852274) (xy 280.542555 -230.842481) (xy 280.491528 -230.825073) (xy 280.44358 -230.800421)
			(xy 280.399732 -230.769051) (xy 280.360919 -230.73163) (xy 280.327967 -230.688957) (xy 280.301581 -230.64194)
			(xy 280.282321 -230.591583) (xy 280.270598 -230.538959) (xy 280.266663 -230.485188) (xy 273.460972 -230.485188)
			(xy 273.46048 -230.512145) (xy 273.45263 -230.565485) (xy 273.437098 -230.617114) (xy 273.414213 -230.665931)
			(xy 273.384465 -230.710895) (xy 273.348487 -230.751049) (xy 273.307045 -230.785537) (xy 273.261024 -230.813623)
			(xy 273.211404 -230.83471) (xy 273.159243 -230.848346) (xy 273.105652 -230.854243) (xy 273.051773 -230.852274)
			(xy 272.998755 -230.842481) (xy 272.947728 -230.825073) (xy 272.89978 -230.800421) (xy 272.855932 -230.769051)
			(xy 272.817119 -230.73163) (xy 272.784167 -230.688957) (xy 272.757781 -230.64194) (xy 272.738521 -230.591583)
			(xy 272.726798 -230.538959) (xy 272.722863 -230.485188) (xy 265.916918 -230.485188) (xy 265.916426 -230.512145)
			(xy 265.908576 -230.565485) (xy 265.893044 -230.617114) (xy 265.870159 -230.665931) (xy 265.840411 -230.710895)
			(xy 265.804433 -230.751049) (xy 265.762991 -230.785537) (xy 265.71697 -230.813623) (xy 265.66735 -230.83471)
			(xy 265.615189 -230.848346) (xy 265.561598 -230.854243) (xy 265.507719 -230.852274) (xy 265.454701 -230.842481)
			(xy 265.403674 -230.825073) (xy 265.355726 -230.800421) (xy 265.311878 -230.769051) (xy 265.273065 -230.73163)
			(xy 265.240113 -230.688957) (xy 265.213727 -230.64194) (xy 265.194467 -230.591583) (xy 265.182744 -230.538959)
			(xy 265.178809 -230.485188) (xy 264.143998 -230.485188) (xy 264.143998 -231.335072) (xy 269.278877 -231.335072)
			(xy 269.282812 -231.281301) (xy 269.294535 -231.228677) (xy 269.313795 -231.17832) (xy 269.340181 -231.131303)
			(xy 269.373133 -231.08863) (xy 269.411946 -231.051209) (xy 269.455794 -231.019839) (xy 269.503742 -230.995187)
			(xy 269.554769 -230.977779) (xy 269.607787 -230.967986) (xy 269.661666 -230.966017) (xy 269.715257 -230.971914)
			(xy 269.767418 -230.98555) (xy 269.817038 -231.006637) (xy 269.863059 -231.034723) (xy 269.904501 -231.069211)
			(xy 269.940479 -231.109365) (xy 269.970227 -231.154329) (xy 269.993112 -231.203146) (xy 270.008644 -231.254775)
			(xy 270.016494 -231.308115) (xy 270.016986 -231.335072) (xy 276.822931 -231.335072) (xy 276.826866 -231.281301)
			(xy 276.838589 -231.228677) (xy 276.857849 -231.17832) (xy 276.884235 -231.131303) (xy 276.917187 -231.08863)
			(xy 276.956 -231.051209) (xy 276.999848 -231.019839) (xy 277.047796 -230.995187) (xy 277.098823 -230.977779)
			(xy 277.151841 -230.967986) (xy 277.20572 -230.966017) (xy 277.259311 -230.971914) (xy 277.311472 -230.98555)
			(xy 277.361092 -231.006637) (xy 277.407113 -231.034723) (xy 277.448555 -231.069211) (xy 277.484533 -231.109365)
			(xy 277.514281 -231.154329) (xy 277.537166 -231.203146) (xy 277.552698 -231.254775) (xy 277.560548 -231.308115)
			(xy 277.56104 -231.335072) (xy 284.366731 -231.335072) (xy 284.370666 -231.281301) (xy 284.382389 -231.228677)
			(xy 284.401649 -231.17832) (xy 284.428035 -231.131303) (xy 284.460987 -231.08863) (xy 284.4998 -231.051209)
			(xy 284.543648 -231.019839) (xy 284.591596 -230.995187) (xy 284.642623 -230.977779) (xy 284.695641 -230.967986)
			(xy 284.74952 -230.966017) (xy 284.803111 -230.971914) (xy 284.855272 -230.98555) (xy 284.904892 -231.006637)
			(xy 284.950913 -231.034723) (xy 284.992355 -231.069211) (xy 285.028333 -231.109365) (xy 285.058081 -231.154329)
			(xy 285.080966 -231.203146) (xy 285.096498 -231.254775) (xy 285.104348 -231.308115) (xy 285.10484 -231.335072)
			(xy 291.910785 -231.335072) (xy 291.91472 -231.281301) (xy 291.926443 -231.228677) (xy 291.945703 -231.17832)
			(xy 291.972089 -231.131303) (xy 292.005041 -231.08863) (xy 292.043854 -231.051209) (xy 292.087702 -231.019839)
			(xy 292.13565 -230.995187) (xy 292.186677 -230.977779) (xy 292.239695 -230.967986) (xy 292.293574 -230.966017)
			(xy 292.347165 -230.971914) (xy 292.399326 -230.98555) (xy 292.448946 -231.006637) (xy 292.494967 -231.034723)
			(xy 292.536409 -231.069211) (xy 292.572387 -231.109365) (xy 292.602135 -231.154329) (xy 292.62502 -231.203146)
			(xy 292.640552 -231.254775) (xy 292.648402 -231.308115) (xy 292.648894 -231.335072) (xy 292.648402 -231.362029)
			(xy 292.640552 -231.415369) (xy 292.62502 -231.466998) (xy 292.602135 -231.515815) (xy 292.572387 -231.560779)
			(xy 292.536409 -231.600933) (xy 292.494967 -231.635421) (xy 292.448946 -231.663507) (xy 292.399326 -231.684594)
			(xy 292.347165 -231.69823) (xy 292.293574 -231.704127) (xy 292.239695 -231.702158) (xy 292.186677 -231.692365)
			(xy 292.13565 -231.674957) (xy 292.087702 -231.650305) (xy 292.043854 -231.618935) (xy 292.005041 -231.581514)
			(xy 291.972089 -231.538841) (xy 291.945703 -231.491824) (xy 291.926443 -231.441467) (xy 291.91472 -231.388843)
			(xy 291.910785 -231.335072) (xy 285.10484 -231.335072) (xy 285.104348 -231.362029) (xy 285.096498 -231.415369)
			(xy 285.080966 -231.466998) (xy 285.058081 -231.515815) (xy 285.028333 -231.560779) (xy 284.992355 -231.600933)
			(xy 284.950913 -231.635421) (xy 284.904892 -231.663507) (xy 284.855272 -231.684594) (xy 284.803111 -231.69823)
			(xy 284.74952 -231.704127) (xy 284.695641 -231.702158) (xy 284.642623 -231.692365) (xy 284.591596 -231.674957)
			(xy 284.543648 -231.650305) (xy 284.4998 -231.618935) (xy 284.460987 -231.581514) (xy 284.428035 -231.538841)
			(xy 284.401649 -231.491824) (xy 284.382389 -231.441467) (xy 284.370666 -231.388843) (xy 284.366731 -231.335072)
			(xy 277.56104 -231.335072) (xy 277.560548 -231.362029) (xy 277.552698 -231.415369) (xy 277.537166 -231.466998)
			(xy 277.514281 -231.515815) (xy 277.484533 -231.560779) (xy 277.448555 -231.600933) (xy 277.407113 -231.635421)
			(xy 277.361092 -231.663507) (xy 277.311472 -231.684594) (xy 277.259311 -231.69823) (xy 277.20572 -231.704127)
			(xy 277.151841 -231.702158) (xy 277.098823 -231.692365) (xy 277.047796 -231.674957) (xy 276.999848 -231.650305)
			(xy 276.956 -231.618935) (xy 276.917187 -231.581514) (xy 276.884235 -231.538841) (xy 276.857849 -231.491824)
			(xy 276.838589 -231.441467) (xy 276.826866 -231.388843) (xy 276.822931 -231.335072) (xy 270.016986 -231.335072)
			(xy 270.016494 -231.362029) (xy 270.008644 -231.415369) (xy 269.993112 -231.466998) (xy 269.970227 -231.515815)
			(xy 269.940479 -231.560779) (xy 269.904501 -231.600933) (xy 269.863059 -231.635421) (xy 269.817038 -231.663507)
			(xy 269.767418 -231.684594) (xy 269.715257 -231.69823) (xy 269.661666 -231.704127) (xy 269.607787 -231.702158)
			(xy 269.554769 -231.692365) (xy 269.503742 -231.674957) (xy 269.455794 -231.650305) (xy 269.411946 -231.618935)
			(xy 269.373133 -231.581514) (xy 269.340181 -231.538841) (xy 269.313795 -231.491824) (xy 269.294535 -231.441467)
			(xy 269.282812 -231.388843) (xy 269.278877 -231.335072) (xy 264.143998 -231.335072) (xy 264.143998 -232.184956)
			(xy 265.178809 -232.184956) (xy 265.182744 -232.131185) (xy 265.194467 -232.078561) (xy 265.213727 -232.028204)
			(xy 265.240113 -231.981187) (xy 265.273065 -231.938514) (xy 265.311878 -231.901093) (xy 265.355726 -231.869723)
			(xy 265.403674 -231.845071) (xy 265.454701 -231.827663) (xy 265.507719 -231.81787) (xy 265.561598 -231.815901)
			(xy 265.615189 -231.821798) (xy 265.66735 -231.835434) (xy 265.71697 -231.856521) (xy 265.762991 -231.884607)
			(xy 265.804433 -231.919095) (xy 265.840411 -231.959249) (xy 265.870159 -232.004213) (xy 265.893044 -232.05303)
			(xy 265.908576 -232.104659) (xy 265.916426 -232.157999) (xy 265.916918 -232.184956) (xy 272.722863 -232.184956)
			(xy 272.726798 -232.131185) (xy 272.738521 -232.078561) (xy 272.757781 -232.028204) (xy 272.784167 -231.981187)
			(xy 272.817119 -231.938514) (xy 272.855932 -231.901093) (xy 272.89978 -231.869723) (xy 272.947728 -231.845071)
			(xy 272.998755 -231.827663) (xy 273.051773 -231.81787) (xy 273.105652 -231.815901) (xy 273.159243 -231.821798)
			(xy 273.211404 -231.835434) (xy 273.261024 -231.856521) (xy 273.307045 -231.884607) (xy 273.348487 -231.919095)
			(xy 273.384465 -231.959249) (xy 273.414213 -232.004213) (xy 273.437098 -232.05303) (xy 273.45263 -232.104659)
			(xy 273.46048 -232.157999) (xy 273.460972 -232.184956) (xy 280.266663 -232.184956) (xy 280.270598 -232.131185)
			(xy 280.282321 -232.078561) (xy 280.301581 -232.028204) (xy 280.327967 -231.981187) (xy 280.360919 -231.938514)
			(xy 280.399732 -231.901093) (xy 280.44358 -231.869723) (xy 280.491528 -231.845071) (xy 280.542555 -231.827663)
			(xy 280.595573 -231.81787) (xy 280.649452 -231.815901) (xy 280.703043 -231.821798) (xy 280.755204 -231.835434)
			(xy 280.804824 -231.856521) (xy 280.850845 -231.884607) (xy 280.892287 -231.919095) (xy 280.928265 -231.959249)
			(xy 280.958013 -232.004213) (xy 280.980898 -232.05303) (xy 280.99643 -232.104659) (xy 281.00428 -232.157999)
			(xy 281.004772 -232.184956) (xy 287.810717 -232.184956) (xy 287.814652 -232.131185) (xy 287.826375 -232.078561)
			(xy 287.845635 -232.028204) (xy 287.872021 -231.981187) (xy 287.904973 -231.938514) (xy 287.943786 -231.901093)
			(xy 287.987634 -231.869723) (xy 288.035582 -231.845071) (xy 288.086609 -231.827663) (xy 288.139627 -231.81787)
			(xy 288.193506 -231.815901) (xy 288.247097 -231.821798) (xy 288.299258 -231.835434) (xy 288.348878 -231.856521)
			(xy 288.394899 -231.884607) (xy 288.436341 -231.919095) (xy 288.472319 -231.959249) (xy 288.502067 -232.004213)
			(xy 288.524952 -232.05303) (xy 288.540484 -232.104659) (xy 288.548334 -232.157999) (xy 288.548826 -232.184956)
			(xy 288.548334 -232.211913) (xy 288.540484 -232.265253) (xy 288.524952 -232.316882) (xy 288.502067 -232.365699)
			(xy 288.472319 -232.410663) (xy 288.436341 -232.450817) (xy 288.394899 -232.485305) (xy 288.348878 -232.513391)
			(xy 288.299258 -232.534478) (xy 288.247097 -232.548114) (xy 288.193506 -232.554011) (xy 288.139627 -232.552042)
			(xy 288.086609 -232.542249) (xy 288.035582 -232.524841) (xy 287.987634 -232.500189) (xy 287.943786 -232.468819)
			(xy 287.904973 -232.431398) (xy 287.872021 -232.388725) (xy 287.845635 -232.341708) (xy 287.826375 -232.291351)
			(xy 287.814652 -232.238727) (xy 287.810717 -232.184956) (xy 281.004772 -232.184956) (xy 281.00428 -232.211913)
			(xy 280.99643 -232.265253) (xy 280.980898 -232.316882) (xy 280.958013 -232.365699) (xy 280.928265 -232.410663)
			(xy 280.892287 -232.450817) (xy 280.850845 -232.485305) (xy 280.804824 -232.513391) (xy 280.755204 -232.534478)
			(xy 280.703043 -232.548114) (xy 280.649452 -232.554011) (xy 280.595573 -232.552042) (xy 280.542555 -232.542249)
			(xy 280.491528 -232.524841) (xy 280.44358 -232.500189) (xy 280.399732 -232.468819) (xy 280.360919 -232.431398)
			(xy 280.327967 -232.388725) (xy 280.301581 -232.341708) (xy 280.282321 -232.291351) (xy 280.270598 -232.238727)
			(xy 280.266663 -232.184956) (xy 273.460972 -232.184956) (xy 273.46048 -232.211913) (xy 273.45263 -232.265253)
			(xy 273.437098 -232.316882) (xy 273.414213 -232.365699) (xy 273.384465 -232.410663) (xy 273.348487 -232.450817)
			(xy 273.307045 -232.485305) (xy 273.261024 -232.513391) (xy 273.211404 -232.534478) (xy 273.159243 -232.548114)
			(xy 273.105652 -232.554011) (xy 273.051773 -232.552042) (xy 272.998755 -232.542249) (xy 272.947728 -232.524841)
			(xy 272.89978 -232.500189) (xy 272.855932 -232.468819) (xy 272.817119 -232.431398) (xy 272.784167 -232.388725)
			(xy 272.757781 -232.341708) (xy 272.738521 -232.291351) (xy 272.726798 -232.238727) (xy 272.722863 -232.184956)
			(xy 265.916918 -232.184956) (xy 265.916426 -232.211913) (xy 265.908576 -232.265253) (xy 265.893044 -232.316882)
			(xy 265.870159 -232.365699) (xy 265.840411 -232.410663) (xy 265.804433 -232.450817) (xy 265.762991 -232.485305)
			(xy 265.71697 -232.513391) (xy 265.66735 -232.534478) (xy 265.615189 -232.548114) (xy 265.561598 -232.554011)
			(xy 265.507719 -232.552042) (xy 265.454701 -232.542249) (xy 265.403674 -232.524841) (xy 265.355726 -232.500189)
			(xy 265.311878 -232.468819) (xy 265.273065 -232.431398) (xy 265.240113 -232.388725) (xy 265.213727 -232.341708)
			(xy 265.194467 -232.291351) (xy 265.182744 -232.238727) (xy 265.178809 -232.184956) (xy 264.143998 -232.184956)
			(xy 264.143998 -233.035094) (xy 269.278877 -233.035094) (xy 269.282812 -232.981323) (xy 269.294535 -232.928699)
			(xy 269.313795 -232.878342) (xy 269.340181 -232.831325) (xy 269.373133 -232.788652) (xy 269.411946 -232.751231)
			(xy 269.455794 -232.719861) (xy 269.503742 -232.695209) (xy 269.554769 -232.677801) (xy 269.607787 -232.668008)
			(xy 269.661666 -232.666039) (xy 269.715257 -232.671936) (xy 269.767418 -232.685572) (xy 269.817038 -232.706659)
			(xy 269.863059 -232.734745) (xy 269.904501 -232.769233) (xy 269.940479 -232.809387) (xy 269.970227 -232.854351)
			(xy 269.993112 -232.903168) (xy 270.008644 -232.954797) (xy 270.016494 -233.008137) (xy 270.016986 -233.035094)
			(xy 276.822931 -233.035094) (xy 276.826866 -232.981323) (xy 276.838589 -232.928699) (xy 276.857849 -232.878342)
			(xy 276.884235 -232.831325) (xy 276.917187 -232.788652) (xy 276.956 -232.751231) (xy 276.999848 -232.719861)
			(xy 277.047796 -232.695209) (xy 277.098823 -232.677801) (xy 277.151841 -232.668008) (xy 277.20572 -232.666039)
			(xy 277.259311 -232.671936) (xy 277.311472 -232.685572) (xy 277.361092 -232.706659) (xy 277.407113 -232.734745)
			(xy 277.448555 -232.769233) (xy 277.484533 -232.809387) (xy 277.514281 -232.854351) (xy 277.537166 -232.903168)
			(xy 277.552698 -232.954797) (xy 277.560548 -233.008137) (xy 277.56104 -233.035094) (xy 284.366731 -233.035094)
			(xy 284.370666 -232.981323) (xy 284.382389 -232.928699) (xy 284.401649 -232.878342) (xy 284.428035 -232.831325)
			(xy 284.460987 -232.788652) (xy 284.4998 -232.751231) (xy 284.543648 -232.719861) (xy 284.591596 -232.695209)
			(xy 284.642623 -232.677801) (xy 284.695641 -232.668008) (xy 284.74952 -232.666039) (xy 284.803111 -232.671936)
			(xy 284.855272 -232.685572) (xy 284.904892 -232.706659) (xy 284.950913 -232.734745) (xy 284.992355 -232.769233)
			(xy 285.028333 -232.809387) (xy 285.058081 -232.854351) (xy 285.080966 -232.903168) (xy 285.096498 -232.954797)
			(xy 285.104348 -233.008137) (xy 285.10484 -233.035094) (xy 291.910785 -233.035094) (xy 291.91472 -232.981323)
			(xy 291.926443 -232.928699) (xy 291.945703 -232.878342) (xy 291.972089 -232.831325) (xy 292.005041 -232.788652)
			(xy 292.043854 -232.751231) (xy 292.087702 -232.719861) (xy 292.13565 -232.695209) (xy 292.186677 -232.677801)
			(xy 292.239695 -232.668008) (xy 292.293574 -232.666039) (xy 292.347165 -232.671936) (xy 292.399326 -232.685572)
			(xy 292.448946 -232.706659) (xy 292.494967 -232.734745) (xy 292.536409 -232.769233) (xy 292.572387 -232.809387)
			(xy 292.602135 -232.854351) (xy 292.62502 -232.903168) (xy 292.640552 -232.954797) (xy 292.648402 -233.008137)
			(xy 292.648894 -233.035094) (xy 292.648402 -233.062051) (xy 292.640552 -233.115391) (xy 292.62502 -233.16702)
			(xy 292.602135 -233.215837) (xy 292.572387 -233.260801) (xy 292.536409 -233.300955) (xy 292.494967 -233.335443)
			(xy 292.448946 -233.363529) (xy 292.399326 -233.384616) (xy 292.347165 -233.398252) (xy 292.293574 -233.404149)
			(xy 292.239695 -233.40218) (xy 292.186677 -233.392387) (xy 292.13565 -233.374979) (xy 292.087702 -233.350327)
			(xy 292.043854 -233.318957) (xy 292.005041 -233.281536) (xy 291.972089 -233.238863) (xy 291.945703 -233.191846)
			(xy 291.926443 -233.141489) (xy 291.91472 -233.088865) (xy 291.910785 -233.035094) (xy 285.10484 -233.035094)
			(xy 285.104348 -233.062051) (xy 285.096498 -233.115391) (xy 285.080966 -233.16702) (xy 285.058081 -233.215837)
			(xy 285.028333 -233.260801) (xy 284.992355 -233.300955) (xy 284.950913 -233.335443) (xy 284.904892 -233.363529)
			(xy 284.855272 -233.384616) (xy 284.803111 -233.398252) (xy 284.74952 -233.404149) (xy 284.695641 -233.40218)
			(xy 284.642623 -233.392387) (xy 284.591596 -233.374979) (xy 284.543648 -233.350327) (xy 284.4998 -233.318957)
			(xy 284.460987 -233.281536) (xy 284.428035 -233.238863) (xy 284.401649 -233.191846) (xy 284.382389 -233.141489)
			(xy 284.370666 -233.088865) (xy 284.366731 -233.035094) (xy 277.56104 -233.035094) (xy 277.560548 -233.062051)
			(xy 277.552698 -233.115391) (xy 277.537166 -233.16702) (xy 277.514281 -233.215837) (xy 277.484533 -233.260801)
			(xy 277.448555 -233.300955) (xy 277.407113 -233.335443) (xy 277.361092 -233.363529) (xy 277.311472 -233.384616)
			(xy 277.259311 -233.398252) (xy 277.20572 -233.404149) (xy 277.151841 -233.40218) (xy 277.098823 -233.392387)
			(xy 277.047796 -233.374979) (xy 276.999848 -233.350327) (xy 276.956 -233.318957) (xy 276.917187 -233.281536)
			(xy 276.884235 -233.238863) (xy 276.857849 -233.191846) (xy 276.838589 -233.141489) (xy 276.826866 -233.088865)
			(xy 276.822931 -233.035094) (xy 270.016986 -233.035094) (xy 270.016494 -233.062051) (xy 270.008644 -233.115391)
			(xy 269.993112 -233.16702) (xy 269.970227 -233.215837) (xy 269.940479 -233.260801) (xy 269.904501 -233.300955)
			(xy 269.863059 -233.335443) (xy 269.817038 -233.363529) (xy 269.767418 -233.384616) (xy 269.715257 -233.398252)
			(xy 269.661666 -233.404149) (xy 269.607787 -233.40218) (xy 269.554769 -233.392387) (xy 269.503742 -233.374979)
			(xy 269.455794 -233.350327) (xy 269.411946 -233.318957) (xy 269.373133 -233.281536) (xy 269.340181 -233.238863)
			(xy 269.313795 -233.191846) (xy 269.294535 -233.141489) (xy 269.282812 -233.088865) (xy 269.278877 -233.035094)
			(xy 264.143998 -233.035094) (xy 264.143998 -233.884978) (xy 265.178809 -233.884978) (xy 265.182744 -233.831207)
			(xy 265.194467 -233.778583) (xy 265.213727 -233.728226) (xy 265.240113 -233.681209) (xy 265.273065 -233.638536)
			(xy 265.311878 -233.601115) (xy 265.355726 -233.569745) (xy 265.403674 -233.545093) (xy 265.454701 -233.527685)
			(xy 265.507719 -233.517892) (xy 265.561598 -233.515923) (xy 265.615189 -233.52182) (xy 265.66735 -233.535456)
			(xy 265.71697 -233.556543) (xy 265.762991 -233.584629) (xy 265.804433 -233.619117) (xy 265.840411 -233.659271)
			(xy 265.870159 -233.704235) (xy 265.893044 -233.753052) (xy 265.908576 -233.804681) (xy 265.916426 -233.858021)
			(xy 265.916918 -233.884978) (xy 272.722863 -233.884978) (xy 272.726798 -233.831207) (xy 272.738521 -233.778583)
			(xy 272.757781 -233.728226) (xy 272.784167 -233.681209) (xy 272.817119 -233.638536) (xy 272.855932 -233.601115)
			(xy 272.89978 -233.569745) (xy 272.947728 -233.545093) (xy 272.998755 -233.527685) (xy 273.051773 -233.517892)
			(xy 273.105652 -233.515923) (xy 273.159243 -233.52182) (xy 273.211404 -233.535456) (xy 273.261024 -233.556543)
			(xy 273.307045 -233.584629) (xy 273.348487 -233.619117) (xy 273.384465 -233.659271) (xy 273.414213 -233.704235)
			(xy 273.437098 -233.753052) (xy 273.45263 -233.804681) (xy 273.46048 -233.858021) (xy 273.460972 -233.884978)
			(xy 280.266663 -233.884978) (xy 280.270598 -233.831207) (xy 280.282321 -233.778583) (xy 280.301581 -233.728226)
			(xy 280.327967 -233.681209) (xy 280.360919 -233.638536) (xy 280.399732 -233.601115) (xy 280.44358 -233.569745)
			(xy 280.491528 -233.545093) (xy 280.542555 -233.527685) (xy 280.595573 -233.517892) (xy 280.649452 -233.515923)
			(xy 280.703043 -233.52182) (xy 280.755204 -233.535456) (xy 280.804824 -233.556543) (xy 280.850845 -233.584629)
			(xy 280.892287 -233.619117) (xy 280.928265 -233.659271) (xy 280.958013 -233.704235) (xy 280.980898 -233.753052)
			(xy 280.99643 -233.804681) (xy 281.00428 -233.858021) (xy 281.004772 -233.884978) (xy 287.810717 -233.884978)
			(xy 287.814652 -233.831207) (xy 287.826375 -233.778583) (xy 287.845635 -233.728226) (xy 287.872021 -233.681209)
			(xy 287.904973 -233.638536) (xy 287.943786 -233.601115) (xy 287.987634 -233.569745) (xy 288.035582 -233.545093)
			(xy 288.086609 -233.527685) (xy 288.139627 -233.517892) (xy 288.193506 -233.515923) (xy 288.247097 -233.52182)
			(xy 288.299258 -233.535456) (xy 288.348878 -233.556543) (xy 288.394899 -233.584629) (xy 288.436341 -233.619117)
			(xy 288.472319 -233.659271) (xy 288.502067 -233.704235) (xy 288.524952 -233.753052) (xy 288.540484 -233.804681)
			(xy 288.548334 -233.858021) (xy 288.548826 -233.884978) (xy 288.548334 -233.911935) (xy 288.540484 -233.965275)
			(xy 288.524952 -234.016904) (xy 288.502067 -234.065721) (xy 288.472319 -234.110685) (xy 288.436341 -234.150839)
			(xy 288.394899 -234.185327) (xy 288.348878 -234.213413) (xy 288.299258 -234.2345) (xy 288.247097 -234.248136)
			(xy 288.193506 -234.254033) (xy 288.139627 -234.252064) (xy 288.086609 -234.242271) (xy 288.035582 -234.224863)
			(xy 287.987634 -234.200211) (xy 287.943786 -234.168841) (xy 287.904973 -234.13142) (xy 287.872021 -234.088747)
			(xy 287.845635 -234.04173) (xy 287.826375 -233.991373) (xy 287.814652 -233.938749) (xy 287.810717 -233.884978)
			(xy 281.004772 -233.884978) (xy 281.00428 -233.911935) (xy 280.99643 -233.965275) (xy 280.980898 -234.016904)
			(xy 280.958013 -234.065721) (xy 280.928265 -234.110685) (xy 280.892287 -234.150839) (xy 280.850845 -234.185327)
			(xy 280.804824 -234.213413) (xy 280.755204 -234.2345) (xy 280.703043 -234.248136) (xy 280.649452 -234.254033)
			(xy 280.595573 -234.252064) (xy 280.542555 -234.242271) (xy 280.491528 -234.224863) (xy 280.44358 -234.200211)
			(xy 280.399732 -234.168841) (xy 280.360919 -234.13142) (xy 280.327967 -234.088747) (xy 280.301581 -234.04173)
			(xy 280.282321 -233.991373) (xy 280.270598 -233.938749) (xy 280.266663 -233.884978) (xy 273.460972 -233.884978)
			(xy 273.46048 -233.911935) (xy 273.45263 -233.965275) (xy 273.437098 -234.016904) (xy 273.414213 -234.065721)
			(xy 273.384465 -234.110685) (xy 273.348487 -234.150839) (xy 273.307045 -234.185327) (xy 273.261024 -234.213413)
			(xy 273.211404 -234.2345) (xy 273.159243 -234.248136) (xy 273.105652 -234.254033) (xy 273.051773 -234.252064)
			(xy 272.998755 -234.242271) (xy 272.947728 -234.224863) (xy 272.89978 -234.200211) (xy 272.855932 -234.168841)
			(xy 272.817119 -234.13142) (xy 272.784167 -234.088747) (xy 272.757781 -234.04173) (xy 272.738521 -233.991373)
			(xy 272.726798 -233.938749) (xy 272.722863 -233.884978) (xy 265.916918 -233.884978) (xy 265.916426 -233.911935)
			(xy 265.908576 -233.965275) (xy 265.893044 -234.016904) (xy 265.870159 -234.065721) (xy 265.840411 -234.110685)
			(xy 265.804433 -234.150839) (xy 265.762991 -234.185327) (xy 265.71697 -234.213413) (xy 265.66735 -234.2345)
			(xy 265.615189 -234.248136) (xy 265.561598 -234.254033) (xy 265.507719 -234.252064) (xy 265.454701 -234.242271)
			(xy 265.403674 -234.224863) (xy 265.355726 -234.200211) (xy 265.311878 -234.168841) (xy 265.273065 -234.13142)
			(xy 265.240113 -234.088747) (xy 265.213727 -234.04173) (xy 265.194467 -233.991373) (xy 265.182744 -233.938749)
			(xy 265.178809 -233.884978) (xy 264.143998 -233.884978) (xy 264.143998 -234.735116) (xy 269.278877 -234.735116)
			(xy 269.282812 -234.681345) (xy 269.294535 -234.628721) (xy 269.313795 -234.578364) (xy 269.340181 -234.531347)
			(xy 269.373133 -234.488674) (xy 269.411946 -234.451253) (xy 269.455794 -234.419883) (xy 269.503742 -234.395231)
			(xy 269.554769 -234.377823) (xy 269.607787 -234.36803) (xy 269.661666 -234.366061) (xy 269.715257 -234.371958)
			(xy 269.767418 -234.385594) (xy 269.817038 -234.406681) (xy 269.863059 -234.434767) (xy 269.904501 -234.469255)
			(xy 269.940479 -234.509409) (xy 269.970227 -234.554373) (xy 269.993112 -234.60319) (xy 270.008644 -234.654819)
			(xy 270.016494 -234.708159) (xy 270.016986 -234.735116) (xy 276.822931 -234.735116) (xy 276.826866 -234.681345)
			(xy 276.838589 -234.628721) (xy 276.857849 -234.578364) (xy 276.884235 -234.531347) (xy 276.917187 -234.488674)
			(xy 276.956 -234.451253) (xy 276.999848 -234.419883) (xy 277.047796 -234.395231) (xy 277.098823 -234.377823)
			(xy 277.151841 -234.36803) (xy 277.20572 -234.366061) (xy 277.259311 -234.371958) (xy 277.311472 -234.385594)
			(xy 277.361092 -234.406681) (xy 277.407113 -234.434767) (xy 277.448555 -234.469255) (xy 277.484533 -234.509409)
			(xy 277.514281 -234.554373) (xy 277.537166 -234.60319) (xy 277.552698 -234.654819) (xy 277.560548 -234.708159)
			(xy 277.56104 -234.735116) (xy 284.366731 -234.735116) (xy 284.370666 -234.681345) (xy 284.382389 -234.628721)
			(xy 284.401649 -234.578364) (xy 284.428035 -234.531347) (xy 284.460987 -234.488674) (xy 284.4998 -234.451253)
			(xy 284.543648 -234.419883) (xy 284.591596 -234.395231) (xy 284.642623 -234.377823) (xy 284.695641 -234.36803)
			(xy 284.74952 -234.366061) (xy 284.803111 -234.371958) (xy 284.855272 -234.385594) (xy 284.904892 -234.406681)
			(xy 284.950913 -234.434767) (xy 284.992355 -234.469255) (xy 285.028333 -234.509409) (xy 285.058081 -234.554373)
			(xy 285.080966 -234.60319) (xy 285.096498 -234.654819) (xy 285.104348 -234.708159) (xy 285.10484 -234.735116)
			(xy 291.910785 -234.735116) (xy 291.91472 -234.681345) (xy 291.926443 -234.628721) (xy 291.945703 -234.578364)
			(xy 291.972089 -234.531347) (xy 292.005041 -234.488674) (xy 292.043854 -234.451253) (xy 292.087702 -234.419883)
			(xy 292.13565 -234.395231) (xy 292.186677 -234.377823) (xy 292.239695 -234.36803) (xy 292.293574 -234.366061)
			(xy 292.347165 -234.371958) (xy 292.399326 -234.385594) (xy 292.448946 -234.406681) (xy 292.494967 -234.434767)
			(xy 292.536409 -234.469255) (xy 292.572387 -234.509409) (xy 292.602135 -234.554373) (xy 292.62502 -234.60319)
			(xy 292.640552 -234.654819) (xy 292.648402 -234.708159) (xy 292.648894 -234.735116) (xy 292.648402 -234.762073)
			(xy 292.640552 -234.815413) (xy 292.62502 -234.867042) (xy 292.602135 -234.915859) (xy 292.572387 -234.960823)
			(xy 292.536409 -235.000977) (xy 292.494967 -235.035465) (xy 292.448946 -235.063551) (xy 292.399326 -235.084638)
			(xy 292.347165 -235.098274) (xy 292.293574 -235.104171) (xy 292.239695 -235.102202) (xy 292.186677 -235.092409)
			(xy 292.13565 -235.075001) (xy 292.087702 -235.050349) (xy 292.043854 -235.018979) (xy 292.005041 -234.981558)
			(xy 291.972089 -234.938885) (xy 291.945703 -234.891868) (xy 291.926443 -234.841511) (xy 291.91472 -234.788887)
			(xy 291.910785 -234.735116) (xy 285.10484 -234.735116) (xy 285.104348 -234.762073) (xy 285.096498 -234.815413)
			(xy 285.080966 -234.867042) (xy 285.058081 -234.915859) (xy 285.028333 -234.960823) (xy 284.992355 -235.000977)
			(xy 284.950913 -235.035465) (xy 284.904892 -235.063551) (xy 284.855272 -235.084638) (xy 284.803111 -235.098274)
			(xy 284.74952 -235.104171) (xy 284.695641 -235.102202) (xy 284.642623 -235.092409) (xy 284.591596 -235.075001)
			(xy 284.543648 -235.050349) (xy 284.4998 -235.018979) (xy 284.460987 -234.981558) (xy 284.428035 -234.938885)
			(xy 284.401649 -234.891868) (xy 284.382389 -234.841511) (xy 284.370666 -234.788887) (xy 284.366731 -234.735116)
			(xy 277.56104 -234.735116) (xy 277.560548 -234.762073) (xy 277.552698 -234.815413) (xy 277.537166 -234.867042)
			(xy 277.514281 -234.915859) (xy 277.484533 -234.960823) (xy 277.448555 -235.000977) (xy 277.407113 -235.035465)
			(xy 277.361092 -235.063551) (xy 277.311472 -235.084638) (xy 277.259311 -235.098274) (xy 277.20572 -235.104171)
			(xy 277.151841 -235.102202) (xy 277.098823 -235.092409) (xy 277.047796 -235.075001) (xy 276.999848 -235.050349)
			(xy 276.956 -235.018979) (xy 276.917187 -234.981558) (xy 276.884235 -234.938885) (xy 276.857849 -234.891868)
			(xy 276.838589 -234.841511) (xy 276.826866 -234.788887) (xy 276.822931 -234.735116) (xy 270.016986 -234.735116)
			(xy 270.016494 -234.762073) (xy 270.008644 -234.815413) (xy 269.993112 -234.867042) (xy 269.970227 -234.915859)
			(xy 269.940479 -234.960823) (xy 269.904501 -235.000977) (xy 269.863059 -235.035465) (xy 269.817038 -235.063551)
			(xy 269.767418 -235.084638) (xy 269.715257 -235.098274) (xy 269.661666 -235.104171) (xy 269.607787 -235.102202)
			(xy 269.554769 -235.092409) (xy 269.503742 -235.075001) (xy 269.455794 -235.050349) (xy 269.411946 -235.018979)
			(xy 269.373133 -234.981558) (xy 269.340181 -234.938885) (xy 269.313795 -234.891868) (xy 269.294535 -234.841511)
			(xy 269.282812 -234.788887) (xy 269.278877 -234.735116) (xy 264.143998 -234.735116) (xy 264.143998 -235.585)
			(xy 265.178809 -235.585) (xy 265.182744 -235.531229) (xy 265.194467 -235.478605) (xy 265.213727 -235.428248)
			(xy 265.240113 -235.381231) (xy 265.273065 -235.338558) (xy 265.311878 -235.301137) (xy 265.355726 -235.269767)
			(xy 265.403674 -235.245115) (xy 265.454701 -235.227707) (xy 265.507719 -235.217914) (xy 265.561598 -235.215945)
			(xy 265.615189 -235.221842) (xy 265.66735 -235.235478) (xy 265.71697 -235.256565) (xy 265.762991 -235.284651)
			(xy 265.804433 -235.319139) (xy 265.840411 -235.359293) (xy 265.870159 -235.404257) (xy 265.893044 -235.453074)
			(xy 265.908576 -235.504703) (xy 265.916426 -235.558043) (xy 265.916918 -235.585) (xy 272.722863 -235.585)
			(xy 272.726798 -235.531229) (xy 272.738521 -235.478605) (xy 272.757781 -235.428248) (xy 272.784167 -235.381231)
			(xy 272.817119 -235.338558) (xy 272.855932 -235.301137) (xy 272.89978 -235.269767) (xy 272.947728 -235.245115)
			(xy 272.998755 -235.227707) (xy 273.051773 -235.217914) (xy 273.105652 -235.215945) (xy 273.159243 -235.221842)
			(xy 273.211404 -235.235478) (xy 273.261024 -235.256565) (xy 273.307045 -235.284651) (xy 273.348487 -235.319139)
			(xy 273.384465 -235.359293) (xy 273.414213 -235.404257) (xy 273.437098 -235.453074) (xy 273.45263 -235.504703)
			(xy 273.46048 -235.558043) (xy 273.460972 -235.585) (xy 280.266663 -235.585) (xy 280.270598 -235.531229)
			(xy 280.282321 -235.478605) (xy 280.301581 -235.428248) (xy 280.327967 -235.381231) (xy 280.360919 -235.338558)
			(xy 280.399732 -235.301137) (xy 280.44358 -235.269767) (xy 280.491528 -235.245115) (xy 280.542555 -235.227707)
			(xy 280.595573 -235.217914) (xy 280.649452 -235.215945) (xy 280.703043 -235.221842) (xy 280.755204 -235.235478)
			(xy 280.804824 -235.256565) (xy 280.850845 -235.284651) (xy 280.892287 -235.319139) (xy 280.928265 -235.359293)
			(xy 280.958013 -235.404257) (xy 280.980898 -235.453074) (xy 280.99643 -235.504703) (xy 281.00428 -235.558043)
			(xy 281.004772 -235.585) (xy 287.810717 -235.585) (xy 287.814652 -235.531229) (xy 287.826375 -235.478605)
			(xy 287.845635 -235.428248) (xy 287.872021 -235.381231) (xy 287.904973 -235.338558) (xy 287.943786 -235.301137)
			(xy 287.987634 -235.269767) (xy 288.035582 -235.245115) (xy 288.086609 -235.227707) (xy 288.139627 -235.217914)
			(xy 288.193506 -235.215945) (xy 288.247097 -235.221842) (xy 288.299258 -235.235478) (xy 288.348878 -235.256565)
			(xy 288.394899 -235.284651) (xy 288.436341 -235.319139) (xy 288.472319 -235.359293) (xy 288.502067 -235.404257)
			(xy 288.524952 -235.453074) (xy 288.540484 -235.504703) (xy 288.548334 -235.558043) (xy 288.548826 -235.585)
			(xy 288.548334 -235.611957) (xy 288.540484 -235.665297) (xy 288.524952 -235.716926) (xy 288.502067 -235.765743)
			(xy 288.472319 -235.810707) (xy 288.436341 -235.850861) (xy 288.394899 -235.885349) (xy 288.348878 -235.913435)
			(xy 288.299258 -235.934522) (xy 288.247097 -235.948158) (xy 288.193506 -235.954055) (xy 288.139627 -235.952086)
			(xy 288.086609 -235.942293) (xy 288.035582 -235.924885) (xy 287.987634 -235.900233) (xy 287.943786 -235.868863)
			(xy 287.904973 -235.831442) (xy 287.872021 -235.788769) (xy 287.845635 -235.741752) (xy 287.826375 -235.691395)
			(xy 287.814652 -235.638771) (xy 287.810717 -235.585) (xy 281.004772 -235.585) (xy 281.00428 -235.611957)
			(xy 280.99643 -235.665297) (xy 280.980898 -235.716926) (xy 280.958013 -235.765743) (xy 280.928265 -235.810707)
			(xy 280.892287 -235.850861) (xy 280.850845 -235.885349) (xy 280.804824 -235.913435) (xy 280.755204 -235.934522)
			(xy 280.703043 -235.948158) (xy 280.649452 -235.954055) (xy 280.595573 -235.952086) (xy 280.542555 -235.942293)
			(xy 280.491528 -235.924885) (xy 280.44358 -235.900233) (xy 280.399732 -235.868863) (xy 280.360919 -235.831442)
			(xy 280.327967 -235.788769) (xy 280.301581 -235.741752) (xy 280.282321 -235.691395) (xy 280.270598 -235.638771)
			(xy 280.266663 -235.585) (xy 273.460972 -235.585) (xy 273.46048 -235.611957) (xy 273.45263 -235.665297)
			(xy 273.437098 -235.716926) (xy 273.414213 -235.765743) (xy 273.384465 -235.810707) (xy 273.348487 -235.850861)
			(xy 273.307045 -235.885349) (xy 273.261024 -235.913435) (xy 273.211404 -235.934522) (xy 273.159243 -235.948158)
			(xy 273.105652 -235.954055) (xy 273.051773 -235.952086) (xy 272.998755 -235.942293) (xy 272.947728 -235.924885)
			(xy 272.89978 -235.900233) (xy 272.855932 -235.868863) (xy 272.817119 -235.831442) (xy 272.784167 -235.788769)
			(xy 272.757781 -235.741752) (xy 272.738521 -235.691395) (xy 272.726798 -235.638771) (xy 272.722863 -235.585)
			(xy 265.916918 -235.585) (xy 265.916426 -235.611957) (xy 265.908576 -235.665297) (xy 265.893044 -235.716926)
			(xy 265.870159 -235.765743) (xy 265.840411 -235.810707) (xy 265.804433 -235.850861) (xy 265.762991 -235.885349)
			(xy 265.71697 -235.913435) (xy 265.66735 -235.934522) (xy 265.615189 -235.948158) (xy 265.561598 -235.954055)
			(xy 265.507719 -235.952086) (xy 265.454701 -235.942293) (xy 265.403674 -235.924885) (xy 265.355726 -235.900233)
			(xy 265.311878 -235.868863) (xy 265.273065 -235.831442) (xy 265.240113 -235.788769) (xy 265.213727 -235.741752)
			(xy 265.194467 -235.691395) (xy 265.182744 -235.638771) (xy 265.178809 -235.585) (xy 264.143998 -235.585)
			(xy 264.143998 -236.435138) (xy 269.278877 -236.435138) (xy 269.282812 -236.381367) (xy 269.294535 -236.328743)
			(xy 269.313795 -236.278386) (xy 269.340181 -236.231369) (xy 269.373133 -236.188696) (xy 269.411946 -236.151275)
			(xy 269.455794 -236.119905) (xy 269.503742 -236.095253) (xy 269.554769 -236.077845) (xy 269.607787 -236.068052)
			(xy 269.661666 -236.066083) (xy 269.715257 -236.07198) (xy 269.767418 -236.085616) (xy 269.817038 -236.106703)
			(xy 269.863059 -236.134789) (xy 269.904501 -236.169277) (xy 269.940479 -236.209431) (xy 269.970227 -236.254395)
			(xy 269.993112 -236.303212) (xy 270.008644 -236.354841) (xy 270.016494 -236.408181) (xy 270.016986 -236.435138)
			(xy 276.822931 -236.435138) (xy 276.826866 -236.381367) (xy 276.838589 -236.328743) (xy 276.857849 -236.278386)
			(xy 276.884235 -236.231369) (xy 276.917187 -236.188696) (xy 276.956 -236.151275) (xy 276.999848 -236.119905)
			(xy 277.047796 -236.095253) (xy 277.098823 -236.077845) (xy 277.151841 -236.068052) (xy 277.20572 -236.066083)
			(xy 277.259311 -236.07198) (xy 277.311472 -236.085616) (xy 277.361092 -236.106703) (xy 277.407113 -236.134789)
			(xy 277.448555 -236.169277) (xy 277.484533 -236.209431) (xy 277.514281 -236.254395) (xy 277.537166 -236.303212)
			(xy 277.552698 -236.354841) (xy 277.560548 -236.408181) (xy 277.56104 -236.435138) (xy 284.366731 -236.435138)
			(xy 284.370666 -236.381367) (xy 284.382389 -236.328743) (xy 284.401649 -236.278386) (xy 284.428035 -236.231369)
			(xy 284.460987 -236.188696) (xy 284.4998 -236.151275) (xy 284.543648 -236.119905) (xy 284.591596 -236.095253)
			(xy 284.642623 -236.077845) (xy 284.695641 -236.068052) (xy 284.74952 -236.066083) (xy 284.803111 -236.07198)
			(xy 284.855272 -236.085616) (xy 284.904892 -236.106703) (xy 284.950913 -236.134789) (xy 284.992355 -236.169277)
			(xy 285.028333 -236.209431) (xy 285.058081 -236.254395) (xy 285.080966 -236.303212) (xy 285.096498 -236.354841)
			(xy 285.104348 -236.408181) (xy 285.10484 -236.435138) (xy 291.910785 -236.435138) (xy 291.91472 -236.381367)
			(xy 291.926443 -236.328743) (xy 291.945703 -236.278386) (xy 291.972089 -236.231369) (xy 292.005041 -236.188696)
			(xy 292.043854 -236.151275) (xy 292.087702 -236.119905) (xy 292.13565 -236.095253) (xy 292.186677 -236.077845)
			(xy 292.239695 -236.068052) (xy 292.293574 -236.066083) (xy 292.347165 -236.07198) (xy 292.399326 -236.085616)
			(xy 292.448946 -236.106703) (xy 292.494967 -236.134789) (xy 292.536409 -236.169277) (xy 292.572387 -236.209431)
			(xy 292.602135 -236.254395) (xy 292.62502 -236.303212) (xy 292.640552 -236.354841) (xy 292.648402 -236.408181)
			(xy 292.648894 -236.435138) (xy 292.648402 -236.462095) (xy 292.640552 -236.515435) (xy 292.62502 -236.567064)
			(xy 292.602135 -236.615881) (xy 292.572387 -236.660845) (xy 292.536409 -236.700999) (xy 292.494967 -236.735487)
			(xy 292.448946 -236.763573) (xy 292.399326 -236.78466) (xy 292.347165 -236.798296) (xy 292.293574 -236.804193)
			(xy 292.239695 -236.802224) (xy 292.186677 -236.792431) (xy 292.13565 -236.775023) (xy 292.087702 -236.750371)
			(xy 292.043854 -236.719001) (xy 292.005041 -236.68158) (xy 291.972089 -236.638907) (xy 291.945703 -236.59189)
			(xy 291.926443 -236.541533) (xy 291.91472 -236.488909) (xy 291.910785 -236.435138) (xy 285.10484 -236.435138)
			(xy 285.104348 -236.462095) (xy 285.096498 -236.515435) (xy 285.080966 -236.567064) (xy 285.058081 -236.615881)
			(xy 285.028333 -236.660845) (xy 284.992355 -236.700999) (xy 284.950913 -236.735487) (xy 284.904892 -236.763573)
			(xy 284.855272 -236.78466) (xy 284.803111 -236.798296) (xy 284.74952 -236.804193) (xy 284.695641 -236.802224)
			(xy 284.642623 -236.792431) (xy 284.591596 -236.775023) (xy 284.543648 -236.750371) (xy 284.4998 -236.719001)
			(xy 284.460987 -236.68158) (xy 284.428035 -236.638907) (xy 284.401649 -236.59189) (xy 284.382389 -236.541533)
			(xy 284.370666 -236.488909) (xy 284.366731 -236.435138) (xy 277.56104 -236.435138) (xy 277.560548 -236.462095)
			(xy 277.552698 -236.515435) (xy 277.537166 -236.567064) (xy 277.514281 -236.615881) (xy 277.484533 -236.660845)
			(xy 277.448555 -236.700999) (xy 277.407113 -236.735487) (xy 277.361092 -236.763573) (xy 277.311472 -236.78466)
			(xy 277.259311 -236.798296) (xy 277.20572 -236.804193) (xy 277.151841 -236.802224) (xy 277.098823 -236.792431)
			(xy 277.047796 -236.775023) (xy 276.999848 -236.750371) (xy 276.956 -236.719001) (xy 276.917187 -236.68158)
			(xy 276.884235 -236.638907) (xy 276.857849 -236.59189) (xy 276.838589 -236.541533) (xy 276.826866 -236.488909)
			(xy 276.822931 -236.435138) (xy 270.016986 -236.435138) (xy 270.016494 -236.462095) (xy 270.008644 -236.515435)
			(xy 269.993112 -236.567064) (xy 269.970227 -236.615881) (xy 269.940479 -236.660845) (xy 269.904501 -236.700999)
			(xy 269.863059 -236.735487) (xy 269.817038 -236.763573) (xy 269.767418 -236.78466) (xy 269.715257 -236.798296)
			(xy 269.661666 -236.804193) (xy 269.607787 -236.802224) (xy 269.554769 -236.792431) (xy 269.503742 -236.775023)
			(xy 269.455794 -236.750371) (xy 269.411946 -236.719001) (xy 269.373133 -236.68158) (xy 269.340181 -236.638907)
			(xy 269.313795 -236.59189) (xy 269.294535 -236.541533) (xy 269.282812 -236.488909) (xy 269.278877 -236.435138)
			(xy 264.143998 -236.435138) (xy 264.143998 -237.285022) (xy 265.178809 -237.285022) (xy 265.182744 -237.231251)
			(xy 265.194467 -237.178627) (xy 265.213727 -237.12827) (xy 265.240113 -237.081253) (xy 265.273065 -237.03858)
			(xy 265.311878 -237.001159) (xy 265.355726 -236.969789) (xy 265.403674 -236.945137) (xy 265.454701 -236.927729)
			(xy 265.507719 -236.917936) (xy 265.561598 -236.915967) (xy 265.615189 -236.921864) (xy 265.66735 -236.9355)
			(xy 265.71697 -236.956587) (xy 265.762991 -236.984673) (xy 265.804433 -237.019161) (xy 265.840411 -237.059315)
			(xy 265.870159 -237.104279) (xy 265.893044 -237.153096) (xy 265.908576 -237.204725) (xy 265.916426 -237.258065)
			(xy 265.916918 -237.285022) (xy 272.722863 -237.285022) (xy 272.726798 -237.231251) (xy 272.738521 -237.178627)
			(xy 272.757781 -237.12827) (xy 272.784167 -237.081253) (xy 272.817119 -237.03858) (xy 272.855932 -237.001159)
			(xy 272.89978 -236.969789) (xy 272.947728 -236.945137) (xy 272.998755 -236.927729) (xy 273.051773 -236.917936)
			(xy 273.105652 -236.915967) (xy 273.159243 -236.921864) (xy 273.211404 -236.9355) (xy 273.261024 -236.956587)
			(xy 273.307045 -236.984673) (xy 273.348487 -237.019161) (xy 273.384465 -237.059315) (xy 273.414213 -237.104279)
			(xy 273.437098 -237.153096) (xy 273.45263 -237.204725) (xy 273.46048 -237.258065) (xy 273.460972 -237.285022)
			(xy 280.266663 -237.285022) (xy 280.270598 -237.231251) (xy 280.282321 -237.178627) (xy 280.301581 -237.12827)
			(xy 280.327967 -237.081253) (xy 280.360919 -237.03858) (xy 280.399732 -237.001159) (xy 280.44358 -236.969789)
			(xy 280.491528 -236.945137) (xy 280.542555 -236.927729) (xy 280.595573 -236.917936) (xy 280.649452 -236.915967)
			(xy 280.703043 -236.921864) (xy 280.755204 -236.9355) (xy 280.804824 -236.956587) (xy 280.850845 -236.984673)
			(xy 280.892287 -237.019161) (xy 280.928265 -237.059315) (xy 280.958013 -237.104279) (xy 280.980898 -237.153096)
			(xy 280.99643 -237.204725) (xy 281.00428 -237.258065) (xy 281.004772 -237.285022) (xy 287.810717 -237.285022)
			(xy 287.814652 -237.231251) (xy 287.826375 -237.178627) (xy 287.845635 -237.12827) (xy 287.872021 -237.081253)
			(xy 287.904973 -237.03858) (xy 287.943786 -237.001159) (xy 287.987634 -236.969789) (xy 288.035582 -236.945137)
			(xy 288.086609 -236.927729) (xy 288.139627 -236.917936) (xy 288.193506 -236.915967) (xy 288.247097 -236.921864)
			(xy 288.299258 -236.9355) (xy 288.348878 -236.956587) (xy 288.394899 -236.984673) (xy 288.436341 -237.019161)
			(xy 288.472319 -237.059315) (xy 288.502067 -237.104279) (xy 288.524952 -237.153096) (xy 288.540484 -237.204725)
			(xy 288.548334 -237.258065) (xy 288.548826 -237.285022) (xy 288.548334 -237.311979) (xy 288.540484 -237.365319)
			(xy 288.524952 -237.416948) (xy 288.502067 -237.465765) (xy 288.472319 -237.510729) (xy 288.436341 -237.550883)
			(xy 288.394899 -237.585371) (xy 288.348878 -237.613457) (xy 288.299258 -237.634544) (xy 288.247097 -237.64818)
			(xy 288.193506 -237.654077) (xy 288.139627 -237.652108) (xy 288.086609 -237.642315) (xy 288.035582 -237.624907)
			(xy 287.987634 -237.600255) (xy 287.943786 -237.568885) (xy 287.904973 -237.531464) (xy 287.872021 -237.488791)
			(xy 287.845635 -237.441774) (xy 287.826375 -237.391417) (xy 287.814652 -237.338793) (xy 287.810717 -237.285022)
			(xy 281.004772 -237.285022) (xy 281.00428 -237.311979) (xy 280.99643 -237.365319) (xy 280.980898 -237.416948)
			(xy 280.958013 -237.465765) (xy 280.928265 -237.510729) (xy 280.892287 -237.550883) (xy 280.850845 -237.585371)
			(xy 280.804824 -237.613457) (xy 280.755204 -237.634544) (xy 280.703043 -237.64818) (xy 280.649452 -237.654077)
			(xy 280.595573 -237.652108) (xy 280.542555 -237.642315) (xy 280.491528 -237.624907) (xy 280.44358 -237.600255)
			(xy 280.399732 -237.568885) (xy 280.360919 -237.531464) (xy 280.327967 -237.488791) (xy 280.301581 -237.441774)
			(xy 280.282321 -237.391417) (xy 280.270598 -237.338793) (xy 280.266663 -237.285022) (xy 273.460972 -237.285022)
			(xy 273.46048 -237.311979) (xy 273.45263 -237.365319) (xy 273.437098 -237.416948) (xy 273.414213 -237.465765)
			(xy 273.384465 -237.510729) (xy 273.348487 -237.550883) (xy 273.307045 -237.585371) (xy 273.261024 -237.613457)
			(xy 273.211404 -237.634544) (xy 273.159243 -237.64818) (xy 273.105652 -237.654077) (xy 273.051773 -237.652108)
			(xy 272.998755 -237.642315) (xy 272.947728 -237.624907) (xy 272.89978 -237.600255) (xy 272.855932 -237.568885)
			(xy 272.817119 -237.531464) (xy 272.784167 -237.488791) (xy 272.757781 -237.441774) (xy 272.738521 -237.391417)
			(xy 272.726798 -237.338793) (xy 272.722863 -237.285022) (xy 265.916918 -237.285022) (xy 265.916426 -237.311979)
			(xy 265.908576 -237.365319) (xy 265.893044 -237.416948) (xy 265.870159 -237.465765) (xy 265.840411 -237.510729)
			(xy 265.804433 -237.550883) (xy 265.762991 -237.585371) (xy 265.71697 -237.613457) (xy 265.66735 -237.634544)
			(xy 265.615189 -237.64818) (xy 265.561598 -237.654077) (xy 265.507719 -237.652108) (xy 265.454701 -237.642315)
			(xy 265.403674 -237.624907) (xy 265.355726 -237.600255) (xy 265.311878 -237.568885) (xy 265.273065 -237.531464)
			(xy 265.240113 -237.488791) (xy 265.213727 -237.441774) (xy 265.194467 -237.391417) (xy 265.182744 -237.338793)
			(xy 265.178809 -237.285022) (xy 264.143998 -237.285022) (xy 264.143998 -238.13516) (xy 269.278877 -238.13516)
			(xy 269.282812 -238.081389) (xy 269.294535 -238.028765) (xy 269.313795 -237.978408) (xy 269.340181 -237.931391)
			(xy 269.373133 -237.888718) (xy 269.411946 -237.851297) (xy 269.455794 -237.819927) (xy 269.503742 -237.795275)
			(xy 269.554769 -237.777867) (xy 269.607787 -237.768074) (xy 269.661666 -237.766105) (xy 269.715257 -237.772002)
			(xy 269.767418 -237.785638) (xy 269.817038 -237.806725) (xy 269.863059 -237.834811) (xy 269.904501 -237.869299)
			(xy 269.940479 -237.909453) (xy 269.970227 -237.954417) (xy 269.993112 -238.003234) (xy 270.008644 -238.054863)
			(xy 270.016494 -238.108203) (xy 270.016986 -238.13516) (xy 276.822931 -238.13516) (xy 276.826866 -238.081389)
			(xy 276.838589 -238.028765) (xy 276.857849 -237.978408) (xy 276.884235 -237.931391) (xy 276.917187 -237.888718)
			(xy 276.956 -237.851297) (xy 276.999848 -237.819927) (xy 277.047796 -237.795275) (xy 277.098823 -237.777867)
			(xy 277.151841 -237.768074) (xy 277.20572 -237.766105) (xy 277.259311 -237.772002) (xy 277.311472 -237.785638)
			(xy 277.361092 -237.806725) (xy 277.407113 -237.834811) (xy 277.448555 -237.869299) (xy 277.484533 -237.909453)
			(xy 277.514281 -237.954417) (xy 277.537166 -238.003234) (xy 277.552698 -238.054863) (xy 277.560548 -238.108203)
			(xy 277.56104 -238.13516) (xy 284.366731 -238.13516) (xy 284.370666 -238.081389) (xy 284.382389 -238.028765)
			(xy 284.401649 -237.978408) (xy 284.428035 -237.931391) (xy 284.460987 -237.888718) (xy 284.4998 -237.851297)
			(xy 284.543648 -237.819927) (xy 284.591596 -237.795275) (xy 284.642623 -237.777867) (xy 284.695641 -237.768074)
			(xy 284.74952 -237.766105) (xy 284.803111 -237.772002) (xy 284.855272 -237.785638) (xy 284.904892 -237.806725)
			(xy 284.950913 -237.834811) (xy 284.992355 -237.869299) (xy 285.028333 -237.909453) (xy 285.058081 -237.954417)
			(xy 285.080966 -238.003234) (xy 285.096498 -238.054863) (xy 285.104348 -238.108203) (xy 285.10484 -238.13516)
			(xy 291.910785 -238.13516) (xy 291.91472 -238.081389) (xy 291.926443 -238.028765) (xy 291.945703 -237.978408)
			(xy 291.972089 -237.931391) (xy 292.005041 -237.888718) (xy 292.043854 -237.851297) (xy 292.087702 -237.819927)
			(xy 292.13565 -237.795275) (xy 292.186677 -237.777867) (xy 292.239695 -237.768074) (xy 292.293574 -237.766105)
			(xy 292.347165 -237.772002) (xy 292.399326 -237.785638) (xy 292.448946 -237.806725) (xy 292.494967 -237.834811)
			(xy 292.536409 -237.869299) (xy 292.572387 -237.909453) (xy 292.602135 -237.954417) (xy 292.62502 -238.003234)
			(xy 292.640552 -238.054863) (xy 292.648402 -238.108203) (xy 292.648894 -238.13516) (xy 292.648402 -238.162117)
			(xy 292.640552 -238.215457) (xy 292.62502 -238.267086) (xy 292.602135 -238.315903) (xy 292.572387 -238.360867)
			(xy 292.536409 -238.401021) (xy 292.494967 -238.435509) (xy 292.448946 -238.463595) (xy 292.399326 -238.484682)
			(xy 292.347165 -238.498318) (xy 292.293574 -238.504215) (xy 292.239695 -238.502246) (xy 292.186677 -238.492453)
			(xy 292.13565 -238.475045) (xy 292.087702 -238.450393) (xy 292.043854 -238.419023) (xy 292.005041 -238.381602)
			(xy 291.972089 -238.338929) (xy 291.945703 -238.291912) (xy 291.926443 -238.241555) (xy 291.91472 -238.188931)
			(xy 291.910785 -238.13516) (xy 285.10484 -238.13516) (xy 285.104348 -238.162117) (xy 285.096498 -238.215457)
			(xy 285.080966 -238.267086) (xy 285.058081 -238.315903) (xy 285.028333 -238.360867) (xy 284.992355 -238.401021)
			(xy 284.950913 -238.435509) (xy 284.904892 -238.463595) (xy 284.855272 -238.484682) (xy 284.803111 -238.498318)
			(xy 284.74952 -238.504215) (xy 284.695641 -238.502246) (xy 284.642623 -238.492453) (xy 284.591596 -238.475045)
			(xy 284.543648 -238.450393) (xy 284.4998 -238.419023) (xy 284.460987 -238.381602) (xy 284.428035 -238.338929)
			(xy 284.401649 -238.291912) (xy 284.382389 -238.241555) (xy 284.370666 -238.188931) (xy 284.366731 -238.13516)
			(xy 277.56104 -238.13516) (xy 277.560548 -238.162117) (xy 277.552698 -238.215457) (xy 277.537166 -238.267086)
			(xy 277.514281 -238.315903) (xy 277.484533 -238.360867) (xy 277.448555 -238.401021) (xy 277.407113 -238.435509)
			(xy 277.361092 -238.463595) (xy 277.311472 -238.484682) (xy 277.259311 -238.498318) (xy 277.20572 -238.504215)
			(xy 277.151841 -238.502246) (xy 277.098823 -238.492453) (xy 277.047796 -238.475045) (xy 276.999848 -238.450393)
			(xy 276.956 -238.419023) (xy 276.917187 -238.381602) (xy 276.884235 -238.338929) (xy 276.857849 -238.291912)
			(xy 276.838589 -238.241555) (xy 276.826866 -238.188931) (xy 276.822931 -238.13516) (xy 270.016986 -238.13516)
			(xy 270.016494 -238.162117) (xy 270.008644 -238.215457) (xy 269.993112 -238.267086) (xy 269.970227 -238.315903)
			(xy 269.940479 -238.360867) (xy 269.904501 -238.401021) (xy 269.863059 -238.435509) (xy 269.817038 -238.463595)
			(xy 269.767418 -238.484682) (xy 269.715257 -238.498318) (xy 269.661666 -238.504215) (xy 269.607787 -238.502246)
			(xy 269.554769 -238.492453) (xy 269.503742 -238.475045) (xy 269.455794 -238.450393) (xy 269.411946 -238.419023)
			(xy 269.373133 -238.381602) (xy 269.340181 -238.338929) (xy 269.313795 -238.291912) (xy 269.294535 -238.241555)
			(xy 269.282812 -238.188931) (xy 269.278877 -238.13516) (xy 264.143998 -238.13516) (xy 264.143998 -238.985044)
			(xy 265.178809 -238.985044) (xy 265.182744 -238.931273) (xy 265.194467 -238.878649) (xy 265.213727 -238.828292)
			(xy 265.240113 -238.781275) (xy 265.273065 -238.738602) (xy 265.311878 -238.701181) (xy 265.355726 -238.669811)
			(xy 265.403674 -238.645159) (xy 265.454701 -238.627751) (xy 265.507719 -238.617958) (xy 265.561598 -238.615989)
			(xy 265.615189 -238.621886) (xy 265.66735 -238.635522) (xy 265.71697 -238.656609) (xy 265.762991 -238.684695)
			(xy 265.804433 -238.719183) (xy 265.840411 -238.759337) (xy 265.870159 -238.804301) (xy 265.893044 -238.853118)
			(xy 265.908576 -238.904747) (xy 265.916426 -238.958087) (xy 265.916918 -238.985044) (xy 269.278877 -238.985044)
			(xy 269.282812 -238.931273) (xy 269.294535 -238.878649) (xy 269.313795 -238.828292) (xy 269.340181 -238.781275)
			(xy 269.373133 -238.738602) (xy 269.411946 -238.701181) (xy 269.455794 -238.669811) (xy 269.503742 -238.645159)
			(xy 269.554769 -238.627751) (xy 269.607787 -238.617958) (xy 269.661666 -238.615989) (xy 269.715257 -238.621886)
			(xy 269.767418 -238.635522) (xy 269.817038 -238.656609) (xy 269.863059 -238.684695) (xy 269.904501 -238.719183)
			(xy 269.940479 -238.759337) (xy 269.970227 -238.804301) (xy 269.993112 -238.853118) (xy 270.008644 -238.904747)
			(xy 270.016494 -238.958087) (xy 270.016986 -238.985044) (xy 272.722863 -238.985044) (xy 272.726798 -238.931273)
			(xy 272.738521 -238.878649) (xy 272.757781 -238.828292) (xy 272.784167 -238.781275) (xy 272.817119 -238.738602)
			(xy 272.855932 -238.701181) (xy 272.89978 -238.669811) (xy 272.947728 -238.645159) (xy 272.998755 -238.627751)
			(xy 273.051773 -238.617958) (xy 273.105652 -238.615989) (xy 273.159243 -238.621886) (xy 273.211404 -238.635522)
			(xy 273.261024 -238.656609) (xy 273.307045 -238.684695) (xy 273.348487 -238.719183) (xy 273.384465 -238.759337)
			(xy 273.414213 -238.804301) (xy 273.437098 -238.853118) (xy 273.45263 -238.904747) (xy 273.46048 -238.958087)
			(xy 273.460972 -238.985044) (xy 276.822931 -238.985044) (xy 276.826866 -238.931273) (xy 276.838589 -238.878649)
			(xy 276.857849 -238.828292) (xy 276.884235 -238.781275) (xy 276.917187 -238.738602) (xy 276.956 -238.701181)
			(xy 276.999848 -238.669811) (xy 277.047796 -238.645159) (xy 277.098823 -238.627751) (xy 277.151841 -238.617958)
			(xy 277.20572 -238.615989) (xy 277.259311 -238.621886) (xy 277.311472 -238.635522) (xy 277.361092 -238.656609)
			(xy 277.407113 -238.684695) (xy 277.448555 -238.719183) (xy 277.484533 -238.759337) (xy 277.514281 -238.804301)
			(xy 277.537166 -238.853118) (xy 277.552698 -238.904747) (xy 277.560548 -238.958087) (xy 277.56104 -238.985044)
			(xy 280.266663 -238.985044) (xy 280.270598 -238.931273) (xy 280.282321 -238.878649) (xy 280.301581 -238.828292)
			(xy 280.327967 -238.781275) (xy 280.360919 -238.738602) (xy 280.399732 -238.701181) (xy 280.44358 -238.669811)
			(xy 280.491528 -238.645159) (xy 280.542555 -238.627751) (xy 280.595573 -238.617958) (xy 280.649452 -238.615989)
			(xy 280.703043 -238.621886) (xy 280.755204 -238.635522) (xy 280.804824 -238.656609) (xy 280.850845 -238.684695)
			(xy 280.892287 -238.719183) (xy 280.928265 -238.759337) (xy 280.958013 -238.804301) (xy 280.980898 -238.853118)
			(xy 280.99643 -238.904747) (xy 281.00428 -238.958087) (xy 281.004772 -238.985044) (xy 284.366731 -238.985044)
			(xy 284.370666 -238.931273) (xy 284.382389 -238.878649) (xy 284.401649 -238.828292) (xy 284.428035 -238.781275)
			(xy 284.460987 -238.738602) (xy 284.4998 -238.701181) (xy 284.543648 -238.669811) (xy 284.591596 -238.645159)
			(xy 284.642623 -238.627751) (xy 284.695641 -238.617958) (xy 284.74952 -238.615989) (xy 284.803111 -238.621886)
			(xy 284.855272 -238.635522) (xy 284.904892 -238.656609) (xy 284.950913 -238.684695) (xy 284.992355 -238.719183)
			(xy 285.028333 -238.759337) (xy 285.058081 -238.804301) (xy 285.080966 -238.853118) (xy 285.096498 -238.904747)
			(xy 285.104348 -238.958087) (xy 285.10484 -238.985044) (xy 287.810717 -238.985044) (xy 287.814652 -238.931273)
			(xy 287.826375 -238.878649) (xy 287.845635 -238.828292) (xy 287.872021 -238.781275) (xy 287.904973 -238.738602)
			(xy 287.943786 -238.701181) (xy 287.987634 -238.669811) (xy 288.035582 -238.645159) (xy 288.086609 -238.627751)
			(xy 288.139627 -238.617958) (xy 288.193506 -238.615989) (xy 288.247097 -238.621886) (xy 288.299258 -238.635522)
			(xy 288.348878 -238.656609) (xy 288.394899 -238.684695) (xy 288.436341 -238.719183) (xy 288.472319 -238.759337)
			(xy 288.502067 -238.804301) (xy 288.524952 -238.853118) (xy 288.540484 -238.904747) (xy 288.548334 -238.958087)
			(xy 288.548826 -238.985044) (xy 291.910785 -238.985044) (xy 291.91472 -238.931273) (xy 291.926443 -238.878649)
			(xy 291.945703 -238.828292) (xy 291.972089 -238.781275) (xy 292.005041 -238.738602) (xy 292.043854 -238.701181)
			(xy 292.087702 -238.669811) (xy 292.13565 -238.645159) (xy 292.186677 -238.627751) (xy 292.239695 -238.617958)
			(xy 292.293574 -238.615989) (xy 292.347165 -238.621886) (xy 292.399326 -238.635522) (xy 292.448946 -238.656609)
			(xy 292.494967 -238.684695) (xy 292.536409 -238.719183) (xy 292.572387 -238.759337) (xy 292.602135 -238.804301)
			(xy 292.62502 -238.853118) (xy 292.640552 -238.904747) (xy 292.648402 -238.958087) (xy 292.648894 -238.985044)
			(xy 292.648402 -239.012001) (xy 292.640552 -239.065341) (xy 292.62502 -239.11697) (xy 292.602135 -239.165787)
			(xy 292.572387 -239.210751) (xy 292.536409 -239.250905) (xy 292.494967 -239.285393) (xy 292.448946 -239.313479)
			(xy 292.399326 -239.334566) (xy 292.347165 -239.348202) (xy 292.293574 -239.354099) (xy 292.239695 -239.35213)
			(xy 292.186677 -239.342337) (xy 292.13565 -239.324929) (xy 292.087702 -239.300277) (xy 292.043854 -239.268907)
			(xy 292.005041 -239.231486) (xy 291.972089 -239.188813) (xy 291.945703 -239.141796) (xy 291.926443 -239.091439)
			(xy 291.91472 -239.038815) (xy 291.910785 -238.985044) (xy 288.548826 -238.985044) (xy 288.548334 -239.012001)
			(xy 288.540484 -239.065341) (xy 288.524952 -239.11697) (xy 288.502067 -239.165787) (xy 288.472319 -239.210751)
			(xy 288.436341 -239.250905) (xy 288.394899 -239.285393) (xy 288.348878 -239.313479) (xy 288.299258 -239.334566)
			(xy 288.247097 -239.348202) (xy 288.193506 -239.354099) (xy 288.139627 -239.35213) (xy 288.086609 -239.342337)
			(xy 288.035582 -239.324929) (xy 287.987634 -239.300277) (xy 287.943786 -239.268907) (xy 287.904973 -239.231486)
			(xy 287.872021 -239.188813) (xy 287.845635 -239.141796) (xy 287.826375 -239.091439) (xy 287.814652 -239.038815)
			(xy 287.810717 -238.985044) (xy 285.10484 -238.985044) (xy 285.104348 -239.012001) (xy 285.096498 -239.065341)
			(xy 285.080966 -239.11697) (xy 285.058081 -239.165787) (xy 285.028333 -239.210751) (xy 284.992355 -239.250905)
			(xy 284.950913 -239.285393) (xy 284.904892 -239.313479) (xy 284.855272 -239.334566) (xy 284.803111 -239.348202)
			(xy 284.74952 -239.354099) (xy 284.695641 -239.35213) (xy 284.642623 -239.342337) (xy 284.591596 -239.324929)
			(xy 284.543648 -239.300277) (xy 284.4998 -239.268907) (xy 284.460987 -239.231486) (xy 284.428035 -239.188813)
			(xy 284.401649 -239.141796) (xy 284.382389 -239.091439) (xy 284.370666 -239.038815) (xy 284.366731 -238.985044)
			(xy 281.004772 -238.985044) (xy 281.00428 -239.012001) (xy 280.99643 -239.065341) (xy 280.980898 -239.11697)
			(xy 280.958013 -239.165787) (xy 280.928265 -239.210751) (xy 280.892287 -239.250905) (xy 280.850845 -239.285393)
			(xy 280.804824 -239.313479) (xy 280.755204 -239.334566) (xy 280.703043 -239.348202) (xy 280.649452 -239.354099)
			(xy 280.595573 -239.35213) (xy 280.542555 -239.342337) (xy 280.491528 -239.324929) (xy 280.44358 -239.300277)
			(xy 280.399732 -239.268907) (xy 280.360919 -239.231486) (xy 280.327967 -239.188813) (xy 280.301581 -239.141796)
			(xy 280.282321 -239.091439) (xy 280.270598 -239.038815) (xy 280.266663 -238.985044) (xy 277.56104 -238.985044)
			(xy 277.560548 -239.012001) (xy 277.552698 -239.065341) (xy 277.537166 -239.11697) (xy 277.514281 -239.165787)
			(xy 277.484533 -239.210751) (xy 277.448555 -239.250905) (xy 277.407113 -239.285393) (xy 277.361092 -239.313479)
			(xy 277.311472 -239.334566) (xy 277.259311 -239.348202) (xy 277.20572 -239.354099) (xy 277.151841 -239.35213)
			(xy 277.098823 -239.342337) (xy 277.047796 -239.324929) (xy 276.999848 -239.300277) (xy 276.956 -239.268907)
			(xy 276.917187 -239.231486) (xy 276.884235 -239.188813) (xy 276.857849 -239.141796) (xy 276.838589 -239.091439)
			(xy 276.826866 -239.038815) (xy 276.822931 -238.985044) (xy 273.460972 -238.985044) (xy 273.46048 -239.012001)
			(xy 273.45263 -239.065341) (xy 273.437098 -239.11697) (xy 273.414213 -239.165787) (xy 273.384465 -239.210751)
			(xy 273.348487 -239.250905) (xy 273.307045 -239.285393) (xy 273.261024 -239.313479) (xy 273.211404 -239.334566)
			(xy 273.159243 -239.348202) (xy 273.105652 -239.354099) (xy 273.051773 -239.35213) (xy 272.998755 -239.342337)
			(xy 272.947728 -239.324929) (xy 272.89978 -239.300277) (xy 272.855932 -239.268907) (xy 272.817119 -239.231486)
			(xy 272.784167 -239.188813) (xy 272.757781 -239.141796) (xy 272.738521 -239.091439) (xy 272.726798 -239.038815)
			(xy 272.722863 -238.985044) (xy 270.016986 -238.985044) (xy 270.016494 -239.012001) (xy 270.008644 -239.065341)
			(xy 269.993112 -239.11697) (xy 269.970227 -239.165787) (xy 269.940479 -239.210751) (xy 269.904501 -239.250905)
			(xy 269.863059 -239.285393) (xy 269.817038 -239.313479) (xy 269.767418 -239.334566) (xy 269.715257 -239.348202)
			(xy 269.661666 -239.354099) (xy 269.607787 -239.35213) (xy 269.554769 -239.342337) (xy 269.503742 -239.324929)
			(xy 269.455794 -239.300277) (xy 269.411946 -239.268907) (xy 269.373133 -239.231486) (xy 269.340181 -239.188813)
			(xy 269.313795 -239.141796) (xy 269.294535 -239.091439) (xy 269.282812 -239.038815) (xy 269.278877 -238.985044)
			(xy 265.916918 -238.985044) (xy 265.916426 -239.012001) (xy 265.908576 -239.065341) (xy 265.893044 -239.11697)
			(xy 265.870159 -239.165787) (xy 265.840411 -239.210751) (xy 265.804433 -239.250905) (xy 265.762991 -239.285393)
			(xy 265.71697 -239.313479) (xy 265.66735 -239.334566) (xy 265.615189 -239.348202) (xy 265.561598 -239.354099)
			(xy 265.507719 -239.35213) (xy 265.454701 -239.342337) (xy 265.403674 -239.324929) (xy 265.355726 -239.300277)
			(xy 265.311878 -239.268907) (xy 265.273065 -239.231486) (xy 265.240113 -239.188813) (xy 265.213727 -239.141796)
			(xy 265.194467 -239.091439) (xy 265.182744 -239.038815) (xy 265.178809 -238.985044) (xy 264.143998 -238.985044)
			(xy 264.143998 -239.835182) (xy 265.178809 -239.835182) (xy 265.182744 -239.781411) (xy 265.194467 -239.728787)
			(xy 265.213727 -239.67843) (xy 265.240113 -239.631413) (xy 265.273065 -239.58874) (xy 265.311878 -239.551319)
			(xy 265.355726 -239.519949) (xy 265.403674 -239.495297) (xy 265.454701 -239.477889) (xy 265.507719 -239.468096)
			(xy 265.561598 -239.466127) (xy 265.615189 -239.472024) (xy 265.66735 -239.48566) (xy 265.71697 -239.506747)
			(xy 265.762991 -239.534833) (xy 265.804433 -239.569321) (xy 265.840411 -239.609475) (xy 265.870159 -239.654439)
			(xy 265.893044 -239.703256) (xy 265.908576 -239.754885) (xy 265.916426 -239.808225) (xy 265.916918 -239.835182)
			(xy 272.722863 -239.835182) (xy 272.726798 -239.781411) (xy 272.738521 -239.728787) (xy 272.757781 -239.67843)
			(xy 272.784167 -239.631413) (xy 272.817119 -239.58874) (xy 272.855932 -239.551319) (xy 272.89978 -239.519949)
			(xy 272.947728 -239.495297) (xy 272.998755 -239.477889) (xy 273.051773 -239.468096) (xy 273.105652 -239.466127)
			(xy 273.159243 -239.472024) (xy 273.211404 -239.48566) (xy 273.261024 -239.506747) (xy 273.307045 -239.534833)
			(xy 273.348487 -239.569321) (xy 273.384465 -239.609475) (xy 273.414213 -239.654439) (xy 273.437098 -239.703256)
			(xy 273.45263 -239.754885) (xy 273.46048 -239.808225) (xy 273.460972 -239.835182) (xy 280.266663 -239.835182)
			(xy 280.270598 -239.781411) (xy 280.282321 -239.728787) (xy 280.301581 -239.67843) (xy 280.327967 -239.631413)
			(xy 280.360919 -239.58874) (xy 280.399732 -239.551319) (xy 280.44358 -239.519949) (xy 280.491528 -239.495297)
			(xy 280.542555 -239.477889) (xy 280.595573 -239.468096) (xy 280.649452 -239.466127) (xy 280.703043 -239.472024)
			(xy 280.755204 -239.48566) (xy 280.804824 -239.506747) (xy 280.850845 -239.534833) (xy 280.892287 -239.569321)
			(xy 280.928265 -239.609475) (xy 280.958013 -239.654439) (xy 280.980898 -239.703256) (xy 280.99643 -239.754885)
			(xy 281.00428 -239.808225) (xy 281.004772 -239.835182) (xy 287.810717 -239.835182) (xy 287.814652 -239.781411)
			(xy 287.826375 -239.728787) (xy 287.845635 -239.67843) (xy 287.872021 -239.631413) (xy 287.904973 -239.58874)
			(xy 287.943786 -239.551319) (xy 287.987634 -239.519949) (xy 288.035582 -239.495297) (xy 288.086609 -239.477889)
			(xy 288.139627 -239.468096) (xy 288.193506 -239.466127) (xy 288.247097 -239.472024) (xy 288.299258 -239.48566)
			(xy 288.348878 -239.506747) (xy 288.394899 -239.534833) (xy 288.436341 -239.569321) (xy 288.472319 -239.609475)
			(xy 288.502067 -239.654439) (xy 288.524952 -239.703256) (xy 288.540484 -239.754885) (xy 288.548334 -239.808225)
			(xy 288.548826 -239.835182) (xy 288.548334 -239.862139) (xy 288.540484 -239.915479) (xy 288.524952 -239.967108)
			(xy 288.502067 -240.015925) (xy 288.472319 -240.060889) (xy 288.436341 -240.101043) (xy 288.394899 -240.135531)
			(xy 288.348878 -240.163617) (xy 288.299258 -240.184704) (xy 288.247097 -240.19834) (xy 288.193506 -240.204237)
			(xy 288.139627 -240.202268) (xy 288.086609 -240.192475) (xy 288.035582 -240.175067) (xy 287.987634 -240.150415)
			(xy 287.943786 -240.119045) (xy 287.904973 -240.081624) (xy 287.872021 -240.038951) (xy 287.845635 -239.991934)
			(xy 287.826375 -239.941577) (xy 287.814652 -239.888953) (xy 287.810717 -239.835182) (xy 281.004772 -239.835182)
			(xy 281.00428 -239.862139) (xy 280.99643 -239.915479) (xy 280.980898 -239.967108) (xy 280.958013 -240.015925)
			(xy 280.928265 -240.060889) (xy 280.892287 -240.101043) (xy 280.850845 -240.135531) (xy 280.804824 -240.163617)
			(xy 280.755204 -240.184704) (xy 280.703043 -240.19834) (xy 280.649452 -240.204237) (xy 280.595573 -240.202268)
			(xy 280.542555 -240.192475) (xy 280.491528 -240.175067) (xy 280.44358 -240.150415) (xy 280.399732 -240.119045)
			(xy 280.360919 -240.081624) (xy 280.327967 -240.038951) (xy 280.301581 -239.991934) (xy 280.282321 -239.941577)
			(xy 280.270598 -239.888953) (xy 280.266663 -239.835182) (xy 273.460972 -239.835182) (xy 273.46048 -239.862139)
			(xy 273.45263 -239.915479) (xy 273.437098 -239.967108) (xy 273.414213 -240.015925) (xy 273.384465 -240.060889)
			(xy 273.348487 -240.101043) (xy 273.307045 -240.135531) (xy 273.261024 -240.163617) (xy 273.211404 -240.184704)
			(xy 273.159243 -240.19834) (xy 273.105652 -240.204237) (xy 273.051773 -240.202268) (xy 272.998755 -240.192475)
			(xy 272.947728 -240.175067) (xy 272.89978 -240.150415) (xy 272.855932 -240.119045) (xy 272.817119 -240.081624)
			(xy 272.784167 -240.038951) (xy 272.757781 -239.991934) (xy 272.738521 -239.941577) (xy 272.726798 -239.888953)
			(xy 272.722863 -239.835182) (xy 265.916918 -239.835182) (xy 265.916426 -239.862139) (xy 265.908576 -239.915479)
			(xy 265.893044 -239.967108) (xy 265.870159 -240.015925) (xy 265.840411 -240.060889) (xy 265.804433 -240.101043)
			(xy 265.762991 -240.135531) (xy 265.71697 -240.163617) (xy 265.66735 -240.184704) (xy 265.615189 -240.19834)
			(xy 265.561598 -240.204237) (xy 265.507719 -240.202268) (xy 265.454701 -240.192475) (xy 265.403674 -240.175067)
			(xy 265.355726 -240.150415) (xy 265.311878 -240.119045) (xy 265.273065 -240.081624) (xy 265.240113 -240.038951)
			(xy 265.213727 -239.991934) (xy 265.194467 -239.941577) (xy 265.182744 -239.888953) (xy 265.178809 -239.835182)
			(xy 264.143998 -239.835182) (xy 264.143998 -240.685066) (xy 269.278877 -240.685066) (xy 269.282812 -240.631295)
			(xy 269.294535 -240.578671) (xy 269.313795 -240.528314) (xy 269.340181 -240.481297) (xy 269.373133 -240.438624)
			(xy 269.411946 -240.401203) (xy 269.455794 -240.369833) (xy 269.503742 -240.345181) (xy 269.554769 -240.327773)
			(xy 269.607787 -240.31798) (xy 269.661666 -240.316011) (xy 269.715257 -240.321908) (xy 269.767418 -240.335544)
			(xy 269.817038 -240.356631) (xy 269.863059 -240.384717) (xy 269.904501 -240.419205) (xy 269.940479 -240.459359)
			(xy 269.970227 -240.504323) (xy 269.993112 -240.55314) (xy 270.008644 -240.604769) (xy 270.016494 -240.658109)
			(xy 270.016986 -240.685066) (xy 276.822931 -240.685066) (xy 276.826866 -240.631295) (xy 276.838589 -240.578671)
			(xy 276.857849 -240.528314) (xy 276.884235 -240.481297) (xy 276.917187 -240.438624) (xy 276.956 -240.401203)
			(xy 276.999848 -240.369833) (xy 277.047796 -240.345181) (xy 277.098823 -240.327773) (xy 277.151841 -240.31798)
			(xy 277.20572 -240.316011) (xy 277.259311 -240.321908) (xy 277.311472 -240.335544) (xy 277.361092 -240.356631)
			(xy 277.407113 -240.384717) (xy 277.448555 -240.419205) (xy 277.484533 -240.459359) (xy 277.514281 -240.504323)
			(xy 277.537166 -240.55314) (xy 277.552698 -240.604769) (xy 277.560548 -240.658109) (xy 277.56104 -240.685066)
			(xy 284.366731 -240.685066) (xy 284.370666 -240.631295) (xy 284.382389 -240.578671) (xy 284.401649 -240.528314)
			(xy 284.428035 -240.481297) (xy 284.460987 -240.438624) (xy 284.4998 -240.401203) (xy 284.543648 -240.369833)
			(xy 284.591596 -240.345181) (xy 284.642623 -240.327773) (xy 284.695641 -240.31798) (xy 284.74952 -240.316011)
			(xy 284.803111 -240.321908) (xy 284.855272 -240.335544) (xy 284.904892 -240.356631) (xy 284.950913 -240.384717)
			(xy 284.992355 -240.419205) (xy 285.028333 -240.459359) (xy 285.058081 -240.504323) (xy 285.080966 -240.55314)
			(xy 285.096498 -240.604769) (xy 285.104348 -240.658109) (xy 285.10484 -240.685066) (xy 291.910785 -240.685066)
			(xy 291.91472 -240.631295) (xy 291.926443 -240.578671) (xy 291.945703 -240.528314) (xy 291.972089 -240.481297)
			(xy 292.005041 -240.438624) (xy 292.043854 -240.401203) (xy 292.087702 -240.369833) (xy 292.13565 -240.345181)
			(xy 292.186677 -240.327773) (xy 292.239695 -240.31798) (xy 292.293574 -240.316011) (xy 292.347165 -240.321908)
			(xy 292.399326 -240.335544) (xy 292.448946 -240.356631) (xy 292.494967 -240.384717) (xy 292.536409 -240.419205)
			(xy 292.572387 -240.459359) (xy 292.602135 -240.504323) (xy 292.62502 -240.55314) (xy 292.640552 -240.604769)
			(xy 292.648402 -240.658109) (xy 292.648894 -240.685066) (xy 292.648402 -240.712023) (xy 292.640552 -240.765363)
			(xy 292.62502 -240.816992) (xy 292.602135 -240.865809) (xy 292.572387 -240.910773) (xy 292.536409 -240.950927)
			(xy 292.494967 -240.985415) (xy 292.448946 -241.013501) (xy 292.399326 -241.034588) (xy 292.347165 -241.048224)
			(xy 292.293574 -241.054121) (xy 292.239695 -241.052152) (xy 292.186677 -241.042359) (xy 292.13565 -241.024951)
			(xy 292.087702 -241.000299) (xy 292.043854 -240.968929) (xy 292.005041 -240.931508) (xy 291.972089 -240.888835)
			(xy 291.945703 -240.841818) (xy 291.926443 -240.791461) (xy 291.91472 -240.738837) (xy 291.910785 -240.685066)
			(xy 285.10484 -240.685066) (xy 285.104348 -240.712023) (xy 285.096498 -240.765363) (xy 285.080966 -240.816992)
			(xy 285.058081 -240.865809) (xy 285.028333 -240.910773) (xy 284.992355 -240.950927) (xy 284.950913 -240.985415)
			(xy 284.904892 -241.013501) (xy 284.855272 -241.034588) (xy 284.803111 -241.048224) (xy 284.74952 -241.054121)
			(xy 284.695641 -241.052152) (xy 284.642623 -241.042359) (xy 284.591596 -241.024951) (xy 284.543648 -241.000299)
			(xy 284.4998 -240.968929) (xy 284.460987 -240.931508) (xy 284.428035 -240.888835) (xy 284.401649 -240.841818)
			(xy 284.382389 -240.791461) (xy 284.370666 -240.738837) (xy 284.366731 -240.685066) (xy 277.56104 -240.685066)
			(xy 277.560548 -240.712023) (xy 277.552698 -240.765363) (xy 277.537166 -240.816992) (xy 277.514281 -240.865809)
			(xy 277.484533 -240.910773) (xy 277.448555 -240.950927) (xy 277.407113 -240.985415) (xy 277.361092 -241.013501)
			(xy 277.311472 -241.034588) (xy 277.259311 -241.048224) (xy 277.20572 -241.054121) (xy 277.151841 -241.052152)
			(xy 277.098823 -241.042359) (xy 277.047796 -241.024951) (xy 276.999848 -241.000299) (xy 276.956 -240.968929)
			(xy 276.917187 -240.931508) (xy 276.884235 -240.888835) (xy 276.857849 -240.841818) (xy 276.838589 -240.791461)
			(xy 276.826866 -240.738837) (xy 276.822931 -240.685066) (xy 270.016986 -240.685066) (xy 270.016494 -240.712023)
			(xy 270.008644 -240.765363) (xy 269.993112 -240.816992) (xy 269.970227 -240.865809) (xy 269.940479 -240.910773)
			(xy 269.904501 -240.950927) (xy 269.863059 -240.985415) (xy 269.817038 -241.013501) (xy 269.767418 -241.034588)
			(xy 269.715257 -241.048224) (xy 269.661666 -241.054121) (xy 269.607787 -241.052152) (xy 269.554769 -241.042359)
			(xy 269.503742 -241.024951) (xy 269.455794 -241.000299) (xy 269.411946 -240.968929) (xy 269.373133 -240.931508)
			(xy 269.340181 -240.888835) (xy 269.313795 -240.841818) (xy 269.294535 -240.791461) (xy 269.282812 -240.738837)
			(xy 269.278877 -240.685066) (xy 264.143998 -240.685066) (xy 264.143998 -241.53495) (xy 265.178809 -241.53495)
			(xy 265.182744 -241.481179) (xy 265.194467 -241.428555) (xy 265.213727 -241.378198) (xy 265.240113 -241.331181)
			(xy 265.273065 -241.288508) (xy 265.311878 -241.251087) (xy 265.355726 -241.219717) (xy 265.403674 -241.195065)
			(xy 265.454701 -241.177657) (xy 265.507719 -241.167864) (xy 265.561598 -241.165895) (xy 265.615189 -241.171792)
			(xy 265.66735 -241.185428) (xy 265.71697 -241.206515) (xy 265.762991 -241.234601) (xy 265.804433 -241.269089)
			(xy 265.840411 -241.309243) (xy 265.870159 -241.354207) (xy 265.893044 -241.403024) (xy 265.908576 -241.454653)
			(xy 265.916426 -241.507993) (xy 265.916918 -241.53495) (xy 272.722863 -241.53495) (xy 272.726798 -241.481179)
			(xy 272.738521 -241.428555) (xy 272.757781 -241.378198) (xy 272.784167 -241.331181) (xy 272.817119 -241.288508)
			(xy 272.855932 -241.251087) (xy 272.89978 -241.219717) (xy 272.947728 -241.195065) (xy 272.998755 -241.177657)
			(xy 273.051773 -241.167864) (xy 273.105652 -241.165895) (xy 273.159243 -241.171792) (xy 273.211404 -241.185428)
			(xy 273.261024 -241.206515) (xy 273.307045 -241.234601) (xy 273.348487 -241.269089) (xy 273.384465 -241.309243)
			(xy 273.414213 -241.354207) (xy 273.437098 -241.403024) (xy 273.45263 -241.454653) (xy 273.46048 -241.507993)
			(xy 273.460972 -241.53495) (xy 280.266663 -241.53495) (xy 280.270598 -241.481179) (xy 280.282321 -241.428555)
			(xy 280.301581 -241.378198) (xy 280.327967 -241.331181) (xy 280.360919 -241.288508) (xy 280.399732 -241.251087)
			(xy 280.44358 -241.219717) (xy 280.491528 -241.195065) (xy 280.542555 -241.177657) (xy 280.595573 -241.167864)
			(xy 280.649452 -241.165895) (xy 280.703043 -241.171792) (xy 280.755204 -241.185428) (xy 280.804824 -241.206515)
			(xy 280.850845 -241.234601) (xy 280.892287 -241.269089) (xy 280.928265 -241.309243) (xy 280.958013 -241.354207)
			(xy 280.980898 -241.403024) (xy 280.99643 -241.454653) (xy 281.00428 -241.507993) (xy 281.004772 -241.53495)
			(xy 287.810717 -241.53495) (xy 287.814652 -241.481179) (xy 287.826375 -241.428555) (xy 287.845635 -241.378198)
			(xy 287.872021 -241.331181) (xy 287.904973 -241.288508) (xy 287.943786 -241.251087) (xy 287.987634 -241.219717)
			(xy 288.035582 -241.195065) (xy 288.086609 -241.177657) (xy 288.139627 -241.167864) (xy 288.193506 -241.165895)
			(xy 288.247097 -241.171792) (xy 288.299258 -241.185428) (xy 288.348878 -241.206515) (xy 288.394899 -241.234601)
			(xy 288.436341 -241.269089) (xy 288.472319 -241.309243) (xy 288.502067 -241.354207) (xy 288.524952 -241.403024)
			(xy 288.540484 -241.454653) (xy 288.548334 -241.507993) (xy 288.548826 -241.53495) (xy 288.548334 -241.561907)
			(xy 288.540484 -241.615247) (xy 288.524952 -241.666876) (xy 288.502067 -241.715693) (xy 288.472319 -241.760657)
			(xy 288.436341 -241.800811) (xy 288.394899 -241.835299) (xy 288.348878 -241.863385) (xy 288.299258 -241.884472)
			(xy 288.247097 -241.898108) (xy 288.193506 -241.904005) (xy 288.139627 -241.902036) (xy 288.086609 -241.892243)
			(xy 288.035582 -241.874835) (xy 287.987634 -241.850183) (xy 287.943786 -241.818813) (xy 287.904973 -241.781392)
			(xy 287.872021 -241.738719) (xy 287.845635 -241.691702) (xy 287.826375 -241.641345) (xy 287.814652 -241.588721)
			(xy 287.810717 -241.53495) (xy 281.004772 -241.53495) (xy 281.00428 -241.561907) (xy 280.99643 -241.615247)
			(xy 280.980898 -241.666876) (xy 280.958013 -241.715693) (xy 280.928265 -241.760657) (xy 280.892287 -241.800811)
			(xy 280.850845 -241.835299) (xy 280.804824 -241.863385) (xy 280.755204 -241.884472) (xy 280.703043 -241.898108)
			(xy 280.649452 -241.904005) (xy 280.595573 -241.902036) (xy 280.542555 -241.892243) (xy 280.491528 -241.874835)
			(xy 280.44358 -241.850183) (xy 280.399732 -241.818813) (xy 280.360919 -241.781392) (xy 280.327967 -241.738719)
			(xy 280.301581 -241.691702) (xy 280.282321 -241.641345) (xy 280.270598 -241.588721) (xy 280.266663 -241.53495)
			(xy 273.460972 -241.53495) (xy 273.46048 -241.561907) (xy 273.45263 -241.615247) (xy 273.437098 -241.666876)
			(xy 273.414213 -241.715693) (xy 273.384465 -241.760657) (xy 273.348487 -241.800811) (xy 273.307045 -241.835299)
			(xy 273.261024 -241.863385) (xy 273.211404 -241.884472) (xy 273.159243 -241.898108) (xy 273.105652 -241.904005)
			(xy 273.051773 -241.902036) (xy 272.998755 -241.892243) (xy 272.947728 -241.874835) (xy 272.89978 -241.850183)
			(xy 272.855932 -241.818813) (xy 272.817119 -241.781392) (xy 272.784167 -241.738719) (xy 272.757781 -241.691702)
			(xy 272.738521 -241.641345) (xy 272.726798 -241.588721) (xy 272.722863 -241.53495) (xy 265.916918 -241.53495)
			(xy 265.916426 -241.561907) (xy 265.908576 -241.615247) (xy 265.893044 -241.666876) (xy 265.870159 -241.715693)
			(xy 265.840411 -241.760657) (xy 265.804433 -241.800811) (xy 265.762991 -241.835299) (xy 265.71697 -241.863385)
			(xy 265.66735 -241.884472) (xy 265.615189 -241.898108) (xy 265.561598 -241.904005) (xy 265.507719 -241.902036)
			(xy 265.454701 -241.892243) (xy 265.403674 -241.874835) (xy 265.355726 -241.850183) (xy 265.311878 -241.818813)
			(xy 265.273065 -241.781392) (xy 265.240113 -241.738719) (xy 265.213727 -241.691702) (xy 265.194467 -241.641345)
			(xy 265.182744 -241.588721) (xy 265.178809 -241.53495) (xy 264.143998 -241.53495) (xy 264.143998 -242.385088)
			(xy 269.278877 -242.385088) (xy 269.282812 -242.331317) (xy 269.294535 -242.278693) (xy 269.313795 -242.228336)
			(xy 269.340181 -242.181319) (xy 269.373133 -242.138646) (xy 269.411946 -242.101225) (xy 269.455794 -242.069855)
			(xy 269.503742 -242.045203) (xy 269.554769 -242.027795) (xy 269.607787 -242.018002) (xy 269.661666 -242.016033)
			(xy 269.715257 -242.02193) (xy 269.767418 -242.035566) (xy 269.817038 -242.056653) (xy 269.863059 -242.084739)
			(xy 269.904501 -242.119227) (xy 269.940479 -242.159381) (xy 269.970227 -242.204345) (xy 269.993112 -242.253162)
			(xy 270.008644 -242.304791) (xy 270.016494 -242.358131) (xy 270.016986 -242.385088) (xy 276.822931 -242.385088)
			(xy 276.826866 -242.331317) (xy 276.838589 -242.278693) (xy 276.857849 -242.228336) (xy 276.884235 -242.181319)
			(xy 276.917187 -242.138646) (xy 276.956 -242.101225) (xy 276.999848 -242.069855) (xy 277.047796 -242.045203)
			(xy 277.098823 -242.027795) (xy 277.151841 -242.018002) (xy 277.20572 -242.016033) (xy 277.259311 -242.02193)
			(xy 277.311472 -242.035566) (xy 277.361092 -242.056653) (xy 277.407113 -242.084739) (xy 277.448555 -242.119227)
			(xy 277.484533 -242.159381) (xy 277.514281 -242.204345) (xy 277.537166 -242.253162) (xy 277.552698 -242.304791)
			(xy 277.560548 -242.358131) (xy 277.56104 -242.385088) (xy 284.366731 -242.385088) (xy 284.370666 -242.331317)
			(xy 284.382389 -242.278693) (xy 284.401649 -242.228336) (xy 284.428035 -242.181319) (xy 284.460987 -242.138646)
			(xy 284.4998 -242.101225) (xy 284.543648 -242.069855) (xy 284.591596 -242.045203) (xy 284.642623 -242.027795)
			(xy 284.695641 -242.018002) (xy 284.74952 -242.016033) (xy 284.803111 -242.02193) (xy 284.855272 -242.035566)
			(xy 284.904892 -242.056653) (xy 284.950913 -242.084739) (xy 284.992355 -242.119227) (xy 285.028333 -242.159381)
			(xy 285.058081 -242.204345) (xy 285.080966 -242.253162) (xy 285.096498 -242.304791) (xy 285.104348 -242.358131)
			(xy 285.10484 -242.385088) (xy 291.910785 -242.385088) (xy 291.91472 -242.331317) (xy 291.926443 -242.278693)
			(xy 291.945703 -242.228336) (xy 291.972089 -242.181319) (xy 292.005041 -242.138646) (xy 292.043854 -242.101225)
			(xy 292.087702 -242.069855) (xy 292.13565 -242.045203) (xy 292.186677 -242.027795) (xy 292.239695 -242.018002)
			(xy 292.293574 -242.016033) (xy 292.347165 -242.02193) (xy 292.399326 -242.035566) (xy 292.448946 -242.056653)
			(xy 292.494967 -242.084739) (xy 292.536409 -242.119227) (xy 292.572387 -242.159381) (xy 292.602135 -242.204345)
			(xy 292.62502 -242.253162) (xy 292.640552 -242.304791) (xy 292.648402 -242.358131) (xy 292.648894 -242.385088)
			(xy 292.648402 -242.412045) (xy 292.640552 -242.465385) (xy 292.62502 -242.517014) (xy 292.602135 -242.565831)
			(xy 292.572387 -242.610795) (xy 292.536409 -242.650949) (xy 292.494967 -242.685437) (xy 292.448946 -242.713523)
			(xy 292.399326 -242.73461) (xy 292.347165 -242.748246) (xy 292.293574 -242.754143) (xy 292.239695 -242.752174)
			(xy 292.186677 -242.742381) (xy 292.13565 -242.724973) (xy 292.087702 -242.700321) (xy 292.043854 -242.668951)
			(xy 292.005041 -242.63153) (xy 291.972089 -242.588857) (xy 291.945703 -242.54184) (xy 291.926443 -242.491483)
			(xy 291.91472 -242.438859) (xy 291.910785 -242.385088) (xy 285.10484 -242.385088) (xy 285.104348 -242.412045)
			(xy 285.096498 -242.465385) (xy 285.080966 -242.517014) (xy 285.058081 -242.565831) (xy 285.028333 -242.610795)
			(xy 284.992355 -242.650949) (xy 284.950913 -242.685437) (xy 284.904892 -242.713523) (xy 284.855272 -242.73461)
			(xy 284.803111 -242.748246) (xy 284.74952 -242.754143) (xy 284.695641 -242.752174) (xy 284.642623 -242.742381)
			(xy 284.591596 -242.724973) (xy 284.543648 -242.700321) (xy 284.4998 -242.668951) (xy 284.460987 -242.63153)
			(xy 284.428035 -242.588857) (xy 284.401649 -242.54184) (xy 284.382389 -242.491483) (xy 284.370666 -242.438859)
			(xy 284.366731 -242.385088) (xy 277.56104 -242.385088) (xy 277.560548 -242.412045) (xy 277.552698 -242.465385)
			(xy 277.537166 -242.517014) (xy 277.514281 -242.565831) (xy 277.484533 -242.610795) (xy 277.448555 -242.650949)
			(xy 277.407113 -242.685437) (xy 277.361092 -242.713523) (xy 277.311472 -242.73461) (xy 277.259311 -242.748246)
			(xy 277.20572 -242.754143) (xy 277.151841 -242.752174) (xy 277.098823 -242.742381) (xy 277.047796 -242.724973)
			(xy 276.999848 -242.700321) (xy 276.956 -242.668951) (xy 276.917187 -242.63153) (xy 276.884235 -242.588857)
			(xy 276.857849 -242.54184) (xy 276.838589 -242.491483) (xy 276.826866 -242.438859) (xy 276.822931 -242.385088)
			(xy 270.016986 -242.385088) (xy 270.016494 -242.412045) (xy 270.008644 -242.465385) (xy 269.993112 -242.517014)
			(xy 269.970227 -242.565831) (xy 269.940479 -242.610795) (xy 269.904501 -242.650949) (xy 269.863059 -242.685437)
			(xy 269.817038 -242.713523) (xy 269.767418 -242.73461) (xy 269.715257 -242.748246) (xy 269.661666 -242.754143)
			(xy 269.607787 -242.752174) (xy 269.554769 -242.742381) (xy 269.503742 -242.724973) (xy 269.455794 -242.700321)
			(xy 269.411946 -242.668951) (xy 269.373133 -242.63153) (xy 269.340181 -242.588857) (xy 269.313795 -242.54184)
			(xy 269.294535 -242.491483) (xy 269.282812 -242.438859) (xy 269.278877 -242.385088) (xy 264.143998 -242.385088)
			(xy 264.143998 -243.234972) (xy 265.178809 -243.234972) (xy 265.182744 -243.181201) (xy 265.194467 -243.128577)
			(xy 265.213727 -243.07822) (xy 265.240113 -243.031203) (xy 265.273065 -242.98853) (xy 265.311878 -242.951109)
			(xy 265.355726 -242.919739) (xy 265.403674 -242.895087) (xy 265.454701 -242.877679) (xy 265.507719 -242.867886)
			(xy 265.561598 -242.865917) (xy 265.615189 -242.871814) (xy 265.66735 -242.88545) (xy 265.71697 -242.906537)
			(xy 265.762991 -242.934623) (xy 265.804433 -242.969111) (xy 265.840411 -243.009265) (xy 265.870159 -243.054229)
			(xy 265.893044 -243.103046) (xy 265.908576 -243.154675) (xy 265.916426 -243.208015) (xy 265.916918 -243.234972)
			(xy 272.722863 -243.234972) (xy 272.726798 -243.181201) (xy 272.738521 -243.128577) (xy 272.757781 -243.07822)
			(xy 272.784167 -243.031203) (xy 272.817119 -242.98853) (xy 272.855932 -242.951109) (xy 272.89978 -242.919739)
			(xy 272.947728 -242.895087) (xy 272.998755 -242.877679) (xy 273.051773 -242.867886) (xy 273.105652 -242.865917)
			(xy 273.159243 -242.871814) (xy 273.211404 -242.88545) (xy 273.261024 -242.906537) (xy 273.307045 -242.934623)
			(xy 273.348487 -242.969111) (xy 273.384465 -243.009265) (xy 273.414213 -243.054229) (xy 273.437098 -243.103046)
			(xy 273.45263 -243.154675) (xy 273.46048 -243.208015) (xy 273.460972 -243.234972) (xy 280.266663 -243.234972)
			(xy 280.270598 -243.181201) (xy 280.282321 -243.128577) (xy 280.301581 -243.07822) (xy 280.327967 -243.031203)
			(xy 280.360919 -242.98853) (xy 280.399732 -242.951109) (xy 280.44358 -242.919739) (xy 280.491528 -242.895087)
			(xy 280.542555 -242.877679) (xy 280.595573 -242.867886) (xy 280.649452 -242.865917) (xy 280.703043 -242.871814)
			(xy 280.755204 -242.88545) (xy 280.804824 -242.906537) (xy 280.850845 -242.934623) (xy 280.892287 -242.969111)
			(xy 280.928265 -243.009265) (xy 280.958013 -243.054229) (xy 280.980898 -243.103046) (xy 280.99643 -243.154675)
			(xy 281.00428 -243.208015) (xy 281.004772 -243.234972) (xy 287.810717 -243.234972) (xy 287.814652 -243.181201)
			(xy 287.826375 -243.128577) (xy 287.845635 -243.07822) (xy 287.872021 -243.031203) (xy 287.904973 -242.98853)
			(xy 287.943786 -242.951109) (xy 287.987634 -242.919739) (xy 288.035582 -242.895087) (xy 288.086609 -242.877679)
			(xy 288.139627 -242.867886) (xy 288.193506 -242.865917) (xy 288.247097 -242.871814) (xy 288.299258 -242.88545)
			(xy 288.348878 -242.906537) (xy 288.394899 -242.934623) (xy 288.436341 -242.969111) (xy 288.472319 -243.009265)
			(xy 288.502067 -243.054229) (xy 288.524952 -243.103046) (xy 288.540484 -243.154675) (xy 288.548334 -243.208015)
			(xy 288.548826 -243.234972) (xy 288.548334 -243.261929) (xy 288.540484 -243.315269) (xy 288.524952 -243.366898)
			(xy 288.502067 -243.415715) (xy 288.472319 -243.460679) (xy 288.436341 -243.500833) (xy 288.394899 -243.535321)
			(xy 288.348878 -243.563407) (xy 288.299258 -243.584494) (xy 288.247097 -243.59813) (xy 288.193506 -243.604027)
			(xy 288.139627 -243.602058) (xy 288.086609 -243.592265) (xy 288.035582 -243.574857) (xy 287.987634 -243.550205)
			(xy 287.943786 -243.518835) (xy 287.904973 -243.481414) (xy 287.872021 -243.438741) (xy 287.845635 -243.391724)
			(xy 287.826375 -243.341367) (xy 287.814652 -243.288743) (xy 287.810717 -243.234972) (xy 281.004772 -243.234972)
			(xy 281.00428 -243.261929) (xy 280.99643 -243.315269) (xy 280.980898 -243.366898) (xy 280.958013 -243.415715)
			(xy 280.928265 -243.460679) (xy 280.892287 -243.500833) (xy 280.850845 -243.535321) (xy 280.804824 -243.563407)
			(xy 280.755204 -243.584494) (xy 280.703043 -243.59813) (xy 280.649452 -243.604027) (xy 280.595573 -243.602058)
			(xy 280.542555 -243.592265) (xy 280.491528 -243.574857) (xy 280.44358 -243.550205) (xy 280.399732 -243.518835)
			(xy 280.360919 -243.481414) (xy 280.327967 -243.438741) (xy 280.301581 -243.391724) (xy 280.282321 -243.341367)
			(xy 280.270598 -243.288743) (xy 280.266663 -243.234972) (xy 273.460972 -243.234972) (xy 273.46048 -243.261929)
			(xy 273.45263 -243.315269) (xy 273.437098 -243.366898) (xy 273.414213 -243.415715) (xy 273.384465 -243.460679)
			(xy 273.348487 -243.500833) (xy 273.307045 -243.535321) (xy 273.261024 -243.563407) (xy 273.211404 -243.584494)
			(xy 273.159243 -243.59813) (xy 273.105652 -243.604027) (xy 273.051773 -243.602058) (xy 272.998755 -243.592265)
			(xy 272.947728 -243.574857) (xy 272.89978 -243.550205) (xy 272.855932 -243.518835) (xy 272.817119 -243.481414)
			(xy 272.784167 -243.438741) (xy 272.757781 -243.391724) (xy 272.738521 -243.341367) (xy 272.726798 -243.288743)
			(xy 272.722863 -243.234972) (xy 265.916918 -243.234972) (xy 265.916426 -243.261929) (xy 265.908576 -243.315269)
			(xy 265.893044 -243.366898) (xy 265.870159 -243.415715) (xy 265.840411 -243.460679) (xy 265.804433 -243.500833)
			(xy 265.762991 -243.535321) (xy 265.71697 -243.563407) (xy 265.66735 -243.584494) (xy 265.615189 -243.59813)
			(xy 265.561598 -243.604027) (xy 265.507719 -243.602058) (xy 265.454701 -243.592265) (xy 265.403674 -243.574857)
			(xy 265.355726 -243.550205) (xy 265.311878 -243.518835) (xy 265.273065 -243.481414) (xy 265.240113 -243.438741)
			(xy 265.213727 -243.391724) (xy 265.194467 -243.341367) (xy 265.182744 -243.288743) (xy 265.178809 -243.234972)
			(xy 264.143998 -243.234972) (xy 264.143998 -244.0851) (xy 269.278885 -244.0851) (xy 269.28301 -244.030059)
			(xy 269.295291 -243.976247) (xy 269.315456 -243.924866) (xy 269.343053 -243.877064) (xy 269.377466 -243.83391)
			(xy 269.417926 -243.796366) (xy 269.46353 -243.765271) (xy 269.513258 -243.74132) (xy 269.566001 -243.725049)
			(xy 269.62058 -243.716819) (xy 269.648178 -243.716302) (xy 269.673396 -243.71678) (xy 269.72336 -243.723677)
			(xy 269.771922 -243.737305) (xy 269.818179 -243.757411) (xy 269.839948 -243.77015) (xy 269.846044 -243.773706)
			(xy 269.859252 -243.777516) (xy 269.931642 -243.777516) (xy 269.940831 -243.777123) (xy 269.958015 -243.770597)
			(xy 269.96517 -243.764816) (xy 269.980781 -243.75152) (xy 270.015859 -243.730287) (xy 270.054195 -243.71574)
			(xy 270.094528 -243.708357) (xy 270.11503 -243.70792) (xy 270.382746 -243.70792) (xy 270.382746 -243.717572)
			(xy 270.383171 -243.727432) (xy 270.390629 -243.745682) (xy 270.4045 -243.759692) (xy 270.422675 -243.767331)
			(xy 270.43253 -243.767864) (xy 270.849852 -243.767864) (xy 270.86179 -243.764816) (xy 270.867632 -243.761768)
			(xy 270.879824 -243.755672) (xy 270.880078 -243.755418) (xy 270.891 -243.74983) (xy 270.89439 -243.748026)
			(xy 270.900642 -243.743564) (xy 270.903446 -243.74094) (xy 270.922242 -243.722398) (xy 270.929622 -243.715817)
			(xy 270.947924 -243.708377) (xy 270.957802 -243.70792) (xy 271.175226 -243.70792) (xy 271.19752 -243.708429)
			(xy 271.241245 -243.717162) (xy 271.282414 -243.734286) (xy 271.319434 -243.759137) (xy 271.350874 -243.790755)
			(xy 271.375516 -243.827915) (xy 271.392407 -243.86918) (xy 271.400893 -243.912953) (xy 271.401286 -243.93525)
			(xy 271.401286 -243.988336) (xy 271.40281 -243.994432) (xy 271.408058 -244.016733) (xy 271.413667 -244.062202)
			(xy 271.413986 -244.0851) (xy 276.822859 -244.0851) (xy 276.826985 -244.03005) (xy 276.83927 -243.976229)
			(xy 276.85944 -243.924841) (xy 276.887043 -243.877033) (xy 276.921465 -243.833873) (xy 276.961934 -243.796327)
			(xy 277.007548 -243.765231) (xy 277.057287 -243.741282) (xy 277.110041 -243.725014) (xy 277.16463 -243.71679)
			(xy 277.192232 -243.716302) (xy 277.217451 -243.716755) (xy 277.267416 -243.72366) (xy 277.315978 -243.737295)
			(xy 277.362234 -243.757408) (xy 277.384002 -243.77015) (xy 277.390098 -243.773706) (xy 277.403306 -243.777516)
			(xy 277.475696 -243.777516) (xy 277.484882 -243.7771) (xy 277.502067 -243.77059) (xy 277.509224 -243.764816)
			(xy 277.524852 -243.751541) (xy 277.559924 -243.730304) (xy 277.598255 -243.715751) (xy 277.638584 -243.708361)
			(xy 277.659084 -243.70792) (xy 277.926546 -243.70792) (xy 277.926546 -243.717572) (xy 277.927038 -243.727439)
			(xy 277.934601 -243.745671) (xy 277.948524 -243.759662) (xy 277.966719 -243.767312) (xy 277.976584 -243.767864)
			(xy 278.393906 -243.767864) (xy 278.405844 -243.764816) (xy 278.411686 -243.761768) (xy 278.423878 -243.755672)
			(xy 278.424132 -243.755418) (xy 278.435308 -243.74983) (xy 278.438866 -243.747955) (xy 278.445378 -243.743235)
			(xy 278.448262 -243.740432) (xy 278.465788 -243.722906) (xy 278.473199 -243.71608) (xy 278.49179 -243.708352)
			(xy 278.501856 -243.70792) (xy 278.71928 -243.70792) (xy 278.73957 -243.708358) (xy 278.779496 -243.715612)
			(xy 278.817488 -243.729871) (xy 278.852326 -243.750679) (xy 278.882894 -243.777369) (xy 278.90821 -243.809083)
			(xy 278.927463 -243.844805) (xy 278.940034 -243.883389) (xy 278.94552 -243.923596) (xy 278.945086 -243.943886)
			(xy 278.945086 -243.98732) (xy 278.94661 -243.99367) (xy 278.951971 -244.016148) (xy 278.957698 -244.062004)
			(xy 278.95804 -244.0851) (xy 284.366659 -244.0851) (xy 284.370785 -244.03005) (xy 284.38307 -243.976229)
			(xy 284.40324 -243.924841) (xy 284.430843 -243.877033) (xy 284.465265 -243.833873) (xy 284.505734 -243.796327)
			(xy 284.551348 -243.765231) (xy 284.601087 -243.741282) (xy 284.653841 -243.725014) (xy 284.70843 -243.71679)
			(xy 284.736032 -243.716302) (xy 284.761251 -243.716755) (xy 284.811216 -243.72366) (xy 284.859778 -243.737295)
			(xy 284.906034 -243.757408) (xy 284.927802 -243.77015) (xy 284.933898 -243.773706) (xy 284.947106 -243.777516)
			(xy 285.019496 -243.777516) (xy 285.028682 -243.7771) (xy 285.045867 -243.77059) (xy 285.053024 -243.764816)
			(xy 285.068652 -243.751541) (xy 285.103724 -243.730304) (xy 285.142055 -243.715751) (xy 285.182384 -243.708361)
			(xy 285.202884 -243.70792) (xy 285.470346 -243.70792) (xy 285.470346 -243.717572) (xy 285.470838 -243.727439)
			(xy 285.478401 -243.745671) (xy 285.492324 -243.759662) (xy 285.510519 -243.767312) (xy 285.520384 -243.767864)
			(xy 285.937706 -243.767864) (xy 285.949644 -243.764816) (xy 285.955486 -243.761768) (xy 285.967678 -243.755672)
			(xy 285.967932 -243.755418) (xy 285.979108 -243.74983) (xy 285.982666 -243.747955) (xy 285.989178 -243.743235)
			(xy 285.992062 -243.740432) (xy 286.009588 -243.722906) (xy 286.016999 -243.71608) (xy 286.03559 -243.708352)
			(xy 286.045656 -243.70792) (xy 286.26308 -243.70792) (xy 286.28337 -243.708358) (xy 286.323296 -243.715612)
			(xy 286.361288 -243.729871) (xy 286.396126 -243.750679) (xy 286.426694 -243.777369) (xy 286.45201 -243.809083)
			(xy 286.471263 -243.844805) (xy 286.483834 -243.883389) (xy 286.48932 -243.923596) (xy 286.488886 -243.943886)
			(xy 286.488886 -243.98732) (xy 286.49041 -243.99367) (xy 286.495771 -244.016148) (xy 286.501498 -244.062004)
			(xy 286.50184 -244.08511) (xy 286.501485 -244.110256) (xy 286.494726 -244.16009) (xy 286.488378 -244.184424)
			(xy 286.487144 -244.18947) (xy 286.486512 -244.199837) (xy 286.487108 -244.204998) (xy 286.489609 -244.226345)
			(xy 286.487362 -244.269264) (xy 286.47706 -244.310988) (xy 286.459072 -244.35002) (xy 286.434044 -244.384959)
			(xy 286.402876 -244.414549) (xy 286.366685 -244.437728) (xy 286.326772 -244.453665) (xy 286.284569 -244.461787)
			(xy 286.26308 -244.4623) (xy 285.995618 -244.4623) (xy 285.995618 -244.445282) (xy 285.980378 -244.420898)
			(xy 285.96717 -244.414548) (xy 285.955486 -244.408452) (xy 285.949644 -244.405404) (xy 285.937706 -244.402356)
			(xy 285.49727 -244.402356) (xy 285.472378 -244.418612) (xy 285.466028 -244.432582) (xy 285.461726 -244.441175)
			(xy 285.447932 -244.454534) (xy 285.43016 -244.461805) (xy 285.420562 -244.4623) (xy 285.202884 -244.4623)
			(xy 285.182389 -244.461807) (xy 285.142074 -244.454396) (xy 285.10375 -244.439853) (xy 285.068666 -244.418655)
			(xy 285.053024 -244.405404) (xy 285.045889 -244.399593) (xy 285.028691 -244.393087) (xy 285.019496 -244.392704)
			(xy 284.947106 -244.392704) (xy 284.933898 -244.396514) (xy 284.927802 -244.40007) (xy 284.906044 -244.412836)
			(xy 284.859796 -244.432984) (xy 284.81123 -244.446627) (xy 284.761255 -244.453508) (xy 284.736032 -244.453918)
			(xy 284.70843 -244.45341) (xy 284.653841 -244.445186) (xy 284.601087 -244.428918) (xy 284.551348 -244.404969)
			(xy 284.505734 -244.373873) (xy 284.465265 -244.336327) (xy 284.430843 -244.293167) (xy 284.40324 -244.245359)
			(xy 284.38307 -244.193971) (xy 284.370785 -244.14015) (xy 284.366659 -244.0851) (xy 278.95804 -244.0851)
			(xy 278.95804 -244.08511) (xy 278.957685 -244.110256) (xy 278.950926 -244.16009) (xy 278.944578 -244.184424)
			(xy 278.943344 -244.18947) (xy 278.942712 -244.199837) (xy 278.943308 -244.204998) (xy 278.945809 -244.226345)
			(xy 278.943562 -244.269264) (xy 278.93326 -244.310988) (xy 278.915272 -244.35002) (xy 278.890244 -244.384959)
			(xy 278.859076 -244.414549) (xy 278.822885 -244.437728) (xy 278.782972 -244.453665) (xy 278.740769 -244.461787)
			(xy 278.71928 -244.4623) (xy 278.451818 -244.4623) (xy 278.451818 -244.445282) (xy 278.436578 -244.420898)
			(xy 278.42337 -244.414548) (xy 278.411686 -244.408452) (xy 278.405844 -244.405404) (xy 278.393906 -244.402356)
			(xy 277.95347 -244.402356) (xy 277.928578 -244.418612) (xy 277.922228 -244.432582) (xy 277.917926 -244.441175)
			(xy 277.904132 -244.454534) (xy 277.88636 -244.461805) (xy 277.876762 -244.4623) (xy 277.659084 -244.4623)
			(xy 277.638589 -244.461807) (xy 277.598274 -244.454396) (xy 277.55995 -244.439853) (xy 277.524866 -244.418655)
			(xy 277.509224 -244.405404) (xy 277.502089 -244.399593) (xy 277.484891 -244.393087) (xy 277.475696 -244.392704)
			(xy 277.403306 -244.392704) (xy 277.390098 -244.396514) (xy 277.384002 -244.40007) (xy 277.362244 -244.412836)
			(xy 277.315996 -244.432984) (xy 277.26743 -244.446627) (xy 277.217455 -244.453508) (xy 277.192232 -244.453918)
			(xy 277.16463 -244.45341) (xy 277.110041 -244.445186) (xy 277.057287 -244.428918) (xy 277.007548 -244.404969)
			(xy 276.961934 -244.373873) (xy 276.921465 -244.336327) (xy 276.887043 -244.293167) (xy 276.85944 -244.245359)
			(xy 276.83927 -244.193971) (xy 276.826985 -244.14015) (xy 276.822859 -244.0851) (xy 271.413986 -244.0851)
			(xy 271.413986 -244.08511) (xy 271.413681 -244.108019) (xy 271.408076 -244.153491) (xy 271.40281 -244.175788)
			(xy 271.401286 -244.181884) (xy 271.401286 -244.23497) (xy 271.400902 -244.257266) (xy 271.392412 -244.301038)
			(xy 271.375519 -244.342302) (xy 271.350875 -244.37946) (xy 271.319434 -244.411076) (xy 271.282413 -244.435926)
			(xy 271.241244 -244.453049) (xy 271.19752 -244.461781) (xy 271.175226 -244.4623) (xy 270.90751 -244.4623)
			(xy 270.90751 -244.445282) (xy 270.89227 -244.420898) (xy 270.879062 -244.414294) (xy 270.867632 -244.408452)
			(xy 270.86179 -244.405404) (xy 270.849852 -244.402356) (xy 270.40967 -244.402356) (xy 270.384524 -244.418612)
			(xy 270.378428 -244.432582) (xy 270.374094 -244.44121) (xy 270.360232 -244.454623) (xy 270.342352 -244.461859)
			(xy 270.332708 -244.4623) (xy 270.11503 -244.4623) (xy 270.094534 -244.461838) (xy 270.054217 -244.454417)
			(xy 270.015893 -244.439865) (xy 269.980811 -244.418658) (xy 269.96517 -244.405404) (xy 269.958021 -244.399613)
			(xy 269.940833 -244.393095) (xy 269.931642 -244.392704) (xy 269.859252 -244.392704) (xy 269.846044 -244.396514)
			(xy 269.839948 -244.40007) (xy 269.818202 -244.412858) (xy 269.77195 -244.433001) (xy 269.72338 -244.446637)
			(xy 269.673402 -244.453511) (xy 269.648178 -244.453918) (xy 269.62058 -244.453381) (xy 269.566001 -244.445151)
			(xy 269.513258 -244.42888) (xy 269.46353 -244.404929) (xy 269.417926 -244.373834) (xy 269.377466 -244.33629)
			(xy 269.343053 -244.293136) (xy 269.315456 -244.245334) (xy 269.295291 -244.193953) (xy 269.28301 -244.140141)
			(xy 269.278885 -244.0851) (xy 264.143998 -244.0851) (xy 264.143998 -244.934994) (xy 265.178809 -244.934994)
			(xy 265.182744 -244.881223) (xy 265.194467 -244.828599) (xy 265.213727 -244.778242) (xy 265.240113 -244.731225)
			(xy 265.273065 -244.688552) (xy 265.311878 -244.651131) (xy 265.355726 -244.619761) (xy 265.403674 -244.595109)
			(xy 265.454701 -244.577701) (xy 265.507719 -244.567908) (xy 265.561598 -244.565939) (xy 265.615189 -244.571836)
			(xy 265.66735 -244.585472) (xy 265.71697 -244.606559) (xy 265.762991 -244.634645) (xy 265.804433 -244.669133)
			(xy 265.840411 -244.709287) (xy 265.870159 -244.754251) (xy 265.893044 -244.803068) (xy 265.908576 -244.854697)
			(xy 265.916426 -244.908037) (xy 265.916918 -244.934994) (xy 272.722863 -244.934994) (xy 272.726798 -244.881223)
			(xy 272.738521 -244.828599) (xy 272.757781 -244.778242) (xy 272.784167 -244.731225) (xy 272.817119 -244.688552)
			(xy 272.855932 -244.651131) (xy 272.89978 -244.619761) (xy 272.947728 -244.595109) (xy 272.998755 -244.577701)
			(xy 273.051773 -244.567908) (xy 273.105652 -244.565939) (xy 273.159243 -244.571836) (xy 273.211404 -244.585472)
			(xy 273.261024 -244.606559) (xy 273.307045 -244.634645) (xy 273.348487 -244.669133) (xy 273.384465 -244.709287)
			(xy 273.414213 -244.754251) (xy 273.437098 -244.803068) (xy 273.45263 -244.854697) (xy 273.46048 -244.908037)
			(xy 273.460972 -244.934994) (xy 280.266663 -244.934994) (xy 280.270598 -244.881223) (xy 280.282321 -244.828599)
			(xy 280.301581 -244.778242) (xy 280.327967 -244.731225) (xy 280.360919 -244.688552) (xy 280.399732 -244.651131)
			(xy 280.44358 -244.619761) (xy 280.491528 -244.595109) (xy 280.542555 -244.577701) (xy 280.595573 -244.567908)
			(xy 280.649452 -244.565939) (xy 280.703043 -244.571836) (xy 280.755204 -244.585472) (xy 280.804824 -244.606559)
			(xy 280.850845 -244.634645) (xy 280.892287 -244.669133) (xy 280.928265 -244.709287) (xy 280.958013 -244.754251)
			(xy 280.980898 -244.803068) (xy 280.99643 -244.854697) (xy 281.00428 -244.908037) (xy 281.004772 -244.934994)
			(xy 287.810717 -244.934994) (xy 287.814652 -244.881223) (xy 287.826375 -244.828599) (xy 287.845635 -244.778242)
			(xy 287.872021 -244.731225) (xy 287.904973 -244.688552) (xy 287.943786 -244.651131) (xy 287.987634 -244.619761)
			(xy 288.035582 -244.595109) (xy 288.086609 -244.577701) (xy 288.139627 -244.567908) (xy 288.193506 -244.565939)
			(xy 288.247097 -244.571836) (xy 288.299258 -244.585472) (xy 288.348878 -244.606559) (xy 288.394899 -244.634645)
			(xy 288.436341 -244.669133) (xy 288.472319 -244.709287) (xy 288.502067 -244.754251) (xy 288.524952 -244.803068)
			(xy 288.540484 -244.854697) (xy 288.548334 -244.908037) (xy 288.548826 -244.934994) (xy 288.548334 -244.961951)
			(xy 288.540484 -245.015291) (xy 288.524952 -245.06692) (xy 288.502067 -245.115737) (xy 288.472319 -245.160701)
			(xy 288.436341 -245.200855) (xy 288.394899 -245.235343) (xy 288.348878 -245.263429) (xy 288.299258 -245.284516)
			(xy 288.247097 -245.298152) (xy 288.193506 -245.304049) (xy 288.139627 -245.30208) (xy 288.086609 -245.292287)
			(xy 288.035582 -245.274879) (xy 287.987634 -245.250227) (xy 287.943786 -245.218857) (xy 287.904973 -245.181436)
			(xy 287.872021 -245.138763) (xy 287.845635 -245.091746) (xy 287.826375 -245.041389) (xy 287.814652 -244.988765)
			(xy 287.810717 -244.934994) (xy 281.004772 -244.934994) (xy 281.00428 -244.961951) (xy 280.99643 -245.015291)
			(xy 280.980898 -245.06692) (xy 280.958013 -245.115737) (xy 280.928265 -245.160701) (xy 280.892287 -245.200855)
			(xy 280.850845 -245.235343) (xy 280.804824 -245.263429) (xy 280.755204 -245.284516) (xy 280.703043 -245.298152)
			(xy 280.649452 -245.304049) (xy 280.595573 -245.30208) (xy 280.542555 -245.292287) (xy 280.491528 -245.274879)
			(xy 280.44358 -245.250227) (xy 280.399732 -245.218857) (xy 280.360919 -245.181436) (xy 280.327967 -245.138763)
			(xy 280.301581 -245.091746) (xy 280.282321 -245.041389) (xy 280.270598 -244.988765) (xy 280.266663 -244.934994)
			(xy 273.460972 -244.934994) (xy 273.46048 -244.961951) (xy 273.45263 -245.015291) (xy 273.437098 -245.06692)
			(xy 273.414213 -245.115737) (xy 273.384465 -245.160701) (xy 273.348487 -245.200855) (xy 273.307045 -245.235343)
			(xy 273.261024 -245.263429) (xy 273.211404 -245.284516) (xy 273.159243 -245.298152) (xy 273.105652 -245.304049)
			(xy 273.051773 -245.30208) (xy 272.998755 -245.292287) (xy 272.947728 -245.274879) (xy 272.89978 -245.250227)
			(xy 272.855932 -245.218857) (xy 272.817119 -245.181436) (xy 272.784167 -245.138763) (xy 272.757781 -245.091746)
			(xy 272.738521 -245.041389) (xy 272.726798 -244.988765) (xy 272.722863 -244.934994) (xy 265.916918 -244.934994)
			(xy 265.916426 -244.961951) (xy 265.908576 -245.015291) (xy 265.893044 -245.06692) (xy 265.870159 -245.115737)
			(xy 265.840411 -245.160701) (xy 265.804433 -245.200855) (xy 265.762991 -245.235343) (xy 265.71697 -245.263429)
			(xy 265.66735 -245.284516) (xy 265.615189 -245.298152) (xy 265.561598 -245.304049) (xy 265.507719 -245.30208)
			(xy 265.454701 -245.292287) (xy 265.403674 -245.274879) (xy 265.355726 -245.250227) (xy 265.311878 -245.218857)
			(xy 265.273065 -245.181436) (xy 265.240113 -245.138763) (xy 265.213727 -245.091746) (xy 265.194467 -245.041389)
			(xy 265.182744 -244.988765) (xy 265.178809 -244.934994) (xy 264.143998 -244.934994) (xy 264.143998 -245.785132)
			(xy 269.278877 -245.785132) (xy 269.282812 -245.731361) (xy 269.294535 -245.678737) (xy 269.313795 -245.62838)
			(xy 269.340181 -245.581363) (xy 269.373133 -245.53869) (xy 269.411946 -245.501269) (xy 269.455794 -245.469899)
			(xy 269.503742 -245.445247) (xy 269.554769 -245.427839) (xy 269.607787 -245.418046) (xy 269.661666 -245.416077)
			(xy 269.715257 -245.421974) (xy 269.767418 -245.43561) (xy 269.817038 -245.456697) (xy 269.863059 -245.484783)
			(xy 269.904501 -245.519271) (xy 269.940479 -245.559425) (xy 269.970227 -245.604389) (xy 269.993112 -245.653206)
			(xy 270.008644 -245.704835) (xy 270.016494 -245.758175) (xy 270.016986 -245.785132) (xy 276.822931 -245.785132)
			(xy 276.826866 -245.731361) (xy 276.838589 -245.678737) (xy 276.857849 -245.62838) (xy 276.884235 -245.581363)
			(xy 276.917187 -245.53869) (xy 276.956 -245.501269) (xy 276.999848 -245.469899) (xy 277.047796 -245.445247)
			(xy 277.098823 -245.427839) (xy 277.151841 -245.418046) (xy 277.20572 -245.416077) (xy 277.259311 -245.421974)
			(xy 277.311472 -245.43561) (xy 277.361092 -245.456697) (xy 277.407113 -245.484783) (xy 277.448555 -245.519271)
			(xy 277.484533 -245.559425) (xy 277.514281 -245.604389) (xy 277.537166 -245.653206) (xy 277.552698 -245.704835)
			(xy 277.560548 -245.758175) (xy 277.56104 -245.785132) (xy 284.366731 -245.785132) (xy 284.370666 -245.731361)
			(xy 284.382389 -245.678737) (xy 284.401649 -245.62838) (xy 284.428035 -245.581363) (xy 284.460987 -245.53869)
			(xy 284.4998 -245.501269) (xy 284.543648 -245.469899) (xy 284.591596 -245.445247) (xy 284.642623 -245.427839)
			(xy 284.695641 -245.418046) (xy 284.74952 -245.416077) (xy 284.803111 -245.421974) (xy 284.855272 -245.43561)
			(xy 284.904892 -245.456697) (xy 284.950913 -245.484783) (xy 284.992355 -245.519271) (xy 285.028333 -245.559425)
			(xy 285.058081 -245.604389) (xy 285.080966 -245.653206) (xy 285.096498 -245.704835) (xy 285.104348 -245.758175)
			(xy 285.10484 -245.785132) (xy 291.910785 -245.785132) (xy 291.91472 -245.731361) (xy 291.926443 -245.678737)
			(xy 291.945703 -245.62838) (xy 291.972089 -245.581363) (xy 292.005041 -245.53869) (xy 292.043854 -245.501269)
			(xy 292.087702 -245.469899) (xy 292.13565 -245.445247) (xy 292.186677 -245.427839) (xy 292.239695 -245.418046)
			(xy 292.293574 -245.416077) (xy 292.347165 -245.421974) (xy 292.399326 -245.43561) (xy 292.448946 -245.456697)
			(xy 292.494967 -245.484783) (xy 292.536409 -245.519271) (xy 292.572387 -245.559425) (xy 292.602135 -245.604389)
			(xy 292.62502 -245.653206) (xy 292.640552 -245.704835) (xy 292.648402 -245.758175) (xy 292.648894 -245.785132)
			(xy 292.648402 -245.812089) (xy 292.640552 -245.865429) (xy 292.62502 -245.917058) (xy 292.602135 -245.965875)
			(xy 292.572387 -246.010839) (xy 292.536409 -246.050993) (xy 292.494967 -246.085481) (xy 292.448946 -246.113567)
			(xy 292.399326 -246.134654) (xy 292.347165 -246.14829) (xy 292.293574 -246.154187) (xy 292.239695 -246.152218)
			(xy 292.186677 -246.142425) (xy 292.13565 -246.125017) (xy 292.087702 -246.100365) (xy 292.043854 -246.068995)
			(xy 292.005041 -246.031574) (xy 291.972089 -245.988901) (xy 291.945703 -245.941884) (xy 291.926443 -245.891527)
			(xy 291.91472 -245.838903) (xy 291.910785 -245.785132) (xy 285.10484 -245.785132) (xy 285.104348 -245.812089)
			(xy 285.096498 -245.865429) (xy 285.080966 -245.917058) (xy 285.058081 -245.965875) (xy 285.028333 -246.010839)
			(xy 284.992355 -246.050993) (xy 284.950913 -246.085481) (xy 284.904892 -246.113567) (xy 284.855272 -246.134654)
			(xy 284.803111 -246.14829) (xy 284.74952 -246.154187) (xy 284.695641 -246.152218) (xy 284.642623 -246.142425)
			(xy 284.591596 -246.125017) (xy 284.543648 -246.100365) (xy 284.4998 -246.068995) (xy 284.460987 -246.031574)
			(xy 284.428035 -245.988901) (xy 284.401649 -245.941884) (xy 284.382389 -245.891527) (xy 284.370666 -245.838903)
			(xy 284.366731 -245.785132) (xy 277.56104 -245.785132) (xy 277.560548 -245.812089) (xy 277.552698 -245.865429)
			(xy 277.537166 -245.917058) (xy 277.514281 -245.965875) (xy 277.484533 -246.010839) (xy 277.448555 -246.050993)
			(xy 277.407113 -246.085481) (xy 277.361092 -246.113567) (xy 277.311472 -246.134654) (xy 277.259311 -246.14829)
			(xy 277.20572 -246.154187) (xy 277.151841 -246.152218) (xy 277.098823 -246.142425) (xy 277.047796 -246.125017)
			(xy 276.999848 -246.100365) (xy 276.956 -246.068995) (xy 276.917187 -246.031574) (xy 276.884235 -245.988901)
			(xy 276.857849 -245.941884) (xy 276.838589 -245.891527) (xy 276.826866 -245.838903) (xy 276.822931 -245.785132)
			(xy 270.016986 -245.785132) (xy 270.016494 -245.812089) (xy 270.008644 -245.865429) (xy 269.993112 -245.917058)
			(xy 269.970227 -245.965875) (xy 269.940479 -246.010839) (xy 269.904501 -246.050993) (xy 269.863059 -246.085481)
			(xy 269.817038 -246.113567) (xy 269.767418 -246.134654) (xy 269.715257 -246.14829) (xy 269.661666 -246.154187)
			(xy 269.607787 -246.152218) (xy 269.554769 -246.142425) (xy 269.503742 -246.125017) (xy 269.455794 -246.100365)
			(xy 269.411946 -246.068995) (xy 269.373133 -246.031574) (xy 269.340181 -245.988901) (xy 269.313795 -245.941884)
			(xy 269.294535 -245.891527) (xy 269.282812 -245.838903) (xy 269.278877 -245.785132) (xy 264.143998 -245.785132)
			(xy 264.143998 -246.635016) (xy 265.178809 -246.635016) (xy 265.182744 -246.581245) (xy 265.194467 -246.528621)
			(xy 265.213727 -246.478264) (xy 265.240113 -246.431247) (xy 265.273065 -246.388574) (xy 265.311878 -246.351153)
			(xy 265.355726 -246.319783) (xy 265.403674 -246.295131) (xy 265.454701 -246.277723) (xy 265.507719 -246.26793)
			(xy 265.561598 -246.265961) (xy 265.615189 -246.271858) (xy 265.66735 -246.285494) (xy 265.71697 -246.306581)
			(xy 265.762991 -246.334667) (xy 265.804433 -246.369155) (xy 265.840411 -246.409309) (xy 265.870159 -246.454273)
			(xy 265.893044 -246.50309) (xy 265.908576 -246.554719) (xy 265.916426 -246.608059) (xy 265.916918 -246.635016)
			(xy 272.722863 -246.635016) (xy 272.726798 -246.581245) (xy 272.738521 -246.528621) (xy 272.757781 -246.478264)
			(xy 272.784167 -246.431247) (xy 272.817119 -246.388574) (xy 272.855932 -246.351153) (xy 272.89978 -246.319783)
			(xy 272.947728 -246.295131) (xy 272.998755 -246.277723) (xy 273.051773 -246.26793) (xy 273.105652 -246.265961)
			(xy 273.159243 -246.271858) (xy 273.211404 -246.285494) (xy 273.261024 -246.306581) (xy 273.307045 -246.334667)
			(xy 273.348487 -246.369155) (xy 273.384465 -246.409309) (xy 273.414213 -246.454273) (xy 273.437098 -246.50309)
			(xy 273.45263 -246.554719) (xy 273.46048 -246.608059) (xy 273.460972 -246.635016) (xy 280.266663 -246.635016)
			(xy 280.270598 -246.581245) (xy 280.282321 -246.528621) (xy 280.301581 -246.478264) (xy 280.327967 -246.431247)
			(xy 280.360919 -246.388574) (xy 280.399732 -246.351153) (xy 280.44358 -246.319783) (xy 280.491528 -246.295131)
			(xy 280.542555 -246.277723) (xy 280.595573 -246.26793) (xy 280.649452 -246.265961) (xy 280.703043 -246.271858)
			(xy 280.755204 -246.285494) (xy 280.804824 -246.306581) (xy 280.850845 -246.334667) (xy 280.892287 -246.369155)
			(xy 280.928265 -246.409309) (xy 280.958013 -246.454273) (xy 280.980898 -246.50309) (xy 280.99643 -246.554719)
			(xy 281.00428 -246.608059) (xy 281.004772 -246.635016) (xy 287.810717 -246.635016) (xy 287.814652 -246.581245)
			(xy 287.826375 -246.528621) (xy 287.845635 -246.478264) (xy 287.872021 -246.431247) (xy 287.904973 -246.388574)
			(xy 287.943786 -246.351153) (xy 287.987634 -246.319783) (xy 288.035582 -246.295131) (xy 288.086609 -246.277723)
			(xy 288.139627 -246.26793) (xy 288.193506 -246.265961) (xy 288.247097 -246.271858) (xy 288.299258 -246.285494)
			(xy 288.348878 -246.306581) (xy 288.394899 -246.334667) (xy 288.436341 -246.369155) (xy 288.472319 -246.409309)
			(xy 288.502067 -246.454273) (xy 288.524952 -246.50309) (xy 288.540484 -246.554719) (xy 288.548334 -246.608059)
			(xy 288.548826 -246.635016) (xy 288.548334 -246.661973) (xy 288.540484 -246.715313) (xy 288.524952 -246.766942)
			(xy 288.502067 -246.815759) (xy 288.472319 -246.860723) (xy 288.436341 -246.900877) (xy 288.394899 -246.935365)
			(xy 288.348878 -246.963451) (xy 288.299258 -246.984538) (xy 288.247097 -246.998174) (xy 288.193506 -247.004071)
			(xy 288.139627 -247.002102) (xy 288.086609 -246.992309) (xy 288.035582 -246.974901) (xy 287.987634 -246.950249)
			(xy 287.943786 -246.918879) (xy 287.904973 -246.881458) (xy 287.872021 -246.838785) (xy 287.845635 -246.791768)
			(xy 287.826375 -246.741411) (xy 287.814652 -246.688787) (xy 287.810717 -246.635016) (xy 281.004772 -246.635016)
			(xy 281.00428 -246.661973) (xy 280.99643 -246.715313) (xy 280.980898 -246.766942) (xy 280.958013 -246.815759)
			(xy 280.928265 -246.860723) (xy 280.892287 -246.900877) (xy 280.850845 -246.935365) (xy 280.804824 -246.963451)
			(xy 280.755204 -246.984538) (xy 280.703043 -246.998174) (xy 280.649452 -247.004071) (xy 280.595573 -247.002102)
			(xy 280.542555 -246.992309) (xy 280.491528 -246.974901) (xy 280.44358 -246.950249) (xy 280.399732 -246.918879)
			(xy 280.360919 -246.881458) (xy 280.327967 -246.838785) (xy 280.301581 -246.791768) (xy 280.282321 -246.741411)
			(xy 280.270598 -246.688787) (xy 280.266663 -246.635016) (xy 273.460972 -246.635016) (xy 273.46048 -246.661973)
			(xy 273.45263 -246.715313) (xy 273.437098 -246.766942) (xy 273.414213 -246.815759) (xy 273.384465 -246.860723)
			(xy 273.348487 -246.900877) (xy 273.307045 -246.935365) (xy 273.261024 -246.963451) (xy 273.211404 -246.984538)
			(xy 273.159243 -246.998174) (xy 273.105652 -247.004071) (xy 273.051773 -247.002102) (xy 272.998755 -246.992309)
			(xy 272.947728 -246.974901) (xy 272.89978 -246.950249) (xy 272.855932 -246.918879) (xy 272.817119 -246.881458)
			(xy 272.784167 -246.838785) (xy 272.757781 -246.791768) (xy 272.738521 -246.741411) (xy 272.726798 -246.688787)
			(xy 272.722863 -246.635016) (xy 265.916918 -246.635016) (xy 265.916426 -246.661973) (xy 265.908576 -246.715313)
			(xy 265.893044 -246.766942) (xy 265.870159 -246.815759) (xy 265.840411 -246.860723) (xy 265.804433 -246.900877)
			(xy 265.762991 -246.935365) (xy 265.71697 -246.963451) (xy 265.66735 -246.984538) (xy 265.615189 -246.998174)
			(xy 265.561598 -247.004071) (xy 265.507719 -247.002102) (xy 265.454701 -246.992309) (xy 265.403674 -246.974901)
			(xy 265.355726 -246.950249) (xy 265.311878 -246.918879) (xy 265.273065 -246.881458) (xy 265.240113 -246.838785)
			(xy 265.213727 -246.791768) (xy 265.194467 -246.741411) (xy 265.182744 -246.688787) (xy 265.178809 -246.635016)
			(xy 264.143998 -246.635016) (xy 264.143998 -247.485154) (xy 269.278877 -247.485154) (xy 269.282812 -247.431383)
			(xy 269.294535 -247.378759) (xy 269.313795 -247.328402) (xy 269.340181 -247.281385) (xy 269.373133 -247.238712)
			(xy 269.411946 -247.201291) (xy 269.455794 -247.169921) (xy 269.503742 -247.145269) (xy 269.554769 -247.127861)
			(xy 269.607787 -247.118068) (xy 269.661666 -247.116099) (xy 269.715257 -247.121996) (xy 269.767418 -247.135632)
			(xy 269.817038 -247.156719) (xy 269.863059 -247.184805) (xy 269.904501 -247.219293) (xy 269.940479 -247.259447)
			(xy 269.970227 -247.304411) (xy 269.993112 -247.353228) (xy 270.008644 -247.404857) (xy 270.016494 -247.458197)
			(xy 270.016986 -247.485154) (xy 276.822931 -247.485154) (xy 276.826866 -247.431383) (xy 276.838589 -247.378759)
			(xy 276.857849 -247.328402) (xy 276.884235 -247.281385) (xy 276.917187 -247.238712) (xy 276.956 -247.201291)
			(xy 276.999848 -247.169921) (xy 277.047796 -247.145269) (xy 277.098823 -247.127861) (xy 277.151841 -247.118068)
			(xy 277.20572 -247.116099) (xy 277.259311 -247.121996) (xy 277.311472 -247.135632) (xy 277.361092 -247.156719)
			(xy 277.407113 -247.184805) (xy 277.448555 -247.219293) (xy 277.484533 -247.259447) (xy 277.514281 -247.304411)
			(xy 277.537166 -247.353228) (xy 277.552698 -247.404857) (xy 277.560548 -247.458197) (xy 277.56104 -247.485154)
			(xy 284.366731 -247.485154) (xy 284.370666 -247.431383) (xy 284.382389 -247.378759) (xy 284.401649 -247.328402)
			(xy 284.428035 -247.281385) (xy 284.460987 -247.238712) (xy 284.4998 -247.201291) (xy 284.543648 -247.169921)
			(xy 284.591596 -247.145269) (xy 284.642623 -247.127861) (xy 284.695641 -247.118068) (xy 284.74952 -247.116099)
			(xy 284.803111 -247.121996) (xy 284.855272 -247.135632) (xy 284.904892 -247.156719) (xy 284.950913 -247.184805)
			(xy 284.992355 -247.219293) (xy 285.028333 -247.259447) (xy 285.058081 -247.304411) (xy 285.080966 -247.353228)
			(xy 285.096498 -247.404857) (xy 285.104348 -247.458197) (xy 285.10484 -247.485154) (xy 291.910785 -247.485154)
			(xy 291.91472 -247.431383) (xy 291.926443 -247.378759) (xy 291.945703 -247.328402) (xy 291.972089 -247.281385)
			(xy 292.005041 -247.238712) (xy 292.043854 -247.201291) (xy 292.087702 -247.169921) (xy 292.13565 -247.145269)
			(xy 292.186677 -247.127861) (xy 292.239695 -247.118068) (xy 292.293574 -247.116099) (xy 292.347165 -247.121996)
			(xy 292.399326 -247.135632) (xy 292.448946 -247.156719) (xy 292.494967 -247.184805) (xy 292.536409 -247.219293)
			(xy 292.572387 -247.259447) (xy 292.602135 -247.304411) (xy 292.62502 -247.353228) (xy 292.640552 -247.404857)
			(xy 292.648402 -247.458197) (xy 292.648894 -247.485154) (xy 292.648402 -247.512111) (xy 292.640552 -247.565451)
			(xy 292.62502 -247.61708) (xy 292.602135 -247.665897) (xy 292.572387 -247.710861) (xy 292.536409 -247.751015)
			(xy 292.494967 -247.785503) (xy 292.448946 -247.813589) (xy 292.399326 -247.834676) (xy 292.347165 -247.848312)
			(xy 292.293574 -247.854209) (xy 292.239695 -247.85224) (xy 292.186677 -247.842447) (xy 292.13565 -247.825039)
			(xy 292.087702 -247.800387) (xy 292.043854 -247.769017) (xy 292.005041 -247.731596) (xy 291.972089 -247.688923)
			(xy 291.945703 -247.641906) (xy 291.926443 -247.591549) (xy 291.91472 -247.538925) (xy 291.910785 -247.485154)
			(xy 285.10484 -247.485154) (xy 285.104348 -247.512111) (xy 285.096498 -247.565451) (xy 285.080966 -247.61708)
			(xy 285.058081 -247.665897) (xy 285.028333 -247.710861) (xy 284.992355 -247.751015) (xy 284.950913 -247.785503)
			(xy 284.904892 -247.813589) (xy 284.855272 -247.834676) (xy 284.803111 -247.848312) (xy 284.74952 -247.854209)
			(xy 284.695641 -247.85224) (xy 284.642623 -247.842447) (xy 284.591596 -247.825039) (xy 284.543648 -247.800387)
			(xy 284.4998 -247.769017) (xy 284.460987 -247.731596) (xy 284.428035 -247.688923) (xy 284.401649 -247.641906)
			(xy 284.382389 -247.591549) (xy 284.370666 -247.538925) (xy 284.366731 -247.485154) (xy 277.56104 -247.485154)
			(xy 277.560548 -247.512111) (xy 277.552698 -247.565451) (xy 277.537166 -247.61708) (xy 277.514281 -247.665897)
			(xy 277.484533 -247.710861) (xy 277.448555 -247.751015) (xy 277.407113 -247.785503) (xy 277.361092 -247.813589)
			(xy 277.311472 -247.834676) (xy 277.259311 -247.848312) (xy 277.20572 -247.854209) (xy 277.151841 -247.85224)
			(xy 277.098823 -247.842447) (xy 277.047796 -247.825039) (xy 276.999848 -247.800387) (xy 276.956 -247.769017)
			(xy 276.917187 -247.731596) (xy 276.884235 -247.688923) (xy 276.857849 -247.641906) (xy 276.838589 -247.591549)
			(xy 276.826866 -247.538925) (xy 276.822931 -247.485154) (xy 270.016986 -247.485154) (xy 270.016494 -247.512111)
			(xy 270.008644 -247.565451) (xy 269.993112 -247.61708) (xy 269.970227 -247.665897) (xy 269.940479 -247.710861)
			(xy 269.904501 -247.751015) (xy 269.863059 -247.785503) (xy 269.817038 -247.813589) (xy 269.767418 -247.834676)
			(xy 269.715257 -247.848312) (xy 269.661666 -247.854209) (xy 269.607787 -247.85224) (xy 269.554769 -247.842447)
			(xy 269.503742 -247.825039) (xy 269.455794 -247.800387) (xy 269.411946 -247.769017) (xy 269.373133 -247.731596)
			(xy 269.340181 -247.688923) (xy 269.313795 -247.641906) (xy 269.294535 -247.591549) (xy 269.282812 -247.538925)
			(xy 269.278877 -247.485154) (xy 264.143998 -247.485154) (xy 264.143998 -248.335038) (xy 265.178809 -248.335038)
			(xy 265.182744 -248.281267) (xy 265.194467 -248.228643) (xy 265.213727 -248.178286) (xy 265.240113 -248.131269)
			(xy 265.273065 -248.088596) (xy 265.311878 -248.051175) (xy 265.355726 -248.019805) (xy 265.403674 -247.995153)
			(xy 265.454701 -247.977745) (xy 265.507719 -247.967952) (xy 265.561598 -247.965983) (xy 265.615189 -247.97188)
			(xy 265.66735 -247.985516) (xy 265.71697 -248.006603) (xy 265.762991 -248.034689) (xy 265.804433 -248.069177)
			(xy 265.840411 -248.109331) (xy 265.870159 -248.154295) (xy 265.893044 -248.203112) (xy 265.908576 -248.254741)
			(xy 265.916426 -248.308081) (xy 265.916918 -248.335038) (xy 272.722863 -248.335038) (xy 272.726798 -248.281267)
			(xy 272.738521 -248.228643) (xy 272.757781 -248.178286) (xy 272.784167 -248.131269) (xy 272.817119 -248.088596)
			(xy 272.855932 -248.051175) (xy 272.89978 -248.019805) (xy 272.947728 -247.995153) (xy 272.998755 -247.977745)
			(xy 273.051773 -247.967952) (xy 273.105652 -247.965983) (xy 273.159243 -247.97188) (xy 273.211404 -247.985516)
			(xy 273.261024 -248.006603) (xy 273.307045 -248.034689) (xy 273.348487 -248.069177) (xy 273.384465 -248.109331)
			(xy 273.414213 -248.154295) (xy 273.437098 -248.203112) (xy 273.45263 -248.254741) (xy 273.46048 -248.308081)
			(xy 273.460972 -248.335038) (xy 280.266663 -248.335038) (xy 280.270598 -248.281267) (xy 280.282321 -248.228643)
			(xy 280.301581 -248.178286) (xy 280.327967 -248.131269) (xy 280.360919 -248.088596) (xy 280.399732 -248.051175)
			(xy 280.44358 -248.019805) (xy 280.491528 -247.995153) (xy 280.542555 -247.977745) (xy 280.595573 -247.967952)
			(xy 280.649452 -247.965983) (xy 280.703043 -247.97188) (xy 280.755204 -247.985516) (xy 280.804824 -248.006603)
			(xy 280.850845 -248.034689) (xy 280.892287 -248.069177) (xy 280.928265 -248.109331) (xy 280.958013 -248.154295)
			(xy 280.980898 -248.203112) (xy 280.99643 -248.254741) (xy 281.00428 -248.308081) (xy 281.004772 -248.335038)
			(xy 287.810717 -248.335038) (xy 287.814652 -248.281267) (xy 287.826375 -248.228643) (xy 287.845635 -248.178286)
			(xy 287.872021 -248.131269) (xy 287.904973 -248.088596) (xy 287.943786 -248.051175) (xy 287.987634 -248.019805)
			(xy 288.035582 -247.995153) (xy 288.086609 -247.977745) (xy 288.139627 -247.967952) (xy 288.193506 -247.965983)
			(xy 288.247097 -247.97188) (xy 288.299258 -247.985516) (xy 288.348878 -248.006603) (xy 288.394899 -248.034689)
			(xy 288.436341 -248.069177) (xy 288.472319 -248.109331) (xy 288.502067 -248.154295) (xy 288.524952 -248.203112)
			(xy 288.540484 -248.254741) (xy 288.548334 -248.308081) (xy 288.548826 -248.335038) (xy 288.548334 -248.361995)
			(xy 288.540484 -248.415335) (xy 288.524952 -248.466964) (xy 288.502067 -248.515781) (xy 288.472319 -248.560745)
			(xy 288.436341 -248.600899) (xy 288.394899 -248.635387) (xy 288.348878 -248.663473) (xy 288.299258 -248.68456)
			(xy 288.247097 -248.698196) (xy 288.193506 -248.704093) (xy 288.139627 -248.702124) (xy 288.086609 -248.692331)
			(xy 288.035582 -248.674923) (xy 287.987634 -248.650271) (xy 287.943786 -248.618901) (xy 287.904973 -248.58148)
			(xy 287.872021 -248.538807) (xy 287.845635 -248.49179) (xy 287.826375 -248.441433) (xy 287.814652 -248.388809)
			(xy 287.810717 -248.335038) (xy 281.004772 -248.335038) (xy 281.00428 -248.361995) (xy 280.99643 -248.415335)
			(xy 280.980898 -248.466964) (xy 280.958013 -248.515781) (xy 280.928265 -248.560745) (xy 280.892287 -248.600899)
			(xy 280.850845 -248.635387) (xy 280.804824 -248.663473) (xy 280.755204 -248.68456) (xy 280.703043 -248.698196)
			(xy 280.649452 -248.704093) (xy 280.595573 -248.702124) (xy 280.542555 -248.692331) (xy 280.491528 -248.674923)
			(xy 280.44358 -248.650271) (xy 280.399732 -248.618901) (xy 280.360919 -248.58148) (xy 280.327967 -248.538807)
			(xy 280.301581 -248.49179) (xy 280.282321 -248.441433) (xy 280.270598 -248.388809) (xy 280.266663 -248.335038)
			(xy 273.460972 -248.335038) (xy 273.46048 -248.361995) (xy 273.45263 -248.415335) (xy 273.437098 -248.466964)
			(xy 273.414213 -248.515781) (xy 273.384465 -248.560745) (xy 273.348487 -248.600899) (xy 273.307045 -248.635387)
			(xy 273.261024 -248.663473) (xy 273.211404 -248.68456) (xy 273.159243 -248.698196) (xy 273.105652 -248.704093)
			(xy 273.051773 -248.702124) (xy 272.998755 -248.692331) (xy 272.947728 -248.674923) (xy 272.89978 -248.650271)
			(xy 272.855932 -248.618901) (xy 272.817119 -248.58148) (xy 272.784167 -248.538807) (xy 272.757781 -248.49179)
			(xy 272.738521 -248.441433) (xy 272.726798 -248.388809) (xy 272.722863 -248.335038) (xy 265.916918 -248.335038)
			(xy 265.916426 -248.361995) (xy 265.908576 -248.415335) (xy 265.893044 -248.466964) (xy 265.870159 -248.515781)
			(xy 265.840411 -248.560745) (xy 265.804433 -248.600899) (xy 265.762991 -248.635387) (xy 265.71697 -248.663473)
			(xy 265.66735 -248.68456) (xy 265.615189 -248.698196) (xy 265.561598 -248.704093) (xy 265.507719 -248.702124)
			(xy 265.454701 -248.692331) (xy 265.403674 -248.674923) (xy 265.355726 -248.650271) (xy 265.311878 -248.618901)
			(xy 265.273065 -248.58148) (xy 265.240113 -248.538807) (xy 265.213727 -248.49179) (xy 265.194467 -248.441433)
			(xy 265.182744 -248.388809) (xy 265.178809 -248.335038) (xy 264.143998 -248.335038) (xy 264.143998 -249.185176)
			(xy 269.278877 -249.185176) (xy 269.282812 -249.131405) (xy 269.294535 -249.078781) (xy 269.313795 -249.028424)
			(xy 269.340181 -248.981407) (xy 269.373133 -248.938734) (xy 269.411946 -248.901313) (xy 269.455794 -248.869943)
			(xy 269.503742 -248.845291) (xy 269.554769 -248.827883) (xy 269.607787 -248.81809) (xy 269.661666 -248.816121)
			(xy 269.715257 -248.822018) (xy 269.767418 -248.835654) (xy 269.817038 -248.856741) (xy 269.863059 -248.884827)
			(xy 269.904501 -248.919315) (xy 269.940479 -248.959469) (xy 269.970227 -249.004433) (xy 269.993112 -249.05325)
			(xy 270.008644 -249.104879) (xy 270.016494 -249.158219) (xy 270.016986 -249.185176) (xy 276.822931 -249.185176)
			(xy 276.826866 -249.131405) (xy 276.838589 -249.078781) (xy 276.857849 -249.028424) (xy 276.884235 -248.981407)
			(xy 276.917187 -248.938734) (xy 276.956 -248.901313) (xy 276.999848 -248.869943) (xy 277.047796 -248.845291)
			(xy 277.098823 -248.827883) (xy 277.151841 -248.81809) (xy 277.20572 -248.816121) (xy 277.259311 -248.822018)
			(xy 277.311472 -248.835654) (xy 277.361092 -248.856741) (xy 277.407113 -248.884827) (xy 277.448555 -248.919315)
			(xy 277.484533 -248.959469) (xy 277.514281 -249.004433) (xy 277.537166 -249.05325) (xy 277.552698 -249.104879)
			(xy 277.560548 -249.158219) (xy 277.56104 -249.185176) (xy 284.366731 -249.185176) (xy 284.370666 -249.131405)
			(xy 284.382389 -249.078781) (xy 284.401649 -249.028424) (xy 284.428035 -248.981407) (xy 284.460987 -248.938734)
			(xy 284.4998 -248.901313) (xy 284.543648 -248.869943) (xy 284.591596 -248.845291) (xy 284.642623 -248.827883)
			(xy 284.695641 -248.81809) (xy 284.74952 -248.816121) (xy 284.803111 -248.822018) (xy 284.855272 -248.835654)
			(xy 284.904892 -248.856741) (xy 284.950913 -248.884827) (xy 284.992355 -248.919315) (xy 285.028333 -248.959469)
			(xy 285.058081 -249.004433) (xy 285.080966 -249.05325) (xy 285.096498 -249.104879) (xy 285.104348 -249.158219)
			(xy 285.10484 -249.185176) (xy 291.910785 -249.185176) (xy 291.91472 -249.131405) (xy 291.926443 -249.078781)
			(xy 291.945703 -249.028424) (xy 291.972089 -248.981407) (xy 292.005041 -248.938734) (xy 292.043854 -248.901313)
			(xy 292.087702 -248.869943) (xy 292.13565 -248.845291) (xy 292.186677 -248.827883) (xy 292.239695 -248.81809)
			(xy 292.293574 -248.816121) (xy 292.347165 -248.822018) (xy 292.399326 -248.835654) (xy 292.448946 -248.856741)
			(xy 292.494967 -248.884827) (xy 292.536409 -248.919315) (xy 292.572387 -248.959469) (xy 292.602135 -249.004433)
			(xy 292.62502 -249.05325) (xy 292.640552 -249.104879) (xy 292.648402 -249.158219) (xy 292.648894 -249.185176)
			(xy 292.648402 -249.212133) (xy 292.640552 -249.265473) (xy 292.62502 -249.317102) (xy 292.602135 -249.365919)
			(xy 292.572387 -249.410883) (xy 292.536409 -249.451037) (xy 292.494967 -249.485525) (xy 292.448946 -249.513611)
			(xy 292.399326 -249.534698) (xy 292.347165 -249.548334) (xy 292.293574 -249.554231) (xy 292.239695 -249.552262)
			(xy 292.186677 -249.542469) (xy 292.13565 -249.525061) (xy 292.087702 -249.500409) (xy 292.043854 -249.469039)
			(xy 292.005041 -249.431618) (xy 291.972089 -249.388945) (xy 291.945703 -249.341928) (xy 291.926443 -249.291571)
			(xy 291.91472 -249.238947) (xy 291.910785 -249.185176) (xy 285.10484 -249.185176) (xy 285.104348 -249.212133)
			(xy 285.096498 -249.265473) (xy 285.080966 -249.317102) (xy 285.058081 -249.365919) (xy 285.028333 -249.410883)
			(xy 284.992355 -249.451037) (xy 284.950913 -249.485525) (xy 284.904892 -249.513611) (xy 284.855272 -249.534698)
			(xy 284.803111 -249.548334) (xy 284.74952 -249.554231) (xy 284.695641 -249.552262) (xy 284.642623 -249.542469)
			(xy 284.591596 -249.525061) (xy 284.543648 -249.500409) (xy 284.4998 -249.469039) (xy 284.460987 -249.431618)
			(xy 284.428035 -249.388945) (xy 284.401649 -249.341928) (xy 284.382389 -249.291571) (xy 284.370666 -249.238947)
			(xy 284.366731 -249.185176) (xy 277.56104 -249.185176) (xy 277.560548 -249.212133) (xy 277.552698 -249.265473)
			(xy 277.537166 -249.317102) (xy 277.514281 -249.365919) (xy 277.484533 -249.410883) (xy 277.448555 -249.451037)
			(xy 277.407113 -249.485525) (xy 277.361092 -249.513611) (xy 277.311472 -249.534698) (xy 277.259311 -249.548334)
			(xy 277.20572 -249.554231) (xy 277.151841 -249.552262) (xy 277.098823 -249.542469) (xy 277.047796 -249.525061)
			(xy 276.999848 -249.500409) (xy 276.956 -249.469039) (xy 276.917187 -249.431618) (xy 276.884235 -249.388945)
			(xy 276.857849 -249.341928) (xy 276.838589 -249.291571) (xy 276.826866 -249.238947) (xy 276.822931 -249.185176)
			(xy 270.016986 -249.185176) (xy 270.016494 -249.212133) (xy 270.008644 -249.265473) (xy 269.993112 -249.317102)
			(xy 269.970227 -249.365919) (xy 269.940479 -249.410883) (xy 269.904501 -249.451037) (xy 269.863059 -249.485525)
			(xy 269.817038 -249.513611) (xy 269.767418 -249.534698) (xy 269.715257 -249.548334) (xy 269.661666 -249.554231)
			(xy 269.607787 -249.552262) (xy 269.554769 -249.542469) (xy 269.503742 -249.525061) (xy 269.455794 -249.500409)
			(xy 269.411946 -249.469039) (xy 269.373133 -249.431618) (xy 269.340181 -249.388945) (xy 269.313795 -249.341928)
			(xy 269.294535 -249.291571) (xy 269.282812 -249.238947) (xy 269.278877 -249.185176) (xy 264.143998 -249.185176)
			(xy 264.143998 -250.03506) (xy 265.178809 -250.03506) (xy 265.182744 -249.981289) (xy 265.194467 -249.928665)
			(xy 265.213727 -249.878308) (xy 265.240113 -249.831291) (xy 265.273065 -249.788618) (xy 265.311878 -249.751197)
			(xy 265.355726 -249.719827) (xy 265.403674 -249.695175) (xy 265.454701 -249.677767) (xy 265.507719 -249.667974)
			(xy 265.561598 -249.666005) (xy 265.615189 -249.671902) (xy 265.66735 -249.685538) (xy 265.71697 -249.706625)
			(xy 265.762991 -249.734711) (xy 265.804433 -249.769199) (xy 265.840411 -249.809353) (xy 265.870159 -249.854317)
			(xy 265.893044 -249.903134) (xy 265.908576 -249.954763) (xy 265.916426 -250.008103) (xy 265.916918 -250.03506)
			(xy 272.722863 -250.03506) (xy 272.726798 -249.981289) (xy 272.738521 -249.928665) (xy 272.757781 -249.878308)
			(xy 272.784167 -249.831291) (xy 272.817119 -249.788618) (xy 272.855932 -249.751197) (xy 272.89978 -249.719827)
			(xy 272.947728 -249.695175) (xy 272.998755 -249.677767) (xy 273.051773 -249.667974) (xy 273.105652 -249.666005)
			(xy 273.159243 -249.671902) (xy 273.211404 -249.685538) (xy 273.261024 -249.706625) (xy 273.307045 -249.734711)
			(xy 273.348487 -249.769199) (xy 273.384465 -249.809353) (xy 273.414213 -249.854317) (xy 273.437098 -249.903134)
			(xy 273.45263 -249.954763) (xy 273.46048 -250.008103) (xy 273.460972 -250.03506) (xy 280.266663 -250.03506)
			(xy 280.270598 -249.981289) (xy 280.282321 -249.928665) (xy 280.301581 -249.878308) (xy 280.327967 -249.831291)
			(xy 280.360919 -249.788618) (xy 280.399732 -249.751197) (xy 280.44358 -249.719827) (xy 280.491528 -249.695175)
			(xy 280.542555 -249.677767) (xy 280.595573 -249.667974) (xy 280.649452 -249.666005) (xy 280.703043 -249.671902)
			(xy 280.755204 -249.685538) (xy 280.804824 -249.706625) (xy 280.850845 -249.734711) (xy 280.892287 -249.769199)
			(xy 280.928265 -249.809353) (xy 280.958013 -249.854317) (xy 280.980898 -249.903134) (xy 280.99643 -249.954763)
			(xy 281.00428 -250.008103) (xy 281.004772 -250.03506) (xy 287.810717 -250.03506) (xy 287.814652 -249.981289)
			(xy 287.826375 -249.928665) (xy 287.845635 -249.878308) (xy 287.872021 -249.831291) (xy 287.904973 -249.788618)
			(xy 287.943786 -249.751197) (xy 287.987634 -249.719827) (xy 288.035582 -249.695175) (xy 288.086609 -249.677767)
			(xy 288.139627 -249.667974) (xy 288.193506 -249.666005) (xy 288.247097 -249.671902) (xy 288.299258 -249.685538)
			(xy 288.348878 -249.706625) (xy 288.394899 -249.734711) (xy 288.436341 -249.769199) (xy 288.472319 -249.809353)
			(xy 288.502067 -249.854317) (xy 288.524952 -249.903134) (xy 288.540484 -249.954763) (xy 288.548334 -250.008103)
			(xy 288.548826 -250.03506) (xy 288.548334 -250.062017) (xy 288.540484 -250.115357) (xy 288.524952 -250.166986)
			(xy 288.502067 -250.215803) (xy 288.472319 -250.260767) (xy 288.436341 -250.300921) (xy 288.394899 -250.335409)
			(xy 288.348878 -250.363495) (xy 288.299258 -250.384582) (xy 288.247097 -250.398218) (xy 288.193506 -250.404115)
			(xy 288.139627 -250.402146) (xy 288.086609 -250.392353) (xy 288.035582 -250.374945) (xy 287.987634 -250.350293)
			(xy 287.943786 -250.318923) (xy 287.904973 -250.281502) (xy 287.872021 -250.238829) (xy 287.845635 -250.191812)
			(xy 287.826375 -250.141455) (xy 287.814652 -250.088831) (xy 287.810717 -250.03506) (xy 281.004772 -250.03506)
			(xy 281.00428 -250.062017) (xy 280.99643 -250.115357) (xy 280.980898 -250.166986) (xy 280.958013 -250.215803)
			(xy 280.928265 -250.260767) (xy 280.892287 -250.300921) (xy 280.850845 -250.335409) (xy 280.804824 -250.363495)
			(xy 280.755204 -250.384582) (xy 280.703043 -250.398218) (xy 280.649452 -250.404115) (xy 280.595573 -250.402146)
			(xy 280.542555 -250.392353) (xy 280.491528 -250.374945) (xy 280.44358 -250.350293) (xy 280.399732 -250.318923)
			(xy 280.360919 -250.281502) (xy 280.327967 -250.238829) (xy 280.301581 -250.191812) (xy 280.282321 -250.141455)
			(xy 280.270598 -250.088831) (xy 280.266663 -250.03506) (xy 273.460972 -250.03506) (xy 273.46048 -250.062017)
			(xy 273.45263 -250.115357) (xy 273.437098 -250.166986) (xy 273.414213 -250.215803) (xy 273.384465 -250.260767)
			(xy 273.348487 -250.300921) (xy 273.307045 -250.335409) (xy 273.261024 -250.363495) (xy 273.211404 -250.384582)
			(xy 273.159243 -250.398218) (xy 273.105652 -250.404115) (xy 273.051773 -250.402146) (xy 272.998755 -250.392353)
			(xy 272.947728 -250.374945) (xy 272.89978 -250.350293) (xy 272.855932 -250.318923) (xy 272.817119 -250.281502)
			(xy 272.784167 -250.238829) (xy 272.757781 -250.191812) (xy 272.738521 -250.141455) (xy 272.726798 -250.088831)
			(xy 272.722863 -250.03506) (xy 265.916918 -250.03506) (xy 265.916426 -250.062017) (xy 265.908576 -250.115357)
			(xy 265.893044 -250.166986) (xy 265.870159 -250.215803) (xy 265.840411 -250.260767) (xy 265.804433 -250.300921)
			(xy 265.762991 -250.335409) (xy 265.71697 -250.363495) (xy 265.66735 -250.384582) (xy 265.615189 -250.398218)
			(xy 265.561598 -250.404115) (xy 265.507719 -250.402146) (xy 265.454701 -250.392353) (xy 265.403674 -250.374945)
			(xy 265.355726 -250.350293) (xy 265.311878 -250.318923) (xy 265.273065 -250.281502) (xy 265.240113 -250.238829)
			(xy 265.213727 -250.191812) (xy 265.194467 -250.141455) (xy 265.182744 -250.088831) (xy 265.178809 -250.03506)
			(xy 264.143998 -250.03506) (xy 264.143998 -250.884944) (xy 269.278877 -250.884944) (xy 269.282812 -250.831173)
			(xy 269.294535 -250.778549) (xy 269.313795 -250.728192) (xy 269.340181 -250.681175) (xy 269.373133 -250.638502)
			(xy 269.411946 -250.601081) (xy 269.455794 -250.569711) (xy 269.503742 -250.545059) (xy 269.554769 -250.527651)
			(xy 269.607787 -250.517858) (xy 269.661666 -250.515889) (xy 269.715257 -250.521786) (xy 269.767418 -250.535422)
			(xy 269.817038 -250.556509) (xy 269.863059 -250.584595) (xy 269.904501 -250.619083) (xy 269.940479 -250.659237)
			(xy 269.970227 -250.704201) (xy 269.993112 -250.753018) (xy 270.008644 -250.804647) (xy 270.016494 -250.857987)
			(xy 270.016986 -250.884944) (xy 276.822931 -250.884944) (xy 276.826866 -250.831173) (xy 276.838589 -250.778549)
			(xy 276.857849 -250.728192) (xy 276.884235 -250.681175) (xy 276.917187 -250.638502) (xy 276.956 -250.601081)
			(xy 276.999848 -250.569711) (xy 277.047796 -250.545059) (xy 277.098823 -250.527651) (xy 277.151841 -250.517858)
			(xy 277.20572 -250.515889) (xy 277.259311 -250.521786) (xy 277.311472 -250.535422) (xy 277.361092 -250.556509)
			(xy 277.407113 -250.584595) (xy 277.448555 -250.619083) (xy 277.484533 -250.659237) (xy 277.514281 -250.704201)
			(xy 277.537166 -250.753018) (xy 277.552698 -250.804647) (xy 277.560548 -250.857987) (xy 277.56104 -250.884944)
			(xy 284.366731 -250.884944) (xy 284.370666 -250.831173) (xy 284.382389 -250.778549) (xy 284.401649 -250.728192)
			(xy 284.428035 -250.681175) (xy 284.460987 -250.638502) (xy 284.4998 -250.601081) (xy 284.543648 -250.569711)
			(xy 284.591596 -250.545059) (xy 284.642623 -250.527651) (xy 284.695641 -250.517858) (xy 284.74952 -250.515889)
			(xy 284.803111 -250.521786) (xy 284.855272 -250.535422) (xy 284.904892 -250.556509) (xy 284.950913 -250.584595)
			(xy 284.992355 -250.619083) (xy 285.028333 -250.659237) (xy 285.058081 -250.704201) (xy 285.080966 -250.753018)
			(xy 285.096498 -250.804647) (xy 285.104348 -250.857987) (xy 285.10484 -250.884944) (xy 291.910785 -250.884944)
			(xy 291.91472 -250.831173) (xy 291.926443 -250.778549) (xy 291.945703 -250.728192) (xy 291.972089 -250.681175)
			(xy 292.005041 -250.638502) (xy 292.043854 -250.601081) (xy 292.087702 -250.569711) (xy 292.13565 -250.545059)
			(xy 292.186677 -250.527651) (xy 292.239695 -250.517858) (xy 292.293574 -250.515889) (xy 292.347165 -250.521786)
			(xy 292.399326 -250.535422) (xy 292.448946 -250.556509) (xy 292.494967 -250.584595) (xy 292.536409 -250.619083)
			(xy 292.572387 -250.659237) (xy 292.602135 -250.704201) (xy 292.62502 -250.753018) (xy 292.640552 -250.804647)
			(xy 292.648402 -250.857987) (xy 292.648894 -250.884944) (xy 292.648402 -250.911901) (xy 292.640552 -250.965241)
			(xy 292.62502 -251.01687) (xy 292.602135 -251.065687) (xy 292.572387 -251.110651) (xy 292.536409 -251.150805)
			(xy 292.494967 -251.185293) (xy 292.448946 -251.213379) (xy 292.399326 -251.234466) (xy 292.347165 -251.248102)
			(xy 292.293574 -251.253999) (xy 292.239695 -251.25203) (xy 292.186677 -251.242237) (xy 292.13565 -251.224829)
			(xy 292.087702 -251.200177) (xy 292.043854 -251.168807) (xy 292.005041 -251.131386) (xy 291.972089 -251.088713)
			(xy 291.945703 -251.041696) (xy 291.926443 -250.991339) (xy 291.91472 -250.938715) (xy 291.910785 -250.884944)
			(xy 285.10484 -250.884944) (xy 285.104348 -250.911901) (xy 285.096498 -250.965241) (xy 285.080966 -251.01687)
			(xy 285.058081 -251.065687) (xy 285.028333 -251.110651) (xy 284.992355 -251.150805) (xy 284.950913 -251.185293)
			(xy 284.904892 -251.213379) (xy 284.855272 -251.234466) (xy 284.803111 -251.248102) (xy 284.74952 -251.253999)
			(xy 284.695641 -251.25203) (xy 284.642623 -251.242237) (xy 284.591596 -251.224829) (xy 284.543648 -251.200177)
			(xy 284.4998 -251.168807) (xy 284.460987 -251.131386) (xy 284.428035 -251.088713) (xy 284.401649 -251.041696)
			(xy 284.382389 -250.991339) (xy 284.370666 -250.938715) (xy 284.366731 -250.884944) (xy 277.56104 -250.884944)
			(xy 277.560548 -250.911901) (xy 277.552698 -250.965241) (xy 277.537166 -251.01687) (xy 277.514281 -251.065687)
			(xy 277.484533 -251.110651) (xy 277.448555 -251.150805) (xy 277.407113 -251.185293) (xy 277.361092 -251.213379)
			(xy 277.311472 -251.234466) (xy 277.259311 -251.248102) (xy 277.20572 -251.253999) (xy 277.151841 -251.25203)
			(xy 277.098823 -251.242237) (xy 277.047796 -251.224829) (xy 276.999848 -251.200177) (xy 276.956 -251.168807)
			(xy 276.917187 -251.131386) (xy 276.884235 -251.088713) (xy 276.857849 -251.041696) (xy 276.838589 -250.991339)
			(xy 276.826866 -250.938715) (xy 276.822931 -250.884944) (xy 270.016986 -250.884944) (xy 270.016494 -250.911901)
			(xy 270.008644 -250.965241) (xy 269.993112 -251.01687) (xy 269.970227 -251.065687) (xy 269.940479 -251.110651)
			(xy 269.904501 -251.150805) (xy 269.863059 -251.185293) (xy 269.817038 -251.213379) (xy 269.767418 -251.234466)
			(xy 269.715257 -251.248102) (xy 269.661666 -251.253999) (xy 269.607787 -251.25203) (xy 269.554769 -251.242237)
			(xy 269.503742 -251.224829) (xy 269.455794 -251.200177) (xy 269.411946 -251.168807) (xy 269.373133 -251.131386)
			(xy 269.340181 -251.088713) (xy 269.313795 -251.041696) (xy 269.294535 -250.991339) (xy 269.282812 -250.938715)
			(xy 269.278877 -250.884944) (xy 264.143998 -250.884944) (xy 264.143998 -251.735082) (xy 265.178809 -251.735082)
			(xy 265.182744 -251.681311) (xy 265.194467 -251.628687) (xy 265.213727 -251.57833) (xy 265.240113 -251.531313)
			(xy 265.273065 -251.48864) (xy 265.311878 -251.451219) (xy 265.355726 -251.419849) (xy 265.403674 -251.395197)
			(xy 265.454701 -251.377789) (xy 265.507719 -251.367996) (xy 265.561598 -251.366027) (xy 265.615189 -251.371924)
			(xy 265.66735 -251.38556) (xy 265.71697 -251.406647) (xy 265.762991 -251.434733) (xy 265.804433 -251.469221)
			(xy 265.840411 -251.509375) (xy 265.870159 -251.554339) (xy 265.893044 -251.603156) (xy 265.908576 -251.654785)
			(xy 265.916426 -251.708125) (xy 265.916918 -251.735082) (xy 272.722863 -251.735082) (xy 272.726798 -251.681311)
			(xy 272.738521 -251.628687) (xy 272.757781 -251.57833) (xy 272.784167 -251.531313) (xy 272.817119 -251.48864)
			(xy 272.855932 -251.451219) (xy 272.89978 -251.419849) (xy 272.947728 -251.395197) (xy 272.998755 -251.377789)
			(xy 273.051773 -251.367996) (xy 273.105652 -251.366027) (xy 273.159243 -251.371924) (xy 273.211404 -251.38556)
			(xy 273.261024 -251.406647) (xy 273.307045 -251.434733) (xy 273.348487 -251.469221) (xy 273.384465 -251.509375)
			(xy 273.414213 -251.554339) (xy 273.437098 -251.603156) (xy 273.45263 -251.654785) (xy 273.46048 -251.708125)
			(xy 273.460972 -251.735082) (xy 280.266663 -251.735082) (xy 280.270598 -251.681311) (xy 280.282321 -251.628687)
			(xy 280.301581 -251.57833) (xy 280.327967 -251.531313) (xy 280.360919 -251.48864) (xy 280.399732 -251.451219)
			(xy 280.44358 -251.419849) (xy 280.491528 -251.395197) (xy 280.542555 -251.377789) (xy 280.595573 -251.367996)
			(xy 280.649452 -251.366027) (xy 280.703043 -251.371924) (xy 280.755204 -251.38556) (xy 280.804824 -251.406647)
			(xy 280.850845 -251.434733) (xy 280.892287 -251.469221) (xy 280.928265 -251.509375) (xy 280.958013 -251.554339)
			(xy 280.980898 -251.603156) (xy 280.99643 -251.654785) (xy 281.00428 -251.708125) (xy 281.004772 -251.735082)
			(xy 287.810717 -251.735082) (xy 287.814652 -251.681311) (xy 287.826375 -251.628687) (xy 287.845635 -251.57833)
			(xy 287.872021 -251.531313) (xy 287.904973 -251.48864) (xy 287.943786 -251.451219) (xy 287.987634 -251.419849)
			(xy 288.035582 -251.395197) (xy 288.086609 -251.377789) (xy 288.139627 -251.367996) (xy 288.193506 -251.366027)
			(xy 288.247097 -251.371924) (xy 288.299258 -251.38556) (xy 288.348878 -251.406647) (xy 288.394899 -251.434733)
			(xy 288.436341 -251.469221) (xy 288.472319 -251.509375) (xy 288.502067 -251.554339) (xy 288.524952 -251.603156)
			(xy 288.540484 -251.654785) (xy 288.548334 -251.708125) (xy 288.548826 -251.735082) (xy 288.548334 -251.762039)
			(xy 288.540484 -251.815379) (xy 288.524952 -251.867008) (xy 288.502067 -251.915825) (xy 288.472319 -251.960789)
			(xy 288.436341 -252.000943) (xy 288.394899 -252.035431) (xy 288.348878 -252.063517) (xy 288.299258 -252.084604)
			(xy 288.247097 -252.09824) (xy 288.193506 -252.104137) (xy 288.139627 -252.102168) (xy 288.086609 -252.092375)
			(xy 288.035582 -252.074967) (xy 287.987634 -252.050315) (xy 287.943786 -252.018945) (xy 287.904973 -251.981524)
			(xy 287.872021 -251.938851) (xy 287.845635 -251.891834) (xy 287.826375 -251.841477) (xy 287.814652 -251.788853)
			(xy 287.810717 -251.735082) (xy 281.004772 -251.735082) (xy 281.00428 -251.762039) (xy 280.99643 -251.815379)
			(xy 280.980898 -251.867008) (xy 280.958013 -251.915825) (xy 280.928265 -251.960789) (xy 280.892287 -252.000943)
			(xy 280.850845 -252.035431) (xy 280.804824 -252.063517) (xy 280.755204 -252.084604) (xy 280.703043 -252.09824)
			(xy 280.649452 -252.104137) (xy 280.595573 -252.102168) (xy 280.542555 -252.092375) (xy 280.491528 -252.074967)
			(xy 280.44358 -252.050315) (xy 280.399732 -252.018945) (xy 280.360919 -251.981524) (xy 280.327967 -251.938851)
			(xy 280.301581 -251.891834) (xy 280.282321 -251.841477) (xy 280.270598 -251.788853) (xy 280.266663 -251.735082)
			(xy 273.460972 -251.735082) (xy 273.46048 -251.762039) (xy 273.45263 -251.815379) (xy 273.437098 -251.867008)
			(xy 273.414213 -251.915825) (xy 273.384465 -251.960789) (xy 273.348487 -252.000943) (xy 273.307045 -252.035431)
			(xy 273.261024 -252.063517) (xy 273.211404 -252.084604) (xy 273.159243 -252.09824) (xy 273.105652 -252.104137)
			(xy 273.051773 -252.102168) (xy 272.998755 -252.092375) (xy 272.947728 -252.074967) (xy 272.89978 -252.050315)
			(xy 272.855932 -252.018945) (xy 272.817119 -251.981524) (xy 272.784167 -251.938851) (xy 272.757781 -251.891834)
			(xy 272.738521 -251.841477) (xy 272.726798 -251.788853) (xy 272.722863 -251.735082) (xy 265.916918 -251.735082)
			(xy 265.916426 -251.762039) (xy 265.908576 -251.815379) (xy 265.893044 -251.867008) (xy 265.870159 -251.915825)
			(xy 265.840411 -251.960789) (xy 265.804433 -252.000943) (xy 265.762991 -252.035431) (xy 265.71697 -252.063517)
			(xy 265.66735 -252.084604) (xy 265.615189 -252.09824) (xy 265.561598 -252.104137) (xy 265.507719 -252.102168)
			(xy 265.454701 -252.092375) (xy 265.403674 -252.074967) (xy 265.355726 -252.050315) (xy 265.311878 -252.018945)
			(xy 265.273065 -251.981524) (xy 265.240113 -251.938851) (xy 265.213727 -251.891834) (xy 265.194467 -251.841477)
			(xy 265.182744 -251.788853) (xy 265.178809 -251.735082) (xy 264.143998 -251.735082) (xy 264.143998 -252.584966)
			(xy 269.278877 -252.584966) (xy 269.282812 -252.531195) (xy 269.294535 -252.478571) (xy 269.313795 -252.428214)
			(xy 269.340181 -252.381197) (xy 269.373133 -252.338524) (xy 269.411946 -252.301103) (xy 269.455794 -252.269733)
			(xy 269.503742 -252.245081) (xy 269.554769 -252.227673) (xy 269.607787 -252.21788) (xy 269.661666 -252.215911)
			(xy 269.715257 -252.221808) (xy 269.767418 -252.235444) (xy 269.817038 -252.256531) (xy 269.863059 -252.284617)
			(xy 269.904501 -252.319105) (xy 269.940479 -252.359259) (xy 269.970227 -252.404223) (xy 269.993112 -252.45304)
			(xy 270.008644 -252.504669) (xy 270.016494 -252.558009) (xy 270.016986 -252.584966) (xy 276.822931 -252.584966)
			(xy 276.826866 -252.531195) (xy 276.838589 -252.478571) (xy 276.857849 -252.428214) (xy 276.884235 -252.381197)
			(xy 276.917187 -252.338524) (xy 276.956 -252.301103) (xy 276.999848 -252.269733) (xy 277.047796 -252.245081)
			(xy 277.098823 -252.227673) (xy 277.151841 -252.21788) (xy 277.20572 -252.215911) (xy 277.259311 -252.221808)
			(xy 277.311472 -252.235444) (xy 277.361092 -252.256531) (xy 277.407113 -252.284617) (xy 277.448555 -252.319105)
			(xy 277.484533 -252.359259) (xy 277.514281 -252.404223) (xy 277.537166 -252.45304) (xy 277.552698 -252.504669)
			(xy 277.560548 -252.558009) (xy 277.56104 -252.584966) (xy 284.366731 -252.584966) (xy 284.370666 -252.531195)
			(xy 284.382389 -252.478571) (xy 284.401649 -252.428214) (xy 284.428035 -252.381197) (xy 284.460987 -252.338524)
			(xy 284.4998 -252.301103) (xy 284.543648 -252.269733) (xy 284.591596 -252.245081) (xy 284.642623 -252.227673)
			(xy 284.695641 -252.21788) (xy 284.74952 -252.215911) (xy 284.803111 -252.221808) (xy 284.855272 -252.235444)
			(xy 284.904892 -252.256531) (xy 284.950913 -252.284617) (xy 284.992355 -252.319105) (xy 285.028333 -252.359259)
			(xy 285.058081 -252.404223) (xy 285.080966 -252.45304) (xy 285.096498 -252.504669) (xy 285.104348 -252.558009)
			(xy 285.10484 -252.584966) (xy 291.910785 -252.584966) (xy 291.91472 -252.531195) (xy 291.926443 -252.478571)
			(xy 291.945703 -252.428214) (xy 291.972089 -252.381197) (xy 292.005041 -252.338524) (xy 292.043854 -252.301103)
			(xy 292.087702 -252.269733) (xy 292.13565 -252.245081) (xy 292.186677 -252.227673) (xy 292.239695 -252.21788)
			(xy 292.293574 -252.215911) (xy 292.347165 -252.221808) (xy 292.399326 -252.235444) (xy 292.448946 -252.256531)
			(xy 292.494967 -252.284617) (xy 292.536409 -252.319105) (xy 292.572387 -252.359259) (xy 292.602135 -252.404223)
			(xy 292.62502 -252.45304) (xy 292.640552 -252.504669) (xy 292.648402 -252.558009) (xy 292.648894 -252.584966)
			(xy 292.648402 -252.611923) (xy 292.640552 -252.665263) (xy 292.62502 -252.716892) (xy 292.602135 -252.765709)
			(xy 292.572387 -252.810673) (xy 292.536409 -252.850827) (xy 292.494967 -252.885315) (xy 292.448946 -252.913401)
			(xy 292.399326 -252.934488) (xy 292.347165 -252.948124) (xy 292.293574 -252.954021) (xy 292.239695 -252.952052)
			(xy 292.186677 -252.942259) (xy 292.13565 -252.924851) (xy 292.087702 -252.900199) (xy 292.043854 -252.868829)
			(xy 292.005041 -252.831408) (xy 291.972089 -252.788735) (xy 291.945703 -252.741718) (xy 291.926443 -252.691361)
			(xy 291.91472 -252.638737) (xy 291.910785 -252.584966) (xy 285.10484 -252.584966) (xy 285.104348 -252.611923)
			(xy 285.096498 -252.665263) (xy 285.080966 -252.716892) (xy 285.058081 -252.765709) (xy 285.028333 -252.810673)
			(xy 284.992355 -252.850827) (xy 284.950913 -252.885315) (xy 284.904892 -252.913401) (xy 284.855272 -252.934488)
			(xy 284.803111 -252.948124) (xy 284.74952 -252.954021) (xy 284.695641 -252.952052) (xy 284.642623 -252.942259)
			(xy 284.591596 -252.924851) (xy 284.543648 -252.900199) (xy 284.4998 -252.868829) (xy 284.460987 -252.831408)
			(xy 284.428035 -252.788735) (xy 284.401649 -252.741718) (xy 284.382389 -252.691361) (xy 284.370666 -252.638737)
			(xy 284.366731 -252.584966) (xy 277.56104 -252.584966) (xy 277.560548 -252.611923) (xy 277.552698 -252.665263)
			(xy 277.537166 -252.716892) (xy 277.514281 -252.765709) (xy 277.484533 -252.810673) (xy 277.448555 -252.850827)
			(xy 277.407113 -252.885315) (xy 277.361092 -252.913401) (xy 277.311472 -252.934488) (xy 277.259311 -252.948124)
			(xy 277.20572 -252.954021) (xy 277.151841 -252.952052) (xy 277.098823 -252.942259) (xy 277.047796 -252.924851)
			(xy 276.999848 -252.900199) (xy 276.956 -252.868829) (xy 276.917187 -252.831408) (xy 276.884235 -252.788735)
			(xy 276.857849 -252.741718) (xy 276.838589 -252.691361) (xy 276.826866 -252.638737) (xy 276.822931 -252.584966)
			(xy 270.016986 -252.584966) (xy 270.016494 -252.611923) (xy 270.008644 -252.665263) (xy 269.993112 -252.716892)
			(xy 269.970227 -252.765709) (xy 269.940479 -252.810673) (xy 269.904501 -252.850827) (xy 269.863059 -252.885315)
			(xy 269.817038 -252.913401) (xy 269.767418 -252.934488) (xy 269.715257 -252.948124) (xy 269.661666 -252.954021)
			(xy 269.607787 -252.952052) (xy 269.554769 -252.942259) (xy 269.503742 -252.924851) (xy 269.455794 -252.900199)
			(xy 269.411946 -252.868829) (xy 269.373133 -252.831408) (xy 269.340181 -252.788735) (xy 269.313795 -252.741718)
			(xy 269.294535 -252.691361) (xy 269.282812 -252.638737) (xy 269.278877 -252.584966) (xy 264.143998 -252.584966)
			(xy 264.143998 -253.435104) (xy 265.178809 -253.435104) (xy 265.182744 -253.381333) (xy 265.194467 -253.328709)
			(xy 265.213727 -253.278352) (xy 265.240113 -253.231335) (xy 265.273065 -253.188662) (xy 265.311878 -253.151241)
			(xy 265.355726 -253.119871) (xy 265.403674 -253.095219) (xy 265.454701 -253.077811) (xy 265.507719 -253.068018)
			(xy 265.561598 -253.066049) (xy 265.615189 -253.071946) (xy 265.66735 -253.085582) (xy 265.71697 -253.106669)
			(xy 265.762991 -253.134755) (xy 265.804433 -253.169243) (xy 265.840411 -253.209397) (xy 265.870159 -253.254361)
			(xy 265.893044 -253.303178) (xy 265.908576 -253.354807) (xy 265.916426 -253.408147) (xy 265.916918 -253.435104)
			(xy 272.722863 -253.435104) (xy 272.726798 -253.381333) (xy 272.738521 -253.328709) (xy 272.757781 -253.278352)
			(xy 272.784167 -253.231335) (xy 272.817119 -253.188662) (xy 272.855932 -253.151241) (xy 272.89978 -253.119871)
			(xy 272.947728 -253.095219) (xy 272.998755 -253.077811) (xy 273.051773 -253.068018) (xy 273.105652 -253.066049)
			(xy 273.159243 -253.071946) (xy 273.211404 -253.085582) (xy 273.261024 -253.106669) (xy 273.307045 -253.134755)
			(xy 273.348487 -253.169243) (xy 273.384465 -253.209397) (xy 273.414213 -253.254361) (xy 273.437098 -253.303178)
			(xy 273.45263 -253.354807) (xy 273.46048 -253.408147) (xy 273.460972 -253.435104) (xy 280.266663 -253.435104)
			(xy 280.270598 -253.381333) (xy 280.282321 -253.328709) (xy 280.301581 -253.278352) (xy 280.327967 -253.231335)
			(xy 280.360919 -253.188662) (xy 280.399732 -253.151241) (xy 280.44358 -253.119871) (xy 280.491528 -253.095219)
			(xy 280.542555 -253.077811) (xy 280.595573 -253.068018) (xy 280.649452 -253.066049) (xy 280.703043 -253.071946)
			(xy 280.755204 -253.085582) (xy 280.804824 -253.106669) (xy 280.850845 -253.134755) (xy 280.892287 -253.169243)
			(xy 280.928265 -253.209397) (xy 280.958013 -253.254361) (xy 280.980898 -253.303178) (xy 280.99643 -253.354807)
			(xy 281.00428 -253.408147) (xy 281.004772 -253.435104) (xy 287.810717 -253.435104) (xy 287.814652 -253.381333)
			(xy 287.826375 -253.328709) (xy 287.845635 -253.278352) (xy 287.872021 -253.231335) (xy 287.904973 -253.188662)
			(xy 287.943786 -253.151241) (xy 287.987634 -253.119871) (xy 288.035582 -253.095219) (xy 288.086609 -253.077811)
			(xy 288.139627 -253.068018) (xy 288.193506 -253.066049) (xy 288.247097 -253.071946) (xy 288.299258 -253.085582)
			(xy 288.348878 -253.106669) (xy 288.394899 -253.134755) (xy 288.436341 -253.169243) (xy 288.472319 -253.209397)
			(xy 288.502067 -253.254361) (xy 288.524952 -253.303178) (xy 288.540484 -253.354807) (xy 288.548334 -253.408147)
			(xy 288.548826 -253.435104) (xy 288.548334 -253.462061) (xy 288.540484 -253.515401) (xy 288.524952 -253.56703)
			(xy 288.502067 -253.615847) (xy 288.472319 -253.660811) (xy 288.436341 -253.700965) (xy 288.394899 -253.735453)
			(xy 288.348878 -253.763539) (xy 288.299258 -253.784626) (xy 288.247097 -253.798262) (xy 288.193506 -253.804159)
			(xy 288.139627 -253.80219) (xy 288.086609 -253.792397) (xy 288.035582 -253.774989) (xy 287.987634 -253.750337)
			(xy 287.943786 -253.718967) (xy 287.904973 -253.681546) (xy 287.872021 -253.638873) (xy 287.845635 -253.591856)
			(xy 287.826375 -253.541499) (xy 287.814652 -253.488875) (xy 287.810717 -253.435104) (xy 281.004772 -253.435104)
			(xy 281.00428 -253.462061) (xy 280.99643 -253.515401) (xy 280.980898 -253.56703) (xy 280.958013 -253.615847)
			(xy 280.928265 -253.660811) (xy 280.892287 -253.700965) (xy 280.850845 -253.735453) (xy 280.804824 -253.763539)
			(xy 280.755204 -253.784626) (xy 280.703043 -253.798262) (xy 280.649452 -253.804159) (xy 280.595573 -253.80219)
			(xy 280.542555 -253.792397) (xy 280.491528 -253.774989) (xy 280.44358 -253.750337) (xy 280.399732 -253.718967)
			(xy 280.360919 -253.681546) (xy 280.327967 -253.638873) (xy 280.301581 -253.591856) (xy 280.282321 -253.541499)
			(xy 280.270598 -253.488875) (xy 280.266663 -253.435104) (xy 273.460972 -253.435104) (xy 273.46048 -253.462061)
			(xy 273.45263 -253.515401) (xy 273.437098 -253.56703) (xy 273.414213 -253.615847) (xy 273.384465 -253.660811)
			(xy 273.348487 -253.700965) (xy 273.307045 -253.735453) (xy 273.261024 -253.763539) (xy 273.211404 -253.784626)
			(xy 273.159243 -253.798262) (xy 273.105652 -253.804159) (xy 273.051773 -253.80219) (xy 272.998755 -253.792397)
			(xy 272.947728 -253.774989) (xy 272.89978 -253.750337) (xy 272.855932 -253.718967) (xy 272.817119 -253.681546)
			(xy 272.784167 -253.638873) (xy 272.757781 -253.591856) (xy 272.738521 -253.541499) (xy 272.726798 -253.488875)
			(xy 272.722863 -253.435104) (xy 265.916918 -253.435104) (xy 265.916426 -253.462061) (xy 265.908576 -253.515401)
			(xy 265.893044 -253.56703) (xy 265.870159 -253.615847) (xy 265.840411 -253.660811) (xy 265.804433 -253.700965)
			(xy 265.762991 -253.735453) (xy 265.71697 -253.763539) (xy 265.66735 -253.784626) (xy 265.615189 -253.798262)
			(xy 265.561598 -253.804159) (xy 265.507719 -253.80219) (xy 265.454701 -253.792397) (xy 265.403674 -253.774989)
			(xy 265.355726 -253.750337) (xy 265.311878 -253.718967) (xy 265.273065 -253.681546) (xy 265.240113 -253.638873)
			(xy 265.213727 -253.591856) (xy 265.194467 -253.541499) (xy 265.182744 -253.488875) (xy 265.178809 -253.435104)
			(xy 264.143998 -253.435104) (xy 264.143998 -254.284988) (xy 265.178809 -254.284988) (xy 265.182744 -254.231217)
			(xy 265.194467 -254.178593) (xy 265.213727 -254.128236) (xy 265.240113 -254.081219) (xy 265.273065 -254.038546)
			(xy 265.311878 -254.001125) (xy 265.355726 -253.969755) (xy 265.403674 -253.945103) (xy 265.454701 -253.927695)
			(xy 265.507719 -253.917902) (xy 265.561598 -253.915933) (xy 265.615189 -253.92183) (xy 265.66735 -253.935466)
			(xy 265.71697 -253.956553) (xy 265.762991 -253.984639) (xy 265.804433 -254.019127) (xy 265.840411 -254.059281)
			(xy 265.870159 -254.104245) (xy 265.893044 -254.153062) (xy 265.908576 -254.204691) (xy 265.916426 -254.258031)
			(xy 265.916918 -254.284988) (xy 269.278877 -254.284988) (xy 269.282812 -254.231217) (xy 269.294535 -254.178593)
			(xy 269.313795 -254.128236) (xy 269.340181 -254.081219) (xy 269.373133 -254.038546) (xy 269.411946 -254.001125)
			(xy 269.455794 -253.969755) (xy 269.503742 -253.945103) (xy 269.554769 -253.927695) (xy 269.607787 -253.917902)
			(xy 269.661666 -253.915933) (xy 269.715257 -253.92183) (xy 269.767418 -253.935466) (xy 269.817038 -253.956553)
			(xy 269.863059 -253.984639) (xy 269.904501 -254.019127) (xy 269.940479 -254.059281) (xy 269.970227 -254.104245)
			(xy 269.993112 -254.153062) (xy 270.008644 -254.204691) (xy 270.016494 -254.258031) (xy 270.016986 -254.284988)
			(xy 272.722863 -254.284988) (xy 272.726798 -254.231217) (xy 272.738521 -254.178593) (xy 272.757781 -254.128236)
			(xy 272.784167 -254.081219) (xy 272.817119 -254.038546) (xy 272.855932 -254.001125) (xy 272.89978 -253.969755)
			(xy 272.947728 -253.945103) (xy 272.998755 -253.927695) (xy 273.051773 -253.917902) (xy 273.105652 -253.915933)
			(xy 273.159243 -253.92183) (xy 273.211404 -253.935466) (xy 273.261024 -253.956553) (xy 273.307045 -253.984639)
			(xy 273.348487 -254.019127) (xy 273.384465 -254.059281) (xy 273.414213 -254.104245) (xy 273.437098 -254.153062)
			(xy 273.45263 -254.204691) (xy 273.46048 -254.258031) (xy 273.460972 -254.284988) (xy 276.822931 -254.284988)
			(xy 276.826866 -254.231217) (xy 276.838589 -254.178593) (xy 276.857849 -254.128236) (xy 276.884235 -254.081219)
			(xy 276.917187 -254.038546) (xy 276.956 -254.001125) (xy 276.999848 -253.969755) (xy 277.047796 -253.945103)
			(xy 277.098823 -253.927695) (xy 277.151841 -253.917902) (xy 277.20572 -253.915933) (xy 277.259311 -253.92183)
			(xy 277.311472 -253.935466) (xy 277.361092 -253.956553) (xy 277.407113 -253.984639) (xy 277.448555 -254.019127)
			(xy 277.484533 -254.059281) (xy 277.514281 -254.104245) (xy 277.537166 -254.153062) (xy 277.552698 -254.204691)
			(xy 277.560548 -254.258031) (xy 277.56104 -254.284988) (xy 280.266663 -254.284988) (xy 280.270598 -254.231217)
			(xy 280.282321 -254.178593) (xy 280.301581 -254.128236) (xy 280.327967 -254.081219) (xy 280.360919 -254.038546)
			(xy 280.399732 -254.001125) (xy 280.44358 -253.969755) (xy 280.491528 -253.945103) (xy 280.542555 -253.927695)
			(xy 280.595573 -253.917902) (xy 280.649452 -253.915933) (xy 280.703043 -253.92183) (xy 280.755204 -253.935466)
			(xy 280.804824 -253.956553) (xy 280.850845 -253.984639) (xy 280.892287 -254.019127) (xy 280.928265 -254.059281)
			(xy 280.958013 -254.104245) (xy 280.980898 -254.153062) (xy 280.99643 -254.204691) (xy 281.00428 -254.258031)
			(xy 281.004772 -254.284988) (xy 284.366731 -254.284988) (xy 284.370666 -254.231217) (xy 284.382389 -254.178593)
			(xy 284.401649 -254.128236) (xy 284.428035 -254.081219) (xy 284.460987 -254.038546) (xy 284.4998 -254.001125)
			(xy 284.543648 -253.969755) (xy 284.591596 -253.945103) (xy 284.642623 -253.927695) (xy 284.695641 -253.917902)
			(xy 284.74952 -253.915933) (xy 284.803111 -253.92183) (xy 284.855272 -253.935466) (xy 284.904892 -253.956553)
			(xy 284.950913 -253.984639) (xy 284.992355 -254.019127) (xy 285.028333 -254.059281) (xy 285.058081 -254.104245)
			(xy 285.080966 -254.153062) (xy 285.096498 -254.204691) (xy 285.104348 -254.258031) (xy 285.10484 -254.284988)
			(xy 287.810717 -254.284988) (xy 287.814652 -254.231217) (xy 287.826375 -254.178593) (xy 287.845635 -254.128236)
			(xy 287.872021 -254.081219) (xy 287.904973 -254.038546) (xy 287.943786 -254.001125) (xy 287.987634 -253.969755)
			(xy 288.035582 -253.945103) (xy 288.086609 -253.927695) (xy 288.139627 -253.917902) (xy 288.193506 -253.915933)
			(xy 288.247097 -253.92183) (xy 288.299258 -253.935466) (xy 288.348878 -253.956553) (xy 288.394899 -253.984639)
			(xy 288.436341 -254.019127) (xy 288.472319 -254.059281) (xy 288.502067 -254.104245) (xy 288.524952 -254.153062)
			(xy 288.540484 -254.204691) (xy 288.548334 -254.258031) (xy 288.548826 -254.284988) (xy 291.910785 -254.284988)
			(xy 291.91472 -254.231217) (xy 291.926443 -254.178593) (xy 291.945703 -254.128236) (xy 291.972089 -254.081219)
			(xy 292.005041 -254.038546) (xy 292.043854 -254.001125) (xy 292.087702 -253.969755) (xy 292.13565 -253.945103)
			(xy 292.186677 -253.927695) (xy 292.239695 -253.917902) (xy 292.293574 -253.915933) (xy 292.347165 -253.92183)
			(xy 292.399326 -253.935466) (xy 292.448946 -253.956553) (xy 292.494967 -253.984639) (xy 292.536409 -254.019127)
			(xy 292.572387 -254.059281) (xy 292.602135 -254.104245) (xy 292.62502 -254.153062) (xy 292.640552 -254.204691)
			(xy 292.648402 -254.258031) (xy 292.648894 -254.284988) (xy 292.648402 -254.311945) (xy 292.640552 -254.365285)
			(xy 292.62502 -254.416914) (xy 292.602135 -254.465731) (xy 292.572387 -254.510695) (xy 292.536409 -254.550849)
			(xy 292.494967 -254.585337) (xy 292.448946 -254.613423) (xy 292.399326 -254.63451) (xy 292.347165 -254.648146)
			(xy 292.293574 -254.654043) (xy 292.239695 -254.652074) (xy 292.186677 -254.642281) (xy 292.13565 -254.624873)
			(xy 292.087702 -254.600221) (xy 292.043854 -254.568851) (xy 292.005041 -254.53143) (xy 291.972089 -254.488757)
			(xy 291.945703 -254.44174) (xy 291.926443 -254.391383) (xy 291.91472 -254.338759) (xy 291.910785 -254.284988)
			(xy 288.548826 -254.284988) (xy 288.548334 -254.311945) (xy 288.540484 -254.365285) (xy 288.524952 -254.416914)
			(xy 288.502067 -254.465731) (xy 288.472319 -254.510695) (xy 288.436341 -254.550849) (xy 288.394899 -254.585337)
			(xy 288.348878 -254.613423) (xy 288.299258 -254.63451) (xy 288.247097 -254.648146) (xy 288.193506 -254.654043)
			(xy 288.139627 -254.652074) (xy 288.086609 -254.642281) (xy 288.035582 -254.624873) (xy 287.987634 -254.600221)
			(xy 287.943786 -254.568851) (xy 287.904973 -254.53143) (xy 287.872021 -254.488757) (xy 287.845635 -254.44174)
			(xy 287.826375 -254.391383) (xy 287.814652 -254.338759) (xy 287.810717 -254.284988) (xy 285.10484 -254.284988)
			(xy 285.104348 -254.311945) (xy 285.096498 -254.365285) (xy 285.080966 -254.416914) (xy 285.058081 -254.465731)
			(xy 285.028333 -254.510695) (xy 284.992355 -254.550849) (xy 284.950913 -254.585337) (xy 284.904892 -254.613423)
			(xy 284.855272 -254.63451) (xy 284.803111 -254.648146) (xy 284.74952 -254.654043) (xy 284.695641 -254.652074)
			(xy 284.642623 -254.642281) (xy 284.591596 -254.624873) (xy 284.543648 -254.600221) (xy 284.4998 -254.568851)
			(xy 284.460987 -254.53143) (xy 284.428035 -254.488757) (xy 284.401649 -254.44174) (xy 284.382389 -254.391383)
			(xy 284.370666 -254.338759) (xy 284.366731 -254.284988) (xy 281.004772 -254.284988) (xy 281.00428 -254.311945)
			(xy 280.99643 -254.365285) (xy 280.980898 -254.416914) (xy 280.958013 -254.465731) (xy 280.928265 -254.510695)
			(xy 280.892287 -254.550849) (xy 280.850845 -254.585337) (xy 280.804824 -254.613423) (xy 280.755204 -254.63451)
			(xy 280.703043 -254.648146) (xy 280.649452 -254.654043) (xy 280.595573 -254.652074) (xy 280.542555 -254.642281)
			(xy 280.491528 -254.624873) (xy 280.44358 -254.600221) (xy 280.399732 -254.568851) (xy 280.360919 -254.53143)
			(xy 280.327967 -254.488757) (xy 280.301581 -254.44174) (xy 280.282321 -254.391383) (xy 280.270598 -254.338759)
			(xy 280.266663 -254.284988) (xy 277.56104 -254.284988) (xy 277.560548 -254.311945) (xy 277.552698 -254.365285)
			(xy 277.537166 -254.416914) (xy 277.514281 -254.465731) (xy 277.484533 -254.510695) (xy 277.448555 -254.550849)
			(xy 277.407113 -254.585337) (xy 277.361092 -254.613423) (xy 277.311472 -254.63451) (xy 277.259311 -254.648146)
			(xy 277.20572 -254.654043) (xy 277.151841 -254.652074) (xy 277.098823 -254.642281) (xy 277.047796 -254.624873)
			(xy 276.999848 -254.600221) (xy 276.956 -254.568851) (xy 276.917187 -254.53143) (xy 276.884235 -254.488757)
			(xy 276.857849 -254.44174) (xy 276.838589 -254.391383) (xy 276.826866 -254.338759) (xy 276.822931 -254.284988)
			(xy 273.460972 -254.284988) (xy 273.46048 -254.311945) (xy 273.45263 -254.365285) (xy 273.437098 -254.416914)
			(xy 273.414213 -254.465731) (xy 273.384465 -254.510695) (xy 273.348487 -254.550849) (xy 273.307045 -254.585337)
			(xy 273.261024 -254.613423) (xy 273.211404 -254.63451) (xy 273.159243 -254.648146) (xy 273.105652 -254.654043)
			(xy 273.051773 -254.652074) (xy 272.998755 -254.642281) (xy 272.947728 -254.624873) (xy 272.89978 -254.600221)
			(xy 272.855932 -254.568851) (xy 272.817119 -254.53143) (xy 272.784167 -254.488757) (xy 272.757781 -254.44174)
			(xy 272.738521 -254.391383) (xy 272.726798 -254.338759) (xy 272.722863 -254.284988) (xy 270.016986 -254.284988)
			(xy 270.016494 -254.311945) (xy 270.008644 -254.365285) (xy 269.993112 -254.416914) (xy 269.970227 -254.465731)
			(xy 269.940479 -254.510695) (xy 269.904501 -254.550849) (xy 269.863059 -254.585337) (xy 269.817038 -254.613423)
			(xy 269.767418 -254.63451) (xy 269.715257 -254.648146) (xy 269.661666 -254.654043) (xy 269.607787 -254.652074)
			(xy 269.554769 -254.642281) (xy 269.503742 -254.624873) (xy 269.455794 -254.600221) (xy 269.411946 -254.568851)
			(xy 269.373133 -254.53143) (xy 269.340181 -254.488757) (xy 269.313795 -254.44174) (xy 269.294535 -254.391383)
			(xy 269.282812 -254.338759) (xy 269.278877 -254.284988) (xy 265.916918 -254.284988) (xy 265.916426 -254.311945)
			(xy 265.908576 -254.365285) (xy 265.893044 -254.416914) (xy 265.870159 -254.465731) (xy 265.840411 -254.510695)
			(xy 265.804433 -254.550849) (xy 265.762991 -254.585337) (xy 265.71697 -254.613423) (xy 265.66735 -254.63451)
			(xy 265.615189 -254.648146) (xy 265.561598 -254.654043) (xy 265.507719 -254.652074) (xy 265.454701 -254.642281)
			(xy 265.403674 -254.624873) (xy 265.355726 -254.600221) (xy 265.311878 -254.568851) (xy 265.273065 -254.53143)
			(xy 265.240113 -254.488757) (xy 265.213727 -254.44174) (xy 265.194467 -254.391383) (xy 265.182744 -254.338759)
			(xy 265.178809 -254.284988) (xy 264.143998 -254.284988) (xy 264.143998 -261.085076) (xy 269.278877 -261.085076)
			(xy 269.282812 -261.031305) (xy 269.294535 -260.978681) (xy 269.313795 -260.928324) (xy 269.340181 -260.881307)
			(xy 269.373133 -260.838634) (xy 269.411946 -260.801213) (xy 269.455794 -260.769843) (xy 269.503742 -260.745191)
			(xy 269.554769 -260.727783) (xy 269.607787 -260.71799) (xy 269.661666 -260.716021) (xy 269.715257 -260.721918)
			(xy 269.767418 -260.735554) (xy 269.817038 -260.756641) (xy 269.863059 -260.784727) (xy 269.904501 -260.819215)
			(xy 269.940479 -260.859369) (xy 269.970227 -260.904333) (xy 269.993112 -260.95315) (xy 270.008644 -261.004779)
			(xy 270.016494 -261.058119) (xy 270.016986 -261.085076) (xy 276.822931 -261.085076) (xy 276.826866 -261.031305)
			(xy 276.838589 -260.978681) (xy 276.857849 -260.928324) (xy 276.884235 -260.881307) (xy 276.917187 -260.838634)
			(xy 276.956 -260.801213) (xy 276.999848 -260.769843) (xy 277.047796 -260.745191) (xy 277.098823 -260.727783)
			(xy 277.151841 -260.71799) (xy 277.20572 -260.716021) (xy 277.259311 -260.721918) (xy 277.311472 -260.735554)
			(xy 277.361092 -260.756641) (xy 277.407113 -260.784727) (xy 277.448555 -260.819215) (xy 277.484533 -260.859369)
			(xy 277.514281 -260.904333) (xy 277.537166 -260.95315) (xy 277.552698 -261.004779) (xy 277.560548 -261.058119)
			(xy 277.56104 -261.085076) (xy 284.366731 -261.085076) (xy 284.370666 -261.031305) (xy 284.382389 -260.978681)
			(xy 284.401649 -260.928324) (xy 284.428035 -260.881307) (xy 284.460987 -260.838634) (xy 284.4998 -260.801213)
			(xy 284.543648 -260.769843) (xy 284.591596 -260.745191) (xy 284.642623 -260.727783) (xy 284.695641 -260.71799)
			(xy 284.74952 -260.716021) (xy 284.803111 -260.721918) (xy 284.855272 -260.735554) (xy 284.904892 -260.756641)
			(xy 284.950913 -260.784727) (xy 284.992355 -260.819215) (xy 285.028333 -260.859369) (xy 285.058081 -260.904333)
			(xy 285.080966 -260.95315) (xy 285.096498 -261.004779) (xy 285.104348 -261.058119) (xy 285.10484 -261.085076)
			(xy 291.910785 -261.085076) (xy 291.91472 -261.031305) (xy 291.926443 -260.978681) (xy 291.945703 -260.928324)
			(xy 291.972089 -260.881307) (xy 292.005041 -260.838634) (xy 292.043854 -260.801213) (xy 292.087702 -260.769843)
			(xy 292.13565 -260.745191) (xy 292.186677 -260.727783) (xy 292.239695 -260.71799) (xy 292.293574 -260.716021)
			(xy 292.347165 -260.721918) (xy 292.399326 -260.735554) (xy 292.448946 -260.756641) (xy 292.494967 -260.784727)
			(xy 292.536409 -260.819215) (xy 292.572387 -260.859369) (xy 292.602135 -260.904333) (xy 292.62502 -260.95315)
			(xy 292.640552 -261.004779) (xy 292.648402 -261.058119) (xy 292.648894 -261.085076) (xy 292.648402 -261.112033)
			(xy 292.640552 -261.165373) (xy 292.62502 -261.217002) (xy 292.602135 -261.265819) (xy 292.572387 -261.310783)
			(xy 292.536409 -261.350937) (xy 292.494967 -261.385425) (xy 292.448946 -261.413511) (xy 292.399326 -261.434598)
			(xy 292.347165 -261.448234) (xy 292.293574 -261.454131) (xy 292.239695 -261.452162) (xy 292.186677 -261.442369)
			(xy 292.13565 -261.424961) (xy 292.087702 -261.400309) (xy 292.043854 -261.368939) (xy 292.005041 -261.331518)
			(xy 291.972089 -261.288845) (xy 291.945703 -261.241828) (xy 291.926443 -261.191471) (xy 291.91472 -261.138847)
			(xy 291.910785 -261.085076) (xy 285.10484 -261.085076) (xy 285.104348 -261.112033) (xy 285.096498 -261.165373)
			(xy 285.080966 -261.217002) (xy 285.058081 -261.265819) (xy 285.028333 -261.310783) (xy 284.992355 -261.350937)
			(xy 284.950913 -261.385425) (xy 284.904892 -261.413511) (xy 284.855272 -261.434598) (xy 284.803111 -261.448234)
			(xy 284.74952 -261.454131) (xy 284.695641 -261.452162) (xy 284.642623 -261.442369) (xy 284.591596 -261.424961)
			(xy 284.543648 -261.400309) (xy 284.4998 -261.368939) (xy 284.460987 -261.331518) (xy 284.428035 -261.288845)
			(xy 284.401649 -261.241828) (xy 284.382389 -261.191471) (xy 284.370666 -261.138847) (xy 284.366731 -261.085076)
			(xy 277.56104 -261.085076) (xy 277.560548 -261.112033) (xy 277.552698 -261.165373) (xy 277.537166 -261.217002)
			(xy 277.514281 -261.265819) (xy 277.484533 -261.310783) (xy 277.448555 -261.350937) (xy 277.407113 -261.385425)
			(xy 277.361092 -261.413511) (xy 277.311472 -261.434598) (xy 277.259311 -261.448234) (xy 277.20572 -261.454131)
			(xy 277.151841 -261.452162) (xy 277.098823 -261.442369) (xy 277.047796 -261.424961) (xy 276.999848 -261.400309)
			(xy 276.956 -261.368939) (xy 276.917187 -261.331518) (xy 276.884235 -261.288845) (xy 276.857849 -261.241828)
			(xy 276.838589 -261.191471) (xy 276.826866 -261.138847) (xy 276.822931 -261.085076) (xy 270.016986 -261.085076)
			(xy 270.016494 -261.112033) (xy 270.008644 -261.165373) (xy 269.993112 -261.217002) (xy 269.970227 -261.265819)
			(xy 269.940479 -261.310783) (xy 269.904501 -261.350937) (xy 269.863059 -261.385425) (xy 269.817038 -261.413511)
			(xy 269.767418 -261.434598) (xy 269.715257 -261.448234) (xy 269.661666 -261.454131) (xy 269.607787 -261.452162)
			(xy 269.554769 -261.442369) (xy 269.503742 -261.424961) (xy 269.455794 -261.400309) (xy 269.411946 -261.368939)
			(xy 269.373133 -261.331518) (xy 269.340181 -261.288845) (xy 269.313795 -261.241828) (xy 269.294535 -261.191471)
			(xy 269.282812 -261.138847) (xy 269.278877 -261.085076) (xy 264.143998 -261.085076) (xy 264.143998 -261.93496)
			(xy 265.178809 -261.93496) (xy 265.182744 -261.881189) (xy 265.194467 -261.828565) (xy 265.213727 -261.778208)
			(xy 265.240113 -261.731191) (xy 265.273065 -261.688518) (xy 265.311878 -261.651097) (xy 265.355726 -261.619727)
			(xy 265.403674 -261.595075) (xy 265.454701 -261.577667) (xy 265.507719 -261.567874) (xy 265.561598 -261.565905)
			(xy 265.615189 -261.571802) (xy 265.66735 -261.585438) (xy 265.71697 -261.606525) (xy 265.762991 -261.634611)
			(xy 265.804433 -261.669099) (xy 265.840411 -261.709253) (xy 265.870159 -261.754217) (xy 265.893044 -261.803034)
			(xy 265.908576 -261.854663) (xy 265.916426 -261.908003) (xy 265.916918 -261.93496) (xy 272.722863 -261.93496)
			(xy 272.726798 -261.881189) (xy 272.738521 -261.828565) (xy 272.757781 -261.778208) (xy 272.784167 -261.731191)
			(xy 272.817119 -261.688518) (xy 272.855932 -261.651097) (xy 272.89978 -261.619727) (xy 272.947728 -261.595075)
			(xy 272.998755 -261.577667) (xy 273.051773 -261.567874) (xy 273.105652 -261.565905) (xy 273.159243 -261.571802)
			(xy 273.211404 -261.585438) (xy 273.261024 -261.606525) (xy 273.307045 -261.634611) (xy 273.348487 -261.669099)
			(xy 273.384465 -261.709253) (xy 273.414213 -261.754217) (xy 273.437098 -261.803034) (xy 273.45263 -261.854663)
			(xy 273.46048 -261.908003) (xy 273.460972 -261.93496) (xy 280.266663 -261.93496) (xy 280.270598 -261.881189)
			(xy 280.282321 -261.828565) (xy 280.301581 -261.778208) (xy 280.327967 -261.731191) (xy 280.360919 -261.688518)
			(xy 280.399732 -261.651097) (xy 280.44358 -261.619727) (xy 280.491528 -261.595075) (xy 280.542555 -261.577667)
			(xy 280.595573 -261.567874) (xy 280.649452 -261.565905) (xy 280.703043 -261.571802) (xy 280.755204 -261.585438)
			(xy 280.804824 -261.606525) (xy 280.850845 -261.634611) (xy 280.892287 -261.669099) (xy 280.928265 -261.709253)
			(xy 280.958013 -261.754217) (xy 280.980898 -261.803034) (xy 280.99643 -261.854663) (xy 281.00428 -261.908003)
			(xy 281.004772 -261.93496) (xy 287.810717 -261.93496) (xy 287.814652 -261.881189) (xy 287.826375 -261.828565)
			(xy 287.845635 -261.778208) (xy 287.872021 -261.731191) (xy 287.904973 -261.688518) (xy 287.943786 -261.651097)
			(xy 287.987634 -261.619727) (xy 288.035582 -261.595075) (xy 288.086609 -261.577667) (xy 288.139627 -261.567874)
			(xy 288.193506 -261.565905) (xy 288.247097 -261.571802) (xy 288.299258 -261.585438) (xy 288.348878 -261.606525)
			(xy 288.394899 -261.634611) (xy 288.436341 -261.669099) (xy 288.472319 -261.709253) (xy 288.502067 -261.754217)
			(xy 288.524952 -261.803034) (xy 288.540484 -261.854663) (xy 288.548334 -261.908003) (xy 288.548826 -261.93496)
			(xy 288.548334 -261.961917) (xy 288.540484 -262.015257) (xy 288.524952 -262.066886) (xy 288.502067 -262.115703)
			(xy 288.472319 -262.160667) (xy 288.436341 -262.200821) (xy 288.394899 -262.235309) (xy 288.348878 -262.263395)
			(xy 288.299258 -262.284482) (xy 288.247097 -262.298118) (xy 288.193506 -262.304015) (xy 288.139627 -262.302046)
			(xy 288.086609 -262.292253) (xy 288.035582 -262.274845) (xy 287.987634 -262.250193) (xy 287.943786 -262.218823)
			(xy 287.904973 -262.181402) (xy 287.872021 -262.138729) (xy 287.845635 -262.091712) (xy 287.826375 -262.041355)
			(xy 287.814652 -261.988731) (xy 287.810717 -261.93496) (xy 281.004772 -261.93496) (xy 281.00428 -261.961917)
			(xy 280.99643 -262.015257) (xy 280.980898 -262.066886) (xy 280.958013 -262.115703) (xy 280.928265 -262.160667)
			(xy 280.892287 -262.200821) (xy 280.850845 -262.235309) (xy 280.804824 -262.263395) (xy 280.755204 -262.284482)
			(xy 280.703043 -262.298118) (xy 280.649452 -262.304015) (xy 280.595573 -262.302046) (xy 280.542555 -262.292253)
			(xy 280.491528 -262.274845) (xy 280.44358 -262.250193) (xy 280.399732 -262.218823) (xy 280.360919 -262.181402)
			(xy 280.327967 -262.138729) (xy 280.301581 -262.091712) (xy 280.282321 -262.041355) (xy 280.270598 -261.988731)
			(xy 280.266663 -261.93496) (xy 273.460972 -261.93496) (xy 273.46048 -261.961917) (xy 273.45263 -262.015257)
			(xy 273.437098 -262.066886) (xy 273.414213 -262.115703) (xy 273.384465 -262.160667) (xy 273.348487 -262.200821)
			(xy 273.307045 -262.235309) (xy 273.261024 -262.263395) (xy 273.211404 -262.284482) (xy 273.159243 -262.298118)
			(xy 273.105652 -262.304015) (xy 273.051773 -262.302046) (xy 272.998755 -262.292253) (xy 272.947728 -262.274845)
			(xy 272.89978 -262.250193) (xy 272.855932 -262.218823) (xy 272.817119 -262.181402) (xy 272.784167 -262.138729)
			(xy 272.757781 -262.091712) (xy 272.738521 -262.041355) (xy 272.726798 -261.988731) (xy 272.722863 -261.93496)
			(xy 265.916918 -261.93496) (xy 265.916426 -261.961917) (xy 265.908576 -262.015257) (xy 265.893044 -262.066886)
			(xy 265.870159 -262.115703) (xy 265.840411 -262.160667) (xy 265.804433 -262.200821) (xy 265.762991 -262.235309)
			(xy 265.71697 -262.263395) (xy 265.66735 -262.284482) (xy 265.615189 -262.298118) (xy 265.561598 -262.304015)
			(xy 265.507719 -262.302046) (xy 265.454701 -262.292253) (xy 265.403674 -262.274845) (xy 265.355726 -262.250193)
			(xy 265.311878 -262.218823) (xy 265.273065 -262.181402) (xy 265.240113 -262.138729) (xy 265.213727 -262.091712)
			(xy 265.194467 -262.041355) (xy 265.182744 -261.988731) (xy 265.178809 -261.93496) (xy 264.143998 -261.93496)
			(xy 264.143998 -262.785098) (xy 269.278877 -262.785098) (xy 269.282812 -262.731327) (xy 269.294535 -262.678703)
			(xy 269.313795 -262.628346) (xy 269.340181 -262.581329) (xy 269.373133 -262.538656) (xy 269.411946 -262.501235)
			(xy 269.455794 -262.469865) (xy 269.503742 -262.445213) (xy 269.554769 -262.427805) (xy 269.607787 -262.418012)
			(xy 269.661666 -262.416043) (xy 269.715257 -262.42194) (xy 269.767418 -262.435576) (xy 269.817038 -262.456663)
			(xy 269.863059 -262.484749) (xy 269.904501 -262.519237) (xy 269.940479 -262.559391) (xy 269.970227 -262.604355)
			(xy 269.993112 -262.653172) (xy 270.008644 -262.704801) (xy 270.016494 -262.758141) (xy 270.016986 -262.785098)
			(xy 276.822931 -262.785098) (xy 276.826866 -262.731327) (xy 276.838589 -262.678703) (xy 276.857849 -262.628346)
			(xy 276.884235 -262.581329) (xy 276.917187 -262.538656) (xy 276.956 -262.501235) (xy 276.999848 -262.469865)
			(xy 277.047796 -262.445213) (xy 277.098823 -262.427805) (xy 277.151841 -262.418012) (xy 277.20572 -262.416043)
			(xy 277.259311 -262.42194) (xy 277.311472 -262.435576) (xy 277.361092 -262.456663) (xy 277.407113 -262.484749)
			(xy 277.448555 -262.519237) (xy 277.484533 -262.559391) (xy 277.514281 -262.604355) (xy 277.537166 -262.653172)
			(xy 277.552698 -262.704801) (xy 277.560548 -262.758141) (xy 277.56104 -262.785098) (xy 284.366731 -262.785098)
			(xy 284.370666 -262.731327) (xy 284.382389 -262.678703) (xy 284.401649 -262.628346) (xy 284.428035 -262.581329)
			(xy 284.460987 -262.538656) (xy 284.4998 -262.501235) (xy 284.543648 -262.469865) (xy 284.591596 -262.445213)
			(xy 284.642623 -262.427805) (xy 284.695641 -262.418012) (xy 284.74952 -262.416043) (xy 284.803111 -262.42194)
			(xy 284.855272 -262.435576) (xy 284.904892 -262.456663) (xy 284.950913 -262.484749) (xy 284.992355 -262.519237)
			(xy 285.028333 -262.559391) (xy 285.058081 -262.604355) (xy 285.080966 -262.653172) (xy 285.096498 -262.704801)
			(xy 285.104348 -262.758141) (xy 285.10484 -262.785098) (xy 291.910785 -262.785098) (xy 291.91472 -262.731327)
			(xy 291.926443 -262.678703) (xy 291.945703 -262.628346) (xy 291.972089 -262.581329) (xy 292.005041 -262.538656)
			(xy 292.043854 -262.501235) (xy 292.087702 -262.469865) (xy 292.13565 -262.445213) (xy 292.186677 -262.427805)
			(xy 292.239695 -262.418012) (xy 292.293574 -262.416043) (xy 292.347165 -262.42194) (xy 292.399326 -262.435576)
			(xy 292.448946 -262.456663) (xy 292.494967 -262.484749) (xy 292.536409 -262.519237) (xy 292.572387 -262.559391)
			(xy 292.602135 -262.604355) (xy 292.62502 -262.653172) (xy 292.640552 -262.704801) (xy 292.648402 -262.758141)
			(xy 292.648894 -262.785098) (xy 292.648402 -262.812055) (xy 292.640552 -262.865395) (xy 292.62502 -262.917024)
			(xy 292.602135 -262.965841) (xy 292.572387 -263.010805) (xy 292.536409 -263.050959) (xy 292.494967 -263.085447)
			(xy 292.448946 -263.113533) (xy 292.399326 -263.13462) (xy 292.347165 -263.148256) (xy 292.293574 -263.154153)
			(xy 292.239695 -263.152184) (xy 292.186677 -263.142391) (xy 292.13565 -263.124983) (xy 292.087702 -263.100331)
			(xy 292.043854 -263.068961) (xy 292.005041 -263.03154) (xy 291.972089 -262.988867) (xy 291.945703 -262.94185)
			(xy 291.926443 -262.891493) (xy 291.91472 -262.838869) (xy 291.910785 -262.785098) (xy 285.10484 -262.785098)
			(xy 285.104348 -262.812055) (xy 285.096498 -262.865395) (xy 285.080966 -262.917024) (xy 285.058081 -262.965841)
			(xy 285.028333 -263.010805) (xy 284.992355 -263.050959) (xy 284.950913 -263.085447) (xy 284.904892 -263.113533)
			(xy 284.855272 -263.13462) (xy 284.803111 -263.148256) (xy 284.74952 -263.154153) (xy 284.695641 -263.152184)
			(xy 284.642623 -263.142391) (xy 284.591596 -263.124983) (xy 284.543648 -263.100331) (xy 284.4998 -263.068961)
			(xy 284.460987 -263.03154) (xy 284.428035 -262.988867) (xy 284.401649 -262.94185) (xy 284.382389 -262.891493)
			(xy 284.370666 -262.838869) (xy 284.366731 -262.785098) (xy 277.56104 -262.785098) (xy 277.560548 -262.812055)
			(xy 277.552698 -262.865395) (xy 277.537166 -262.917024) (xy 277.514281 -262.965841) (xy 277.484533 -263.010805)
			(xy 277.448555 -263.050959) (xy 277.407113 -263.085447) (xy 277.361092 -263.113533) (xy 277.311472 -263.13462)
			(xy 277.259311 -263.148256) (xy 277.20572 -263.154153) (xy 277.151841 -263.152184) (xy 277.098823 -263.142391)
			(xy 277.047796 -263.124983) (xy 276.999848 -263.100331) (xy 276.956 -263.068961) (xy 276.917187 -263.03154)
			(xy 276.884235 -262.988867) (xy 276.857849 -262.94185) (xy 276.838589 -262.891493) (xy 276.826866 -262.838869)
			(xy 276.822931 -262.785098) (xy 270.016986 -262.785098) (xy 270.016494 -262.812055) (xy 270.008644 -262.865395)
			(xy 269.993112 -262.917024) (xy 269.970227 -262.965841) (xy 269.940479 -263.010805) (xy 269.904501 -263.050959)
			(xy 269.863059 -263.085447) (xy 269.817038 -263.113533) (xy 269.767418 -263.13462) (xy 269.715257 -263.148256)
			(xy 269.661666 -263.154153) (xy 269.607787 -263.152184) (xy 269.554769 -263.142391) (xy 269.503742 -263.124983)
			(xy 269.455794 -263.100331) (xy 269.411946 -263.068961) (xy 269.373133 -263.03154) (xy 269.340181 -262.988867)
			(xy 269.313795 -262.94185) (xy 269.294535 -262.891493) (xy 269.282812 -262.838869) (xy 269.278877 -262.785098)
			(xy 264.143998 -262.785098) (xy 264.143998 -263.634982) (xy 265.178809 -263.634982) (xy 265.182744 -263.581211)
			(xy 265.194467 -263.528587) (xy 265.213727 -263.47823) (xy 265.240113 -263.431213) (xy 265.273065 -263.38854)
			(xy 265.311878 -263.351119) (xy 265.355726 -263.319749) (xy 265.403674 -263.295097) (xy 265.454701 -263.277689)
			(xy 265.507719 -263.267896) (xy 265.561598 -263.265927) (xy 265.615189 -263.271824) (xy 265.66735 -263.28546)
			(xy 265.71697 -263.306547) (xy 265.762991 -263.334633) (xy 265.804433 -263.369121) (xy 265.840411 -263.409275)
			(xy 265.870159 -263.454239) (xy 265.893044 -263.503056) (xy 265.908576 -263.554685) (xy 265.916426 -263.608025)
			(xy 265.916918 -263.634982) (xy 272.722863 -263.634982) (xy 272.726798 -263.581211) (xy 272.738521 -263.528587)
			(xy 272.757781 -263.47823) (xy 272.784167 -263.431213) (xy 272.817119 -263.38854) (xy 272.855932 -263.351119)
			(xy 272.89978 -263.319749) (xy 272.947728 -263.295097) (xy 272.998755 -263.277689) (xy 273.051773 -263.267896)
			(xy 273.105652 -263.265927) (xy 273.159243 -263.271824) (xy 273.211404 -263.28546) (xy 273.261024 -263.306547)
			(xy 273.307045 -263.334633) (xy 273.348487 -263.369121) (xy 273.384465 -263.409275) (xy 273.414213 -263.454239)
			(xy 273.437098 -263.503056) (xy 273.45263 -263.554685) (xy 273.46048 -263.608025) (xy 273.460972 -263.634982)
			(xy 280.266663 -263.634982) (xy 280.270598 -263.581211) (xy 280.282321 -263.528587) (xy 280.301581 -263.47823)
			(xy 280.327967 -263.431213) (xy 280.360919 -263.38854) (xy 280.399732 -263.351119) (xy 280.44358 -263.319749)
			(xy 280.491528 -263.295097) (xy 280.542555 -263.277689) (xy 280.595573 -263.267896) (xy 280.649452 -263.265927)
			(xy 280.703043 -263.271824) (xy 280.755204 -263.28546) (xy 280.804824 -263.306547) (xy 280.850845 -263.334633)
			(xy 280.892287 -263.369121) (xy 280.928265 -263.409275) (xy 280.958013 -263.454239) (xy 280.980898 -263.503056)
			(xy 280.99643 -263.554685) (xy 281.00428 -263.608025) (xy 281.004772 -263.634982) (xy 287.810717 -263.634982)
			(xy 287.814652 -263.581211) (xy 287.826375 -263.528587) (xy 287.845635 -263.47823) (xy 287.872021 -263.431213)
			(xy 287.904973 -263.38854) (xy 287.943786 -263.351119) (xy 287.987634 -263.319749) (xy 288.035582 -263.295097)
			(xy 288.086609 -263.277689) (xy 288.139627 -263.267896) (xy 288.193506 -263.265927) (xy 288.247097 -263.271824)
			(xy 288.299258 -263.28546) (xy 288.348878 -263.306547) (xy 288.394899 -263.334633) (xy 288.436341 -263.369121)
			(xy 288.472319 -263.409275) (xy 288.502067 -263.454239) (xy 288.524952 -263.503056) (xy 288.540484 -263.554685)
			(xy 288.548334 -263.608025) (xy 288.548826 -263.634982) (xy 288.548334 -263.661939) (xy 288.540484 -263.715279)
			(xy 288.524952 -263.766908) (xy 288.502067 -263.815725) (xy 288.472319 -263.860689) (xy 288.436341 -263.900843)
			(xy 288.394899 -263.935331) (xy 288.348878 -263.963417) (xy 288.299258 -263.984504) (xy 288.247097 -263.99814)
			(xy 288.193506 -264.004037) (xy 288.139627 -264.002068) (xy 288.086609 -263.992275) (xy 288.035582 -263.974867)
			(xy 287.987634 -263.950215) (xy 287.943786 -263.918845) (xy 287.904973 -263.881424) (xy 287.872021 -263.838751)
			(xy 287.845635 -263.791734) (xy 287.826375 -263.741377) (xy 287.814652 -263.688753) (xy 287.810717 -263.634982)
			(xy 281.004772 -263.634982) (xy 281.00428 -263.661939) (xy 280.99643 -263.715279) (xy 280.980898 -263.766908)
			(xy 280.958013 -263.815725) (xy 280.928265 -263.860689) (xy 280.892287 -263.900843) (xy 280.850845 -263.935331)
			(xy 280.804824 -263.963417) (xy 280.755204 -263.984504) (xy 280.703043 -263.99814) (xy 280.649452 -264.004037)
			(xy 280.595573 -264.002068) (xy 280.542555 -263.992275) (xy 280.491528 -263.974867) (xy 280.44358 -263.950215)
			(xy 280.399732 -263.918845) (xy 280.360919 -263.881424) (xy 280.327967 -263.838751) (xy 280.301581 -263.791734)
			(xy 280.282321 -263.741377) (xy 280.270598 -263.688753) (xy 280.266663 -263.634982) (xy 273.460972 -263.634982)
			(xy 273.46048 -263.661939) (xy 273.45263 -263.715279) (xy 273.437098 -263.766908) (xy 273.414213 -263.815725)
			(xy 273.384465 -263.860689) (xy 273.348487 -263.900843) (xy 273.307045 -263.935331) (xy 273.261024 -263.963417)
			(xy 273.211404 -263.984504) (xy 273.159243 -263.99814) (xy 273.105652 -264.004037) (xy 273.051773 -264.002068)
			(xy 272.998755 -263.992275) (xy 272.947728 -263.974867) (xy 272.89978 -263.950215) (xy 272.855932 -263.918845)
			(xy 272.817119 -263.881424) (xy 272.784167 -263.838751) (xy 272.757781 -263.791734) (xy 272.738521 -263.741377)
			(xy 272.726798 -263.688753) (xy 272.722863 -263.634982) (xy 265.916918 -263.634982) (xy 265.916426 -263.661939)
			(xy 265.908576 -263.715279) (xy 265.893044 -263.766908) (xy 265.870159 -263.815725) (xy 265.840411 -263.860689)
			(xy 265.804433 -263.900843) (xy 265.762991 -263.935331) (xy 265.71697 -263.963417) (xy 265.66735 -263.984504)
			(xy 265.615189 -263.99814) (xy 265.561598 -264.004037) (xy 265.507719 -264.002068) (xy 265.454701 -263.992275)
			(xy 265.403674 -263.974867) (xy 265.355726 -263.950215) (xy 265.311878 -263.918845) (xy 265.273065 -263.881424)
			(xy 265.240113 -263.838751) (xy 265.213727 -263.791734) (xy 265.194467 -263.741377) (xy 265.182744 -263.688753)
			(xy 265.178809 -263.634982) (xy 264.143998 -263.634982) (xy 264.143998 -264.48512) (xy 269.278877 -264.48512)
			(xy 269.282812 -264.431349) (xy 269.294535 -264.378725) (xy 269.313795 -264.328368) (xy 269.340181 -264.281351)
			(xy 269.373133 -264.238678) (xy 269.411946 -264.201257) (xy 269.455794 -264.169887) (xy 269.503742 -264.145235)
			(xy 269.554769 -264.127827) (xy 269.607787 -264.118034) (xy 269.661666 -264.116065) (xy 269.715257 -264.121962)
			(xy 269.767418 -264.135598) (xy 269.817038 -264.156685) (xy 269.863059 -264.184771) (xy 269.904501 -264.219259)
			(xy 269.940479 -264.259413) (xy 269.970227 -264.304377) (xy 269.993112 -264.353194) (xy 270.008644 -264.404823)
			(xy 270.016494 -264.458163) (xy 270.016986 -264.48512) (xy 276.822931 -264.48512) (xy 276.826866 -264.431349)
			(xy 276.838589 -264.378725) (xy 276.857849 -264.328368) (xy 276.884235 -264.281351) (xy 276.917187 -264.238678)
			(xy 276.956 -264.201257) (xy 276.999848 -264.169887) (xy 277.047796 -264.145235) (xy 277.098823 -264.127827)
			(xy 277.151841 -264.118034) (xy 277.20572 -264.116065) (xy 277.259311 -264.121962) (xy 277.311472 -264.135598)
			(xy 277.361092 -264.156685) (xy 277.407113 -264.184771) (xy 277.448555 -264.219259) (xy 277.484533 -264.259413)
			(xy 277.514281 -264.304377) (xy 277.537166 -264.353194) (xy 277.552698 -264.404823) (xy 277.560548 -264.458163)
			(xy 277.56104 -264.48512) (xy 284.366731 -264.48512) (xy 284.370666 -264.431349) (xy 284.382389 -264.378725)
			(xy 284.401649 -264.328368) (xy 284.428035 -264.281351) (xy 284.460987 -264.238678) (xy 284.4998 -264.201257)
			(xy 284.543648 -264.169887) (xy 284.591596 -264.145235) (xy 284.642623 -264.127827) (xy 284.695641 -264.118034)
			(xy 284.74952 -264.116065) (xy 284.803111 -264.121962) (xy 284.855272 -264.135598) (xy 284.904892 -264.156685)
			(xy 284.950913 -264.184771) (xy 284.992355 -264.219259) (xy 285.028333 -264.259413) (xy 285.058081 -264.304377)
			(xy 285.080966 -264.353194) (xy 285.096498 -264.404823) (xy 285.104348 -264.458163) (xy 285.10484 -264.48512)
			(xy 291.910785 -264.48512) (xy 291.91472 -264.431349) (xy 291.926443 -264.378725) (xy 291.945703 -264.328368)
			(xy 291.972089 -264.281351) (xy 292.005041 -264.238678) (xy 292.043854 -264.201257) (xy 292.087702 -264.169887)
			(xy 292.13565 -264.145235) (xy 292.186677 -264.127827) (xy 292.239695 -264.118034) (xy 292.293574 -264.116065)
			(xy 292.347165 -264.121962) (xy 292.399326 -264.135598) (xy 292.448946 -264.156685) (xy 292.494967 -264.184771)
			(xy 292.536409 -264.219259) (xy 292.572387 -264.259413) (xy 292.602135 -264.304377) (xy 292.62502 -264.353194)
			(xy 292.640552 -264.404823) (xy 292.648402 -264.458163) (xy 292.648894 -264.48512) (xy 292.648402 -264.512077)
			(xy 292.640552 -264.565417) (xy 292.62502 -264.617046) (xy 292.602135 -264.665863) (xy 292.572387 -264.710827)
			(xy 292.536409 -264.750981) (xy 292.494967 -264.785469) (xy 292.448946 -264.813555) (xy 292.399326 -264.834642)
			(xy 292.347165 -264.848278) (xy 292.293574 -264.854175) (xy 292.239695 -264.852206) (xy 292.186677 -264.842413)
			(xy 292.13565 -264.825005) (xy 292.087702 -264.800353) (xy 292.043854 -264.768983) (xy 292.005041 -264.731562)
			(xy 291.972089 -264.688889) (xy 291.945703 -264.641872) (xy 291.926443 -264.591515) (xy 291.91472 -264.538891)
			(xy 291.910785 -264.48512) (xy 285.10484 -264.48512) (xy 285.104348 -264.512077) (xy 285.096498 -264.565417)
			(xy 285.080966 -264.617046) (xy 285.058081 -264.665863) (xy 285.028333 -264.710827) (xy 284.992355 -264.750981)
			(xy 284.950913 -264.785469) (xy 284.904892 -264.813555) (xy 284.855272 -264.834642) (xy 284.803111 -264.848278)
			(xy 284.74952 -264.854175) (xy 284.695641 -264.852206) (xy 284.642623 -264.842413) (xy 284.591596 -264.825005)
			(xy 284.543648 -264.800353) (xy 284.4998 -264.768983) (xy 284.460987 -264.731562) (xy 284.428035 -264.688889)
			(xy 284.401649 -264.641872) (xy 284.382389 -264.591515) (xy 284.370666 -264.538891) (xy 284.366731 -264.48512)
			(xy 277.56104 -264.48512) (xy 277.560548 -264.512077) (xy 277.552698 -264.565417) (xy 277.537166 -264.617046)
			(xy 277.514281 -264.665863) (xy 277.484533 -264.710827) (xy 277.448555 -264.750981) (xy 277.407113 -264.785469)
			(xy 277.361092 -264.813555) (xy 277.311472 -264.834642) (xy 277.259311 -264.848278) (xy 277.20572 -264.854175)
			(xy 277.151841 -264.852206) (xy 277.098823 -264.842413) (xy 277.047796 -264.825005) (xy 276.999848 -264.800353)
			(xy 276.956 -264.768983) (xy 276.917187 -264.731562) (xy 276.884235 -264.688889) (xy 276.857849 -264.641872)
			(xy 276.838589 -264.591515) (xy 276.826866 -264.538891) (xy 276.822931 -264.48512) (xy 270.016986 -264.48512)
			(xy 270.016494 -264.512077) (xy 270.008644 -264.565417) (xy 269.993112 -264.617046) (xy 269.970227 -264.665863)
			(xy 269.940479 -264.710827) (xy 269.904501 -264.750981) (xy 269.863059 -264.785469) (xy 269.817038 -264.813555)
			(xy 269.767418 -264.834642) (xy 269.715257 -264.848278) (xy 269.661666 -264.854175) (xy 269.607787 -264.852206)
			(xy 269.554769 -264.842413) (xy 269.503742 -264.825005) (xy 269.455794 -264.800353) (xy 269.411946 -264.768983)
			(xy 269.373133 -264.731562) (xy 269.340181 -264.688889) (xy 269.313795 -264.641872) (xy 269.294535 -264.591515)
			(xy 269.282812 -264.538891) (xy 269.278877 -264.48512) (xy 264.143998 -264.48512) (xy 264.143998 -265.335004)
			(xy 265.178809 -265.335004) (xy 265.182744 -265.281233) (xy 265.194467 -265.228609) (xy 265.213727 -265.178252)
			(xy 265.240113 -265.131235) (xy 265.273065 -265.088562) (xy 265.311878 -265.051141) (xy 265.355726 -265.019771)
			(xy 265.403674 -264.995119) (xy 265.454701 -264.977711) (xy 265.507719 -264.967918) (xy 265.561598 -264.965949)
			(xy 265.615189 -264.971846) (xy 265.66735 -264.985482) (xy 265.71697 -265.006569) (xy 265.762991 -265.034655)
			(xy 265.804433 -265.069143) (xy 265.840411 -265.109297) (xy 265.870159 -265.154261) (xy 265.893044 -265.203078)
			(xy 265.908576 -265.254707) (xy 265.916426 -265.308047) (xy 265.916918 -265.335004) (xy 272.722863 -265.335004)
			(xy 272.726798 -265.281233) (xy 272.738521 -265.228609) (xy 272.757781 -265.178252) (xy 272.784167 -265.131235)
			(xy 272.817119 -265.088562) (xy 272.855932 -265.051141) (xy 272.89978 -265.019771) (xy 272.947728 -264.995119)
			(xy 272.998755 -264.977711) (xy 273.051773 -264.967918) (xy 273.105652 -264.965949) (xy 273.159243 -264.971846)
			(xy 273.211404 -264.985482) (xy 273.261024 -265.006569) (xy 273.307045 -265.034655) (xy 273.348487 -265.069143)
			(xy 273.384465 -265.109297) (xy 273.414213 -265.154261) (xy 273.437098 -265.203078) (xy 273.45263 -265.254707)
			(xy 273.46048 -265.308047) (xy 273.460972 -265.335004) (xy 280.266663 -265.335004) (xy 280.270598 -265.281233)
			(xy 280.282321 -265.228609) (xy 280.301581 -265.178252) (xy 280.327967 -265.131235) (xy 280.360919 -265.088562)
			(xy 280.399732 -265.051141) (xy 280.44358 -265.019771) (xy 280.491528 -264.995119) (xy 280.542555 -264.977711)
			(xy 280.595573 -264.967918) (xy 280.649452 -264.965949) (xy 280.703043 -264.971846) (xy 280.755204 -264.985482)
			(xy 280.804824 -265.006569) (xy 280.850845 -265.034655) (xy 280.892287 -265.069143) (xy 280.928265 -265.109297)
			(xy 280.958013 -265.154261) (xy 280.980898 -265.203078) (xy 280.99643 -265.254707) (xy 281.00428 -265.308047)
			(xy 281.004772 -265.335004) (xy 287.810717 -265.335004) (xy 287.814652 -265.281233) (xy 287.826375 -265.228609)
			(xy 287.845635 -265.178252) (xy 287.872021 -265.131235) (xy 287.904973 -265.088562) (xy 287.943786 -265.051141)
			(xy 287.987634 -265.019771) (xy 288.035582 -264.995119) (xy 288.086609 -264.977711) (xy 288.139627 -264.967918)
			(xy 288.193506 -264.965949) (xy 288.247097 -264.971846) (xy 288.299258 -264.985482) (xy 288.348878 -265.006569)
			(xy 288.394899 -265.034655) (xy 288.436341 -265.069143) (xy 288.472319 -265.109297) (xy 288.502067 -265.154261)
			(xy 288.524952 -265.203078) (xy 288.540484 -265.254707) (xy 288.548334 -265.308047) (xy 288.548826 -265.335004)
			(xy 288.548334 -265.361961) (xy 288.540484 -265.415301) (xy 288.524952 -265.46693) (xy 288.502067 -265.515747)
			(xy 288.472319 -265.560711) (xy 288.436341 -265.600865) (xy 288.394899 -265.635353) (xy 288.348878 -265.663439)
			(xy 288.299258 -265.684526) (xy 288.247097 -265.698162) (xy 288.193506 -265.704059) (xy 288.139627 -265.70209)
			(xy 288.086609 -265.692297) (xy 288.035582 -265.674889) (xy 287.987634 -265.650237) (xy 287.943786 -265.618867)
			(xy 287.904973 -265.581446) (xy 287.872021 -265.538773) (xy 287.845635 -265.491756) (xy 287.826375 -265.441399)
			(xy 287.814652 -265.388775) (xy 287.810717 -265.335004) (xy 281.004772 -265.335004) (xy 281.00428 -265.361961)
			(xy 280.99643 -265.415301) (xy 280.980898 -265.46693) (xy 280.958013 -265.515747) (xy 280.928265 -265.560711)
			(xy 280.892287 -265.600865) (xy 280.850845 -265.635353) (xy 280.804824 -265.663439) (xy 280.755204 -265.684526)
			(xy 280.703043 -265.698162) (xy 280.649452 -265.704059) (xy 280.595573 -265.70209) (xy 280.542555 -265.692297)
			(xy 280.491528 -265.674889) (xy 280.44358 -265.650237) (xy 280.399732 -265.618867) (xy 280.360919 -265.581446)
			(xy 280.327967 -265.538773) (xy 280.301581 -265.491756) (xy 280.282321 -265.441399) (xy 280.270598 -265.388775)
			(xy 280.266663 -265.335004) (xy 273.460972 -265.335004) (xy 273.46048 -265.361961) (xy 273.45263 -265.415301)
			(xy 273.437098 -265.46693) (xy 273.414213 -265.515747) (xy 273.384465 -265.560711) (xy 273.348487 -265.600865)
			(xy 273.307045 -265.635353) (xy 273.261024 -265.663439) (xy 273.211404 -265.684526) (xy 273.159243 -265.698162)
			(xy 273.105652 -265.704059) (xy 273.051773 -265.70209) (xy 272.998755 -265.692297) (xy 272.947728 -265.674889)
			(xy 272.89978 -265.650237) (xy 272.855932 -265.618867) (xy 272.817119 -265.581446) (xy 272.784167 -265.538773)
			(xy 272.757781 -265.491756) (xy 272.738521 -265.441399) (xy 272.726798 -265.388775) (xy 272.722863 -265.335004)
			(xy 265.916918 -265.335004) (xy 265.916426 -265.361961) (xy 265.908576 -265.415301) (xy 265.893044 -265.46693)
			(xy 265.870159 -265.515747) (xy 265.840411 -265.560711) (xy 265.804433 -265.600865) (xy 265.762991 -265.635353)
			(xy 265.71697 -265.663439) (xy 265.66735 -265.684526) (xy 265.615189 -265.698162) (xy 265.561598 -265.704059)
			(xy 265.507719 -265.70209) (xy 265.454701 -265.692297) (xy 265.403674 -265.674889) (xy 265.355726 -265.650237)
			(xy 265.311878 -265.618867) (xy 265.273065 -265.581446) (xy 265.240113 -265.538773) (xy 265.213727 -265.491756)
			(xy 265.194467 -265.441399) (xy 265.182744 -265.388775) (xy 265.178809 -265.335004) (xy 264.143998 -265.335004)
			(xy 264.143998 -266.185142) (xy 269.278877 -266.185142) (xy 269.282812 -266.131371) (xy 269.294535 -266.078747)
			(xy 269.313795 -266.02839) (xy 269.340181 -265.981373) (xy 269.373133 -265.9387) (xy 269.411946 -265.901279)
			(xy 269.455794 -265.869909) (xy 269.503742 -265.845257) (xy 269.554769 -265.827849) (xy 269.607787 -265.818056)
			(xy 269.661666 -265.816087) (xy 269.715257 -265.821984) (xy 269.767418 -265.83562) (xy 269.817038 -265.856707)
			(xy 269.863059 -265.884793) (xy 269.904501 -265.919281) (xy 269.940479 -265.959435) (xy 269.970227 -266.004399)
			(xy 269.993112 -266.053216) (xy 270.008644 -266.104845) (xy 270.016494 -266.158185) (xy 270.016986 -266.185142)
			(xy 276.822931 -266.185142) (xy 276.826866 -266.131371) (xy 276.838589 -266.078747) (xy 276.857849 -266.02839)
			(xy 276.884235 -265.981373) (xy 276.917187 -265.9387) (xy 276.956 -265.901279) (xy 276.999848 -265.869909)
			(xy 277.047796 -265.845257) (xy 277.098823 -265.827849) (xy 277.151841 -265.818056) (xy 277.20572 -265.816087)
			(xy 277.259311 -265.821984) (xy 277.311472 -265.83562) (xy 277.361092 -265.856707) (xy 277.407113 -265.884793)
			(xy 277.448555 -265.919281) (xy 277.484533 -265.959435) (xy 277.514281 -266.004399) (xy 277.537166 -266.053216)
			(xy 277.552698 -266.104845) (xy 277.560548 -266.158185) (xy 277.56104 -266.185142) (xy 284.366731 -266.185142)
			(xy 284.370666 -266.131371) (xy 284.382389 -266.078747) (xy 284.401649 -266.02839) (xy 284.428035 -265.981373)
			(xy 284.460987 -265.9387) (xy 284.4998 -265.901279) (xy 284.543648 -265.869909) (xy 284.591596 -265.845257)
			(xy 284.642623 -265.827849) (xy 284.695641 -265.818056) (xy 284.74952 -265.816087) (xy 284.803111 -265.821984)
			(xy 284.855272 -265.83562) (xy 284.904892 -265.856707) (xy 284.950913 -265.884793) (xy 284.992355 -265.919281)
			(xy 285.028333 -265.959435) (xy 285.058081 -266.004399) (xy 285.080966 -266.053216) (xy 285.096498 -266.104845)
			(xy 285.104348 -266.158185) (xy 285.10484 -266.185142) (xy 291.910785 -266.185142) (xy 291.91472 -266.131371)
			(xy 291.926443 -266.078747) (xy 291.945703 -266.02839) (xy 291.972089 -265.981373) (xy 292.005041 -265.9387)
			(xy 292.043854 -265.901279) (xy 292.087702 -265.869909) (xy 292.13565 -265.845257) (xy 292.186677 -265.827849)
			(xy 292.239695 -265.818056) (xy 292.293574 -265.816087) (xy 292.347165 -265.821984) (xy 292.399326 -265.83562)
			(xy 292.448946 -265.856707) (xy 292.494967 -265.884793) (xy 292.536409 -265.919281) (xy 292.572387 -265.959435)
			(xy 292.602135 -266.004399) (xy 292.62502 -266.053216) (xy 292.640552 -266.104845) (xy 292.648402 -266.158185)
			(xy 292.648894 -266.185142) (xy 292.648402 -266.212099) (xy 292.640552 -266.265439) (xy 292.62502 -266.317068)
			(xy 292.602135 -266.365885) (xy 292.572387 -266.410849) (xy 292.536409 -266.451003) (xy 292.494967 -266.485491)
			(xy 292.448946 -266.513577) (xy 292.399326 -266.534664) (xy 292.347165 -266.5483) (xy 292.293574 -266.554197)
			(xy 292.239695 -266.552228) (xy 292.186677 -266.542435) (xy 292.13565 -266.525027) (xy 292.087702 -266.500375)
			(xy 292.043854 -266.469005) (xy 292.005041 -266.431584) (xy 291.972089 -266.388911) (xy 291.945703 -266.341894)
			(xy 291.926443 -266.291537) (xy 291.91472 -266.238913) (xy 291.910785 -266.185142) (xy 285.10484 -266.185142)
			(xy 285.104348 -266.212099) (xy 285.096498 -266.265439) (xy 285.080966 -266.317068) (xy 285.058081 -266.365885)
			(xy 285.028333 -266.410849) (xy 284.992355 -266.451003) (xy 284.950913 -266.485491) (xy 284.904892 -266.513577)
			(xy 284.855272 -266.534664) (xy 284.803111 -266.5483) (xy 284.74952 -266.554197) (xy 284.695641 -266.552228)
			(xy 284.642623 -266.542435) (xy 284.591596 -266.525027) (xy 284.543648 -266.500375) (xy 284.4998 -266.469005)
			(xy 284.460987 -266.431584) (xy 284.428035 -266.388911) (xy 284.401649 -266.341894) (xy 284.382389 -266.291537)
			(xy 284.370666 -266.238913) (xy 284.366731 -266.185142) (xy 277.56104 -266.185142) (xy 277.560548 -266.212099)
			(xy 277.552698 -266.265439) (xy 277.537166 -266.317068) (xy 277.514281 -266.365885) (xy 277.484533 -266.410849)
			(xy 277.448555 -266.451003) (xy 277.407113 -266.485491) (xy 277.361092 -266.513577) (xy 277.311472 -266.534664)
			(xy 277.259311 -266.5483) (xy 277.20572 -266.554197) (xy 277.151841 -266.552228) (xy 277.098823 -266.542435)
			(xy 277.047796 -266.525027) (xy 276.999848 -266.500375) (xy 276.956 -266.469005) (xy 276.917187 -266.431584)
			(xy 276.884235 -266.388911) (xy 276.857849 -266.341894) (xy 276.838589 -266.291537) (xy 276.826866 -266.238913)
			(xy 276.822931 -266.185142) (xy 270.016986 -266.185142) (xy 270.016494 -266.212099) (xy 270.008644 -266.265439)
			(xy 269.993112 -266.317068) (xy 269.970227 -266.365885) (xy 269.940479 -266.410849) (xy 269.904501 -266.451003)
			(xy 269.863059 -266.485491) (xy 269.817038 -266.513577) (xy 269.767418 -266.534664) (xy 269.715257 -266.5483)
			(xy 269.661666 -266.554197) (xy 269.607787 -266.552228) (xy 269.554769 -266.542435) (xy 269.503742 -266.525027)
			(xy 269.455794 -266.500375) (xy 269.411946 -266.469005) (xy 269.373133 -266.431584) (xy 269.340181 -266.388911)
			(xy 269.313795 -266.341894) (xy 269.294535 -266.291537) (xy 269.282812 -266.238913) (xy 269.278877 -266.185142)
			(xy 264.143998 -266.185142) (xy 264.143998 -267.035026) (xy 265.178809 -267.035026) (xy 265.182744 -266.981255)
			(xy 265.194467 -266.928631) (xy 265.213727 -266.878274) (xy 265.240113 -266.831257) (xy 265.273065 -266.788584)
			(xy 265.311878 -266.751163) (xy 265.355726 -266.719793) (xy 265.403674 -266.695141) (xy 265.454701 -266.677733)
			(xy 265.507719 -266.66794) (xy 265.561598 -266.665971) (xy 265.615189 -266.671868) (xy 265.66735 -266.685504)
			(xy 265.71697 -266.706591) (xy 265.762991 -266.734677) (xy 265.804433 -266.769165) (xy 265.840411 -266.809319)
			(xy 265.870159 -266.854283) (xy 265.893044 -266.9031) (xy 265.908576 -266.954729) (xy 265.916426 -267.008069)
			(xy 265.916918 -267.035026) (xy 272.722863 -267.035026) (xy 272.726798 -266.981255) (xy 272.738521 -266.928631)
			(xy 272.757781 -266.878274) (xy 272.784167 -266.831257) (xy 272.817119 -266.788584) (xy 272.855932 -266.751163)
			(xy 272.89978 -266.719793) (xy 272.947728 -266.695141) (xy 272.998755 -266.677733) (xy 273.051773 -266.66794)
			(xy 273.105652 -266.665971) (xy 273.159243 -266.671868) (xy 273.211404 -266.685504) (xy 273.261024 -266.706591)
			(xy 273.307045 -266.734677) (xy 273.348487 -266.769165) (xy 273.384465 -266.809319) (xy 273.414213 -266.854283)
			(xy 273.437098 -266.9031) (xy 273.45263 -266.954729) (xy 273.46048 -267.008069) (xy 273.460972 -267.035026)
			(xy 280.266663 -267.035026) (xy 280.270598 -266.981255) (xy 280.282321 -266.928631) (xy 280.301581 -266.878274)
			(xy 280.327967 -266.831257) (xy 280.360919 -266.788584) (xy 280.399732 -266.751163) (xy 280.44358 -266.719793)
			(xy 280.491528 -266.695141) (xy 280.542555 -266.677733) (xy 280.595573 -266.66794) (xy 280.649452 -266.665971)
			(xy 280.703043 -266.671868) (xy 280.755204 -266.685504) (xy 280.804824 -266.706591) (xy 280.850845 -266.734677)
			(xy 280.892287 -266.769165) (xy 280.928265 -266.809319) (xy 280.958013 -266.854283) (xy 280.980898 -266.9031)
			(xy 280.99643 -266.954729) (xy 281.00428 -267.008069) (xy 281.004772 -267.035026) (xy 287.810717 -267.035026)
			(xy 287.814652 -266.981255) (xy 287.826375 -266.928631) (xy 287.845635 -266.878274) (xy 287.872021 -266.831257)
			(xy 287.904973 -266.788584) (xy 287.943786 -266.751163) (xy 287.987634 -266.719793) (xy 288.035582 -266.695141)
			(xy 288.086609 -266.677733) (xy 288.139627 -266.66794) (xy 288.193506 -266.665971) (xy 288.247097 -266.671868)
			(xy 288.299258 -266.685504) (xy 288.348878 -266.706591) (xy 288.394899 -266.734677) (xy 288.436341 -266.769165)
			(xy 288.472319 -266.809319) (xy 288.502067 -266.854283) (xy 288.524952 -266.9031) (xy 288.540484 -266.954729)
			(xy 288.548334 -267.008069) (xy 288.548826 -267.035026) (xy 288.548334 -267.061983) (xy 288.540484 -267.115323)
			(xy 288.524952 -267.166952) (xy 288.502067 -267.215769) (xy 288.472319 -267.260733) (xy 288.436341 -267.300887)
			(xy 288.394899 -267.335375) (xy 288.348878 -267.363461) (xy 288.299258 -267.384548) (xy 288.247097 -267.398184)
			(xy 288.193506 -267.404081) (xy 288.139627 -267.402112) (xy 288.086609 -267.392319) (xy 288.035582 -267.374911)
			(xy 287.987634 -267.350259) (xy 287.943786 -267.318889) (xy 287.904973 -267.281468) (xy 287.872021 -267.238795)
			(xy 287.845635 -267.191778) (xy 287.826375 -267.141421) (xy 287.814652 -267.088797) (xy 287.810717 -267.035026)
			(xy 281.004772 -267.035026) (xy 281.00428 -267.061983) (xy 280.99643 -267.115323) (xy 280.980898 -267.166952)
			(xy 280.958013 -267.215769) (xy 280.928265 -267.260733) (xy 280.892287 -267.300887) (xy 280.850845 -267.335375)
			(xy 280.804824 -267.363461) (xy 280.755204 -267.384548) (xy 280.703043 -267.398184) (xy 280.649452 -267.404081)
			(xy 280.595573 -267.402112) (xy 280.542555 -267.392319) (xy 280.491528 -267.374911) (xy 280.44358 -267.350259)
			(xy 280.399732 -267.318889) (xy 280.360919 -267.281468) (xy 280.327967 -267.238795) (xy 280.301581 -267.191778)
			(xy 280.282321 -267.141421) (xy 280.270598 -267.088797) (xy 280.266663 -267.035026) (xy 273.460972 -267.035026)
			(xy 273.46048 -267.061983) (xy 273.45263 -267.115323) (xy 273.437098 -267.166952) (xy 273.414213 -267.215769)
			(xy 273.384465 -267.260733) (xy 273.348487 -267.300887) (xy 273.307045 -267.335375) (xy 273.261024 -267.363461)
			(xy 273.211404 -267.384548) (xy 273.159243 -267.398184) (xy 273.105652 -267.404081) (xy 273.051773 -267.402112)
			(xy 272.998755 -267.392319) (xy 272.947728 -267.374911) (xy 272.89978 -267.350259) (xy 272.855932 -267.318889)
			(xy 272.817119 -267.281468) (xy 272.784167 -267.238795) (xy 272.757781 -267.191778) (xy 272.738521 -267.141421)
			(xy 272.726798 -267.088797) (xy 272.722863 -267.035026) (xy 265.916918 -267.035026) (xy 265.916426 -267.061983)
			(xy 265.908576 -267.115323) (xy 265.893044 -267.166952) (xy 265.870159 -267.215769) (xy 265.840411 -267.260733)
			(xy 265.804433 -267.300887) (xy 265.762991 -267.335375) (xy 265.71697 -267.363461) (xy 265.66735 -267.384548)
			(xy 265.615189 -267.398184) (xy 265.561598 -267.404081) (xy 265.507719 -267.402112) (xy 265.454701 -267.392319)
			(xy 265.403674 -267.374911) (xy 265.355726 -267.350259) (xy 265.311878 -267.318889) (xy 265.273065 -267.281468)
			(xy 265.240113 -267.238795) (xy 265.213727 -267.191778) (xy 265.194467 -267.141421) (xy 265.182744 -267.088797)
			(xy 265.178809 -267.035026) (xy 264.143998 -267.035026) (xy 264.143998 -267.885164) (xy 269.278877 -267.885164)
			(xy 269.282812 -267.831393) (xy 269.294535 -267.778769) (xy 269.313795 -267.728412) (xy 269.340181 -267.681395)
			(xy 269.373133 -267.638722) (xy 269.411946 -267.601301) (xy 269.455794 -267.569931) (xy 269.503742 -267.545279)
			(xy 269.554769 -267.527871) (xy 269.607787 -267.518078) (xy 269.661666 -267.516109) (xy 269.715257 -267.522006)
			(xy 269.767418 -267.535642) (xy 269.817038 -267.556729) (xy 269.863059 -267.584815) (xy 269.904501 -267.619303)
			(xy 269.940479 -267.659457) (xy 269.970227 -267.704421) (xy 269.993112 -267.753238) (xy 270.008644 -267.804867)
			(xy 270.016494 -267.858207) (xy 270.016986 -267.885164) (xy 276.822931 -267.885164) (xy 276.826866 -267.831393)
			(xy 276.838589 -267.778769) (xy 276.857849 -267.728412) (xy 276.884235 -267.681395) (xy 276.917187 -267.638722)
			(xy 276.956 -267.601301) (xy 276.999848 -267.569931) (xy 277.047796 -267.545279) (xy 277.098823 -267.527871)
			(xy 277.151841 -267.518078) (xy 277.20572 -267.516109) (xy 277.259311 -267.522006) (xy 277.311472 -267.535642)
			(xy 277.361092 -267.556729) (xy 277.407113 -267.584815) (xy 277.448555 -267.619303) (xy 277.484533 -267.659457)
			(xy 277.514281 -267.704421) (xy 277.537166 -267.753238) (xy 277.552698 -267.804867) (xy 277.560548 -267.858207)
			(xy 277.56104 -267.885164) (xy 284.366731 -267.885164) (xy 284.370666 -267.831393) (xy 284.382389 -267.778769)
			(xy 284.401649 -267.728412) (xy 284.428035 -267.681395) (xy 284.460987 -267.638722) (xy 284.4998 -267.601301)
			(xy 284.543648 -267.569931) (xy 284.591596 -267.545279) (xy 284.642623 -267.527871) (xy 284.695641 -267.518078)
			(xy 284.74952 -267.516109) (xy 284.803111 -267.522006) (xy 284.855272 -267.535642) (xy 284.904892 -267.556729)
			(xy 284.950913 -267.584815) (xy 284.992355 -267.619303) (xy 285.028333 -267.659457) (xy 285.058081 -267.704421)
			(xy 285.080966 -267.753238) (xy 285.096498 -267.804867) (xy 285.104348 -267.858207) (xy 285.10484 -267.885164)
			(xy 291.910785 -267.885164) (xy 291.91472 -267.831393) (xy 291.926443 -267.778769) (xy 291.945703 -267.728412)
			(xy 291.972089 -267.681395) (xy 292.005041 -267.638722) (xy 292.043854 -267.601301) (xy 292.087702 -267.569931)
			(xy 292.13565 -267.545279) (xy 292.186677 -267.527871) (xy 292.239695 -267.518078) (xy 292.293574 -267.516109)
			(xy 292.347165 -267.522006) (xy 292.399326 -267.535642) (xy 292.448946 -267.556729) (xy 292.494967 -267.584815)
			(xy 292.536409 -267.619303) (xy 292.572387 -267.659457) (xy 292.602135 -267.704421) (xy 292.62502 -267.753238)
			(xy 292.640552 -267.804867) (xy 292.648402 -267.858207) (xy 292.648894 -267.885164) (xy 292.648402 -267.912121)
			(xy 292.640552 -267.965461) (xy 292.62502 -268.01709) (xy 292.602135 -268.065907) (xy 292.572387 -268.110871)
			(xy 292.536409 -268.151025) (xy 292.494967 -268.185513) (xy 292.448946 -268.213599) (xy 292.399326 -268.234686)
			(xy 292.347165 -268.248322) (xy 292.293574 -268.254219) (xy 292.239695 -268.25225) (xy 292.186677 -268.242457)
			(xy 292.13565 -268.225049) (xy 292.087702 -268.200397) (xy 292.043854 -268.169027) (xy 292.005041 -268.131606)
			(xy 291.972089 -268.088933) (xy 291.945703 -268.041916) (xy 291.926443 -267.991559) (xy 291.91472 -267.938935)
			(xy 291.910785 -267.885164) (xy 285.10484 -267.885164) (xy 285.104348 -267.912121) (xy 285.096498 -267.965461)
			(xy 285.080966 -268.01709) (xy 285.058081 -268.065907) (xy 285.028333 -268.110871) (xy 284.992355 -268.151025)
			(xy 284.950913 -268.185513) (xy 284.904892 -268.213599) (xy 284.855272 -268.234686) (xy 284.803111 -268.248322)
			(xy 284.74952 -268.254219) (xy 284.695641 -268.25225) (xy 284.642623 -268.242457) (xy 284.591596 -268.225049)
			(xy 284.543648 -268.200397) (xy 284.4998 -268.169027) (xy 284.460987 -268.131606) (xy 284.428035 -268.088933)
			(xy 284.401649 -268.041916) (xy 284.382389 -267.991559) (xy 284.370666 -267.938935) (xy 284.366731 -267.885164)
			(xy 277.56104 -267.885164) (xy 277.560548 -267.912121) (xy 277.552698 -267.965461) (xy 277.537166 -268.01709)
			(xy 277.514281 -268.065907) (xy 277.484533 -268.110871) (xy 277.448555 -268.151025) (xy 277.407113 -268.185513)
			(xy 277.361092 -268.213599) (xy 277.311472 -268.234686) (xy 277.259311 -268.248322) (xy 277.20572 -268.254219)
			(xy 277.151841 -268.25225) (xy 277.098823 -268.242457) (xy 277.047796 -268.225049) (xy 276.999848 -268.200397)
			(xy 276.956 -268.169027) (xy 276.917187 -268.131606) (xy 276.884235 -268.088933) (xy 276.857849 -268.041916)
			(xy 276.838589 -267.991559) (xy 276.826866 -267.938935) (xy 276.822931 -267.885164) (xy 270.016986 -267.885164)
			(xy 270.016494 -267.912121) (xy 270.008644 -267.965461) (xy 269.993112 -268.01709) (xy 269.970227 -268.065907)
			(xy 269.940479 -268.110871) (xy 269.904501 -268.151025) (xy 269.863059 -268.185513) (xy 269.817038 -268.213599)
			(xy 269.767418 -268.234686) (xy 269.715257 -268.248322) (xy 269.661666 -268.254219) (xy 269.607787 -268.25225)
			(xy 269.554769 -268.242457) (xy 269.503742 -268.225049) (xy 269.455794 -268.200397) (xy 269.411946 -268.169027)
			(xy 269.373133 -268.131606) (xy 269.340181 -268.088933) (xy 269.313795 -268.041916) (xy 269.294535 -267.991559)
			(xy 269.282812 -267.938935) (xy 269.278877 -267.885164) (xy 264.143998 -267.885164) (xy 264.143998 -268.735048)
			(xy 265.178809 -268.735048) (xy 265.182744 -268.681277) (xy 265.194467 -268.628653) (xy 265.213727 -268.578296)
			(xy 265.240113 -268.531279) (xy 265.273065 -268.488606) (xy 265.311878 -268.451185) (xy 265.355726 -268.419815)
			(xy 265.403674 -268.395163) (xy 265.454701 -268.377755) (xy 265.507719 -268.367962) (xy 265.561598 -268.365993)
			(xy 265.615189 -268.37189) (xy 265.66735 -268.385526) (xy 265.71697 -268.406613) (xy 265.762991 -268.434699)
			(xy 265.804433 -268.469187) (xy 265.840411 -268.509341) (xy 265.870159 -268.554305) (xy 265.893044 -268.603122)
			(xy 265.908576 -268.654751) (xy 265.916426 -268.708091) (xy 265.916918 -268.735048) (xy 272.722863 -268.735048)
			(xy 272.726798 -268.681277) (xy 272.738521 -268.628653) (xy 272.757781 -268.578296) (xy 272.784167 -268.531279)
			(xy 272.817119 -268.488606) (xy 272.855932 -268.451185) (xy 272.89978 -268.419815) (xy 272.947728 -268.395163)
			(xy 272.998755 -268.377755) (xy 273.051773 -268.367962) (xy 273.105652 -268.365993) (xy 273.159243 -268.37189)
			(xy 273.211404 -268.385526) (xy 273.261024 -268.406613) (xy 273.307045 -268.434699) (xy 273.348487 -268.469187)
			(xy 273.384465 -268.509341) (xy 273.414213 -268.554305) (xy 273.437098 -268.603122) (xy 273.45263 -268.654751)
			(xy 273.46048 -268.708091) (xy 273.460972 -268.735048) (xy 280.266663 -268.735048) (xy 280.270598 -268.681277)
			(xy 280.282321 -268.628653) (xy 280.301581 -268.578296) (xy 280.327967 -268.531279) (xy 280.360919 -268.488606)
			(xy 280.399732 -268.451185) (xy 280.44358 -268.419815) (xy 280.491528 -268.395163) (xy 280.542555 -268.377755)
			(xy 280.595573 -268.367962) (xy 280.649452 -268.365993) (xy 280.703043 -268.37189) (xy 280.755204 -268.385526)
			(xy 280.804824 -268.406613) (xy 280.850845 -268.434699) (xy 280.892287 -268.469187) (xy 280.928265 -268.509341)
			(xy 280.958013 -268.554305) (xy 280.980898 -268.603122) (xy 280.99643 -268.654751) (xy 281.00428 -268.708091)
			(xy 281.004772 -268.735048) (xy 287.810717 -268.735048) (xy 287.814652 -268.681277) (xy 287.826375 -268.628653)
			(xy 287.845635 -268.578296) (xy 287.872021 -268.531279) (xy 287.904973 -268.488606) (xy 287.943786 -268.451185)
			(xy 287.987634 -268.419815) (xy 288.035582 -268.395163) (xy 288.086609 -268.377755) (xy 288.139627 -268.367962)
			(xy 288.193506 -268.365993) (xy 288.247097 -268.37189) (xy 288.299258 -268.385526) (xy 288.348878 -268.406613)
			(xy 288.394899 -268.434699) (xy 288.436341 -268.469187) (xy 288.472319 -268.509341) (xy 288.502067 -268.554305)
			(xy 288.524952 -268.603122) (xy 288.540484 -268.654751) (xy 288.548334 -268.708091) (xy 288.548826 -268.735048)
			(xy 288.548334 -268.762005) (xy 288.540484 -268.815345) (xy 288.524952 -268.866974) (xy 288.502067 -268.915791)
			(xy 288.472319 -268.960755) (xy 288.436341 -269.000909) (xy 288.394899 -269.035397) (xy 288.348878 -269.063483)
			(xy 288.299258 -269.08457) (xy 288.247097 -269.098206) (xy 288.193506 -269.104103) (xy 288.139627 -269.102134)
			(xy 288.086609 -269.092341) (xy 288.035582 -269.074933) (xy 287.987634 -269.050281) (xy 287.943786 -269.018911)
			(xy 287.904973 -268.98149) (xy 287.872021 -268.938817) (xy 287.845635 -268.8918) (xy 287.826375 -268.841443)
			(xy 287.814652 -268.788819) (xy 287.810717 -268.735048) (xy 281.004772 -268.735048) (xy 281.00428 -268.762005)
			(xy 280.99643 -268.815345) (xy 280.980898 -268.866974) (xy 280.958013 -268.915791) (xy 280.928265 -268.960755)
			(xy 280.892287 -269.000909) (xy 280.850845 -269.035397) (xy 280.804824 -269.063483) (xy 280.755204 -269.08457)
			(xy 280.703043 -269.098206) (xy 280.649452 -269.104103) (xy 280.595573 -269.102134) (xy 280.542555 -269.092341)
			(xy 280.491528 -269.074933) (xy 280.44358 -269.050281) (xy 280.399732 -269.018911) (xy 280.360919 -268.98149)
			(xy 280.327967 -268.938817) (xy 280.301581 -268.8918) (xy 280.282321 -268.841443) (xy 280.270598 -268.788819)
			(xy 280.266663 -268.735048) (xy 273.460972 -268.735048) (xy 273.46048 -268.762005) (xy 273.45263 -268.815345)
			(xy 273.437098 -268.866974) (xy 273.414213 -268.915791) (xy 273.384465 -268.960755) (xy 273.348487 -269.000909)
			(xy 273.307045 -269.035397) (xy 273.261024 -269.063483) (xy 273.211404 -269.08457) (xy 273.159243 -269.098206)
			(xy 273.105652 -269.104103) (xy 273.051773 -269.102134) (xy 272.998755 -269.092341) (xy 272.947728 -269.074933)
			(xy 272.89978 -269.050281) (xy 272.855932 -269.018911) (xy 272.817119 -268.98149) (xy 272.784167 -268.938817)
			(xy 272.757781 -268.8918) (xy 272.738521 -268.841443) (xy 272.726798 -268.788819) (xy 272.722863 -268.735048)
			(xy 265.916918 -268.735048) (xy 265.916426 -268.762005) (xy 265.908576 -268.815345) (xy 265.893044 -268.866974)
			(xy 265.870159 -268.915791) (xy 265.840411 -268.960755) (xy 265.804433 -269.000909) (xy 265.762991 -269.035397)
			(xy 265.71697 -269.063483) (xy 265.66735 -269.08457) (xy 265.615189 -269.098206) (xy 265.561598 -269.104103)
			(xy 265.507719 -269.102134) (xy 265.454701 -269.092341) (xy 265.403674 -269.074933) (xy 265.355726 -269.050281)
			(xy 265.311878 -269.018911) (xy 265.273065 -268.98149) (xy 265.240113 -268.938817) (xy 265.213727 -268.8918)
			(xy 265.194467 -268.841443) (xy 265.182744 -268.788819) (xy 265.178809 -268.735048) (xy 264.143998 -268.735048)
			(xy 264.143998 -269.585186) (xy 269.278877 -269.585186) (xy 269.282812 -269.531415) (xy 269.294535 -269.478791)
			(xy 269.313795 -269.428434) (xy 269.340181 -269.381417) (xy 269.373133 -269.338744) (xy 269.411946 -269.301323)
			(xy 269.455794 -269.269953) (xy 269.503742 -269.245301) (xy 269.554769 -269.227893) (xy 269.607787 -269.2181)
			(xy 269.661666 -269.216131) (xy 269.715257 -269.222028) (xy 269.767418 -269.235664) (xy 269.817038 -269.256751)
			(xy 269.863059 -269.284837) (xy 269.904501 -269.319325) (xy 269.940479 -269.359479) (xy 269.970227 -269.404443)
			(xy 269.993112 -269.45326) (xy 270.008644 -269.504889) (xy 270.016494 -269.558229) (xy 270.016986 -269.585186)
			(xy 276.822931 -269.585186) (xy 276.826866 -269.531415) (xy 276.838589 -269.478791) (xy 276.857849 -269.428434)
			(xy 276.884235 -269.381417) (xy 276.917187 -269.338744) (xy 276.956 -269.301323) (xy 276.999848 -269.269953)
			(xy 277.047796 -269.245301) (xy 277.098823 -269.227893) (xy 277.151841 -269.2181) (xy 277.20572 -269.216131)
			(xy 277.259311 -269.222028) (xy 277.311472 -269.235664) (xy 277.361092 -269.256751) (xy 277.407113 -269.284837)
			(xy 277.448555 -269.319325) (xy 277.484533 -269.359479) (xy 277.514281 -269.404443) (xy 277.537166 -269.45326)
			(xy 277.552698 -269.504889) (xy 277.560548 -269.558229) (xy 277.56104 -269.585186) (xy 284.366731 -269.585186)
			(xy 284.370666 -269.531415) (xy 284.382389 -269.478791) (xy 284.401649 -269.428434) (xy 284.428035 -269.381417)
			(xy 284.460987 -269.338744) (xy 284.4998 -269.301323) (xy 284.543648 -269.269953) (xy 284.591596 -269.245301)
			(xy 284.642623 -269.227893) (xy 284.695641 -269.2181) (xy 284.74952 -269.216131) (xy 284.803111 -269.222028)
			(xy 284.855272 -269.235664) (xy 284.904892 -269.256751) (xy 284.950913 -269.284837) (xy 284.992355 -269.319325)
			(xy 285.028333 -269.359479) (xy 285.058081 -269.404443) (xy 285.080966 -269.45326) (xy 285.096498 -269.504889)
			(xy 285.104348 -269.558229) (xy 285.10484 -269.585186) (xy 291.910785 -269.585186) (xy 291.91472 -269.531415)
			(xy 291.926443 -269.478791) (xy 291.945703 -269.428434) (xy 291.972089 -269.381417) (xy 292.005041 -269.338744)
			(xy 292.043854 -269.301323) (xy 292.087702 -269.269953) (xy 292.13565 -269.245301) (xy 292.186677 -269.227893)
			(xy 292.239695 -269.2181) (xy 292.293574 -269.216131) (xy 292.347165 -269.222028) (xy 292.399326 -269.235664)
			(xy 292.448946 -269.256751) (xy 292.494967 -269.284837) (xy 292.536409 -269.319325) (xy 292.572387 -269.359479)
			(xy 292.602135 -269.404443) (xy 292.62502 -269.45326) (xy 292.640552 -269.504889) (xy 292.648402 -269.558229)
			(xy 292.648894 -269.585186) (xy 292.648402 -269.612143) (xy 292.640552 -269.665483) (xy 292.62502 -269.717112)
			(xy 292.602135 -269.765929) (xy 292.572387 -269.810893) (xy 292.536409 -269.851047) (xy 292.494967 -269.885535)
			(xy 292.448946 -269.913621) (xy 292.399326 -269.934708) (xy 292.347165 -269.948344) (xy 292.293574 -269.954241)
			(xy 292.239695 -269.952272) (xy 292.186677 -269.942479) (xy 292.13565 -269.925071) (xy 292.087702 -269.900419)
			(xy 292.043854 -269.869049) (xy 292.005041 -269.831628) (xy 291.972089 -269.788955) (xy 291.945703 -269.741938)
			(xy 291.926443 -269.691581) (xy 291.91472 -269.638957) (xy 291.910785 -269.585186) (xy 285.10484 -269.585186)
			(xy 285.104348 -269.612143) (xy 285.096498 -269.665483) (xy 285.080966 -269.717112) (xy 285.058081 -269.765929)
			(xy 285.028333 -269.810893) (xy 284.992355 -269.851047) (xy 284.950913 -269.885535) (xy 284.904892 -269.913621)
			(xy 284.855272 -269.934708) (xy 284.803111 -269.948344) (xy 284.74952 -269.954241) (xy 284.695641 -269.952272)
			(xy 284.642623 -269.942479) (xy 284.591596 -269.925071) (xy 284.543648 -269.900419) (xy 284.4998 -269.869049)
			(xy 284.460987 -269.831628) (xy 284.428035 -269.788955) (xy 284.401649 -269.741938) (xy 284.382389 -269.691581)
			(xy 284.370666 -269.638957) (xy 284.366731 -269.585186) (xy 277.56104 -269.585186) (xy 277.560548 -269.612143)
			(xy 277.552698 -269.665483) (xy 277.537166 -269.717112) (xy 277.514281 -269.765929) (xy 277.484533 -269.810893)
			(xy 277.448555 -269.851047) (xy 277.407113 -269.885535) (xy 277.361092 -269.913621) (xy 277.311472 -269.934708)
			(xy 277.259311 -269.948344) (xy 277.20572 -269.954241) (xy 277.151841 -269.952272) (xy 277.098823 -269.942479)
			(xy 277.047796 -269.925071) (xy 276.999848 -269.900419) (xy 276.956 -269.869049) (xy 276.917187 -269.831628)
			(xy 276.884235 -269.788955) (xy 276.857849 -269.741938) (xy 276.838589 -269.691581) (xy 276.826866 -269.638957)
			(xy 276.822931 -269.585186) (xy 270.016986 -269.585186) (xy 270.016494 -269.612143) (xy 270.008644 -269.665483)
			(xy 269.993112 -269.717112) (xy 269.970227 -269.765929) (xy 269.940479 -269.810893) (xy 269.904501 -269.851047)
			(xy 269.863059 -269.885535) (xy 269.817038 -269.913621) (xy 269.767418 -269.934708) (xy 269.715257 -269.948344)
			(xy 269.661666 -269.954241) (xy 269.607787 -269.952272) (xy 269.554769 -269.942479) (xy 269.503742 -269.925071)
			(xy 269.455794 -269.900419) (xy 269.411946 -269.869049) (xy 269.373133 -269.831628) (xy 269.340181 -269.788955)
			(xy 269.313795 -269.741938) (xy 269.294535 -269.691581) (xy 269.282812 -269.638957) (xy 269.278877 -269.585186)
			(xy 264.143998 -269.585186) (xy 264.143998 -270.43507) (xy 265.178809 -270.43507) (xy 265.182744 -270.381299)
			(xy 265.194467 -270.328675) (xy 265.213727 -270.278318) (xy 265.240113 -270.231301) (xy 265.273065 -270.188628)
			(xy 265.311878 -270.151207) (xy 265.355726 -270.119837) (xy 265.403674 -270.095185) (xy 265.454701 -270.077777)
			(xy 265.507719 -270.067984) (xy 265.561598 -270.066015) (xy 265.615189 -270.071912) (xy 265.66735 -270.085548)
			(xy 265.71697 -270.106635) (xy 265.762991 -270.134721) (xy 265.804433 -270.169209) (xy 265.840411 -270.209363)
			(xy 265.870159 -270.254327) (xy 265.893044 -270.303144) (xy 265.908576 -270.354773) (xy 265.916426 -270.408113)
			(xy 265.916918 -270.43507) (xy 269.278877 -270.43507) (xy 269.282812 -270.381299) (xy 269.294535 -270.328675)
			(xy 269.313795 -270.278318) (xy 269.340181 -270.231301) (xy 269.373133 -270.188628) (xy 269.411946 -270.151207)
			(xy 269.455794 -270.119837) (xy 269.503742 -270.095185) (xy 269.554769 -270.077777) (xy 269.607787 -270.067984)
			(xy 269.661666 -270.066015) (xy 269.715257 -270.071912) (xy 269.767418 -270.085548) (xy 269.817038 -270.106635)
			(xy 269.863059 -270.134721) (xy 269.904501 -270.169209) (xy 269.940479 -270.209363) (xy 269.970227 -270.254327)
			(xy 269.993112 -270.303144) (xy 270.008644 -270.354773) (xy 270.016494 -270.408113) (xy 270.016986 -270.43507)
			(xy 272.722863 -270.43507) (xy 272.726798 -270.381299) (xy 272.738521 -270.328675) (xy 272.757781 -270.278318)
			(xy 272.784167 -270.231301) (xy 272.817119 -270.188628) (xy 272.855932 -270.151207) (xy 272.89978 -270.119837)
			(xy 272.947728 -270.095185) (xy 272.998755 -270.077777) (xy 273.051773 -270.067984) (xy 273.105652 -270.066015)
			(xy 273.159243 -270.071912) (xy 273.211404 -270.085548) (xy 273.261024 -270.106635) (xy 273.307045 -270.134721)
			(xy 273.348487 -270.169209) (xy 273.384465 -270.209363) (xy 273.414213 -270.254327) (xy 273.437098 -270.303144)
			(xy 273.45263 -270.354773) (xy 273.46048 -270.408113) (xy 273.460972 -270.43507) (xy 276.822931 -270.43507)
			(xy 276.826866 -270.381299) (xy 276.838589 -270.328675) (xy 276.857849 -270.278318) (xy 276.884235 -270.231301)
			(xy 276.917187 -270.188628) (xy 276.956 -270.151207) (xy 276.999848 -270.119837) (xy 277.047796 -270.095185)
			(xy 277.098823 -270.077777) (xy 277.151841 -270.067984) (xy 277.20572 -270.066015) (xy 277.259311 -270.071912)
			(xy 277.311472 -270.085548) (xy 277.361092 -270.106635) (xy 277.407113 -270.134721) (xy 277.448555 -270.169209)
			(xy 277.484533 -270.209363) (xy 277.514281 -270.254327) (xy 277.537166 -270.303144) (xy 277.552698 -270.354773)
			(xy 277.560548 -270.408113) (xy 277.56104 -270.43507) (xy 280.266663 -270.43507) (xy 280.270598 -270.381299)
			(xy 280.282321 -270.328675) (xy 280.301581 -270.278318) (xy 280.327967 -270.231301) (xy 280.360919 -270.188628)
			(xy 280.399732 -270.151207) (xy 280.44358 -270.119837) (xy 280.491528 -270.095185) (xy 280.542555 -270.077777)
			(xy 280.595573 -270.067984) (xy 280.649452 -270.066015) (xy 280.703043 -270.071912) (xy 280.755204 -270.085548)
			(xy 280.804824 -270.106635) (xy 280.850845 -270.134721) (xy 280.892287 -270.169209) (xy 280.928265 -270.209363)
			(xy 280.958013 -270.254327) (xy 280.980898 -270.303144) (xy 280.99643 -270.354773) (xy 281.00428 -270.408113)
			(xy 281.004772 -270.43507) (xy 284.366731 -270.43507) (xy 284.370666 -270.381299) (xy 284.382389 -270.328675)
			(xy 284.401649 -270.278318) (xy 284.428035 -270.231301) (xy 284.460987 -270.188628) (xy 284.4998 -270.151207)
			(xy 284.543648 -270.119837) (xy 284.591596 -270.095185) (xy 284.642623 -270.077777) (xy 284.695641 -270.067984)
			(xy 284.74952 -270.066015) (xy 284.803111 -270.071912) (xy 284.855272 -270.085548) (xy 284.904892 -270.106635)
			(xy 284.950913 -270.134721) (xy 284.992355 -270.169209) (xy 285.028333 -270.209363) (xy 285.058081 -270.254327)
			(xy 285.080966 -270.303144) (xy 285.096498 -270.354773) (xy 285.104348 -270.408113) (xy 285.10484 -270.43507)
			(xy 287.810717 -270.43507) (xy 287.814652 -270.381299) (xy 287.826375 -270.328675) (xy 287.845635 -270.278318)
			(xy 287.872021 -270.231301) (xy 287.904973 -270.188628) (xy 287.943786 -270.151207) (xy 287.987634 -270.119837)
			(xy 288.035582 -270.095185) (xy 288.086609 -270.077777) (xy 288.139627 -270.067984) (xy 288.193506 -270.066015)
			(xy 288.247097 -270.071912) (xy 288.299258 -270.085548) (xy 288.348878 -270.106635) (xy 288.394899 -270.134721)
			(xy 288.436341 -270.169209) (xy 288.472319 -270.209363) (xy 288.502067 -270.254327) (xy 288.524952 -270.303144)
			(xy 288.540484 -270.354773) (xy 288.548334 -270.408113) (xy 288.548826 -270.43507) (xy 291.910785 -270.43507)
			(xy 291.91472 -270.381299) (xy 291.926443 -270.328675) (xy 291.945703 -270.278318) (xy 291.972089 -270.231301)
			(xy 292.005041 -270.188628) (xy 292.043854 -270.151207) (xy 292.087702 -270.119837) (xy 292.13565 -270.095185)
			(xy 292.186677 -270.077777) (xy 292.239695 -270.067984) (xy 292.293574 -270.066015) (xy 292.347165 -270.071912)
			(xy 292.399326 -270.085548) (xy 292.448946 -270.106635) (xy 292.494967 -270.134721) (xy 292.536409 -270.169209)
			(xy 292.572387 -270.209363) (xy 292.602135 -270.254327) (xy 292.62502 -270.303144) (xy 292.640552 -270.354773)
			(xy 292.648402 -270.408113) (xy 292.648894 -270.43507) (xy 292.648402 -270.462027) (xy 292.640552 -270.515367)
			(xy 292.62502 -270.566996) (xy 292.602135 -270.615813) (xy 292.572387 -270.660777) (xy 292.536409 -270.700931)
			(xy 292.494967 -270.735419) (xy 292.448946 -270.763505) (xy 292.399326 -270.784592) (xy 292.347165 -270.798228)
			(xy 292.293574 -270.804125) (xy 292.239695 -270.802156) (xy 292.186677 -270.792363) (xy 292.13565 -270.774955)
			(xy 292.087702 -270.750303) (xy 292.043854 -270.718933) (xy 292.005041 -270.681512) (xy 291.972089 -270.638839)
			(xy 291.945703 -270.591822) (xy 291.926443 -270.541465) (xy 291.91472 -270.488841) (xy 291.910785 -270.43507)
			(xy 288.548826 -270.43507) (xy 288.548334 -270.462027) (xy 288.540484 -270.515367) (xy 288.524952 -270.566996)
			(xy 288.502067 -270.615813) (xy 288.472319 -270.660777) (xy 288.436341 -270.700931) (xy 288.394899 -270.735419)
			(xy 288.348878 -270.763505) (xy 288.299258 -270.784592) (xy 288.247097 -270.798228) (xy 288.193506 -270.804125)
			(xy 288.139627 -270.802156) (xy 288.086609 -270.792363) (xy 288.035582 -270.774955) (xy 287.987634 -270.750303)
			(xy 287.943786 -270.718933) (xy 287.904973 -270.681512) (xy 287.872021 -270.638839) (xy 287.845635 -270.591822)
			(xy 287.826375 -270.541465) (xy 287.814652 -270.488841) (xy 287.810717 -270.43507) (xy 285.10484 -270.43507)
			(xy 285.104348 -270.462027) (xy 285.096498 -270.515367) (xy 285.080966 -270.566996) (xy 285.058081 -270.615813)
			(xy 285.028333 -270.660777) (xy 284.992355 -270.700931) (xy 284.950913 -270.735419) (xy 284.904892 -270.763505)
			(xy 284.855272 -270.784592) (xy 284.803111 -270.798228) (xy 284.74952 -270.804125) (xy 284.695641 -270.802156)
			(xy 284.642623 -270.792363) (xy 284.591596 -270.774955) (xy 284.543648 -270.750303) (xy 284.4998 -270.718933)
			(xy 284.460987 -270.681512) (xy 284.428035 -270.638839) (xy 284.401649 -270.591822) (xy 284.382389 -270.541465)
			(xy 284.370666 -270.488841) (xy 284.366731 -270.43507) (xy 281.004772 -270.43507) (xy 281.00428 -270.462027)
			(xy 280.99643 -270.515367) (xy 280.980898 -270.566996) (xy 280.958013 -270.615813) (xy 280.928265 -270.660777)
			(xy 280.892287 -270.700931) (xy 280.850845 -270.735419) (xy 280.804824 -270.763505) (xy 280.755204 -270.784592)
			(xy 280.703043 -270.798228) (xy 280.649452 -270.804125) (xy 280.595573 -270.802156) (xy 280.542555 -270.792363)
			(xy 280.491528 -270.774955) (xy 280.44358 -270.750303) (xy 280.399732 -270.718933) (xy 280.360919 -270.681512)
			(xy 280.327967 -270.638839) (xy 280.301581 -270.591822) (xy 280.282321 -270.541465) (xy 280.270598 -270.488841)
			(xy 280.266663 -270.43507) (xy 277.56104 -270.43507) (xy 277.560548 -270.462027) (xy 277.552698 -270.515367)
			(xy 277.537166 -270.566996) (xy 277.514281 -270.615813) (xy 277.484533 -270.660777) (xy 277.448555 -270.700931)
			(xy 277.407113 -270.735419) (xy 277.361092 -270.763505) (xy 277.311472 -270.784592) (xy 277.259311 -270.798228)
			(xy 277.20572 -270.804125) (xy 277.151841 -270.802156) (xy 277.098823 -270.792363) (xy 277.047796 -270.774955)
			(xy 276.999848 -270.750303) (xy 276.956 -270.718933) (xy 276.917187 -270.681512) (xy 276.884235 -270.638839)
			(xy 276.857849 -270.591822) (xy 276.838589 -270.541465) (xy 276.826866 -270.488841) (xy 276.822931 -270.43507)
			(xy 273.460972 -270.43507) (xy 273.46048 -270.462027) (xy 273.45263 -270.515367) (xy 273.437098 -270.566996)
			(xy 273.414213 -270.615813) (xy 273.384465 -270.660777) (xy 273.348487 -270.700931) (xy 273.307045 -270.735419)
			(xy 273.261024 -270.763505) (xy 273.211404 -270.784592) (xy 273.159243 -270.798228) (xy 273.105652 -270.804125)
			(xy 273.051773 -270.802156) (xy 272.998755 -270.792363) (xy 272.947728 -270.774955) (xy 272.89978 -270.750303)
			(xy 272.855932 -270.718933) (xy 272.817119 -270.681512) (xy 272.784167 -270.638839) (xy 272.757781 -270.591822)
			(xy 272.738521 -270.541465) (xy 272.726798 -270.488841) (xy 272.722863 -270.43507) (xy 270.016986 -270.43507)
			(xy 270.016494 -270.462027) (xy 270.008644 -270.515367) (xy 269.993112 -270.566996) (xy 269.970227 -270.615813)
			(xy 269.940479 -270.660777) (xy 269.904501 -270.700931) (xy 269.863059 -270.735419) (xy 269.817038 -270.763505)
			(xy 269.767418 -270.784592) (xy 269.715257 -270.798228) (xy 269.661666 -270.804125) (xy 269.607787 -270.802156)
			(xy 269.554769 -270.792363) (xy 269.503742 -270.774955) (xy 269.455794 -270.750303) (xy 269.411946 -270.718933)
			(xy 269.373133 -270.681512) (xy 269.340181 -270.638839) (xy 269.313795 -270.591822) (xy 269.294535 -270.541465)
			(xy 269.282812 -270.488841) (xy 269.278877 -270.43507) (xy 265.916918 -270.43507) (xy 265.916426 -270.462027)
			(xy 265.908576 -270.515367) (xy 265.893044 -270.566996) (xy 265.870159 -270.615813) (xy 265.840411 -270.660777)
			(xy 265.804433 -270.700931) (xy 265.762991 -270.735419) (xy 265.71697 -270.763505) (xy 265.66735 -270.784592)
			(xy 265.615189 -270.798228) (xy 265.561598 -270.804125) (xy 265.507719 -270.802156) (xy 265.454701 -270.792363)
			(xy 265.403674 -270.774955) (xy 265.355726 -270.750303) (xy 265.311878 -270.718933) (xy 265.273065 -270.681512)
			(xy 265.240113 -270.638839) (xy 265.213727 -270.591822) (xy 265.194467 -270.541465) (xy 265.182744 -270.488841)
			(xy 265.178809 -270.43507) (xy 264.143998 -270.43507) (xy 264.143998 -271.284954) (xy 265.178809 -271.284954)
			(xy 265.182744 -271.231183) (xy 265.194467 -271.178559) (xy 265.213727 -271.128202) (xy 265.240113 -271.081185)
			(xy 265.273065 -271.038512) (xy 265.311878 -271.001091) (xy 265.355726 -270.969721) (xy 265.403674 -270.945069)
			(xy 265.454701 -270.927661) (xy 265.507719 -270.917868) (xy 265.561598 -270.915899) (xy 265.615189 -270.921796)
			(xy 265.66735 -270.935432) (xy 265.71697 -270.956519) (xy 265.762991 -270.984605) (xy 265.804433 -271.019093)
			(xy 265.840411 -271.059247) (xy 265.870159 -271.104211) (xy 265.893044 -271.153028) (xy 265.908576 -271.204657)
			(xy 265.916426 -271.257997) (xy 265.916918 -271.284954) (xy 272.722863 -271.284954) (xy 272.726798 -271.231183)
			(xy 272.738521 -271.178559) (xy 272.757781 -271.128202) (xy 272.784167 -271.081185) (xy 272.817119 -271.038512)
			(xy 272.855932 -271.001091) (xy 272.89978 -270.969721) (xy 272.947728 -270.945069) (xy 272.998755 -270.927661)
			(xy 273.051773 -270.917868) (xy 273.105652 -270.915899) (xy 273.159243 -270.921796) (xy 273.211404 -270.935432)
			(xy 273.261024 -270.956519) (xy 273.307045 -270.984605) (xy 273.348487 -271.019093) (xy 273.384465 -271.059247)
			(xy 273.414213 -271.104211) (xy 273.437098 -271.153028) (xy 273.45263 -271.204657) (xy 273.46048 -271.257997)
			(xy 273.460972 -271.284954) (xy 280.266663 -271.284954) (xy 280.270598 -271.231183) (xy 280.282321 -271.178559)
			(xy 280.301581 -271.128202) (xy 280.327967 -271.081185) (xy 280.360919 -271.038512) (xy 280.399732 -271.001091)
			(xy 280.44358 -270.969721) (xy 280.491528 -270.945069) (xy 280.542555 -270.927661) (xy 280.595573 -270.917868)
			(xy 280.649452 -270.915899) (xy 280.703043 -270.921796) (xy 280.755204 -270.935432) (xy 280.804824 -270.956519)
			(xy 280.850845 -270.984605) (xy 280.892287 -271.019093) (xy 280.928265 -271.059247) (xy 280.958013 -271.104211)
			(xy 280.980898 -271.153028) (xy 280.99643 -271.204657) (xy 281.00428 -271.257997) (xy 281.004772 -271.284954)
			(xy 287.810717 -271.284954) (xy 287.814652 -271.231183) (xy 287.826375 -271.178559) (xy 287.845635 -271.128202)
			(xy 287.872021 -271.081185) (xy 287.904973 -271.038512) (xy 287.943786 -271.001091) (xy 287.987634 -270.969721)
			(xy 288.035582 -270.945069) (xy 288.086609 -270.927661) (xy 288.139627 -270.917868) (xy 288.193506 -270.915899)
			(xy 288.247097 -270.921796) (xy 288.299258 -270.935432) (xy 288.348878 -270.956519) (xy 288.394899 -270.984605)
			(xy 288.436341 -271.019093) (xy 288.472319 -271.059247) (xy 288.502067 -271.104211) (xy 288.524952 -271.153028)
			(xy 288.540484 -271.204657) (xy 288.548334 -271.257997) (xy 288.548826 -271.284954) (xy 288.548334 -271.311911)
			(xy 288.540484 -271.365251) (xy 288.524952 -271.41688) (xy 288.502067 -271.465697) (xy 288.472319 -271.510661)
			(xy 288.436341 -271.550815) (xy 288.394899 -271.585303) (xy 288.348878 -271.613389) (xy 288.299258 -271.634476)
			(xy 288.247097 -271.648112) (xy 288.193506 -271.654009) (xy 288.139627 -271.65204) (xy 288.086609 -271.642247)
			(xy 288.035582 -271.624839) (xy 287.987634 -271.600187) (xy 287.943786 -271.568817) (xy 287.904973 -271.531396)
			(xy 287.872021 -271.488723) (xy 287.845635 -271.441706) (xy 287.826375 -271.391349) (xy 287.814652 -271.338725)
			(xy 287.810717 -271.284954) (xy 281.004772 -271.284954) (xy 281.00428 -271.311911) (xy 280.99643 -271.365251)
			(xy 280.980898 -271.41688) (xy 280.958013 -271.465697) (xy 280.928265 -271.510661) (xy 280.892287 -271.550815)
			(xy 280.850845 -271.585303) (xy 280.804824 -271.613389) (xy 280.755204 -271.634476) (xy 280.703043 -271.648112)
			(xy 280.649452 -271.654009) (xy 280.595573 -271.65204) (xy 280.542555 -271.642247) (xy 280.491528 -271.624839)
			(xy 280.44358 -271.600187) (xy 280.399732 -271.568817) (xy 280.360919 -271.531396) (xy 280.327967 -271.488723)
			(xy 280.301581 -271.441706) (xy 280.282321 -271.391349) (xy 280.270598 -271.338725) (xy 280.266663 -271.284954)
			(xy 273.460972 -271.284954) (xy 273.46048 -271.311911) (xy 273.45263 -271.365251) (xy 273.437098 -271.41688)
			(xy 273.414213 -271.465697) (xy 273.384465 -271.510661) (xy 273.348487 -271.550815) (xy 273.307045 -271.585303)
			(xy 273.261024 -271.613389) (xy 273.211404 -271.634476) (xy 273.159243 -271.648112) (xy 273.105652 -271.654009)
			(xy 273.051773 -271.65204) (xy 272.998755 -271.642247) (xy 272.947728 -271.624839) (xy 272.89978 -271.600187)
			(xy 272.855932 -271.568817) (xy 272.817119 -271.531396) (xy 272.784167 -271.488723) (xy 272.757781 -271.441706)
			(xy 272.738521 -271.391349) (xy 272.726798 -271.338725) (xy 272.722863 -271.284954) (xy 265.916918 -271.284954)
			(xy 265.916426 -271.311911) (xy 265.908576 -271.365251) (xy 265.893044 -271.41688) (xy 265.870159 -271.465697)
			(xy 265.840411 -271.510661) (xy 265.804433 -271.550815) (xy 265.762991 -271.585303) (xy 265.71697 -271.613389)
			(xy 265.66735 -271.634476) (xy 265.615189 -271.648112) (xy 265.561598 -271.654009) (xy 265.507719 -271.65204)
			(xy 265.454701 -271.642247) (xy 265.403674 -271.624839) (xy 265.355726 -271.600187) (xy 265.311878 -271.568817)
			(xy 265.273065 -271.531396) (xy 265.240113 -271.488723) (xy 265.213727 -271.441706) (xy 265.194467 -271.391349)
			(xy 265.182744 -271.338725) (xy 265.178809 -271.284954) (xy 264.143998 -271.284954) (xy 264.143998 -272.135092)
			(xy 269.278877 -272.135092) (xy 269.282812 -272.081321) (xy 269.294535 -272.028697) (xy 269.313795 -271.97834)
			(xy 269.340181 -271.931323) (xy 269.373133 -271.88865) (xy 269.411946 -271.851229) (xy 269.455794 -271.819859)
			(xy 269.503742 -271.795207) (xy 269.554769 -271.777799) (xy 269.607787 -271.768006) (xy 269.661666 -271.766037)
			(xy 269.715257 -271.771934) (xy 269.767418 -271.78557) (xy 269.817038 -271.806657) (xy 269.863059 -271.834743)
			(xy 269.904501 -271.869231) (xy 269.940479 -271.909385) (xy 269.970227 -271.954349) (xy 269.993112 -272.003166)
			(xy 270.008644 -272.054795) (xy 270.016494 -272.108135) (xy 270.016986 -272.135092) (xy 276.822931 -272.135092)
			(xy 276.826866 -272.081321) (xy 276.838589 -272.028697) (xy 276.857849 -271.97834) (xy 276.884235 -271.931323)
			(xy 276.917187 -271.88865) (xy 276.956 -271.851229) (xy 276.999848 -271.819859) (xy 277.047796 -271.795207)
			(xy 277.098823 -271.777799) (xy 277.151841 -271.768006) (xy 277.20572 -271.766037) (xy 277.259311 -271.771934)
			(xy 277.311472 -271.78557) (xy 277.361092 -271.806657) (xy 277.407113 -271.834743) (xy 277.448555 -271.869231)
			(xy 277.484533 -271.909385) (xy 277.514281 -271.954349) (xy 277.537166 -272.003166) (xy 277.552698 -272.054795)
			(xy 277.560548 -272.108135) (xy 277.56104 -272.135092) (xy 284.366731 -272.135092) (xy 284.370666 -272.081321)
			(xy 284.382389 -272.028697) (xy 284.401649 -271.97834) (xy 284.428035 -271.931323) (xy 284.460987 -271.88865)
			(xy 284.4998 -271.851229) (xy 284.543648 -271.819859) (xy 284.591596 -271.795207) (xy 284.642623 -271.777799)
			(xy 284.695641 -271.768006) (xy 284.74952 -271.766037) (xy 284.803111 -271.771934) (xy 284.855272 -271.78557)
			(xy 284.904892 -271.806657) (xy 284.950913 -271.834743) (xy 284.992355 -271.869231) (xy 285.028333 -271.909385)
			(xy 285.058081 -271.954349) (xy 285.080966 -272.003166) (xy 285.096498 -272.054795) (xy 285.104348 -272.108135)
			(xy 285.10484 -272.135092) (xy 291.910785 -272.135092) (xy 291.91472 -272.081321) (xy 291.926443 -272.028697)
			(xy 291.945703 -271.97834) (xy 291.972089 -271.931323) (xy 292.005041 -271.88865) (xy 292.043854 -271.851229)
			(xy 292.087702 -271.819859) (xy 292.13565 -271.795207) (xy 292.186677 -271.777799) (xy 292.239695 -271.768006)
			(xy 292.293574 -271.766037) (xy 292.347165 -271.771934) (xy 292.399326 -271.78557) (xy 292.448946 -271.806657)
			(xy 292.494967 -271.834743) (xy 292.536409 -271.869231) (xy 292.572387 -271.909385) (xy 292.602135 -271.954349)
			(xy 292.62502 -272.003166) (xy 292.640552 -272.054795) (xy 292.648402 -272.108135) (xy 292.648894 -272.135092)
			(xy 292.648402 -272.162049) (xy 292.640552 -272.215389) (xy 292.62502 -272.267018) (xy 292.602135 -272.315835)
			(xy 292.572387 -272.360799) (xy 292.536409 -272.400953) (xy 292.494967 -272.435441) (xy 292.448946 -272.463527)
			(xy 292.399326 -272.484614) (xy 292.347165 -272.49825) (xy 292.293574 -272.504147) (xy 292.239695 -272.502178)
			(xy 292.186677 -272.492385) (xy 292.13565 -272.474977) (xy 292.087702 -272.450325) (xy 292.043854 -272.418955)
			(xy 292.005041 -272.381534) (xy 291.972089 -272.338861) (xy 291.945703 -272.291844) (xy 291.926443 -272.241487)
			(xy 291.91472 -272.188863) (xy 291.910785 -272.135092) (xy 285.10484 -272.135092) (xy 285.104348 -272.162049)
			(xy 285.096498 -272.215389) (xy 285.080966 -272.267018) (xy 285.058081 -272.315835) (xy 285.028333 -272.360799)
			(xy 284.992355 -272.400953) (xy 284.950913 -272.435441) (xy 284.904892 -272.463527) (xy 284.855272 -272.484614)
			(xy 284.803111 -272.49825) (xy 284.74952 -272.504147) (xy 284.695641 -272.502178) (xy 284.642623 -272.492385)
			(xy 284.591596 -272.474977) (xy 284.543648 -272.450325) (xy 284.4998 -272.418955) (xy 284.460987 -272.381534)
			(xy 284.428035 -272.338861) (xy 284.401649 -272.291844) (xy 284.382389 -272.241487) (xy 284.370666 -272.188863)
			(xy 284.366731 -272.135092) (xy 277.56104 -272.135092) (xy 277.560548 -272.162049) (xy 277.552698 -272.215389)
			(xy 277.537166 -272.267018) (xy 277.514281 -272.315835) (xy 277.484533 -272.360799) (xy 277.448555 -272.400953)
			(xy 277.407113 -272.435441) (xy 277.361092 -272.463527) (xy 277.311472 -272.484614) (xy 277.259311 -272.49825)
			(xy 277.20572 -272.504147) (xy 277.151841 -272.502178) (xy 277.098823 -272.492385) (xy 277.047796 -272.474977)
			(xy 276.999848 -272.450325) (xy 276.956 -272.418955) (xy 276.917187 -272.381534) (xy 276.884235 -272.338861)
			(xy 276.857849 -272.291844) (xy 276.838589 -272.241487) (xy 276.826866 -272.188863) (xy 276.822931 -272.135092)
			(xy 270.016986 -272.135092) (xy 270.016494 -272.162049) (xy 270.008644 -272.215389) (xy 269.993112 -272.267018)
			(xy 269.970227 -272.315835) (xy 269.940479 -272.360799) (xy 269.904501 -272.400953) (xy 269.863059 -272.435441)
			(xy 269.817038 -272.463527) (xy 269.767418 -272.484614) (xy 269.715257 -272.49825) (xy 269.661666 -272.504147)
			(xy 269.607787 -272.502178) (xy 269.554769 -272.492385) (xy 269.503742 -272.474977) (xy 269.455794 -272.450325)
			(xy 269.411946 -272.418955) (xy 269.373133 -272.381534) (xy 269.340181 -272.338861) (xy 269.313795 -272.291844)
			(xy 269.294535 -272.241487) (xy 269.282812 -272.188863) (xy 269.278877 -272.135092) (xy 264.143998 -272.135092)
			(xy 264.143998 -272.984976) (xy 265.178809 -272.984976) (xy 265.182744 -272.931205) (xy 265.194467 -272.878581)
			(xy 265.213727 -272.828224) (xy 265.240113 -272.781207) (xy 265.273065 -272.738534) (xy 265.311878 -272.701113)
			(xy 265.355726 -272.669743) (xy 265.403674 -272.645091) (xy 265.454701 -272.627683) (xy 265.507719 -272.61789)
			(xy 265.561598 -272.615921) (xy 265.615189 -272.621818) (xy 265.66735 -272.635454) (xy 265.71697 -272.656541)
			(xy 265.762991 -272.684627) (xy 265.804433 -272.719115) (xy 265.840411 -272.759269) (xy 265.870159 -272.804233)
			(xy 265.893044 -272.85305) (xy 265.908576 -272.904679) (xy 265.916426 -272.958019) (xy 265.916918 -272.984976)
			(xy 272.722863 -272.984976) (xy 272.726798 -272.931205) (xy 272.738521 -272.878581) (xy 272.757781 -272.828224)
			(xy 272.784167 -272.781207) (xy 272.817119 -272.738534) (xy 272.855932 -272.701113) (xy 272.89978 -272.669743)
			(xy 272.947728 -272.645091) (xy 272.998755 -272.627683) (xy 273.051773 -272.61789) (xy 273.105652 -272.615921)
			(xy 273.159243 -272.621818) (xy 273.211404 -272.635454) (xy 273.261024 -272.656541) (xy 273.307045 -272.684627)
			(xy 273.348487 -272.719115) (xy 273.384465 -272.759269) (xy 273.414213 -272.804233) (xy 273.437098 -272.85305)
			(xy 273.45263 -272.904679) (xy 273.46048 -272.958019) (xy 273.460972 -272.984976) (xy 280.266663 -272.984976)
			(xy 280.270598 -272.931205) (xy 280.282321 -272.878581) (xy 280.301581 -272.828224) (xy 280.327967 -272.781207)
			(xy 280.360919 -272.738534) (xy 280.399732 -272.701113) (xy 280.44358 -272.669743) (xy 280.491528 -272.645091)
			(xy 280.542555 -272.627683) (xy 280.595573 -272.61789) (xy 280.649452 -272.615921) (xy 280.703043 -272.621818)
			(xy 280.755204 -272.635454) (xy 280.804824 -272.656541) (xy 280.850845 -272.684627) (xy 280.892287 -272.719115)
			(xy 280.928265 -272.759269) (xy 280.958013 -272.804233) (xy 280.980898 -272.85305) (xy 280.99643 -272.904679)
			(xy 281.00428 -272.958019) (xy 281.004772 -272.984976) (xy 287.810717 -272.984976) (xy 287.814652 -272.931205)
			(xy 287.826375 -272.878581) (xy 287.845635 -272.828224) (xy 287.872021 -272.781207) (xy 287.904973 -272.738534)
			(xy 287.943786 -272.701113) (xy 287.987634 -272.669743) (xy 288.035582 -272.645091) (xy 288.086609 -272.627683)
			(xy 288.139627 -272.61789) (xy 288.193506 -272.615921) (xy 288.247097 -272.621818) (xy 288.299258 -272.635454)
			(xy 288.348878 -272.656541) (xy 288.394899 -272.684627) (xy 288.436341 -272.719115) (xy 288.472319 -272.759269)
			(xy 288.502067 -272.804233) (xy 288.524952 -272.85305) (xy 288.540484 -272.904679) (xy 288.548334 -272.958019)
			(xy 288.548826 -272.984976) (xy 288.548334 -273.011933) (xy 288.540484 -273.065273) (xy 288.524952 -273.116902)
			(xy 288.502067 -273.165719) (xy 288.472319 -273.210683) (xy 288.436341 -273.250837) (xy 288.394899 -273.285325)
			(xy 288.348878 -273.313411) (xy 288.299258 -273.334498) (xy 288.247097 -273.348134) (xy 288.193506 -273.354031)
			(xy 288.139627 -273.352062) (xy 288.086609 -273.342269) (xy 288.035582 -273.324861) (xy 287.987634 -273.300209)
			(xy 287.943786 -273.268839) (xy 287.904973 -273.231418) (xy 287.872021 -273.188745) (xy 287.845635 -273.141728)
			(xy 287.826375 -273.091371) (xy 287.814652 -273.038747) (xy 287.810717 -272.984976) (xy 281.004772 -272.984976)
			(xy 281.00428 -273.011933) (xy 280.99643 -273.065273) (xy 280.980898 -273.116902) (xy 280.958013 -273.165719)
			(xy 280.928265 -273.210683) (xy 280.892287 -273.250837) (xy 280.850845 -273.285325) (xy 280.804824 -273.313411)
			(xy 280.755204 -273.334498) (xy 280.703043 -273.348134) (xy 280.649452 -273.354031) (xy 280.595573 -273.352062)
			(xy 280.542555 -273.342269) (xy 280.491528 -273.324861) (xy 280.44358 -273.300209) (xy 280.399732 -273.268839)
			(xy 280.360919 -273.231418) (xy 280.327967 -273.188745) (xy 280.301581 -273.141728) (xy 280.282321 -273.091371)
			(xy 280.270598 -273.038747) (xy 280.266663 -272.984976) (xy 273.460972 -272.984976) (xy 273.46048 -273.011933)
			(xy 273.45263 -273.065273) (xy 273.437098 -273.116902) (xy 273.414213 -273.165719) (xy 273.384465 -273.210683)
			(xy 273.348487 -273.250837) (xy 273.307045 -273.285325) (xy 273.261024 -273.313411) (xy 273.211404 -273.334498)
			(xy 273.159243 -273.348134) (xy 273.105652 -273.354031) (xy 273.051773 -273.352062) (xy 272.998755 -273.342269)
			(xy 272.947728 -273.324861) (xy 272.89978 -273.300209) (xy 272.855932 -273.268839) (xy 272.817119 -273.231418)
			(xy 272.784167 -273.188745) (xy 272.757781 -273.141728) (xy 272.738521 -273.091371) (xy 272.726798 -273.038747)
			(xy 272.722863 -272.984976) (xy 265.916918 -272.984976) (xy 265.916426 -273.011933) (xy 265.908576 -273.065273)
			(xy 265.893044 -273.116902) (xy 265.870159 -273.165719) (xy 265.840411 -273.210683) (xy 265.804433 -273.250837)
			(xy 265.762991 -273.285325) (xy 265.71697 -273.313411) (xy 265.66735 -273.334498) (xy 265.615189 -273.348134)
			(xy 265.561598 -273.354031) (xy 265.507719 -273.352062) (xy 265.454701 -273.342269) (xy 265.403674 -273.324861)
			(xy 265.355726 -273.300209) (xy 265.311878 -273.268839) (xy 265.273065 -273.231418) (xy 265.240113 -273.188745)
			(xy 265.213727 -273.141728) (xy 265.194467 -273.091371) (xy 265.182744 -273.038747) (xy 265.178809 -272.984976)
			(xy 264.143998 -272.984976) (xy 264.143998 -273.835114) (xy 269.278877 -273.835114) (xy 269.282812 -273.781343)
			(xy 269.294535 -273.728719) (xy 269.313795 -273.678362) (xy 269.340181 -273.631345) (xy 269.373133 -273.588672)
			(xy 269.411946 -273.551251) (xy 269.455794 -273.519881) (xy 269.503742 -273.495229) (xy 269.554769 -273.477821)
			(xy 269.607787 -273.468028) (xy 269.661666 -273.466059) (xy 269.715257 -273.471956) (xy 269.767418 -273.485592)
			(xy 269.817038 -273.506679) (xy 269.863059 -273.534765) (xy 269.904501 -273.569253) (xy 269.940479 -273.609407)
			(xy 269.970227 -273.654371) (xy 269.993112 -273.703188) (xy 270.008644 -273.754817) (xy 270.016494 -273.808157)
			(xy 270.016986 -273.835114) (xy 276.822931 -273.835114) (xy 276.826866 -273.781343) (xy 276.838589 -273.728719)
			(xy 276.857849 -273.678362) (xy 276.884235 -273.631345) (xy 276.917187 -273.588672) (xy 276.956 -273.551251)
			(xy 276.999848 -273.519881) (xy 277.047796 -273.495229) (xy 277.098823 -273.477821) (xy 277.151841 -273.468028)
			(xy 277.20572 -273.466059) (xy 277.259311 -273.471956) (xy 277.311472 -273.485592) (xy 277.361092 -273.506679)
			(xy 277.407113 -273.534765) (xy 277.448555 -273.569253) (xy 277.484533 -273.609407) (xy 277.514281 -273.654371)
			(xy 277.537166 -273.703188) (xy 277.552698 -273.754817) (xy 277.560548 -273.808157) (xy 277.56104 -273.835114)
			(xy 284.366731 -273.835114) (xy 284.370666 -273.781343) (xy 284.382389 -273.728719) (xy 284.401649 -273.678362)
			(xy 284.428035 -273.631345) (xy 284.460987 -273.588672) (xy 284.4998 -273.551251) (xy 284.543648 -273.519881)
			(xy 284.591596 -273.495229) (xy 284.642623 -273.477821) (xy 284.695641 -273.468028) (xy 284.74952 -273.466059)
			(xy 284.803111 -273.471956) (xy 284.855272 -273.485592) (xy 284.904892 -273.506679) (xy 284.950913 -273.534765)
			(xy 284.992355 -273.569253) (xy 285.028333 -273.609407) (xy 285.058081 -273.654371) (xy 285.080966 -273.703188)
			(xy 285.096498 -273.754817) (xy 285.104348 -273.808157) (xy 285.10484 -273.835114) (xy 291.910785 -273.835114)
			(xy 291.91472 -273.781343) (xy 291.926443 -273.728719) (xy 291.945703 -273.678362) (xy 291.972089 -273.631345)
			(xy 292.005041 -273.588672) (xy 292.043854 -273.551251) (xy 292.087702 -273.519881) (xy 292.13565 -273.495229)
			(xy 292.186677 -273.477821) (xy 292.239695 -273.468028) (xy 292.293574 -273.466059) (xy 292.347165 -273.471956)
			(xy 292.399326 -273.485592) (xy 292.448946 -273.506679) (xy 292.494967 -273.534765) (xy 292.536409 -273.569253)
			(xy 292.572387 -273.609407) (xy 292.602135 -273.654371) (xy 292.62502 -273.703188) (xy 292.640552 -273.754817)
			(xy 292.648402 -273.808157) (xy 292.648894 -273.835114) (xy 292.648402 -273.862071) (xy 292.640552 -273.915411)
			(xy 292.62502 -273.96704) (xy 292.602135 -274.015857) (xy 292.572387 -274.060821) (xy 292.536409 -274.100975)
			(xy 292.494967 -274.135463) (xy 292.448946 -274.163549) (xy 292.399326 -274.184636) (xy 292.347165 -274.198272)
			(xy 292.293574 -274.204169) (xy 292.239695 -274.2022) (xy 292.186677 -274.192407) (xy 292.13565 -274.174999)
			(xy 292.087702 -274.150347) (xy 292.043854 -274.118977) (xy 292.005041 -274.081556) (xy 291.972089 -274.038883)
			(xy 291.945703 -273.991866) (xy 291.926443 -273.941509) (xy 291.91472 -273.888885) (xy 291.910785 -273.835114)
			(xy 285.10484 -273.835114) (xy 285.104348 -273.862071) (xy 285.096498 -273.915411) (xy 285.080966 -273.96704)
			(xy 285.058081 -274.015857) (xy 285.028333 -274.060821) (xy 284.992355 -274.100975) (xy 284.950913 -274.135463)
			(xy 284.904892 -274.163549) (xy 284.855272 -274.184636) (xy 284.803111 -274.198272) (xy 284.74952 -274.204169)
			(xy 284.695641 -274.2022) (xy 284.642623 -274.192407) (xy 284.591596 -274.174999) (xy 284.543648 -274.150347)
			(xy 284.4998 -274.118977) (xy 284.460987 -274.081556) (xy 284.428035 -274.038883) (xy 284.401649 -273.991866)
			(xy 284.382389 -273.941509) (xy 284.370666 -273.888885) (xy 284.366731 -273.835114) (xy 277.56104 -273.835114)
			(xy 277.560548 -273.862071) (xy 277.552698 -273.915411) (xy 277.537166 -273.96704) (xy 277.514281 -274.015857)
			(xy 277.484533 -274.060821) (xy 277.448555 -274.100975) (xy 277.407113 -274.135463) (xy 277.361092 -274.163549)
			(xy 277.311472 -274.184636) (xy 277.259311 -274.198272) (xy 277.20572 -274.204169) (xy 277.151841 -274.2022)
			(xy 277.098823 -274.192407) (xy 277.047796 -274.174999) (xy 276.999848 -274.150347) (xy 276.956 -274.118977)
			(xy 276.917187 -274.081556) (xy 276.884235 -274.038883) (xy 276.857849 -273.991866) (xy 276.838589 -273.941509)
			(xy 276.826866 -273.888885) (xy 276.822931 -273.835114) (xy 270.016986 -273.835114) (xy 270.016494 -273.862071)
			(xy 270.008644 -273.915411) (xy 269.993112 -273.96704) (xy 269.970227 -274.015857) (xy 269.940479 -274.060821)
			(xy 269.904501 -274.100975) (xy 269.863059 -274.135463) (xy 269.817038 -274.163549) (xy 269.767418 -274.184636)
			(xy 269.715257 -274.198272) (xy 269.661666 -274.204169) (xy 269.607787 -274.2022) (xy 269.554769 -274.192407)
			(xy 269.503742 -274.174999) (xy 269.455794 -274.150347) (xy 269.411946 -274.118977) (xy 269.373133 -274.081556)
			(xy 269.340181 -274.038883) (xy 269.313795 -273.991866) (xy 269.294535 -273.941509) (xy 269.282812 -273.888885)
			(xy 269.278877 -273.835114) (xy 264.143998 -273.835114) (xy 264.143998 -274.684998) (xy 265.178809 -274.684998)
			(xy 265.182744 -274.631227) (xy 265.194467 -274.578603) (xy 265.213727 -274.528246) (xy 265.240113 -274.481229)
			(xy 265.273065 -274.438556) (xy 265.311878 -274.401135) (xy 265.355726 -274.369765) (xy 265.403674 -274.345113)
			(xy 265.454701 -274.327705) (xy 265.507719 -274.317912) (xy 265.561598 -274.315943) (xy 265.615189 -274.32184)
			(xy 265.66735 -274.335476) (xy 265.71697 -274.356563) (xy 265.762991 -274.384649) (xy 265.804433 -274.419137)
			(xy 265.840411 -274.459291) (xy 265.870159 -274.504255) (xy 265.893044 -274.553072) (xy 265.908576 -274.604701)
			(xy 265.916426 -274.658041) (xy 265.916918 -274.684998) (xy 272.722863 -274.684998) (xy 272.726798 -274.631227)
			(xy 272.738521 -274.578603) (xy 272.757781 -274.528246) (xy 272.784167 -274.481229) (xy 272.817119 -274.438556)
			(xy 272.855932 -274.401135) (xy 272.89978 -274.369765) (xy 272.947728 -274.345113) (xy 272.998755 -274.327705)
			(xy 273.051773 -274.317912) (xy 273.105652 -274.315943) (xy 273.159243 -274.32184) (xy 273.211404 -274.335476)
			(xy 273.261024 -274.356563) (xy 273.307045 -274.384649) (xy 273.348487 -274.419137) (xy 273.384465 -274.459291)
			(xy 273.414213 -274.504255) (xy 273.437098 -274.553072) (xy 273.45263 -274.604701) (xy 273.46048 -274.658041)
			(xy 273.460972 -274.684998) (xy 280.266663 -274.684998) (xy 280.270598 -274.631227) (xy 280.282321 -274.578603)
			(xy 280.301581 -274.528246) (xy 280.327967 -274.481229) (xy 280.360919 -274.438556) (xy 280.399732 -274.401135)
			(xy 280.44358 -274.369765) (xy 280.491528 -274.345113) (xy 280.542555 -274.327705) (xy 280.595573 -274.317912)
			(xy 280.649452 -274.315943) (xy 280.703043 -274.32184) (xy 280.755204 -274.335476) (xy 280.804824 -274.356563)
			(xy 280.850845 -274.384649) (xy 280.892287 -274.419137) (xy 280.928265 -274.459291) (xy 280.958013 -274.504255)
			(xy 280.980898 -274.553072) (xy 280.99643 -274.604701) (xy 281.00428 -274.658041) (xy 281.004772 -274.684998)
			(xy 287.810717 -274.684998) (xy 287.814652 -274.631227) (xy 287.826375 -274.578603) (xy 287.845635 -274.528246)
			(xy 287.872021 -274.481229) (xy 287.904973 -274.438556) (xy 287.943786 -274.401135) (xy 287.987634 -274.369765)
			(xy 288.035582 -274.345113) (xy 288.086609 -274.327705) (xy 288.139627 -274.317912) (xy 288.193506 -274.315943)
			(xy 288.247097 -274.32184) (xy 288.299258 -274.335476) (xy 288.348878 -274.356563) (xy 288.394899 -274.384649)
			(xy 288.436341 -274.419137) (xy 288.472319 -274.459291) (xy 288.502067 -274.504255) (xy 288.524952 -274.553072)
			(xy 288.540484 -274.604701) (xy 288.548334 -274.658041) (xy 288.548826 -274.684998) (xy 288.548334 -274.711955)
			(xy 288.540484 -274.765295) (xy 288.524952 -274.816924) (xy 288.502067 -274.865741) (xy 288.472319 -274.910705)
			(xy 288.436341 -274.950859) (xy 288.394899 -274.985347) (xy 288.348878 -275.013433) (xy 288.299258 -275.03452)
			(xy 288.247097 -275.048156) (xy 288.193506 -275.054053) (xy 288.139627 -275.052084) (xy 288.086609 -275.042291)
			(xy 288.035582 -275.024883) (xy 287.987634 -275.000231) (xy 287.943786 -274.968861) (xy 287.904973 -274.93144)
			(xy 287.872021 -274.888767) (xy 287.845635 -274.84175) (xy 287.826375 -274.791393) (xy 287.814652 -274.738769)
			(xy 287.810717 -274.684998) (xy 281.004772 -274.684998) (xy 281.00428 -274.711955) (xy 280.99643 -274.765295)
			(xy 280.980898 -274.816924) (xy 280.958013 -274.865741) (xy 280.928265 -274.910705) (xy 280.892287 -274.950859)
			(xy 280.850845 -274.985347) (xy 280.804824 -275.013433) (xy 280.755204 -275.03452) (xy 280.703043 -275.048156)
			(xy 280.649452 -275.054053) (xy 280.595573 -275.052084) (xy 280.542555 -275.042291) (xy 280.491528 -275.024883)
			(xy 280.44358 -275.000231) (xy 280.399732 -274.968861) (xy 280.360919 -274.93144) (xy 280.327967 -274.888767)
			(xy 280.301581 -274.84175) (xy 280.282321 -274.791393) (xy 280.270598 -274.738769) (xy 280.266663 -274.684998)
			(xy 273.460972 -274.684998) (xy 273.46048 -274.711955) (xy 273.45263 -274.765295) (xy 273.437098 -274.816924)
			(xy 273.414213 -274.865741) (xy 273.384465 -274.910705) (xy 273.348487 -274.950859) (xy 273.307045 -274.985347)
			(xy 273.261024 -275.013433) (xy 273.211404 -275.03452) (xy 273.159243 -275.048156) (xy 273.105652 -275.054053)
			(xy 273.051773 -275.052084) (xy 272.998755 -275.042291) (xy 272.947728 -275.024883) (xy 272.89978 -275.000231)
			(xy 272.855932 -274.968861) (xy 272.817119 -274.93144) (xy 272.784167 -274.888767) (xy 272.757781 -274.84175)
			(xy 272.738521 -274.791393) (xy 272.726798 -274.738769) (xy 272.722863 -274.684998) (xy 265.916918 -274.684998)
			(xy 265.916426 -274.711955) (xy 265.908576 -274.765295) (xy 265.893044 -274.816924) (xy 265.870159 -274.865741)
			(xy 265.840411 -274.910705) (xy 265.804433 -274.950859) (xy 265.762991 -274.985347) (xy 265.71697 -275.013433)
			(xy 265.66735 -275.03452) (xy 265.615189 -275.048156) (xy 265.561598 -275.054053) (xy 265.507719 -275.052084)
			(xy 265.454701 -275.042291) (xy 265.403674 -275.024883) (xy 265.355726 -275.000231) (xy 265.311878 -274.968861)
			(xy 265.273065 -274.93144) (xy 265.240113 -274.888767) (xy 265.213727 -274.84175) (xy 265.194467 -274.791393)
			(xy 265.182744 -274.738769) (xy 265.178809 -274.684998) (xy 264.143998 -274.684998) (xy 264.143998 -275.535136)
			(xy 269.278877 -275.535136) (xy 269.282812 -275.481365) (xy 269.294535 -275.428741) (xy 269.313795 -275.378384)
			(xy 269.340181 -275.331367) (xy 269.373133 -275.288694) (xy 269.411946 -275.251273) (xy 269.455794 -275.219903)
			(xy 269.503742 -275.195251) (xy 269.554769 -275.177843) (xy 269.607787 -275.16805) (xy 269.661666 -275.166081)
			(xy 269.715257 -275.171978) (xy 269.767418 -275.185614) (xy 269.817038 -275.206701) (xy 269.863059 -275.234787)
			(xy 269.904501 -275.269275) (xy 269.940479 -275.309429) (xy 269.970227 -275.354393) (xy 269.993112 -275.40321)
			(xy 270.008644 -275.454839) (xy 270.016494 -275.508179) (xy 270.016986 -275.535136) (xy 276.822931 -275.535136)
			(xy 276.826866 -275.481365) (xy 276.838589 -275.428741) (xy 276.857849 -275.378384) (xy 276.884235 -275.331367)
			(xy 276.917187 -275.288694) (xy 276.956 -275.251273) (xy 276.999848 -275.219903) (xy 277.047796 -275.195251)
			(xy 277.098823 -275.177843) (xy 277.151841 -275.16805) (xy 277.20572 -275.166081) (xy 277.259311 -275.171978)
			(xy 277.311472 -275.185614) (xy 277.361092 -275.206701) (xy 277.407113 -275.234787) (xy 277.448555 -275.269275)
			(xy 277.484533 -275.309429) (xy 277.514281 -275.354393) (xy 277.537166 -275.40321) (xy 277.552698 -275.454839)
			(xy 277.560548 -275.508179) (xy 277.56104 -275.535136) (xy 284.366731 -275.535136) (xy 284.370666 -275.481365)
			(xy 284.382389 -275.428741) (xy 284.401649 -275.378384) (xy 284.428035 -275.331367) (xy 284.460987 -275.288694)
			(xy 284.4998 -275.251273) (xy 284.543648 -275.219903) (xy 284.591596 -275.195251) (xy 284.642623 -275.177843)
			(xy 284.695641 -275.16805) (xy 284.74952 -275.166081) (xy 284.803111 -275.171978) (xy 284.855272 -275.185614)
			(xy 284.904892 -275.206701) (xy 284.950913 -275.234787) (xy 284.992355 -275.269275) (xy 285.028333 -275.309429)
			(xy 285.058081 -275.354393) (xy 285.080966 -275.40321) (xy 285.096498 -275.454839) (xy 285.104348 -275.508179)
			(xy 285.10484 -275.535136) (xy 291.910785 -275.535136) (xy 291.91472 -275.481365) (xy 291.926443 -275.428741)
			(xy 291.945703 -275.378384) (xy 291.972089 -275.331367) (xy 292.005041 -275.288694) (xy 292.043854 -275.251273)
			(xy 292.087702 -275.219903) (xy 292.13565 -275.195251) (xy 292.186677 -275.177843) (xy 292.239695 -275.16805)
			(xy 292.293574 -275.166081) (xy 292.347165 -275.171978) (xy 292.399326 -275.185614) (xy 292.448946 -275.206701)
			(xy 292.494967 -275.234787) (xy 292.536409 -275.269275) (xy 292.572387 -275.309429) (xy 292.602135 -275.354393)
			(xy 292.62502 -275.40321) (xy 292.640552 -275.454839) (xy 292.648402 -275.508179) (xy 292.648894 -275.535136)
			(xy 292.648402 -275.562093) (xy 292.640552 -275.615433) (xy 292.62502 -275.667062) (xy 292.602135 -275.715879)
			(xy 292.572387 -275.760843) (xy 292.536409 -275.800997) (xy 292.494967 -275.835485) (xy 292.448946 -275.863571)
			(xy 292.399326 -275.884658) (xy 292.347165 -275.898294) (xy 292.293574 -275.904191) (xy 292.239695 -275.902222)
			(xy 292.186677 -275.892429) (xy 292.13565 -275.875021) (xy 292.087702 -275.850369) (xy 292.043854 -275.818999)
			(xy 292.005041 -275.781578) (xy 291.972089 -275.738905) (xy 291.945703 -275.691888) (xy 291.926443 -275.641531)
			(xy 291.91472 -275.588907) (xy 291.910785 -275.535136) (xy 285.10484 -275.535136) (xy 285.104348 -275.562093)
			(xy 285.096498 -275.615433) (xy 285.080966 -275.667062) (xy 285.058081 -275.715879) (xy 285.028333 -275.760843)
			(xy 284.992355 -275.800997) (xy 284.950913 -275.835485) (xy 284.904892 -275.863571) (xy 284.855272 -275.884658)
			(xy 284.803111 -275.898294) (xy 284.74952 -275.904191) (xy 284.695641 -275.902222) (xy 284.642623 -275.892429)
			(xy 284.591596 -275.875021) (xy 284.543648 -275.850369) (xy 284.4998 -275.818999) (xy 284.460987 -275.781578)
			(xy 284.428035 -275.738905) (xy 284.401649 -275.691888) (xy 284.382389 -275.641531) (xy 284.370666 -275.588907)
			(xy 284.366731 -275.535136) (xy 277.56104 -275.535136) (xy 277.560548 -275.562093) (xy 277.552698 -275.615433)
			(xy 277.537166 -275.667062) (xy 277.514281 -275.715879) (xy 277.484533 -275.760843) (xy 277.448555 -275.800997)
			(xy 277.407113 -275.835485) (xy 277.361092 -275.863571) (xy 277.311472 -275.884658) (xy 277.259311 -275.898294)
			(xy 277.20572 -275.904191) (xy 277.151841 -275.902222) (xy 277.098823 -275.892429) (xy 277.047796 -275.875021)
			(xy 276.999848 -275.850369) (xy 276.956 -275.818999) (xy 276.917187 -275.781578) (xy 276.884235 -275.738905)
			(xy 276.857849 -275.691888) (xy 276.838589 -275.641531) (xy 276.826866 -275.588907) (xy 276.822931 -275.535136)
			(xy 270.016986 -275.535136) (xy 270.016494 -275.562093) (xy 270.008644 -275.615433) (xy 269.993112 -275.667062)
			(xy 269.970227 -275.715879) (xy 269.940479 -275.760843) (xy 269.904501 -275.800997) (xy 269.863059 -275.835485)
			(xy 269.817038 -275.863571) (xy 269.767418 -275.884658) (xy 269.715257 -275.898294) (xy 269.661666 -275.904191)
			(xy 269.607787 -275.902222) (xy 269.554769 -275.892429) (xy 269.503742 -275.875021) (xy 269.455794 -275.850369)
			(xy 269.411946 -275.818999) (xy 269.373133 -275.781578) (xy 269.340181 -275.738905) (xy 269.313795 -275.691888)
			(xy 269.294535 -275.641531) (xy 269.282812 -275.588907) (xy 269.278877 -275.535136) (xy 264.143998 -275.535136)
			(xy 264.143998 -276.38502) (xy 265.178809 -276.38502) (xy 265.182744 -276.331249) (xy 265.194467 -276.278625)
			(xy 265.213727 -276.228268) (xy 265.240113 -276.181251) (xy 265.273065 -276.138578) (xy 265.311878 -276.101157)
			(xy 265.355726 -276.069787) (xy 265.403674 -276.045135) (xy 265.454701 -276.027727) (xy 265.507719 -276.017934)
			(xy 265.561598 -276.015965) (xy 265.615189 -276.021862) (xy 265.66735 -276.035498) (xy 265.71697 -276.056585)
			(xy 265.762991 -276.084671) (xy 265.804433 -276.119159) (xy 265.840411 -276.159313) (xy 265.870159 -276.204277)
			(xy 265.893044 -276.253094) (xy 265.908576 -276.304723) (xy 265.916426 -276.358063) (xy 265.916918 -276.38502)
			(xy 269.278877 -276.38502) (xy 269.282812 -276.331249) (xy 269.294535 -276.278625) (xy 269.313795 -276.228268)
			(xy 269.340181 -276.181251) (xy 269.373133 -276.138578) (xy 269.411946 -276.101157) (xy 269.455794 -276.069787)
			(xy 269.503742 -276.045135) (xy 269.554769 -276.027727) (xy 269.607787 -276.017934) (xy 269.661666 -276.015965)
			(xy 269.715257 -276.021862) (xy 269.767418 -276.035498) (xy 269.817038 -276.056585) (xy 269.863059 -276.084671)
			(xy 269.904501 -276.119159) (xy 269.940479 -276.159313) (xy 269.970227 -276.204277) (xy 269.993112 -276.253094)
			(xy 270.008644 -276.304723) (xy 270.016494 -276.358063) (xy 270.016986 -276.38502) (xy 272.722863 -276.38502)
			(xy 272.726798 -276.331249) (xy 272.738521 -276.278625) (xy 272.757781 -276.228268) (xy 272.784167 -276.181251)
			(xy 272.817119 -276.138578) (xy 272.855932 -276.101157) (xy 272.89978 -276.069787) (xy 272.947728 -276.045135)
			(xy 272.998755 -276.027727) (xy 273.051773 -276.017934) (xy 273.105652 -276.015965) (xy 273.159243 -276.021862)
			(xy 273.211404 -276.035498) (xy 273.261024 -276.056585) (xy 273.307045 -276.084671) (xy 273.348487 -276.119159)
			(xy 273.384465 -276.159313) (xy 273.414213 -276.204277) (xy 273.437098 -276.253094) (xy 273.45263 -276.304723)
			(xy 273.46048 -276.358063) (xy 273.460972 -276.38502) (xy 276.822931 -276.38502) (xy 276.826866 -276.331249)
			(xy 276.838589 -276.278625) (xy 276.857849 -276.228268) (xy 276.884235 -276.181251) (xy 276.917187 -276.138578)
			(xy 276.956 -276.101157) (xy 276.999848 -276.069787) (xy 277.047796 -276.045135) (xy 277.098823 -276.027727)
			(xy 277.151841 -276.017934) (xy 277.20572 -276.015965) (xy 277.259311 -276.021862) (xy 277.311472 -276.035498)
			(xy 277.361092 -276.056585) (xy 277.407113 -276.084671) (xy 277.448555 -276.119159) (xy 277.484533 -276.159313)
			(xy 277.514281 -276.204277) (xy 277.537166 -276.253094) (xy 277.552698 -276.304723) (xy 277.560548 -276.358063)
			(xy 277.56104 -276.38502) (xy 280.266663 -276.38502) (xy 280.270598 -276.331249) (xy 280.282321 -276.278625)
			(xy 280.301581 -276.228268) (xy 280.327967 -276.181251) (xy 280.360919 -276.138578) (xy 280.399732 -276.101157)
			(xy 280.44358 -276.069787) (xy 280.491528 -276.045135) (xy 280.542555 -276.027727) (xy 280.595573 -276.017934)
			(xy 280.649452 -276.015965) (xy 280.703043 -276.021862) (xy 280.755204 -276.035498) (xy 280.804824 -276.056585)
			(xy 280.850845 -276.084671) (xy 280.892287 -276.119159) (xy 280.928265 -276.159313) (xy 280.958013 -276.204277)
			(xy 280.980898 -276.253094) (xy 280.99643 -276.304723) (xy 281.00428 -276.358063) (xy 281.004772 -276.38502)
			(xy 284.366731 -276.38502) (xy 284.370666 -276.331249) (xy 284.382389 -276.278625) (xy 284.401649 -276.228268)
			(xy 284.428035 -276.181251) (xy 284.460987 -276.138578) (xy 284.4998 -276.101157) (xy 284.543648 -276.069787)
			(xy 284.591596 -276.045135) (xy 284.642623 -276.027727) (xy 284.695641 -276.017934) (xy 284.74952 -276.015965)
			(xy 284.803111 -276.021862) (xy 284.855272 -276.035498) (xy 284.904892 -276.056585) (xy 284.950913 -276.084671)
			(xy 284.992355 -276.119159) (xy 285.028333 -276.159313) (xy 285.058081 -276.204277) (xy 285.080966 -276.253094)
			(xy 285.096498 -276.304723) (xy 285.104348 -276.358063) (xy 285.10484 -276.38502) (xy 287.810717 -276.38502)
			(xy 287.814652 -276.331249) (xy 287.826375 -276.278625) (xy 287.845635 -276.228268) (xy 287.872021 -276.181251)
			(xy 287.904973 -276.138578) (xy 287.943786 -276.101157) (xy 287.987634 -276.069787) (xy 288.035582 -276.045135)
			(xy 288.086609 -276.027727) (xy 288.139627 -276.017934) (xy 288.193506 -276.015965) (xy 288.247097 -276.021862)
			(xy 288.299258 -276.035498) (xy 288.348878 -276.056585) (xy 288.394899 -276.084671) (xy 288.436341 -276.119159)
			(xy 288.472319 -276.159313) (xy 288.502067 -276.204277) (xy 288.524952 -276.253094) (xy 288.540484 -276.304723)
			(xy 288.548334 -276.358063) (xy 288.548826 -276.38502) (xy 291.910785 -276.38502) (xy 291.91472 -276.331249)
			(xy 291.926443 -276.278625) (xy 291.945703 -276.228268) (xy 291.972089 -276.181251) (xy 292.005041 -276.138578)
			(xy 292.043854 -276.101157) (xy 292.087702 -276.069787) (xy 292.13565 -276.045135) (xy 292.186677 -276.027727)
			(xy 292.239695 -276.017934) (xy 292.293574 -276.015965) (xy 292.347165 -276.021862) (xy 292.399326 -276.035498)
			(xy 292.448946 -276.056585) (xy 292.494967 -276.084671) (xy 292.536409 -276.119159) (xy 292.572387 -276.159313)
			(xy 292.602135 -276.204277) (xy 292.62502 -276.253094) (xy 292.640552 -276.304723) (xy 292.648402 -276.358063)
			(xy 292.648894 -276.38502) (xy 292.648402 -276.411977) (xy 292.640552 -276.465317) (xy 292.62502 -276.516946)
			(xy 292.602135 -276.565763) (xy 292.572387 -276.610727) (xy 292.536409 -276.650881) (xy 292.494967 -276.685369)
			(xy 292.448946 -276.713455) (xy 292.399326 -276.734542) (xy 292.347165 -276.748178) (xy 292.293574 -276.754075)
			(xy 292.239695 -276.752106) (xy 292.186677 -276.742313) (xy 292.13565 -276.724905) (xy 292.087702 -276.700253)
			(xy 292.043854 -276.668883) (xy 292.005041 -276.631462) (xy 291.972089 -276.588789) (xy 291.945703 -276.541772)
			(xy 291.926443 -276.491415) (xy 291.91472 -276.438791) (xy 291.910785 -276.38502) (xy 288.548826 -276.38502)
			(xy 288.548334 -276.411977) (xy 288.540484 -276.465317) (xy 288.524952 -276.516946) (xy 288.502067 -276.565763)
			(xy 288.472319 -276.610727) (xy 288.436341 -276.650881) (xy 288.394899 -276.685369) (xy 288.348878 -276.713455)
			(xy 288.299258 -276.734542) (xy 288.247097 -276.748178) (xy 288.193506 -276.754075) (xy 288.139627 -276.752106)
			(xy 288.086609 -276.742313) (xy 288.035582 -276.724905) (xy 287.987634 -276.700253) (xy 287.943786 -276.668883)
			(xy 287.904973 -276.631462) (xy 287.872021 -276.588789) (xy 287.845635 -276.541772) (xy 287.826375 -276.491415)
			(xy 287.814652 -276.438791) (xy 287.810717 -276.38502) (xy 285.10484 -276.38502) (xy 285.104348 -276.411977)
			(xy 285.096498 -276.465317) (xy 285.080966 -276.516946) (xy 285.058081 -276.565763) (xy 285.028333 -276.610727)
			(xy 284.992355 -276.650881) (xy 284.950913 -276.685369) (xy 284.904892 -276.713455) (xy 284.855272 -276.734542)
			(xy 284.803111 -276.748178) (xy 284.74952 -276.754075) (xy 284.695641 -276.752106) (xy 284.642623 -276.742313)
			(xy 284.591596 -276.724905) (xy 284.543648 -276.700253) (xy 284.4998 -276.668883) (xy 284.460987 -276.631462)
			(xy 284.428035 -276.588789) (xy 284.401649 -276.541772) (xy 284.382389 -276.491415) (xy 284.370666 -276.438791)
			(xy 284.366731 -276.38502) (xy 281.004772 -276.38502) (xy 281.00428 -276.411977) (xy 280.99643 -276.465317)
			(xy 280.980898 -276.516946) (xy 280.958013 -276.565763) (xy 280.928265 -276.610727) (xy 280.892287 -276.650881)
			(xy 280.850845 -276.685369) (xy 280.804824 -276.713455) (xy 280.755204 -276.734542) (xy 280.703043 -276.748178)
			(xy 280.649452 -276.754075) (xy 280.595573 -276.752106) (xy 280.542555 -276.742313) (xy 280.491528 -276.724905)
			(xy 280.44358 -276.700253) (xy 280.399732 -276.668883) (xy 280.360919 -276.631462) (xy 280.327967 -276.588789)
			(xy 280.301581 -276.541772) (xy 280.282321 -276.491415) (xy 280.270598 -276.438791) (xy 280.266663 -276.38502)
			(xy 277.56104 -276.38502) (xy 277.560548 -276.411977) (xy 277.552698 -276.465317) (xy 277.537166 -276.516946)
			(xy 277.514281 -276.565763) (xy 277.484533 -276.610727) (xy 277.448555 -276.650881) (xy 277.407113 -276.685369)
			(xy 277.361092 -276.713455) (xy 277.311472 -276.734542) (xy 277.259311 -276.748178) (xy 277.20572 -276.754075)
			(xy 277.151841 -276.752106) (xy 277.098823 -276.742313) (xy 277.047796 -276.724905) (xy 276.999848 -276.700253)
			(xy 276.956 -276.668883) (xy 276.917187 -276.631462) (xy 276.884235 -276.588789) (xy 276.857849 -276.541772)
			(xy 276.838589 -276.491415) (xy 276.826866 -276.438791) (xy 276.822931 -276.38502) (xy 273.460972 -276.38502)
			(xy 273.46048 -276.411977) (xy 273.45263 -276.465317) (xy 273.437098 -276.516946) (xy 273.414213 -276.565763)
			(xy 273.384465 -276.610727) (xy 273.348487 -276.650881) (xy 273.307045 -276.685369) (xy 273.261024 -276.713455)
			(xy 273.211404 -276.734542) (xy 273.159243 -276.748178) (xy 273.105652 -276.754075) (xy 273.051773 -276.752106)
			(xy 272.998755 -276.742313) (xy 272.947728 -276.724905) (xy 272.89978 -276.700253) (xy 272.855932 -276.668883)
			(xy 272.817119 -276.631462) (xy 272.784167 -276.588789) (xy 272.757781 -276.541772) (xy 272.738521 -276.491415)
			(xy 272.726798 -276.438791) (xy 272.722863 -276.38502) (xy 270.016986 -276.38502) (xy 270.016494 -276.411977)
			(xy 270.008644 -276.465317) (xy 269.993112 -276.516946) (xy 269.970227 -276.565763) (xy 269.940479 -276.610727)
			(xy 269.904501 -276.650881) (xy 269.863059 -276.685369) (xy 269.817038 -276.713455) (xy 269.767418 -276.734542)
			(xy 269.715257 -276.748178) (xy 269.661666 -276.754075) (xy 269.607787 -276.752106) (xy 269.554769 -276.742313)
			(xy 269.503742 -276.724905) (xy 269.455794 -276.700253) (xy 269.411946 -276.668883) (xy 269.373133 -276.631462)
			(xy 269.340181 -276.588789) (xy 269.313795 -276.541772) (xy 269.294535 -276.491415) (xy 269.282812 -276.438791)
			(xy 269.278877 -276.38502) (xy 265.916918 -276.38502) (xy 265.916426 -276.411977) (xy 265.908576 -276.465317)
			(xy 265.893044 -276.516946) (xy 265.870159 -276.565763) (xy 265.840411 -276.610727) (xy 265.804433 -276.650881)
			(xy 265.762991 -276.685369) (xy 265.71697 -276.713455) (xy 265.66735 -276.734542) (xy 265.615189 -276.748178)
			(xy 265.561598 -276.754075) (xy 265.507719 -276.752106) (xy 265.454701 -276.742313) (xy 265.403674 -276.724905)
			(xy 265.355726 -276.700253) (xy 265.311878 -276.668883) (xy 265.273065 -276.631462) (xy 265.240113 -276.588789)
			(xy 265.213727 -276.541772) (xy 265.194467 -276.491415) (xy 265.182744 -276.438791) (xy 265.178809 -276.38502)
			(xy 264.143998 -276.38502) (xy 264.143998 -277.235158) (xy 265.178809 -277.235158) (xy 265.182744 -277.181387)
			(xy 265.194467 -277.128763) (xy 265.213727 -277.078406) (xy 265.240113 -277.031389) (xy 265.273065 -276.988716)
			(xy 265.311878 -276.951295) (xy 265.355726 -276.919925) (xy 265.403674 -276.895273) (xy 265.454701 -276.877865)
			(xy 265.507719 -276.868072) (xy 265.561598 -276.866103) (xy 265.615189 -276.872) (xy 265.66735 -276.885636)
			(xy 265.71697 -276.906723) (xy 265.762991 -276.934809) (xy 265.804433 -276.969297) (xy 265.840411 -277.009451)
			(xy 265.870159 -277.054415) (xy 265.893044 -277.103232) (xy 265.908576 -277.154861) (xy 265.916426 -277.208201)
			(xy 265.916918 -277.235158) (xy 272.722863 -277.235158) (xy 272.726798 -277.181387) (xy 272.738521 -277.128763)
			(xy 272.757781 -277.078406) (xy 272.784167 -277.031389) (xy 272.817119 -276.988716) (xy 272.855932 -276.951295)
			(xy 272.89978 -276.919925) (xy 272.947728 -276.895273) (xy 272.998755 -276.877865) (xy 273.051773 -276.868072)
			(xy 273.105652 -276.866103) (xy 273.159243 -276.872) (xy 273.211404 -276.885636) (xy 273.261024 -276.906723)
			(xy 273.307045 -276.934809) (xy 273.348487 -276.969297) (xy 273.384465 -277.009451) (xy 273.414213 -277.054415)
			(xy 273.437098 -277.103232) (xy 273.45263 -277.154861) (xy 273.46048 -277.208201) (xy 273.460972 -277.235158)
			(xy 280.266663 -277.235158) (xy 280.270598 -277.181387) (xy 280.282321 -277.128763) (xy 280.301581 -277.078406)
			(xy 280.327967 -277.031389) (xy 280.360919 -276.988716) (xy 280.399732 -276.951295) (xy 280.44358 -276.919925)
			(xy 280.491528 -276.895273) (xy 280.542555 -276.877865) (xy 280.595573 -276.868072) (xy 280.649452 -276.866103)
			(xy 280.703043 -276.872) (xy 280.755204 -276.885636) (xy 280.804824 -276.906723) (xy 280.850845 -276.934809)
			(xy 280.892287 -276.969297) (xy 280.928265 -277.009451) (xy 280.958013 -277.054415) (xy 280.980898 -277.103232)
			(xy 280.99643 -277.154861) (xy 281.00428 -277.208201) (xy 281.004772 -277.235158) (xy 287.810717 -277.235158)
			(xy 287.814652 -277.181387) (xy 287.826375 -277.128763) (xy 287.845635 -277.078406) (xy 287.872021 -277.031389)
			(xy 287.904973 -276.988716) (xy 287.943786 -276.951295) (xy 287.987634 -276.919925) (xy 288.035582 -276.895273)
			(xy 288.086609 -276.877865) (xy 288.139627 -276.868072) (xy 288.193506 -276.866103) (xy 288.247097 -276.872)
			(xy 288.299258 -276.885636) (xy 288.348878 -276.906723) (xy 288.394899 -276.934809) (xy 288.436341 -276.969297)
			(xy 288.472319 -277.009451) (xy 288.502067 -277.054415) (xy 288.524952 -277.103232) (xy 288.540484 -277.154861)
			(xy 288.548334 -277.208201) (xy 288.548826 -277.235158) (xy 288.548334 -277.262115) (xy 288.540484 -277.315455)
			(xy 288.524952 -277.367084) (xy 288.502067 -277.415901) (xy 288.472319 -277.460865) (xy 288.436341 -277.501019)
			(xy 288.394899 -277.535507) (xy 288.348878 -277.563593) (xy 288.299258 -277.58468) (xy 288.247097 -277.598316)
			(xy 288.193506 -277.604213) (xy 288.139627 -277.602244) (xy 288.086609 -277.592451) (xy 288.035582 -277.575043)
			(xy 287.987634 -277.550391) (xy 287.943786 -277.519021) (xy 287.904973 -277.4816) (xy 287.872021 -277.438927)
			(xy 287.845635 -277.39191) (xy 287.826375 -277.341553) (xy 287.814652 -277.288929) (xy 287.810717 -277.235158)
			(xy 281.004772 -277.235158) (xy 281.00428 -277.262115) (xy 280.99643 -277.315455) (xy 280.980898 -277.367084)
			(xy 280.958013 -277.415901) (xy 280.928265 -277.460865) (xy 280.892287 -277.501019) (xy 280.850845 -277.535507)
			(xy 280.804824 -277.563593) (xy 280.755204 -277.58468) (xy 280.703043 -277.598316) (xy 280.649452 -277.604213)
			(xy 280.595573 -277.602244) (xy 280.542555 -277.592451) (xy 280.491528 -277.575043) (xy 280.44358 -277.550391)
			(xy 280.399732 -277.519021) (xy 280.360919 -277.4816) (xy 280.327967 -277.438927) (xy 280.301581 -277.39191)
			(xy 280.282321 -277.341553) (xy 280.270598 -277.288929) (xy 280.266663 -277.235158) (xy 273.460972 -277.235158)
			(xy 273.46048 -277.262115) (xy 273.45263 -277.315455) (xy 273.437098 -277.367084) (xy 273.414213 -277.415901)
			(xy 273.384465 -277.460865) (xy 273.348487 -277.501019) (xy 273.307045 -277.535507) (xy 273.261024 -277.563593)
			(xy 273.211404 -277.58468) (xy 273.159243 -277.598316) (xy 273.105652 -277.604213) (xy 273.051773 -277.602244)
			(xy 272.998755 -277.592451) (xy 272.947728 -277.575043) (xy 272.89978 -277.550391) (xy 272.855932 -277.519021)
			(xy 272.817119 -277.4816) (xy 272.784167 -277.438927) (xy 272.757781 -277.39191) (xy 272.738521 -277.341553)
			(xy 272.726798 -277.288929) (xy 272.722863 -277.235158) (xy 265.916918 -277.235158) (xy 265.916426 -277.262115)
			(xy 265.908576 -277.315455) (xy 265.893044 -277.367084) (xy 265.870159 -277.415901) (xy 265.840411 -277.460865)
			(xy 265.804433 -277.501019) (xy 265.762991 -277.535507) (xy 265.71697 -277.563593) (xy 265.66735 -277.58468)
			(xy 265.615189 -277.598316) (xy 265.561598 -277.604213) (xy 265.507719 -277.602244) (xy 265.454701 -277.592451)
			(xy 265.403674 -277.575043) (xy 265.355726 -277.550391) (xy 265.311878 -277.519021) (xy 265.273065 -277.4816)
			(xy 265.240113 -277.438927) (xy 265.213727 -277.39191) (xy 265.194467 -277.341553) (xy 265.182744 -277.288929)
			(xy 265.178809 -277.235158) (xy 264.143998 -277.235158) (xy 264.143998 -278.085042) (xy 269.278877 -278.085042)
			(xy 269.282812 -278.031271) (xy 269.294535 -277.978647) (xy 269.313795 -277.92829) (xy 269.340181 -277.881273)
			(xy 269.373133 -277.8386) (xy 269.411946 -277.801179) (xy 269.455794 -277.769809) (xy 269.503742 -277.745157)
			(xy 269.554769 -277.727749) (xy 269.607787 -277.717956) (xy 269.661666 -277.715987) (xy 269.715257 -277.721884)
			(xy 269.767418 -277.73552) (xy 269.817038 -277.756607) (xy 269.863059 -277.784693) (xy 269.904501 -277.819181)
			(xy 269.940479 -277.859335) (xy 269.970227 -277.904299) (xy 269.993112 -277.953116) (xy 270.008644 -278.004745)
			(xy 270.016494 -278.058085) (xy 270.016986 -278.085042) (xy 276.822931 -278.085042) (xy 276.826866 -278.031271)
			(xy 276.838589 -277.978647) (xy 276.857849 -277.92829) (xy 276.884235 -277.881273) (xy 276.917187 -277.8386)
			(xy 276.956 -277.801179) (xy 276.999848 -277.769809) (xy 277.047796 -277.745157) (xy 277.098823 -277.727749)
			(xy 277.151841 -277.717956) (xy 277.20572 -277.715987) (xy 277.259311 -277.721884) (xy 277.311472 -277.73552)
			(xy 277.361092 -277.756607) (xy 277.407113 -277.784693) (xy 277.448555 -277.819181) (xy 277.484533 -277.859335)
			(xy 277.514281 -277.904299) (xy 277.537166 -277.953116) (xy 277.552698 -278.004745) (xy 277.560548 -278.058085)
			(xy 277.56104 -278.085042) (xy 284.366731 -278.085042) (xy 284.370666 -278.031271) (xy 284.382389 -277.978647)
			(xy 284.401649 -277.92829) (xy 284.428035 -277.881273) (xy 284.460987 -277.8386) (xy 284.4998 -277.801179)
			(xy 284.543648 -277.769809) (xy 284.591596 -277.745157) (xy 284.642623 -277.727749) (xy 284.695641 -277.717956)
			(xy 284.74952 -277.715987) (xy 284.803111 -277.721884) (xy 284.855272 -277.73552) (xy 284.904892 -277.756607)
			(xy 284.950913 -277.784693) (xy 284.992355 -277.819181) (xy 285.028333 -277.859335) (xy 285.058081 -277.904299)
			(xy 285.080966 -277.953116) (xy 285.096498 -278.004745) (xy 285.104348 -278.058085) (xy 285.10484 -278.085042)
			(xy 291.910785 -278.085042) (xy 291.91472 -278.031271) (xy 291.926443 -277.978647) (xy 291.945703 -277.92829)
			(xy 291.972089 -277.881273) (xy 292.005041 -277.8386) (xy 292.043854 -277.801179) (xy 292.087702 -277.769809)
			(xy 292.13565 -277.745157) (xy 292.186677 -277.727749) (xy 292.239695 -277.717956) (xy 292.293574 -277.715987)
			(xy 292.347165 -277.721884) (xy 292.399326 -277.73552) (xy 292.448946 -277.756607) (xy 292.494967 -277.784693)
			(xy 292.536409 -277.819181) (xy 292.572387 -277.859335) (xy 292.602135 -277.904299) (xy 292.62502 -277.953116)
			(xy 292.640552 -278.004745) (xy 292.648402 -278.058085) (xy 292.648894 -278.085042) (xy 292.648402 -278.111999)
			(xy 292.640552 -278.165339) (xy 292.62502 -278.216968) (xy 292.602135 -278.265785) (xy 292.572387 -278.310749)
			(xy 292.536409 -278.350903) (xy 292.494967 -278.385391) (xy 292.448946 -278.413477) (xy 292.399326 -278.434564)
			(xy 292.347165 -278.4482) (xy 292.293574 -278.454097) (xy 292.239695 -278.452128) (xy 292.186677 -278.442335)
			(xy 292.13565 -278.424927) (xy 292.087702 -278.400275) (xy 292.043854 -278.368905) (xy 292.005041 -278.331484)
			(xy 291.972089 -278.288811) (xy 291.945703 -278.241794) (xy 291.926443 -278.191437) (xy 291.91472 -278.138813)
			(xy 291.910785 -278.085042) (xy 285.10484 -278.085042) (xy 285.104348 -278.111999) (xy 285.096498 -278.165339)
			(xy 285.080966 -278.216968) (xy 285.058081 -278.265785) (xy 285.028333 -278.310749) (xy 284.992355 -278.350903)
			(xy 284.950913 -278.385391) (xy 284.904892 -278.413477) (xy 284.855272 -278.434564) (xy 284.803111 -278.4482)
			(xy 284.74952 -278.454097) (xy 284.695641 -278.452128) (xy 284.642623 -278.442335) (xy 284.591596 -278.424927)
			(xy 284.543648 -278.400275) (xy 284.4998 -278.368905) (xy 284.460987 -278.331484) (xy 284.428035 -278.288811)
			(xy 284.401649 -278.241794) (xy 284.382389 -278.191437) (xy 284.370666 -278.138813) (xy 284.366731 -278.085042)
			(xy 277.56104 -278.085042) (xy 277.560548 -278.111999) (xy 277.552698 -278.165339) (xy 277.537166 -278.216968)
			(xy 277.514281 -278.265785) (xy 277.484533 -278.310749) (xy 277.448555 -278.350903) (xy 277.407113 -278.385391)
			(xy 277.361092 -278.413477) (xy 277.311472 -278.434564) (xy 277.259311 -278.4482) (xy 277.20572 -278.454097)
			(xy 277.151841 -278.452128) (xy 277.098823 -278.442335) (xy 277.047796 -278.424927) (xy 276.999848 -278.400275)
			(xy 276.956 -278.368905) (xy 276.917187 -278.331484) (xy 276.884235 -278.288811) (xy 276.857849 -278.241794)
			(xy 276.838589 -278.191437) (xy 276.826866 -278.138813) (xy 276.822931 -278.085042) (xy 270.016986 -278.085042)
			(xy 270.016494 -278.111999) (xy 270.008644 -278.165339) (xy 269.993112 -278.216968) (xy 269.970227 -278.265785)
			(xy 269.940479 -278.310749) (xy 269.904501 -278.350903) (xy 269.863059 -278.385391) (xy 269.817038 -278.413477)
			(xy 269.767418 -278.434564) (xy 269.715257 -278.4482) (xy 269.661666 -278.454097) (xy 269.607787 -278.452128)
			(xy 269.554769 -278.442335) (xy 269.503742 -278.424927) (xy 269.455794 -278.400275) (xy 269.411946 -278.368905)
			(xy 269.373133 -278.331484) (xy 269.340181 -278.288811) (xy 269.313795 -278.241794) (xy 269.294535 -278.191437)
			(xy 269.282812 -278.138813) (xy 269.278877 -278.085042) (xy 264.143998 -278.085042) (xy 264.143998 -278.93518)
			(xy 265.178809 -278.93518) (xy 265.182744 -278.881409) (xy 265.194467 -278.828785) (xy 265.213727 -278.778428)
			(xy 265.240113 -278.731411) (xy 265.273065 -278.688738) (xy 265.311878 -278.651317) (xy 265.355726 -278.619947)
			(xy 265.403674 -278.595295) (xy 265.454701 -278.577887) (xy 265.507719 -278.568094) (xy 265.561598 -278.566125)
			(xy 265.615189 -278.572022) (xy 265.66735 -278.585658) (xy 265.71697 -278.606745) (xy 265.762991 -278.634831)
			(xy 265.804433 -278.669319) (xy 265.840411 -278.709473) (xy 265.870159 -278.754437) (xy 265.893044 -278.803254)
			(xy 265.908576 -278.854883) (xy 265.916426 -278.908223) (xy 265.916918 -278.93518) (xy 272.722863 -278.93518)
			(xy 272.726798 -278.881409) (xy 272.738521 -278.828785) (xy 272.757781 -278.778428) (xy 272.784167 -278.731411)
			(xy 272.817119 -278.688738) (xy 272.855932 -278.651317) (xy 272.89978 -278.619947) (xy 272.947728 -278.595295)
			(xy 272.998755 -278.577887) (xy 273.051773 -278.568094) (xy 273.105652 -278.566125) (xy 273.159243 -278.572022)
			(xy 273.211404 -278.585658) (xy 273.261024 -278.606745) (xy 273.307045 -278.634831) (xy 273.348487 -278.669319)
			(xy 273.384465 -278.709473) (xy 273.414213 -278.754437) (xy 273.437098 -278.803254) (xy 273.45263 -278.854883)
			(xy 273.46048 -278.908223) (xy 273.460972 -278.93518) (xy 280.266663 -278.93518) (xy 280.270598 -278.881409)
			(xy 280.282321 -278.828785) (xy 280.301581 -278.778428) (xy 280.327967 -278.731411) (xy 280.360919 -278.688738)
			(xy 280.399732 -278.651317) (xy 280.44358 -278.619947) (xy 280.491528 -278.595295) (xy 280.542555 -278.577887)
			(xy 280.595573 -278.568094) (xy 280.649452 -278.566125) (xy 280.703043 -278.572022) (xy 280.755204 -278.585658)
			(xy 280.804824 -278.606745) (xy 280.850845 -278.634831) (xy 280.892287 -278.669319) (xy 280.928265 -278.709473)
			(xy 280.958013 -278.754437) (xy 280.980898 -278.803254) (xy 280.99643 -278.854883) (xy 281.00428 -278.908223)
			(xy 281.004772 -278.93518) (xy 287.810717 -278.93518) (xy 287.814652 -278.881409) (xy 287.826375 -278.828785)
			(xy 287.845635 -278.778428) (xy 287.872021 -278.731411) (xy 287.904973 -278.688738) (xy 287.943786 -278.651317)
			(xy 287.987634 -278.619947) (xy 288.035582 -278.595295) (xy 288.086609 -278.577887) (xy 288.139627 -278.568094)
			(xy 288.193506 -278.566125) (xy 288.247097 -278.572022) (xy 288.299258 -278.585658) (xy 288.348878 -278.606745)
			(xy 288.394899 -278.634831) (xy 288.436341 -278.669319) (xy 288.472319 -278.709473) (xy 288.502067 -278.754437)
			(xy 288.524952 -278.803254) (xy 288.540484 -278.854883) (xy 288.548334 -278.908223) (xy 288.548826 -278.93518)
			(xy 288.548334 -278.962137) (xy 288.540484 -279.015477) (xy 288.524952 -279.067106) (xy 288.502067 -279.115923)
			(xy 288.472319 -279.160887) (xy 288.436341 -279.201041) (xy 288.394899 -279.235529) (xy 288.348878 -279.263615)
			(xy 288.299258 -279.284702) (xy 288.247097 -279.298338) (xy 288.193506 -279.304235) (xy 288.139627 -279.302266)
			(xy 288.086609 -279.292473) (xy 288.035582 -279.275065) (xy 287.987634 -279.250413) (xy 287.943786 -279.219043)
			(xy 287.904973 -279.181622) (xy 287.872021 -279.138949) (xy 287.845635 -279.091932) (xy 287.826375 -279.041575)
			(xy 287.814652 -278.988951) (xy 287.810717 -278.93518) (xy 281.004772 -278.93518) (xy 281.00428 -278.962137)
			(xy 280.99643 -279.015477) (xy 280.980898 -279.067106) (xy 280.958013 -279.115923) (xy 280.928265 -279.160887)
			(xy 280.892287 -279.201041) (xy 280.850845 -279.235529) (xy 280.804824 -279.263615) (xy 280.755204 -279.284702)
			(xy 280.703043 -279.298338) (xy 280.649452 -279.304235) (xy 280.595573 -279.302266) (xy 280.542555 -279.292473)
			(xy 280.491528 -279.275065) (xy 280.44358 -279.250413) (xy 280.399732 -279.219043) (xy 280.360919 -279.181622)
			(xy 280.327967 -279.138949) (xy 280.301581 -279.091932) (xy 280.282321 -279.041575) (xy 280.270598 -278.988951)
			(xy 280.266663 -278.93518) (xy 273.460972 -278.93518) (xy 273.46048 -278.962137) (xy 273.45263 -279.015477)
			(xy 273.437098 -279.067106) (xy 273.414213 -279.115923) (xy 273.384465 -279.160887) (xy 273.348487 -279.201041)
			(xy 273.307045 -279.235529) (xy 273.261024 -279.263615) (xy 273.211404 -279.284702) (xy 273.159243 -279.298338)
			(xy 273.105652 -279.304235) (xy 273.051773 -279.302266) (xy 272.998755 -279.292473) (xy 272.947728 -279.275065)
			(xy 272.89978 -279.250413) (xy 272.855932 -279.219043) (xy 272.817119 -279.181622) (xy 272.784167 -279.138949)
			(xy 272.757781 -279.091932) (xy 272.738521 -279.041575) (xy 272.726798 -278.988951) (xy 272.722863 -278.93518)
			(xy 265.916918 -278.93518) (xy 265.916426 -278.962137) (xy 265.908576 -279.015477) (xy 265.893044 -279.067106)
			(xy 265.870159 -279.115923) (xy 265.840411 -279.160887) (xy 265.804433 -279.201041) (xy 265.762991 -279.235529)
			(xy 265.71697 -279.263615) (xy 265.66735 -279.284702) (xy 265.615189 -279.298338) (xy 265.561598 -279.304235)
			(xy 265.507719 -279.302266) (xy 265.454701 -279.292473) (xy 265.403674 -279.275065) (xy 265.355726 -279.250413)
			(xy 265.311878 -279.219043) (xy 265.273065 -279.181622) (xy 265.240113 -279.138949) (xy 265.213727 -279.091932)
			(xy 265.194467 -279.041575) (xy 265.182744 -278.988951) (xy 265.178809 -278.93518) (xy 264.143998 -278.93518)
			(xy 264.143998 -279.785064) (xy 269.278877 -279.785064) (xy 269.282812 -279.731293) (xy 269.294535 -279.678669)
			(xy 269.313795 -279.628312) (xy 269.340181 -279.581295) (xy 269.373133 -279.538622) (xy 269.411946 -279.501201)
			(xy 269.455794 -279.469831) (xy 269.503742 -279.445179) (xy 269.554769 -279.427771) (xy 269.607787 -279.417978)
			(xy 269.661666 -279.416009) (xy 269.715257 -279.421906) (xy 269.767418 -279.435542) (xy 269.817038 -279.456629)
			(xy 269.863059 -279.484715) (xy 269.904501 -279.519203) (xy 269.940479 -279.559357) (xy 269.970227 -279.604321)
			(xy 269.993112 -279.653138) (xy 270.008644 -279.704767) (xy 270.016494 -279.758107) (xy 270.016986 -279.785064)
			(xy 276.822931 -279.785064) (xy 276.826866 -279.731293) (xy 276.838589 -279.678669) (xy 276.857849 -279.628312)
			(xy 276.884235 -279.581295) (xy 276.917187 -279.538622) (xy 276.956 -279.501201) (xy 276.999848 -279.469831)
			(xy 277.047796 -279.445179) (xy 277.098823 -279.427771) (xy 277.151841 -279.417978) (xy 277.20572 -279.416009)
			(xy 277.259311 -279.421906) (xy 277.311472 -279.435542) (xy 277.361092 -279.456629) (xy 277.407113 -279.484715)
			(xy 277.448555 -279.519203) (xy 277.484533 -279.559357) (xy 277.514281 -279.604321) (xy 277.537166 -279.653138)
			(xy 277.552698 -279.704767) (xy 277.560548 -279.758107) (xy 277.56104 -279.785064) (xy 284.366731 -279.785064)
			(xy 284.370666 -279.731293) (xy 284.382389 -279.678669) (xy 284.401649 -279.628312) (xy 284.428035 -279.581295)
			(xy 284.460987 -279.538622) (xy 284.4998 -279.501201) (xy 284.543648 -279.469831) (xy 284.591596 -279.445179)
			(xy 284.642623 -279.427771) (xy 284.695641 -279.417978) (xy 284.74952 -279.416009) (xy 284.803111 -279.421906)
			(xy 284.855272 -279.435542) (xy 284.904892 -279.456629) (xy 284.950913 -279.484715) (xy 284.992355 -279.519203)
			(xy 285.028333 -279.559357) (xy 285.058081 -279.604321) (xy 285.080966 -279.653138) (xy 285.096498 -279.704767)
			(xy 285.104348 -279.758107) (xy 285.10484 -279.785064) (xy 291.910785 -279.785064) (xy 291.91472 -279.731293)
			(xy 291.926443 -279.678669) (xy 291.945703 -279.628312) (xy 291.972089 -279.581295) (xy 292.005041 -279.538622)
			(xy 292.043854 -279.501201) (xy 292.087702 -279.469831) (xy 292.13565 -279.445179) (xy 292.186677 -279.427771)
			(xy 292.239695 -279.417978) (xy 292.293574 -279.416009) (xy 292.347165 -279.421906) (xy 292.399326 -279.435542)
			(xy 292.448946 -279.456629) (xy 292.494967 -279.484715) (xy 292.536409 -279.519203) (xy 292.572387 -279.559357)
			(xy 292.602135 -279.604321) (xy 292.62502 -279.653138) (xy 292.640552 -279.704767) (xy 292.648402 -279.758107)
			(xy 292.648894 -279.785064) (xy 292.648402 -279.812021) (xy 292.640552 -279.865361) (xy 292.62502 -279.91699)
			(xy 292.602135 -279.965807) (xy 292.572387 -280.010771) (xy 292.536409 -280.050925) (xy 292.494967 -280.085413)
			(xy 292.448946 -280.113499) (xy 292.399326 -280.134586) (xy 292.347165 -280.148222) (xy 292.293574 -280.154119)
			(xy 292.239695 -280.15215) (xy 292.186677 -280.142357) (xy 292.13565 -280.124949) (xy 292.087702 -280.100297)
			(xy 292.043854 -280.068927) (xy 292.005041 -280.031506) (xy 291.972089 -279.988833) (xy 291.945703 -279.941816)
			(xy 291.926443 -279.891459) (xy 291.91472 -279.838835) (xy 291.910785 -279.785064) (xy 285.10484 -279.785064)
			(xy 285.104348 -279.812021) (xy 285.096498 -279.865361) (xy 285.080966 -279.91699) (xy 285.058081 -279.965807)
			(xy 285.028333 -280.010771) (xy 284.992355 -280.050925) (xy 284.950913 -280.085413) (xy 284.904892 -280.113499)
			(xy 284.855272 -280.134586) (xy 284.803111 -280.148222) (xy 284.74952 -280.154119) (xy 284.695641 -280.15215)
			(xy 284.642623 -280.142357) (xy 284.591596 -280.124949) (xy 284.543648 -280.100297) (xy 284.4998 -280.068927)
			(xy 284.460987 -280.031506) (xy 284.428035 -279.988833) (xy 284.401649 -279.941816) (xy 284.382389 -279.891459)
			(xy 284.370666 -279.838835) (xy 284.366731 -279.785064) (xy 277.56104 -279.785064) (xy 277.560548 -279.812021)
			(xy 277.552698 -279.865361) (xy 277.537166 -279.91699) (xy 277.514281 -279.965807) (xy 277.484533 -280.010771)
			(xy 277.448555 -280.050925) (xy 277.407113 -280.085413) (xy 277.361092 -280.113499) (xy 277.311472 -280.134586)
			(xy 277.259311 -280.148222) (xy 277.20572 -280.154119) (xy 277.151841 -280.15215) (xy 277.098823 -280.142357)
			(xy 277.047796 -280.124949) (xy 276.999848 -280.100297) (xy 276.956 -280.068927) (xy 276.917187 -280.031506)
			(xy 276.884235 -279.988833) (xy 276.857849 -279.941816) (xy 276.838589 -279.891459) (xy 276.826866 -279.838835)
			(xy 276.822931 -279.785064) (xy 270.016986 -279.785064) (xy 270.016494 -279.812021) (xy 270.008644 -279.865361)
			(xy 269.993112 -279.91699) (xy 269.970227 -279.965807) (xy 269.940479 -280.010771) (xy 269.904501 -280.050925)
			(xy 269.863059 -280.085413) (xy 269.817038 -280.113499) (xy 269.767418 -280.134586) (xy 269.715257 -280.148222)
			(xy 269.661666 -280.154119) (xy 269.607787 -280.15215) (xy 269.554769 -280.142357) (xy 269.503742 -280.124949)
			(xy 269.455794 -280.100297) (xy 269.411946 -280.068927) (xy 269.373133 -280.031506) (xy 269.340181 -279.988833)
			(xy 269.313795 -279.941816) (xy 269.294535 -279.891459) (xy 269.282812 -279.838835) (xy 269.278877 -279.785064)
			(xy 264.143998 -279.785064) (xy 264.143998 -280.634948) (xy 265.178809 -280.634948) (xy 265.182744 -280.581177)
			(xy 265.194467 -280.528553) (xy 265.213727 -280.478196) (xy 265.240113 -280.431179) (xy 265.273065 -280.388506)
			(xy 265.311878 -280.351085) (xy 265.355726 -280.319715) (xy 265.403674 -280.295063) (xy 265.454701 -280.277655)
			(xy 265.507719 -280.267862) (xy 265.561598 -280.265893) (xy 265.615189 -280.27179) (xy 265.66735 -280.285426)
			(xy 265.71697 -280.306513) (xy 265.762991 -280.334599) (xy 265.804433 -280.369087) (xy 265.840411 -280.409241)
			(xy 265.870159 -280.454205) (xy 265.893044 -280.503022) (xy 265.908576 -280.554651) (xy 265.916426 -280.607991)
			(xy 265.916918 -280.634948) (xy 272.722863 -280.634948) (xy 272.726798 -280.581177) (xy 272.738521 -280.528553)
			(xy 272.757781 -280.478196) (xy 272.784167 -280.431179) (xy 272.817119 -280.388506) (xy 272.855932 -280.351085)
			(xy 272.89978 -280.319715) (xy 272.947728 -280.295063) (xy 272.998755 -280.277655) (xy 273.051773 -280.267862)
			(xy 273.105652 -280.265893) (xy 273.159243 -280.27179) (xy 273.211404 -280.285426) (xy 273.261024 -280.306513)
			(xy 273.307045 -280.334599) (xy 273.348487 -280.369087) (xy 273.384465 -280.409241) (xy 273.414213 -280.454205)
			(xy 273.437098 -280.503022) (xy 273.45263 -280.554651) (xy 273.46048 -280.607991) (xy 273.460972 -280.634948)
			(xy 280.266663 -280.634948) (xy 280.270598 -280.581177) (xy 280.282321 -280.528553) (xy 280.301581 -280.478196)
			(xy 280.327967 -280.431179) (xy 280.360919 -280.388506) (xy 280.399732 -280.351085) (xy 280.44358 -280.319715)
			(xy 280.491528 -280.295063) (xy 280.542555 -280.277655) (xy 280.595573 -280.267862) (xy 280.649452 -280.265893)
			(xy 280.703043 -280.27179) (xy 280.755204 -280.285426) (xy 280.804824 -280.306513) (xy 280.850845 -280.334599)
			(xy 280.892287 -280.369087) (xy 280.928265 -280.409241) (xy 280.958013 -280.454205) (xy 280.980898 -280.503022)
			(xy 280.99643 -280.554651) (xy 281.00428 -280.607991) (xy 281.004772 -280.634948) (xy 287.810717 -280.634948)
			(xy 287.814652 -280.581177) (xy 287.826375 -280.528553) (xy 287.845635 -280.478196) (xy 287.872021 -280.431179)
			(xy 287.904973 -280.388506) (xy 287.943786 -280.351085) (xy 287.987634 -280.319715) (xy 288.035582 -280.295063)
			(xy 288.086609 -280.277655) (xy 288.139627 -280.267862) (xy 288.193506 -280.265893) (xy 288.247097 -280.27179)
			(xy 288.299258 -280.285426) (xy 288.348878 -280.306513) (xy 288.394899 -280.334599) (xy 288.436341 -280.369087)
			(xy 288.472319 -280.409241) (xy 288.502067 -280.454205) (xy 288.524952 -280.503022) (xy 288.540484 -280.554651)
			(xy 288.548334 -280.607991) (xy 288.548826 -280.634948) (xy 288.548334 -280.661905) (xy 288.540484 -280.715245)
			(xy 288.524952 -280.766874) (xy 288.502067 -280.815691) (xy 288.472319 -280.860655) (xy 288.436341 -280.900809)
			(xy 288.394899 -280.935297) (xy 288.348878 -280.963383) (xy 288.299258 -280.98447) (xy 288.247097 -280.998106)
			(xy 288.193506 -281.004003) (xy 288.139627 -281.002034) (xy 288.086609 -280.992241) (xy 288.035582 -280.974833)
			(xy 287.987634 -280.950181) (xy 287.943786 -280.918811) (xy 287.904973 -280.88139) (xy 287.872021 -280.838717)
			(xy 287.845635 -280.7917) (xy 287.826375 -280.741343) (xy 287.814652 -280.688719) (xy 287.810717 -280.634948)
			(xy 281.004772 -280.634948) (xy 281.00428 -280.661905) (xy 280.99643 -280.715245) (xy 280.980898 -280.766874)
			(xy 280.958013 -280.815691) (xy 280.928265 -280.860655) (xy 280.892287 -280.900809) (xy 280.850845 -280.935297)
			(xy 280.804824 -280.963383) (xy 280.755204 -280.98447) (xy 280.703043 -280.998106) (xy 280.649452 -281.004003)
			(xy 280.595573 -281.002034) (xy 280.542555 -280.992241) (xy 280.491528 -280.974833) (xy 280.44358 -280.950181)
			(xy 280.399732 -280.918811) (xy 280.360919 -280.88139) (xy 280.327967 -280.838717) (xy 280.301581 -280.7917)
			(xy 280.282321 -280.741343) (xy 280.270598 -280.688719) (xy 280.266663 -280.634948) (xy 273.460972 -280.634948)
			(xy 273.46048 -280.661905) (xy 273.45263 -280.715245) (xy 273.437098 -280.766874) (xy 273.414213 -280.815691)
			(xy 273.384465 -280.860655) (xy 273.348487 -280.900809) (xy 273.307045 -280.935297) (xy 273.261024 -280.963383)
			(xy 273.211404 -280.98447) (xy 273.159243 -280.998106) (xy 273.105652 -281.004003) (xy 273.051773 -281.002034)
			(xy 272.998755 -280.992241) (xy 272.947728 -280.974833) (xy 272.89978 -280.950181) (xy 272.855932 -280.918811)
			(xy 272.817119 -280.88139) (xy 272.784167 -280.838717) (xy 272.757781 -280.7917) (xy 272.738521 -280.741343)
			(xy 272.726798 -280.688719) (xy 272.722863 -280.634948) (xy 265.916918 -280.634948) (xy 265.916426 -280.661905)
			(xy 265.908576 -280.715245) (xy 265.893044 -280.766874) (xy 265.870159 -280.815691) (xy 265.840411 -280.860655)
			(xy 265.804433 -280.900809) (xy 265.762991 -280.935297) (xy 265.71697 -280.963383) (xy 265.66735 -280.98447)
			(xy 265.615189 -280.998106) (xy 265.561598 -281.004003) (xy 265.507719 -281.002034) (xy 265.454701 -280.992241)
			(xy 265.403674 -280.974833) (xy 265.355726 -280.950181) (xy 265.311878 -280.918811) (xy 265.273065 -280.88139)
			(xy 265.240113 -280.838717) (xy 265.213727 -280.7917) (xy 265.194467 -280.741343) (xy 265.182744 -280.688719)
			(xy 265.178809 -280.634948) (xy 264.143998 -280.634948) (xy 264.143998 -281.485086) (xy 269.278877 -281.485086)
			(xy 269.282812 -281.431315) (xy 269.294535 -281.378691) (xy 269.313795 -281.328334) (xy 269.340181 -281.281317)
			(xy 269.373133 -281.238644) (xy 269.411946 -281.201223) (xy 269.455794 -281.169853) (xy 269.503742 -281.145201)
			(xy 269.554769 -281.127793) (xy 269.607787 -281.118) (xy 269.661666 -281.116031) (xy 269.715257 -281.121928)
			(xy 269.767418 -281.135564) (xy 269.817038 -281.156651) (xy 269.863059 -281.184737) (xy 269.904501 -281.219225)
			(xy 269.940479 -281.259379) (xy 269.970227 -281.304343) (xy 269.993112 -281.35316) (xy 270.008644 -281.404789)
			(xy 270.016494 -281.458129) (xy 270.016986 -281.485086) (xy 276.822931 -281.485086) (xy 276.826866 -281.431315)
			(xy 276.838589 -281.378691) (xy 276.857849 -281.328334) (xy 276.884235 -281.281317) (xy 276.917187 -281.238644)
			(xy 276.956 -281.201223) (xy 276.999848 -281.169853) (xy 277.047796 -281.145201) (xy 277.098823 -281.127793)
			(xy 277.151841 -281.118) (xy 277.20572 -281.116031) (xy 277.259311 -281.121928) (xy 277.311472 -281.135564)
			(xy 277.361092 -281.156651) (xy 277.407113 -281.184737) (xy 277.448555 -281.219225) (xy 277.484533 -281.259379)
			(xy 277.514281 -281.304343) (xy 277.537166 -281.35316) (xy 277.552698 -281.404789) (xy 277.560548 -281.458129)
			(xy 277.56104 -281.485086) (xy 284.366731 -281.485086) (xy 284.370666 -281.431315) (xy 284.382389 -281.378691)
			(xy 284.401649 -281.328334) (xy 284.428035 -281.281317) (xy 284.460987 -281.238644) (xy 284.4998 -281.201223)
			(xy 284.543648 -281.169853) (xy 284.591596 -281.145201) (xy 284.642623 -281.127793) (xy 284.695641 -281.118)
			(xy 284.74952 -281.116031) (xy 284.803111 -281.121928) (xy 284.855272 -281.135564) (xy 284.904892 -281.156651)
			(xy 284.950913 -281.184737) (xy 284.992355 -281.219225) (xy 285.028333 -281.259379) (xy 285.058081 -281.304343)
			(xy 285.080966 -281.35316) (xy 285.096498 -281.404789) (xy 285.104348 -281.458129) (xy 285.10484 -281.485086)
			(xy 291.910785 -281.485086) (xy 291.91472 -281.431315) (xy 291.926443 -281.378691) (xy 291.945703 -281.328334)
			(xy 291.972089 -281.281317) (xy 292.005041 -281.238644) (xy 292.043854 -281.201223) (xy 292.087702 -281.169853)
			(xy 292.13565 -281.145201) (xy 292.186677 -281.127793) (xy 292.239695 -281.118) (xy 292.293574 -281.116031)
			(xy 292.347165 -281.121928) (xy 292.399326 -281.135564) (xy 292.448946 -281.156651) (xy 292.494967 -281.184737)
			(xy 292.536409 -281.219225) (xy 292.572387 -281.259379) (xy 292.602135 -281.304343) (xy 292.62502 -281.35316)
			(xy 292.640552 -281.404789) (xy 292.648402 -281.458129) (xy 292.648894 -281.485086) (xy 292.648402 -281.512043)
			(xy 292.640552 -281.565383) (xy 292.62502 -281.617012) (xy 292.602135 -281.665829) (xy 292.572387 -281.710793)
			(xy 292.536409 -281.750947) (xy 292.494967 -281.785435) (xy 292.448946 -281.813521) (xy 292.399326 -281.834608)
			(xy 292.347165 -281.848244) (xy 292.293574 -281.854141) (xy 292.239695 -281.852172) (xy 292.186677 -281.842379)
			(xy 292.13565 -281.824971) (xy 292.087702 -281.800319) (xy 292.043854 -281.768949) (xy 292.005041 -281.731528)
			(xy 291.972089 -281.688855) (xy 291.945703 -281.641838) (xy 291.926443 -281.591481) (xy 291.91472 -281.538857)
			(xy 291.910785 -281.485086) (xy 285.10484 -281.485086) (xy 285.104348 -281.512043) (xy 285.096498 -281.565383)
			(xy 285.080966 -281.617012) (xy 285.058081 -281.665829) (xy 285.028333 -281.710793) (xy 284.992355 -281.750947)
			(xy 284.950913 -281.785435) (xy 284.904892 -281.813521) (xy 284.855272 -281.834608) (xy 284.803111 -281.848244)
			(xy 284.74952 -281.854141) (xy 284.695641 -281.852172) (xy 284.642623 -281.842379) (xy 284.591596 -281.824971)
			(xy 284.543648 -281.800319) (xy 284.4998 -281.768949) (xy 284.460987 -281.731528) (xy 284.428035 -281.688855)
			(xy 284.401649 -281.641838) (xy 284.382389 -281.591481) (xy 284.370666 -281.538857) (xy 284.366731 -281.485086)
			(xy 277.56104 -281.485086) (xy 277.560548 -281.512043) (xy 277.552698 -281.565383) (xy 277.537166 -281.617012)
			(xy 277.514281 -281.665829) (xy 277.484533 -281.710793) (xy 277.448555 -281.750947) (xy 277.407113 -281.785435)
			(xy 277.361092 -281.813521) (xy 277.311472 -281.834608) (xy 277.259311 -281.848244) (xy 277.20572 -281.854141)
			(xy 277.151841 -281.852172) (xy 277.098823 -281.842379) (xy 277.047796 -281.824971) (xy 276.999848 -281.800319)
			(xy 276.956 -281.768949) (xy 276.917187 -281.731528) (xy 276.884235 -281.688855) (xy 276.857849 -281.641838)
			(xy 276.838589 -281.591481) (xy 276.826866 -281.538857) (xy 276.822931 -281.485086) (xy 270.016986 -281.485086)
			(xy 270.016494 -281.512043) (xy 270.008644 -281.565383) (xy 269.993112 -281.617012) (xy 269.970227 -281.665829)
			(xy 269.940479 -281.710793) (xy 269.904501 -281.750947) (xy 269.863059 -281.785435) (xy 269.817038 -281.813521)
			(xy 269.767418 -281.834608) (xy 269.715257 -281.848244) (xy 269.661666 -281.854141) (xy 269.607787 -281.852172)
			(xy 269.554769 -281.842379) (xy 269.503742 -281.824971) (xy 269.455794 -281.800319) (xy 269.411946 -281.768949)
			(xy 269.373133 -281.731528) (xy 269.340181 -281.688855) (xy 269.313795 -281.641838) (xy 269.294535 -281.591481)
			(xy 269.282812 -281.538857) (xy 269.278877 -281.485086) (xy 264.143998 -281.485086) (xy 264.143998 -282.33497)
			(xy 265.178809 -282.33497) (xy 265.182744 -282.281199) (xy 265.194467 -282.228575) (xy 265.213727 -282.178218)
			(xy 265.240113 -282.131201) (xy 265.273065 -282.088528) (xy 265.311878 -282.051107) (xy 265.355726 -282.019737)
			(xy 265.403674 -281.995085) (xy 265.454701 -281.977677) (xy 265.507719 -281.967884) (xy 265.561598 -281.965915)
			(xy 265.615189 -281.971812) (xy 265.66735 -281.985448) (xy 265.71697 -282.006535) (xy 265.762991 -282.034621)
			(xy 265.804433 -282.069109) (xy 265.840411 -282.109263) (xy 265.870159 -282.154227) (xy 265.893044 -282.203044)
			(xy 265.908576 -282.254673) (xy 265.916426 -282.308013) (xy 265.916918 -282.33497) (xy 272.722863 -282.33497)
			(xy 272.726798 -282.281199) (xy 272.738521 -282.228575) (xy 272.757781 -282.178218) (xy 272.784167 -282.131201)
			(xy 272.817119 -282.088528) (xy 272.855932 -282.051107) (xy 272.89978 -282.019737) (xy 272.947728 -281.995085)
			(xy 272.998755 -281.977677) (xy 273.051773 -281.967884) (xy 273.105652 -281.965915) (xy 273.159243 -281.971812)
			(xy 273.211404 -281.985448) (xy 273.261024 -282.006535) (xy 273.307045 -282.034621) (xy 273.348487 -282.069109)
			(xy 273.384465 -282.109263) (xy 273.414213 -282.154227) (xy 273.437098 -282.203044) (xy 273.45263 -282.254673)
			(xy 273.46048 -282.308013) (xy 273.460972 -282.33497) (xy 280.266663 -282.33497) (xy 280.270598 -282.281199)
			(xy 280.282321 -282.228575) (xy 280.301581 -282.178218) (xy 280.327967 -282.131201) (xy 280.360919 -282.088528)
			(xy 280.399732 -282.051107) (xy 280.44358 -282.019737) (xy 280.491528 -281.995085) (xy 280.542555 -281.977677)
			(xy 280.595573 -281.967884) (xy 280.649452 -281.965915) (xy 280.703043 -281.971812) (xy 280.755204 -281.985448)
			(xy 280.804824 -282.006535) (xy 280.850845 -282.034621) (xy 280.892287 -282.069109) (xy 280.928265 -282.109263)
			(xy 280.958013 -282.154227) (xy 280.980898 -282.203044) (xy 280.99643 -282.254673) (xy 281.00428 -282.308013)
			(xy 281.004772 -282.33497) (xy 287.810717 -282.33497) (xy 287.814652 -282.281199) (xy 287.826375 -282.228575)
			(xy 287.845635 -282.178218) (xy 287.872021 -282.131201) (xy 287.904973 -282.088528) (xy 287.943786 -282.051107)
			(xy 287.987634 -282.019737) (xy 288.035582 -281.995085) (xy 288.086609 -281.977677) (xy 288.139627 -281.967884)
			(xy 288.193506 -281.965915) (xy 288.247097 -281.971812) (xy 288.299258 -281.985448) (xy 288.348878 -282.006535)
			(xy 288.394899 -282.034621) (xy 288.436341 -282.069109) (xy 288.472319 -282.109263) (xy 288.502067 -282.154227)
			(xy 288.524952 -282.203044) (xy 288.540484 -282.254673) (xy 288.548334 -282.308013) (xy 288.548826 -282.33497)
			(xy 288.548334 -282.361927) (xy 288.540484 -282.415267) (xy 288.524952 -282.466896) (xy 288.502067 -282.515713)
			(xy 288.472319 -282.560677) (xy 288.436341 -282.600831) (xy 288.394899 -282.635319) (xy 288.348878 -282.663405)
			(xy 288.299258 -282.684492) (xy 288.247097 -282.698128) (xy 288.193506 -282.704025) (xy 288.139627 -282.702056)
			(xy 288.086609 -282.692263) (xy 288.035582 -282.674855) (xy 287.987634 -282.650203) (xy 287.943786 -282.618833)
			(xy 287.904973 -282.581412) (xy 287.872021 -282.538739) (xy 287.845635 -282.491722) (xy 287.826375 -282.441365)
			(xy 287.814652 -282.388741) (xy 287.810717 -282.33497) (xy 281.004772 -282.33497) (xy 281.00428 -282.361927)
			(xy 280.99643 -282.415267) (xy 280.980898 -282.466896) (xy 280.958013 -282.515713) (xy 280.928265 -282.560677)
			(xy 280.892287 -282.600831) (xy 280.850845 -282.635319) (xy 280.804824 -282.663405) (xy 280.755204 -282.684492)
			(xy 280.703043 -282.698128) (xy 280.649452 -282.704025) (xy 280.595573 -282.702056) (xy 280.542555 -282.692263)
			(xy 280.491528 -282.674855) (xy 280.44358 -282.650203) (xy 280.399732 -282.618833) (xy 280.360919 -282.581412)
			(xy 280.327967 -282.538739) (xy 280.301581 -282.491722) (xy 280.282321 -282.441365) (xy 280.270598 -282.388741)
			(xy 280.266663 -282.33497) (xy 273.460972 -282.33497) (xy 273.46048 -282.361927) (xy 273.45263 -282.415267)
			(xy 273.437098 -282.466896) (xy 273.414213 -282.515713) (xy 273.384465 -282.560677) (xy 273.348487 -282.600831)
			(xy 273.307045 -282.635319) (xy 273.261024 -282.663405) (xy 273.211404 -282.684492) (xy 273.159243 -282.698128)
			(xy 273.105652 -282.704025) (xy 273.051773 -282.702056) (xy 272.998755 -282.692263) (xy 272.947728 -282.674855)
			(xy 272.89978 -282.650203) (xy 272.855932 -282.618833) (xy 272.817119 -282.581412) (xy 272.784167 -282.538739)
			(xy 272.757781 -282.491722) (xy 272.738521 -282.441365) (xy 272.726798 -282.388741) (xy 272.722863 -282.33497)
			(xy 265.916918 -282.33497) (xy 265.916426 -282.361927) (xy 265.908576 -282.415267) (xy 265.893044 -282.466896)
			(xy 265.870159 -282.515713) (xy 265.840411 -282.560677) (xy 265.804433 -282.600831) (xy 265.762991 -282.635319)
			(xy 265.71697 -282.663405) (xy 265.66735 -282.684492) (xy 265.615189 -282.698128) (xy 265.561598 -282.704025)
			(xy 265.507719 -282.702056) (xy 265.454701 -282.692263) (xy 265.403674 -282.674855) (xy 265.355726 -282.650203)
			(xy 265.311878 -282.618833) (xy 265.273065 -282.581412) (xy 265.240113 -282.538739) (xy 265.213727 -282.491722)
			(xy 265.194467 -282.441365) (xy 265.182744 -282.388741) (xy 265.178809 -282.33497) (xy 264.143998 -282.33497)
			(xy 264.143998 -283.185108) (xy 269.278877 -283.185108) (xy 269.282812 -283.131337) (xy 269.294535 -283.078713)
			(xy 269.313795 -283.028356) (xy 269.340181 -282.981339) (xy 269.373133 -282.938666) (xy 269.411946 -282.901245)
			(xy 269.455794 -282.869875) (xy 269.503742 -282.845223) (xy 269.554769 -282.827815) (xy 269.607787 -282.818022)
			(xy 269.661666 -282.816053) (xy 269.715257 -282.82195) (xy 269.767418 -282.835586) (xy 269.817038 -282.856673)
			(xy 269.863059 -282.884759) (xy 269.904501 -282.919247) (xy 269.940479 -282.959401) (xy 269.970227 -283.004365)
			(xy 269.993112 -283.053182) (xy 270.008644 -283.104811) (xy 270.016494 -283.158151) (xy 270.016986 -283.185108)
			(xy 276.822931 -283.185108) (xy 276.826866 -283.131337) (xy 276.838589 -283.078713) (xy 276.857849 -283.028356)
			(xy 276.884235 -282.981339) (xy 276.917187 -282.938666) (xy 276.956 -282.901245) (xy 276.999848 -282.869875)
			(xy 277.047796 -282.845223) (xy 277.098823 -282.827815) (xy 277.151841 -282.818022) (xy 277.20572 -282.816053)
			(xy 277.259311 -282.82195) (xy 277.311472 -282.835586) (xy 277.361092 -282.856673) (xy 277.407113 -282.884759)
			(xy 277.448555 -282.919247) (xy 277.484533 -282.959401) (xy 277.514281 -283.004365) (xy 277.537166 -283.053182)
			(xy 277.552698 -283.104811) (xy 277.560548 -283.158151) (xy 277.56104 -283.185108) (xy 284.366731 -283.185108)
			(xy 284.370666 -283.131337) (xy 284.382389 -283.078713) (xy 284.401649 -283.028356) (xy 284.428035 -282.981339)
			(xy 284.460987 -282.938666) (xy 284.4998 -282.901245) (xy 284.543648 -282.869875) (xy 284.591596 -282.845223)
			(xy 284.642623 -282.827815) (xy 284.695641 -282.818022) (xy 284.74952 -282.816053) (xy 284.803111 -282.82195)
			(xy 284.855272 -282.835586) (xy 284.904892 -282.856673) (xy 284.950913 -282.884759) (xy 284.992355 -282.919247)
			(xy 285.028333 -282.959401) (xy 285.058081 -283.004365) (xy 285.080966 -283.053182) (xy 285.096498 -283.104811)
			(xy 285.104348 -283.158151) (xy 285.10484 -283.185108) (xy 291.910785 -283.185108) (xy 291.91472 -283.131337)
			(xy 291.926443 -283.078713) (xy 291.945703 -283.028356) (xy 291.972089 -282.981339) (xy 292.005041 -282.938666)
			(xy 292.043854 -282.901245) (xy 292.087702 -282.869875) (xy 292.13565 -282.845223) (xy 292.186677 -282.827815)
			(xy 292.239695 -282.818022) (xy 292.293574 -282.816053) (xy 292.347165 -282.82195) (xy 292.399326 -282.835586)
			(xy 292.448946 -282.856673) (xy 292.494967 -282.884759) (xy 292.536409 -282.919247) (xy 292.572387 -282.959401)
			(xy 292.602135 -283.004365) (xy 292.62502 -283.053182) (xy 292.640552 -283.104811) (xy 292.648402 -283.158151)
			(xy 292.648894 -283.185108) (xy 292.648402 -283.212065) (xy 292.640552 -283.265405) (xy 292.62502 -283.317034)
			(xy 292.602135 -283.365851) (xy 292.572387 -283.410815) (xy 292.536409 -283.450969) (xy 292.494967 -283.485457)
			(xy 292.448946 -283.513543) (xy 292.399326 -283.53463) (xy 292.347165 -283.548266) (xy 292.293574 -283.554163)
			(xy 292.239695 -283.552194) (xy 292.186677 -283.542401) (xy 292.13565 -283.524993) (xy 292.087702 -283.500341)
			(xy 292.043854 -283.468971) (xy 292.005041 -283.43155) (xy 291.972089 -283.388877) (xy 291.945703 -283.34186)
			(xy 291.926443 -283.291503) (xy 291.91472 -283.238879) (xy 291.910785 -283.185108) (xy 285.10484 -283.185108)
			(xy 285.104348 -283.212065) (xy 285.096498 -283.265405) (xy 285.080966 -283.317034) (xy 285.058081 -283.365851)
			(xy 285.028333 -283.410815) (xy 284.992355 -283.450969) (xy 284.950913 -283.485457) (xy 284.904892 -283.513543)
			(xy 284.855272 -283.53463) (xy 284.803111 -283.548266) (xy 284.74952 -283.554163) (xy 284.695641 -283.552194)
			(xy 284.642623 -283.542401) (xy 284.591596 -283.524993) (xy 284.543648 -283.500341) (xy 284.4998 -283.468971)
			(xy 284.460987 -283.43155) (xy 284.428035 -283.388877) (xy 284.401649 -283.34186) (xy 284.382389 -283.291503)
			(xy 284.370666 -283.238879) (xy 284.366731 -283.185108) (xy 277.56104 -283.185108) (xy 277.560548 -283.212065)
			(xy 277.552698 -283.265405) (xy 277.537166 -283.317034) (xy 277.514281 -283.365851) (xy 277.484533 -283.410815)
			(xy 277.448555 -283.450969) (xy 277.407113 -283.485457) (xy 277.361092 -283.513543) (xy 277.311472 -283.53463)
			(xy 277.259311 -283.548266) (xy 277.20572 -283.554163) (xy 277.151841 -283.552194) (xy 277.098823 -283.542401)
			(xy 277.047796 -283.524993) (xy 276.999848 -283.500341) (xy 276.956 -283.468971) (xy 276.917187 -283.43155)
			(xy 276.884235 -283.388877) (xy 276.857849 -283.34186) (xy 276.838589 -283.291503) (xy 276.826866 -283.238879)
			(xy 276.822931 -283.185108) (xy 270.016986 -283.185108) (xy 270.016494 -283.212065) (xy 270.008644 -283.265405)
			(xy 269.993112 -283.317034) (xy 269.970227 -283.365851) (xy 269.940479 -283.410815) (xy 269.904501 -283.450969)
			(xy 269.863059 -283.485457) (xy 269.817038 -283.513543) (xy 269.767418 -283.53463) (xy 269.715257 -283.548266)
			(xy 269.661666 -283.554163) (xy 269.607787 -283.552194) (xy 269.554769 -283.542401) (xy 269.503742 -283.524993)
			(xy 269.455794 -283.500341) (xy 269.411946 -283.468971) (xy 269.373133 -283.43155) (xy 269.340181 -283.388877)
			(xy 269.313795 -283.34186) (xy 269.294535 -283.291503) (xy 269.282812 -283.238879) (xy 269.278877 -283.185108)
			(xy 264.143998 -283.185108) (xy 264.143998 -284.034992) (xy 265.178809 -284.034992) (xy 265.182744 -283.981221)
			(xy 265.194467 -283.928597) (xy 265.213727 -283.87824) (xy 265.240113 -283.831223) (xy 265.273065 -283.78855)
			(xy 265.311878 -283.751129) (xy 265.355726 -283.719759) (xy 265.403674 -283.695107) (xy 265.454701 -283.677699)
			(xy 265.507719 -283.667906) (xy 265.561598 -283.665937) (xy 265.615189 -283.671834) (xy 265.66735 -283.68547)
			(xy 265.71697 -283.706557) (xy 265.762991 -283.734643) (xy 265.804433 -283.769131) (xy 265.840411 -283.809285)
			(xy 265.870159 -283.854249) (xy 265.893044 -283.903066) (xy 265.908576 -283.954695) (xy 265.916426 -284.008035)
			(xy 265.916918 -284.034992) (xy 272.722863 -284.034992) (xy 272.726798 -283.981221) (xy 272.738521 -283.928597)
			(xy 272.757781 -283.87824) (xy 272.784167 -283.831223) (xy 272.817119 -283.78855) (xy 272.855932 -283.751129)
			(xy 272.89978 -283.719759) (xy 272.947728 -283.695107) (xy 272.998755 -283.677699) (xy 273.051773 -283.667906)
			(xy 273.105652 -283.665937) (xy 273.159243 -283.671834) (xy 273.211404 -283.68547) (xy 273.261024 -283.706557)
			(xy 273.307045 -283.734643) (xy 273.348487 -283.769131) (xy 273.384465 -283.809285) (xy 273.414213 -283.854249)
			(xy 273.437098 -283.903066) (xy 273.45263 -283.954695) (xy 273.46048 -284.008035) (xy 273.460972 -284.034992)
			(xy 280.266663 -284.034992) (xy 280.270598 -283.981221) (xy 280.282321 -283.928597) (xy 280.301581 -283.87824)
			(xy 280.327967 -283.831223) (xy 280.360919 -283.78855) (xy 280.399732 -283.751129) (xy 280.44358 -283.719759)
			(xy 280.491528 -283.695107) (xy 280.542555 -283.677699) (xy 280.595573 -283.667906) (xy 280.649452 -283.665937)
			(xy 280.703043 -283.671834) (xy 280.755204 -283.68547) (xy 280.804824 -283.706557) (xy 280.850845 -283.734643)
			(xy 280.892287 -283.769131) (xy 280.928265 -283.809285) (xy 280.958013 -283.854249) (xy 280.980898 -283.903066)
			(xy 280.99643 -283.954695) (xy 281.00428 -284.008035) (xy 281.004772 -284.034992) (xy 287.810717 -284.034992)
			(xy 287.814652 -283.981221) (xy 287.826375 -283.928597) (xy 287.845635 -283.87824) (xy 287.872021 -283.831223)
			(xy 287.904973 -283.78855) (xy 287.943786 -283.751129) (xy 287.987634 -283.719759) (xy 288.035582 -283.695107)
			(xy 288.086609 -283.677699) (xy 288.139627 -283.667906) (xy 288.193506 -283.665937) (xy 288.247097 -283.671834)
			(xy 288.299258 -283.68547) (xy 288.348878 -283.706557) (xy 288.394899 -283.734643) (xy 288.436341 -283.769131)
			(xy 288.472319 -283.809285) (xy 288.502067 -283.854249) (xy 288.524952 -283.903066) (xy 288.540484 -283.954695)
			(xy 288.548334 -284.008035) (xy 288.548826 -284.034992) (xy 288.548334 -284.061949) (xy 288.540484 -284.115289)
			(xy 288.524952 -284.166918) (xy 288.502067 -284.215735) (xy 288.472319 -284.260699) (xy 288.436341 -284.300853)
			(xy 288.394899 -284.335341) (xy 288.348878 -284.363427) (xy 288.299258 -284.384514) (xy 288.247097 -284.39815)
			(xy 288.193506 -284.404047) (xy 288.139627 -284.402078) (xy 288.086609 -284.392285) (xy 288.035582 -284.374877)
			(xy 287.987634 -284.350225) (xy 287.943786 -284.318855) (xy 287.904973 -284.281434) (xy 287.872021 -284.238761)
			(xy 287.845635 -284.191744) (xy 287.826375 -284.141387) (xy 287.814652 -284.088763) (xy 287.810717 -284.034992)
			(xy 281.004772 -284.034992) (xy 281.00428 -284.061949) (xy 280.99643 -284.115289) (xy 280.980898 -284.166918)
			(xy 280.958013 -284.215735) (xy 280.928265 -284.260699) (xy 280.892287 -284.300853) (xy 280.850845 -284.335341)
			(xy 280.804824 -284.363427) (xy 280.755204 -284.384514) (xy 280.703043 -284.39815) (xy 280.649452 -284.404047)
			(xy 280.595573 -284.402078) (xy 280.542555 -284.392285) (xy 280.491528 -284.374877) (xy 280.44358 -284.350225)
			(xy 280.399732 -284.318855) (xy 280.360919 -284.281434) (xy 280.327967 -284.238761) (xy 280.301581 -284.191744)
			(xy 280.282321 -284.141387) (xy 280.270598 -284.088763) (xy 280.266663 -284.034992) (xy 273.460972 -284.034992)
			(xy 273.46048 -284.061949) (xy 273.45263 -284.115289) (xy 273.437098 -284.166918) (xy 273.414213 -284.215735)
			(xy 273.384465 -284.260699) (xy 273.348487 -284.300853) (xy 273.307045 -284.335341) (xy 273.261024 -284.363427)
			(xy 273.211404 -284.384514) (xy 273.159243 -284.39815) (xy 273.105652 -284.404047) (xy 273.051773 -284.402078)
			(xy 272.998755 -284.392285) (xy 272.947728 -284.374877) (xy 272.89978 -284.350225) (xy 272.855932 -284.318855)
			(xy 272.817119 -284.281434) (xy 272.784167 -284.238761) (xy 272.757781 -284.191744) (xy 272.738521 -284.141387)
			(xy 272.726798 -284.088763) (xy 272.722863 -284.034992) (xy 265.916918 -284.034992) (xy 265.916426 -284.061949)
			(xy 265.908576 -284.115289) (xy 265.893044 -284.166918) (xy 265.870159 -284.215735) (xy 265.840411 -284.260699)
			(xy 265.804433 -284.300853) (xy 265.762991 -284.335341) (xy 265.71697 -284.363427) (xy 265.66735 -284.384514)
			(xy 265.615189 -284.39815) (xy 265.561598 -284.404047) (xy 265.507719 -284.402078) (xy 265.454701 -284.392285)
			(xy 265.403674 -284.374877) (xy 265.355726 -284.350225) (xy 265.311878 -284.318855) (xy 265.273065 -284.281434)
			(xy 265.240113 -284.238761) (xy 265.213727 -284.191744) (xy 265.194467 -284.141387) (xy 265.182744 -284.088763)
			(xy 265.178809 -284.034992) (xy 264.143998 -284.034992) (xy 264.143998 -284.88513) (xy 269.278877 -284.88513)
			(xy 269.282812 -284.831359) (xy 269.294535 -284.778735) (xy 269.313795 -284.728378) (xy 269.340181 -284.681361)
			(xy 269.373133 -284.638688) (xy 269.411946 -284.601267) (xy 269.455794 -284.569897) (xy 269.503742 -284.545245)
			(xy 269.554769 -284.527837) (xy 269.607787 -284.518044) (xy 269.661666 -284.516075) (xy 269.715257 -284.521972)
			(xy 269.767418 -284.535608) (xy 269.817038 -284.556695) (xy 269.863059 -284.584781) (xy 269.904501 -284.619269)
			(xy 269.940479 -284.659423) (xy 269.970227 -284.704387) (xy 269.993112 -284.753204) (xy 270.008644 -284.804833)
			(xy 270.016494 -284.858173) (xy 270.016986 -284.88513) (xy 276.822931 -284.88513) (xy 276.826866 -284.831359)
			(xy 276.838589 -284.778735) (xy 276.857849 -284.728378) (xy 276.884235 -284.681361) (xy 276.917187 -284.638688)
			(xy 276.956 -284.601267) (xy 276.999848 -284.569897) (xy 277.047796 -284.545245) (xy 277.098823 -284.527837)
			(xy 277.151841 -284.518044) (xy 277.20572 -284.516075) (xy 277.259311 -284.521972) (xy 277.311472 -284.535608)
			(xy 277.361092 -284.556695) (xy 277.407113 -284.584781) (xy 277.448555 -284.619269) (xy 277.484533 -284.659423)
			(xy 277.514281 -284.704387) (xy 277.537166 -284.753204) (xy 277.552698 -284.804833) (xy 277.560548 -284.858173)
			(xy 277.56104 -284.88513) (xy 284.366731 -284.88513) (xy 284.370666 -284.831359) (xy 284.382389 -284.778735)
			(xy 284.401649 -284.728378) (xy 284.428035 -284.681361) (xy 284.460987 -284.638688) (xy 284.4998 -284.601267)
			(xy 284.543648 -284.569897) (xy 284.591596 -284.545245) (xy 284.642623 -284.527837) (xy 284.695641 -284.518044)
			(xy 284.74952 -284.516075) (xy 284.803111 -284.521972) (xy 284.855272 -284.535608) (xy 284.904892 -284.556695)
			(xy 284.950913 -284.584781) (xy 284.992355 -284.619269) (xy 285.028333 -284.659423) (xy 285.058081 -284.704387)
			(xy 285.080966 -284.753204) (xy 285.096498 -284.804833) (xy 285.104348 -284.858173) (xy 285.10484 -284.88513)
			(xy 291.910785 -284.88513) (xy 291.91472 -284.831359) (xy 291.926443 -284.778735) (xy 291.945703 -284.728378)
			(xy 291.972089 -284.681361) (xy 292.005041 -284.638688) (xy 292.043854 -284.601267) (xy 292.087702 -284.569897)
			(xy 292.13565 -284.545245) (xy 292.186677 -284.527837) (xy 292.239695 -284.518044) (xy 292.293574 -284.516075)
			(xy 292.347165 -284.521972) (xy 292.399326 -284.535608) (xy 292.448946 -284.556695) (xy 292.494967 -284.584781)
			(xy 292.536409 -284.619269) (xy 292.572387 -284.659423) (xy 292.602135 -284.704387) (xy 292.62502 -284.753204)
			(xy 292.640552 -284.804833) (xy 292.648402 -284.858173) (xy 292.648894 -284.88513) (xy 292.648402 -284.912087)
			(xy 292.640552 -284.965427) (xy 292.62502 -285.017056) (xy 292.602135 -285.065873) (xy 292.572387 -285.110837)
			(xy 292.536409 -285.150991) (xy 292.494967 -285.185479) (xy 292.448946 -285.213565) (xy 292.399326 -285.234652)
			(xy 292.347165 -285.248288) (xy 292.293574 -285.254185) (xy 292.239695 -285.252216) (xy 292.186677 -285.242423)
			(xy 292.13565 -285.225015) (xy 292.087702 -285.200363) (xy 292.043854 -285.168993) (xy 292.005041 -285.131572)
			(xy 291.972089 -285.088899) (xy 291.945703 -285.041882) (xy 291.926443 -284.991525) (xy 291.91472 -284.938901)
			(xy 291.910785 -284.88513) (xy 285.10484 -284.88513) (xy 285.104348 -284.912087) (xy 285.096498 -284.965427)
			(xy 285.080966 -285.017056) (xy 285.058081 -285.065873) (xy 285.028333 -285.110837) (xy 284.992355 -285.150991)
			(xy 284.950913 -285.185479) (xy 284.904892 -285.213565) (xy 284.855272 -285.234652) (xy 284.803111 -285.248288)
			(xy 284.74952 -285.254185) (xy 284.695641 -285.252216) (xy 284.642623 -285.242423) (xy 284.591596 -285.225015)
			(xy 284.543648 -285.200363) (xy 284.4998 -285.168993) (xy 284.460987 -285.131572) (xy 284.428035 -285.088899)
			(xy 284.401649 -285.041882) (xy 284.382389 -284.991525) (xy 284.370666 -284.938901) (xy 284.366731 -284.88513)
			(xy 277.56104 -284.88513) (xy 277.560548 -284.912087) (xy 277.552698 -284.965427) (xy 277.537166 -285.017056)
			(xy 277.514281 -285.065873) (xy 277.484533 -285.110837) (xy 277.448555 -285.150991) (xy 277.407113 -285.185479)
			(xy 277.361092 -285.213565) (xy 277.311472 -285.234652) (xy 277.259311 -285.248288) (xy 277.20572 -285.254185)
			(xy 277.151841 -285.252216) (xy 277.098823 -285.242423) (xy 277.047796 -285.225015) (xy 276.999848 -285.200363)
			(xy 276.956 -285.168993) (xy 276.917187 -285.131572) (xy 276.884235 -285.088899) (xy 276.857849 -285.041882)
			(xy 276.838589 -284.991525) (xy 276.826866 -284.938901) (xy 276.822931 -284.88513) (xy 270.016986 -284.88513)
			(xy 270.016494 -284.912087) (xy 270.008644 -284.965427) (xy 269.993112 -285.017056) (xy 269.970227 -285.065873)
			(xy 269.940479 -285.110837) (xy 269.904501 -285.150991) (xy 269.863059 -285.185479) (xy 269.817038 -285.213565)
			(xy 269.767418 -285.234652) (xy 269.715257 -285.248288) (xy 269.661666 -285.254185) (xy 269.607787 -285.252216)
			(xy 269.554769 -285.242423) (xy 269.503742 -285.225015) (xy 269.455794 -285.200363) (xy 269.411946 -285.168993)
			(xy 269.373133 -285.131572) (xy 269.340181 -285.088899) (xy 269.313795 -285.041882) (xy 269.294535 -284.991525)
			(xy 269.282812 -284.938901) (xy 269.278877 -284.88513) (xy 264.143998 -284.88513) (xy 264.143998 -285.735014)
			(xy 265.178809 -285.735014) (xy 265.182744 -285.681243) (xy 265.194467 -285.628619) (xy 265.213727 -285.578262)
			(xy 265.240113 -285.531245) (xy 265.273065 -285.488572) (xy 265.311878 -285.451151) (xy 265.355726 -285.419781)
			(xy 265.403674 -285.395129) (xy 265.454701 -285.377721) (xy 265.507719 -285.367928) (xy 265.561598 -285.365959)
			(xy 265.615189 -285.371856) (xy 265.66735 -285.385492) (xy 265.71697 -285.406579) (xy 265.762991 -285.434665)
			(xy 265.804433 -285.469153) (xy 265.840411 -285.509307) (xy 265.870159 -285.554271) (xy 265.893044 -285.603088)
			(xy 265.908576 -285.654717) (xy 265.916426 -285.708057) (xy 265.916918 -285.735014) (xy 269.278877 -285.735014)
			(xy 269.282812 -285.681243) (xy 269.294535 -285.628619) (xy 269.313795 -285.578262) (xy 269.340181 -285.531245)
			(xy 269.373133 -285.488572) (xy 269.411946 -285.451151) (xy 269.455794 -285.419781) (xy 269.503742 -285.395129)
			(xy 269.554769 -285.377721) (xy 269.607787 -285.367928) (xy 269.661666 -285.365959) (xy 269.715257 -285.371856)
			(xy 269.767418 -285.385492) (xy 269.817038 -285.406579) (xy 269.863059 -285.434665) (xy 269.904501 -285.469153)
			(xy 269.940479 -285.509307) (xy 269.970227 -285.554271) (xy 269.993112 -285.603088) (xy 270.008644 -285.654717)
			(xy 270.016494 -285.708057) (xy 270.016986 -285.735014) (xy 272.722863 -285.735014) (xy 272.726798 -285.681243)
			(xy 272.738521 -285.628619) (xy 272.757781 -285.578262) (xy 272.784167 -285.531245) (xy 272.817119 -285.488572)
			(xy 272.855932 -285.451151) (xy 272.89978 -285.419781) (xy 272.947728 -285.395129) (xy 272.998755 -285.377721)
			(xy 273.051773 -285.367928) (xy 273.105652 -285.365959) (xy 273.159243 -285.371856) (xy 273.211404 -285.385492)
			(xy 273.261024 -285.406579) (xy 273.307045 -285.434665) (xy 273.348487 -285.469153) (xy 273.384465 -285.509307)
			(xy 273.414213 -285.554271) (xy 273.437098 -285.603088) (xy 273.45263 -285.654717) (xy 273.46048 -285.708057)
			(xy 273.460972 -285.735014) (xy 276.822931 -285.735014) (xy 276.826866 -285.681243) (xy 276.838589 -285.628619)
			(xy 276.857849 -285.578262) (xy 276.884235 -285.531245) (xy 276.917187 -285.488572) (xy 276.956 -285.451151)
			(xy 276.999848 -285.419781) (xy 277.047796 -285.395129) (xy 277.098823 -285.377721) (xy 277.151841 -285.367928)
			(xy 277.20572 -285.365959) (xy 277.259311 -285.371856) (xy 277.311472 -285.385492) (xy 277.361092 -285.406579)
			(xy 277.407113 -285.434665) (xy 277.448555 -285.469153) (xy 277.484533 -285.509307) (xy 277.514281 -285.554271)
			(xy 277.537166 -285.603088) (xy 277.552698 -285.654717) (xy 277.560548 -285.708057) (xy 277.56104 -285.735014)
			(xy 280.266663 -285.735014) (xy 280.270598 -285.681243) (xy 280.282321 -285.628619) (xy 280.301581 -285.578262)
			(xy 280.327967 -285.531245) (xy 280.360919 -285.488572) (xy 280.399732 -285.451151) (xy 280.44358 -285.419781)
			(xy 280.491528 -285.395129) (xy 280.542555 -285.377721) (xy 280.595573 -285.367928) (xy 280.649452 -285.365959)
			(xy 280.703043 -285.371856) (xy 280.755204 -285.385492) (xy 280.804824 -285.406579) (xy 280.850845 -285.434665)
			(xy 280.892287 -285.469153) (xy 280.928265 -285.509307) (xy 280.958013 -285.554271) (xy 280.980898 -285.603088)
			(xy 280.99643 -285.654717) (xy 281.00428 -285.708057) (xy 281.004772 -285.735014) (xy 284.366731 -285.735014)
			(xy 284.370666 -285.681243) (xy 284.382389 -285.628619) (xy 284.401649 -285.578262) (xy 284.428035 -285.531245)
			(xy 284.460987 -285.488572) (xy 284.4998 -285.451151) (xy 284.543648 -285.419781) (xy 284.591596 -285.395129)
			(xy 284.642623 -285.377721) (xy 284.695641 -285.367928) (xy 284.74952 -285.365959) (xy 284.803111 -285.371856)
			(xy 284.855272 -285.385492) (xy 284.904892 -285.406579) (xy 284.950913 -285.434665) (xy 284.992355 -285.469153)
			(xy 285.028333 -285.509307) (xy 285.058081 -285.554271) (xy 285.080966 -285.603088) (xy 285.096498 -285.654717)
			(xy 285.104348 -285.708057) (xy 285.10484 -285.735014) (xy 287.810717 -285.735014) (xy 287.814652 -285.681243)
			(xy 287.826375 -285.628619) (xy 287.845635 -285.578262) (xy 287.872021 -285.531245) (xy 287.904973 -285.488572)
			(xy 287.943786 -285.451151) (xy 287.987634 -285.419781) (xy 288.035582 -285.395129) (xy 288.086609 -285.377721)
			(xy 288.139627 -285.367928) (xy 288.193506 -285.365959) (xy 288.247097 -285.371856) (xy 288.299258 -285.385492)
			(xy 288.348878 -285.406579) (xy 288.394899 -285.434665) (xy 288.436341 -285.469153) (xy 288.472319 -285.509307)
			(xy 288.502067 -285.554271) (xy 288.524952 -285.603088) (xy 288.540484 -285.654717) (xy 288.548334 -285.708057)
			(xy 288.548826 -285.735014) (xy 291.910785 -285.735014) (xy 291.91472 -285.681243) (xy 291.926443 -285.628619)
			(xy 291.945703 -285.578262) (xy 291.972089 -285.531245) (xy 292.005041 -285.488572) (xy 292.043854 -285.451151)
			(xy 292.087702 -285.419781) (xy 292.13565 -285.395129) (xy 292.186677 -285.377721) (xy 292.239695 -285.367928)
			(xy 292.293574 -285.365959) (xy 292.347165 -285.371856) (xy 292.399326 -285.385492) (xy 292.448946 -285.406579)
			(xy 292.494967 -285.434665) (xy 292.536409 -285.469153) (xy 292.572387 -285.509307) (xy 292.602135 -285.554271)
			(xy 292.62502 -285.603088) (xy 292.640552 -285.654717) (xy 292.648402 -285.708057) (xy 292.648894 -285.735014)
			(xy 292.648402 -285.761971) (xy 292.640552 -285.815311) (xy 292.62502 -285.86694) (xy 292.602135 -285.915757)
			(xy 292.572387 -285.960721) (xy 292.536409 -286.000875) (xy 292.494967 -286.035363) (xy 292.448946 -286.063449)
			(xy 292.399326 -286.084536) (xy 292.347165 -286.098172) (xy 292.293574 -286.104069) (xy 292.239695 -286.1021)
			(xy 292.186677 -286.092307) (xy 292.13565 -286.074899) (xy 292.087702 -286.050247) (xy 292.043854 -286.018877)
			(xy 292.005041 -285.981456) (xy 291.972089 -285.938783) (xy 291.945703 -285.891766) (xy 291.926443 -285.841409)
			(xy 291.91472 -285.788785) (xy 291.910785 -285.735014) (xy 288.548826 -285.735014) (xy 288.548334 -285.761971)
			(xy 288.540484 -285.815311) (xy 288.524952 -285.86694) (xy 288.502067 -285.915757) (xy 288.472319 -285.960721)
			(xy 288.436341 -286.000875) (xy 288.394899 -286.035363) (xy 288.348878 -286.063449) (xy 288.299258 -286.084536)
			(xy 288.247097 -286.098172) (xy 288.193506 -286.104069) (xy 288.139627 -286.1021) (xy 288.086609 -286.092307)
			(xy 288.035582 -286.074899) (xy 287.987634 -286.050247) (xy 287.943786 -286.018877) (xy 287.904973 -285.981456)
			(xy 287.872021 -285.938783) (xy 287.845635 -285.891766) (xy 287.826375 -285.841409) (xy 287.814652 -285.788785)
			(xy 287.810717 -285.735014) (xy 285.10484 -285.735014) (xy 285.104348 -285.761971) (xy 285.096498 -285.815311)
			(xy 285.080966 -285.86694) (xy 285.058081 -285.915757) (xy 285.028333 -285.960721) (xy 284.992355 -286.000875)
			(xy 284.950913 -286.035363) (xy 284.904892 -286.063449) (xy 284.855272 -286.084536) (xy 284.803111 -286.098172)
			(xy 284.74952 -286.104069) (xy 284.695641 -286.1021) (xy 284.642623 -286.092307) (xy 284.591596 -286.074899)
			(xy 284.543648 -286.050247) (xy 284.4998 -286.018877) (xy 284.460987 -285.981456) (xy 284.428035 -285.938783)
			(xy 284.401649 -285.891766) (xy 284.382389 -285.841409) (xy 284.370666 -285.788785) (xy 284.366731 -285.735014)
			(xy 281.004772 -285.735014) (xy 281.00428 -285.761971) (xy 280.99643 -285.815311) (xy 280.980898 -285.86694)
			(xy 280.958013 -285.915757) (xy 280.928265 -285.960721) (xy 280.892287 -286.000875) (xy 280.850845 -286.035363)
			(xy 280.804824 -286.063449) (xy 280.755204 -286.084536) (xy 280.703043 -286.098172) (xy 280.649452 -286.104069)
			(xy 280.595573 -286.1021) (xy 280.542555 -286.092307) (xy 280.491528 -286.074899) (xy 280.44358 -286.050247)
			(xy 280.399732 -286.018877) (xy 280.360919 -285.981456) (xy 280.327967 -285.938783) (xy 280.301581 -285.891766)
			(xy 280.282321 -285.841409) (xy 280.270598 -285.788785) (xy 280.266663 -285.735014) (xy 277.56104 -285.735014)
			(xy 277.560548 -285.761971) (xy 277.552698 -285.815311) (xy 277.537166 -285.86694) (xy 277.514281 -285.915757)
			(xy 277.484533 -285.960721) (xy 277.448555 -286.000875) (xy 277.407113 -286.035363) (xy 277.361092 -286.063449)
			(xy 277.311472 -286.084536) (xy 277.259311 -286.098172) (xy 277.20572 -286.104069) (xy 277.151841 -286.1021)
			(xy 277.098823 -286.092307) (xy 277.047796 -286.074899) (xy 276.999848 -286.050247) (xy 276.956 -286.018877)
			(xy 276.917187 -285.981456) (xy 276.884235 -285.938783) (xy 276.857849 -285.891766) (xy 276.838589 -285.841409)
			(xy 276.826866 -285.788785) (xy 276.822931 -285.735014) (xy 273.460972 -285.735014) (xy 273.46048 -285.761971)
			(xy 273.45263 -285.815311) (xy 273.437098 -285.86694) (xy 273.414213 -285.915757) (xy 273.384465 -285.960721)
			(xy 273.348487 -286.000875) (xy 273.307045 -286.035363) (xy 273.261024 -286.063449) (xy 273.211404 -286.084536)
			(xy 273.159243 -286.098172) (xy 273.105652 -286.104069) (xy 273.051773 -286.1021) (xy 272.998755 -286.092307)
			(xy 272.947728 -286.074899) (xy 272.89978 -286.050247) (xy 272.855932 -286.018877) (xy 272.817119 -285.981456)
			(xy 272.784167 -285.938783) (xy 272.757781 -285.891766) (xy 272.738521 -285.841409) (xy 272.726798 -285.788785)
			(xy 272.722863 -285.735014) (xy 270.016986 -285.735014) (xy 270.016494 -285.761971) (xy 270.008644 -285.815311)
			(xy 269.993112 -285.86694) (xy 269.970227 -285.915757) (xy 269.940479 -285.960721) (xy 269.904501 -286.000875)
			(xy 269.863059 -286.035363) (xy 269.817038 -286.063449) (xy 269.767418 -286.084536) (xy 269.715257 -286.098172)
			(xy 269.661666 -286.104069) (xy 269.607787 -286.1021) (xy 269.554769 -286.092307) (xy 269.503742 -286.074899)
			(xy 269.455794 -286.050247) (xy 269.411946 -286.018877) (xy 269.373133 -285.981456) (xy 269.340181 -285.938783)
			(xy 269.313795 -285.891766) (xy 269.294535 -285.841409) (xy 269.282812 -285.788785) (xy 269.278877 -285.735014)
			(xy 265.916918 -285.735014) (xy 265.916426 -285.761971) (xy 265.908576 -285.815311) (xy 265.893044 -285.86694)
			(xy 265.870159 -285.915757) (xy 265.840411 -285.960721) (xy 265.804433 -286.000875) (xy 265.762991 -286.035363)
			(xy 265.71697 -286.063449) (xy 265.66735 -286.084536) (xy 265.615189 -286.098172) (xy 265.561598 -286.104069)
			(xy 265.507719 -286.1021) (xy 265.454701 -286.092307) (xy 265.403674 -286.074899) (xy 265.355726 -286.050247)
			(xy 265.311878 -286.018877) (xy 265.273065 -285.981456) (xy 265.240113 -285.938783) (xy 265.213727 -285.891766)
			(xy 265.194467 -285.841409) (xy 265.182744 -285.788785) (xy 265.178809 -285.735014) (xy 264.143998 -285.735014)
			(xy 264.143998 -286.585152) (xy 265.178809 -286.585152) (xy 265.182744 -286.531381) (xy 265.194467 -286.478757)
			(xy 265.213727 -286.4284) (xy 265.240113 -286.381383) (xy 265.273065 -286.33871) (xy 265.311878 -286.301289)
			(xy 265.355726 -286.269919) (xy 265.403674 -286.245267) (xy 265.454701 -286.227859) (xy 265.507719 -286.218066)
			(xy 265.561598 -286.216097) (xy 265.615189 -286.221994) (xy 265.66735 -286.23563) (xy 265.71697 -286.256717)
			(xy 265.762991 -286.284803) (xy 265.804433 -286.319291) (xy 265.840411 -286.359445) (xy 265.870159 -286.404409)
			(xy 265.893044 -286.453226) (xy 265.908576 -286.504855) (xy 265.916426 -286.558195) (xy 265.916918 -286.585152)
			(xy 272.722863 -286.585152) (xy 272.726798 -286.531381) (xy 272.738521 -286.478757) (xy 272.757781 -286.4284)
			(xy 272.784167 -286.381383) (xy 272.817119 -286.33871) (xy 272.855932 -286.301289) (xy 272.89978 -286.269919)
			(xy 272.947728 -286.245267) (xy 272.998755 -286.227859) (xy 273.051773 -286.218066) (xy 273.105652 -286.216097)
			(xy 273.159243 -286.221994) (xy 273.211404 -286.23563) (xy 273.261024 -286.256717) (xy 273.307045 -286.284803)
			(xy 273.348487 -286.319291) (xy 273.384465 -286.359445) (xy 273.414213 -286.404409) (xy 273.437098 -286.453226)
			(xy 273.45263 -286.504855) (xy 273.46048 -286.558195) (xy 273.460972 -286.585152) (xy 280.266663 -286.585152)
			(xy 280.270598 -286.531381) (xy 280.282321 -286.478757) (xy 280.301581 -286.4284) (xy 280.327967 -286.381383)
			(xy 280.360919 -286.33871) (xy 280.399732 -286.301289) (xy 280.44358 -286.269919) (xy 280.491528 -286.245267)
			(xy 280.542555 -286.227859) (xy 280.595573 -286.218066) (xy 280.649452 -286.216097) (xy 280.703043 -286.221994)
			(xy 280.755204 -286.23563) (xy 280.804824 -286.256717) (xy 280.850845 -286.284803) (xy 280.892287 -286.319291)
			(xy 280.928265 -286.359445) (xy 280.958013 -286.404409) (xy 280.980898 -286.453226) (xy 280.99643 -286.504855)
			(xy 281.00428 -286.558195) (xy 281.004772 -286.585152) (xy 287.810717 -286.585152) (xy 287.814652 -286.531381)
			(xy 287.826375 -286.478757) (xy 287.845635 -286.4284) (xy 287.872021 -286.381383) (xy 287.904973 -286.33871)
			(xy 287.943786 -286.301289) (xy 287.987634 -286.269919) (xy 288.035582 -286.245267) (xy 288.086609 -286.227859)
			(xy 288.139627 -286.218066) (xy 288.193506 -286.216097) (xy 288.247097 -286.221994) (xy 288.299258 -286.23563)
			(xy 288.348878 -286.256717) (xy 288.394899 -286.284803) (xy 288.436341 -286.319291) (xy 288.472319 -286.359445)
			(xy 288.502067 -286.404409) (xy 288.524952 -286.453226) (xy 288.540484 -286.504855) (xy 288.548334 -286.558195)
			(xy 288.548826 -286.585152) (xy 288.548334 -286.612109) (xy 288.540484 -286.665449) (xy 288.524952 -286.717078)
			(xy 288.502067 -286.765895) (xy 288.472319 -286.810859) (xy 288.436341 -286.851013) (xy 288.394899 -286.885501)
			(xy 288.348878 -286.913587) (xy 288.299258 -286.934674) (xy 288.247097 -286.94831) (xy 288.193506 -286.954207)
			(xy 288.139627 -286.952238) (xy 288.086609 -286.942445) (xy 288.035582 -286.925037) (xy 287.987634 -286.900385)
			(xy 287.943786 -286.869015) (xy 287.904973 -286.831594) (xy 287.872021 -286.788921) (xy 287.845635 -286.741904)
			(xy 287.826375 -286.691547) (xy 287.814652 -286.638923) (xy 287.810717 -286.585152) (xy 281.004772 -286.585152)
			(xy 281.00428 -286.612109) (xy 280.99643 -286.665449) (xy 280.980898 -286.717078) (xy 280.958013 -286.765895)
			(xy 280.928265 -286.810859) (xy 280.892287 -286.851013) (xy 280.850845 -286.885501) (xy 280.804824 -286.913587)
			(xy 280.755204 -286.934674) (xy 280.703043 -286.94831) (xy 280.649452 -286.954207) (xy 280.595573 -286.952238)
			(xy 280.542555 -286.942445) (xy 280.491528 -286.925037) (xy 280.44358 -286.900385) (xy 280.399732 -286.869015)
			(xy 280.360919 -286.831594) (xy 280.327967 -286.788921) (xy 280.301581 -286.741904) (xy 280.282321 -286.691547)
			(xy 280.270598 -286.638923) (xy 280.266663 -286.585152) (xy 273.460972 -286.585152) (xy 273.46048 -286.612109)
			(xy 273.45263 -286.665449) (xy 273.437098 -286.717078) (xy 273.414213 -286.765895) (xy 273.384465 -286.810859)
			(xy 273.348487 -286.851013) (xy 273.307045 -286.885501) (xy 273.261024 -286.913587) (xy 273.211404 -286.934674)
			(xy 273.159243 -286.94831) (xy 273.105652 -286.954207) (xy 273.051773 -286.952238) (xy 272.998755 -286.942445)
			(xy 272.947728 -286.925037) (xy 272.89978 -286.900385) (xy 272.855932 -286.869015) (xy 272.817119 -286.831594)
			(xy 272.784167 -286.788921) (xy 272.757781 -286.741904) (xy 272.738521 -286.691547) (xy 272.726798 -286.638923)
			(xy 272.722863 -286.585152) (xy 265.916918 -286.585152) (xy 265.916426 -286.612109) (xy 265.908576 -286.665449)
			(xy 265.893044 -286.717078) (xy 265.870159 -286.765895) (xy 265.840411 -286.810859) (xy 265.804433 -286.851013)
			(xy 265.762991 -286.885501) (xy 265.71697 -286.913587) (xy 265.66735 -286.934674) (xy 265.615189 -286.94831)
			(xy 265.561598 -286.954207) (xy 265.507719 -286.952238) (xy 265.454701 -286.942445) (xy 265.403674 -286.925037)
			(xy 265.355726 -286.900385) (xy 265.311878 -286.869015) (xy 265.273065 -286.831594) (xy 265.240113 -286.788921)
			(xy 265.213727 -286.741904) (xy 265.194467 -286.691547) (xy 265.182744 -286.638923) (xy 265.178809 -286.585152)
			(xy 264.143998 -286.585152) (xy 264.143998 -287.435036) (xy 269.278877 -287.435036) (xy 269.282812 -287.381265)
			(xy 269.294535 -287.328641) (xy 269.313795 -287.278284) (xy 269.340181 -287.231267) (xy 269.373133 -287.188594)
			(xy 269.411946 -287.151173) (xy 269.455794 -287.119803) (xy 269.503742 -287.095151) (xy 269.554769 -287.077743)
			(xy 269.607787 -287.06795) (xy 269.661666 -287.065981) (xy 269.715257 -287.071878) (xy 269.767418 -287.085514)
			(xy 269.817038 -287.106601) (xy 269.863059 -287.134687) (xy 269.904501 -287.169175) (xy 269.940479 -287.209329)
			(xy 269.970227 -287.254293) (xy 269.993112 -287.30311) (xy 270.008644 -287.354739) (xy 270.016494 -287.408079)
			(xy 270.016986 -287.435036) (xy 276.822931 -287.435036) (xy 276.826866 -287.381265) (xy 276.838589 -287.328641)
			(xy 276.857849 -287.278284) (xy 276.884235 -287.231267) (xy 276.917187 -287.188594) (xy 276.956 -287.151173)
			(xy 276.999848 -287.119803) (xy 277.047796 -287.095151) (xy 277.098823 -287.077743) (xy 277.151841 -287.06795)
			(xy 277.20572 -287.065981) (xy 277.259311 -287.071878) (xy 277.311472 -287.085514) (xy 277.361092 -287.106601)
			(xy 277.407113 -287.134687) (xy 277.448555 -287.169175) (xy 277.484533 -287.209329) (xy 277.514281 -287.254293)
			(xy 277.537166 -287.30311) (xy 277.552698 -287.354739) (xy 277.560548 -287.408079) (xy 277.56104 -287.435036)
			(xy 284.366731 -287.435036) (xy 284.370666 -287.381265) (xy 284.382389 -287.328641) (xy 284.401649 -287.278284)
			(xy 284.428035 -287.231267) (xy 284.460987 -287.188594) (xy 284.4998 -287.151173) (xy 284.543648 -287.119803)
			(xy 284.591596 -287.095151) (xy 284.642623 -287.077743) (xy 284.695641 -287.06795) (xy 284.74952 -287.065981)
			(xy 284.803111 -287.071878) (xy 284.855272 -287.085514) (xy 284.904892 -287.106601) (xy 284.950913 -287.134687)
			(xy 284.992355 -287.169175) (xy 285.028333 -287.209329) (xy 285.058081 -287.254293) (xy 285.080966 -287.30311)
			(xy 285.096498 -287.354739) (xy 285.104348 -287.408079) (xy 285.10484 -287.435036) (xy 291.910785 -287.435036)
			(xy 291.91472 -287.381265) (xy 291.926443 -287.328641) (xy 291.945703 -287.278284) (xy 291.972089 -287.231267)
			(xy 292.005041 -287.188594) (xy 292.043854 -287.151173) (xy 292.087702 -287.119803) (xy 292.13565 -287.095151)
			(xy 292.186677 -287.077743) (xy 292.239695 -287.06795) (xy 292.293574 -287.065981) (xy 292.347165 -287.071878)
			(xy 292.399326 -287.085514) (xy 292.448946 -287.106601) (xy 292.494967 -287.134687) (xy 292.536409 -287.169175)
			(xy 292.572387 -287.209329) (xy 292.602135 -287.254293) (xy 292.62502 -287.30311) (xy 292.640552 -287.354739)
			(xy 292.648402 -287.408079) (xy 292.648894 -287.435036) (xy 292.648402 -287.461993) (xy 292.640552 -287.515333)
			(xy 292.62502 -287.566962) (xy 292.602135 -287.615779) (xy 292.572387 -287.660743) (xy 292.536409 -287.700897)
			(xy 292.494967 -287.735385) (xy 292.448946 -287.763471) (xy 292.399326 -287.784558) (xy 292.347165 -287.798194)
			(xy 292.293574 -287.804091) (xy 292.239695 -287.802122) (xy 292.186677 -287.792329) (xy 292.13565 -287.774921)
			(xy 292.087702 -287.750269) (xy 292.043854 -287.718899) (xy 292.005041 -287.681478) (xy 291.972089 -287.638805)
			(xy 291.945703 -287.591788) (xy 291.926443 -287.541431) (xy 291.91472 -287.488807) (xy 291.910785 -287.435036)
			(xy 285.10484 -287.435036) (xy 285.104348 -287.461993) (xy 285.096498 -287.515333) (xy 285.080966 -287.566962)
			(xy 285.058081 -287.615779) (xy 285.028333 -287.660743) (xy 284.992355 -287.700897) (xy 284.950913 -287.735385)
			(xy 284.904892 -287.763471) (xy 284.855272 -287.784558) (xy 284.803111 -287.798194) (xy 284.74952 -287.804091)
			(xy 284.695641 -287.802122) (xy 284.642623 -287.792329) (xy 284.591596 -287.774921) (xy 284.543648 -287.750269)
			(xy 284.4998 -287.718899) (xy 284.460987 -287.681478) (xy 284.428035 -287.638805) (xy 284.401649 -287.591788)
			(xy 284.382389 -287.541431) (xy 284.370666 -287.488807) (xy 284.366731 -287.435036) (xy 277.56104 -287.435036)
			(xy 277.560548 -287.461993) (xy 277.552698 -287.515333) (xy 277.537166 -287.566962) (xy 277.514281 -287.615779)
			(xy 277.484533 -287.660743) (xy 277.448555 -287.700897) (xy 277.407113 -287.735385) (xy 277.361092 -287.763471)
			(xy 277.311472 -287.784558) (xy 277.259311 -287.798194) (xy 277.20572 -287.804091) (xy 277.151841 -287.802122)
			(xy 277.098823 -287.792329) (xy 277.047796 -287.774921) (xy 276.999848 -287.750269) (xy 276.956 -287.718899)
			(xy 276.917187 -287.681478) (xy 276.884235 -287.638805) (xy 276.857849 -287.591788) (xy 276.838589 -287.541431)
			(xy 276.826866 -287.488807) (xy 276.822931 -287.435036) (xy 270.016986 -287.435036) (xy 270.016494 -287.461993)
			(xy 270.008644 -287.515333) (xy 269.993112 -287.566962) (xy 269.970227 -287.615779) (xy 269.940479 -287.660743)
			(xy 269.904501 -287.700897) (xy 269.863059 -287.735385) (xy 269.817038 -287.763471) (xy 269.767418 -287.784558)
			(xy 269.715257 -287.798194) (xy 269.661666 -287.804091) (xy 269.607787 -287.802122) (xy 269.554769 -287.792329)
			(xy 269.503742 -287.774921) (xy 269.455794 -287.750269) (xy 269.411946 -287.718899) (xy 269.373133 -287.681478)
			(xy 269.340181 -287.638805) (xy 269.313795 -287.591788) (xy 269.294535 -287.541431) (xy 269.282812 -287.488807)
			(xy 269.278877 -287.435036) (xy 264.143998 -287.435036) (xy 264.143998 -288.285174) (xy 265.178809 -288.285174)
			(xy 265.182744 -288.231403) (xy 265.194467 -288.178779) (xy 265.213727 -288.128422) (xy 265.240113 -288.081405)
			(xy 265.273065 -288.038732) (xy 265.311878 -288.001311) (xy 265.355726 -287.969941) (xy 265.403674 -287.945289)
			(xy 265.454701 -287.927881) (xy 265.507719 -287.918088) (xy 265.561598 -287.916119) (xy 265.615189 -287.922016)
			(xy 265.66735 -287.935652) (xy 265.71697 -287.956739) (xy 265.762991 -287.984825) (xy 265.804433 -288.019313)
			(xy 265.840411 -288.059467) (xy 265.870159 -288.104431) (xy 265.893044 -288.153248) (xy 265.908576 -288.204877)
			(xy 265.916426 -288.258217) (xy 265.916918 -288.285174) (xy 272.722863 -288.285174) (xy 272.726798 -288.231403)
			(xy 272.738521 -288.178779) (xy 272.757781 -288.128422) (xy 272.784167 -288.081405) (xy 272.817119 -288.038732)
			(xy 272.855932 -288.001311) (xy 272.89978 -287.969941) (xy 272.947728 -287.945289) (xy 272.998755 -287.927881)
			(xy 273.051773 -287.918088) (xy 273.105652 -287.916119) (xy 273.159243 -287.922016) (xy 273.211404 -287.935652)
			(xy 273.261024 -287.956739) (xy 273.307045 -287.984825) (xy 273.348487 -288.019313) (xy 273.384465 -288.059467)
			(xy 273.414213 -288.104431) (xy 273.437098 -288.153248) (xy 273.45263 -288.204877) (xy 273.46048 -288.258217)
			(xy 273.460972 -288.285174) (xy 280.266663 -288.285174) (xy 280.270598 -288.231403) (xy 280.282321 -288.178779)
			(xy 280.301581 -288.128422) (xy 280.327967 -288.081405) (xy 280.360919 -288.038732) (xy 280.399732 -288.001311)
			(xy 280.44358 -287.969941) (xy 280.491528 -287.945289) (xy 280.542555 -287.927881) (xy 280.595573 -287.918088)
			(xy 280.649452 -287.916119) (xy 280.703043 -287.922016) (xy 280.755204 -287.935652) (xy 280.804824 -287.956739)
			(xy 280.850845 -287.984825) (xy 280.892287 -288.019313) (xy 280.928265 -288.059467) (xy 280.958013 -288.104431)
			(xy 280.980898 -288.153248) (xy 280.99643 -288.204877) (xy 281.00428 -288.258217) (xy 281.004772 -288.285174)
			(xy 287.810717 -288.285174) (xy 287.814652 -288.231403) (xy 287.826375 -288.178779) (xy 287.845635 -288.128422)
			(xy 287.872021 -288.081405) (xy 287.904973 -288.038732) (xy 287.943786 -288.001311) (xy 287.987634 -287.969941)
			(xy 288.035582 -287.945289) (xy 288.086609 -287.927881) (xy 288.139627 -287.918088) (xy 288.193506 -287.916119)
			(xy 288.247097 -287.922016) (xy 288.299258 -287.935652) (xy 288.348878 -287.956739) (xy 288.394899 -287.984825)
			(xy 288.436341 -288.019313) (xy 288.472319 -288.059467) (xy 288.502067 -288.104431) (xy 288.524952 -288.153248)
			(xy 288.540484 -288.204877) (xy 288.548334 -288.258217) (xy 288.548826 -288.285174) (xy 288.548334 -288.312131)
			(xy 288.540484 -288.365471) (xy 288.524952 -288.4171) (xy 288.502067 -288.465917) (xy 288.472319 -288.510881)
			(xy 288.436341 -288.551035) (xy 288.394899 -288.585523) (xy 288.348878 -288.613609) (xy 288.299258 -288.634696)
			(xy 288.247097 -288.648332) (xy 288.193506 -288.654229) (xy 288.139627 -288.65226) (xy 288.086609 -288.642467)
			(xy 288.035582 -288.625059) (xy 287.987634 -288.600407) (xy 287.943786 -288.569037) (xy 287.904973 -288.531616)
			(xy 287.872021 -288.488943) (xy 287.845635 -288.441926) (xy 287.826375 -288.391569) (xy 287.814652 -288.338945)
			(xy 287.810717 -288.285174) (xy 281.004772 -288.285174) (xy 281.00428 -288.312131) (xy 280.99643 -288.365471)
			(xy 280.980898 -288.4171) (xy 280.958013 -288.465917) (xy 280.928265 -288.510881) (xy 280.892287 -288.551035)
			(xy 280.850845 -288.585523) (xy 280.804824 -288.613609) (xy 280.755204 -288.634696) (xy 280.703043 -288.648332)
			(xy 280.649452 -288.654229) (xy 280.595573 -288.65226) (xy 280.542555 -288.642467) (xy 280.491528 -288.625059)
			(xy 280.44358 -288.600407) (xy 280.399732 -288.569037) (xy 280.360919 -288.531616) (xy 280.327967 -288.488943)
			(xy 280.301581 -288.441926) (xy 280.282321 -288.391569) (xy 280.270598 -288.338945) (xy 280.266663 -288.285174)
			(xy 273.460972 -288.285174) (xy 273.46048 -288.312131) (xy 273.45263 -288.365471) (xy 273.437098 -288.4171)
			(xy 273.414213 -288.465917) (xy 273.384465 -288.510881) (xy 273.348487 -288.551035) (xy 273.307045 -288.585523)
			(xy 273.261024 -288.613609) (xy 273.211404 -288.634696) (xy 273.159243 -288.648332) (xy 273.105652 -288.654229)
			(xy 273.051773 -288.65226) (xy 272.998755 -288.642467) (xy 272.947728 -288.625059) (xy 272.89978 -288.600407)
			(xy 272.855932 -288.569037) (xy 272.817119 -288.531616) (xy 272.784167 -288.488943) (xy 272.757781 -288.441926)
			(xy 272.738521 -288.391569) (xy 272.726798 -288.338945) (xy 272.722863 -288.285174) (xy 265.916918 -288.285174)
			(xy 265.916426 -288.312131) (xy 265.908576 -288.365471) (xy 265.893044 -288.4171) (xy 265.870159 -288.465917)
			(xy 265.840411 -288.510881) (xy 265.804433 -288.551035) (xy 265.762991 -288.585523) (xy 265.71697 -288.613609)
			(xy 265.66735 -288.634696) (xy 265.615189 -288.648332) (xy 265.561598 -288.654229) (xy 265.507719 -288.65226)
			(xy 265.454701 -288.642467) (xy 265.403674 -288.625059) (xy 265.355726 -288.600407) (xy 265.311878 -288.569037)
			(xy 265.273065 -288.531616) (xy 265.240113 -288.488943) (xy 265.213727 -288.441926) (xy 265.194467 -288.391569)
			(xy 265.182744 -288.338945) (xy 265.178809 -288.285174) (xy 264.143998 -288.285174) (xy 264.143998 -289.135058)
			(xy 269.278877 -289.135058) (xy 269.282812 -289.081287) (xy 269.294535 -289.028663) (xy 269.313795 -288.978306)
			(xy 269.340181 -288.931289) (xy 269.373133 -288.888616) (xy 269.411946 -288.851195) (xy 269.455794 -288.819825)
			(xy 269.503742 -288.795173) (xy 269.554769 -288.777765) (xy 269.607787 -288.767972) (xy 269.661666 -288.766003)
			(xy 269.715257 -288.7719) (xy 269.767418 -288.785536) (xy 269.817038 -288.806623) (xy 269.863059 -288.834709)
			(xy 269.904501 -288.869197) (xy 269.940479 -288.909351) (xy 269.970227 -288.954315) (xy 269.993112 -289.003132)
			(xy 270.008644 -289.054761) (xy 270.016494 -289.108101) (xy 270.016986 -289.135058) (xy 276.822931 -289.135058)
			(xy 276.826866 -289.081287) (xy 276.838589 -289.028663) (xy 276.857849 -288.978306) (xy 276.884235 -288.931289)
			(xy 276.917187 -288.888616) (xy 276.956 -288.851195) (xy 276.999848 -288.819825) (xy 277.047796 -288.795173)
			(xy 277.098823 -288.777765) (xy 277.151841 -288.767972) (xy 277.20572 -288.766003) (xy 277.259311 -288.7719)
			(xy 277.311472 -288.785536) (xy 277.361092 -288.806623) (xy 277.407113 -288.834709) (xy 277.448555 -288.869197)
			(xy 277.484533 -288.909351) (xy 277.514281 -288.954315) (xy 277.537166 -289.003132) (xy 277.552698 -289.054761)
			(xy 277.560548 -289.108101) (xy 277.56104 -289.135058) (xy 284.366731 -289.135058) (xy 284.370666 -289.081287)
			(xy 284.382389 -289.028663) (xy 284.401649 -288.978306) (xy 284.428035 -288.931289) (xy 284.460987 -288.888616)
			(xy 284.4998 -288.851195) (xy 284.543648 -288.819825) (xy 284.591596 -288.795173) (xy 284.642623 -288.777765)
			(xy 284.695641 -288.767972) (xy 284.74952 -288.766003) (xy 284.803111 -288.7719) (xy 284.855272 -288.785536)
			(xy 284.904892 -288.806623) (xy 284.950913 -288.834709) (xy 284.992355 -288.869197) (xy 285.028333 -288.909351)
			(xy 285.058081 -288.954315) (xy 285.080966 -289.003132) (xy 285.096498 -289.054761) (xy 285.104348 -289.108101)
			(xy 285.10484 -289.135058) (xy 291.910785 -289.135058) (xy 291.91472 -289.081287) (xy 291.926443 -289.028663)
			(xy 291.945703 -288.978306) (xy 291.972089 -288.931289) (xy 292.005041 -288.888616) (xy 292.043854 -288.851195)
			(xy 292.087702 -288.819825) (xy 292.13565 -288.795173) (xy 292.186677 -288.777765) (xy 292.239695 -288.767972)
			(xy 292.293574 -288.766003) (xy 292.347165 -288.7719) (xy 292.399326 -288.785536) (xy 292.448946 -288.806623)
			(xy 292.494967 -288.834709) (xy 292.536409 -288.869197) (xy 292.572387 -288.909351) (xy 292.602135 -288.954315)
			(xy 292.62502 -289.003132) (xy 292.640552 -289.054761) (xy 292.648402 -289.108101) (xy 292.648894 -289.135058)
			(xy 292.648402 -289.162015) (xy 292.640552 -289.215355) (xy 292.62502 -289.266984) (xy 292.602135 -289.315801)
			(xy 292.572387 -289.360765) (xy 292.536409 -289.400919) (xy 292.494967 -289.435407) (xy 292.448946 -289.463493)
			(xy 292.399326 -289.48458) (xy 292.347165 -289.498216) (xy 292.293574 -289.504113) (xy 292.239695 -289.502144)
			(xy 292.186677 -289.492351) (xy 292.13565 -289.474943) (xy 292.087702 -289.450291) (xy 292.043854 -289.418921)
			(xy 292.005041 -289.3815) (xy 291.972089 -289.338827) (xy 291.945703 -289.29181) (xy 291.926443 -289.241453)
			(xy 291.91472 -289.188829) (xy 291.910785 -289.135058) (xy 285.10484 -289.135058) (xy 285.104348 -289.162015)
			(xy 285.096498 -289.215355) (xy 285.080966 -289.266984) (xy 285.058081 -289.315801) (xy 285.028333 -289.360765)
			(xy 284.992355 -289.400919) (xy 284.950913 -289.435407) (xy 284.904892 -289.463493) (xy 284.855272 -289.48458)
			(xy 284.803111 -289.498216) (xy 284.74952 -289.504113) (xy 284.695641 -289.502144) (xy 284.642623 -289.492351)
			(xy 284.591596 -289.474943) (xy 284.543648 -289.450291) (xy 284.4998 -289.418921) (xy 284.460987 -289.3815)
			(xy 284.428035 -289.338827) (xy 284.401649 -289.29181) (xy 284.382389 -289.241453) (xy 284.370666 -289.188829)
			(xy 284.366731 -289.135058) (xy 277.56104 -289.135058) (xy 277.560548 -289.162015) (xy 277.552698 -289.215355)
			(xy 277.537166 -289.266984) (xy 277.514281 -289.315801) (xy 277.484533 -289.360765) (xy 277.448555 -289.400919)
			(xy 277.407113 -289.435407) (xy 277.361092 -289.463493) (xy 277.311472 -289.48458) (xy 277.259311 -289.498216)
			(xy 277.20572 -289.504113) (xy 277.151841 -289.502144) (xy 277.098823 -289.492351) (xy 277.047796 -289.474943)
			(xy 276.999848 -289.450291) (xy 276.956 -289.418921) (xy 276.917187 -289.3815) (xy 276.884235 -289.338827)
			(xy 276.857849 -289.29181) (xy 276.838589 -289.241453) (xy 276.826866 -289.188829) (xy 276.822931 -289.135058)
			(xy 270.016986 -289.135058) (xy 270.016494 -289.162015) (xy 270.008644 -289.215355) (xy 269.993112 -289.266984)
			(xy 269.970227 -289.315801) (xy 269.940479 -289.360765) (xy 269.904501 -289.400919) (xy 269.863059 -289.435407)
			(xy 269.817038 -289.463493) (xy 269.767418 -289.48458) (xy 269.715257 -289.498216) (xy 269.661666 -289.504113)
			(xy 269.607787 -289.502144) (xy 269.554769 -289.492351) (xy 269.503742 -289.474943) (xy 269.455794 -289.450291)
			(xy 269.411946 -289.418921) (xy 269.373133 -289.3815) (xy 269.340181 -289.338827) (xy 269.313795 -289.29181)
			(xy 269.294535 -289.241453) (xy 269.282812 -289.188829) (xy 269.278877 -289.135058) (xy 264.143998 -289.135058)
			(xy 264.143998 -289.985196) (xy 265.178809 -289.985196) (xy 265.182744 -289.931425) (xy 265.194467 -289.878801)
			(xy 265.213727 -289.828444) (xy 265.240113 -289.781427) (xy 265.273065 -289.738754) (xy 265.311878 -289.701333)
			(xy 265.355726 -289.669963) (xy 265.403674 -289.645311) (xy 265.454701 -289.627903) (xy 265.507719 -289.61811)
			(xy 265.561598 -289.616141) (xy 265.615189 -289.622038) (xy 265.66735 -289.635674) (xy 265.71697 -289.656761)
			(xy 265.762991 -289.684847) (xy 265.804433 -289.719335) (xy 265.840411 -289.759489) (xy 265.870159 -289.804453)
			(xy 265.893044 -289.85327) (xy 265.908576 -289.904899) (xy 265.916426 -289.958239) (xy 265.916918 -289.985196)
			(xy 272.722863 -289.985196) (xy 272.726798 -289.931425) (xy 272.738521 -289.878801) (xy 272.757781 -289.828444)
			(xy 272.784167 -289.781427) (xy 272.817119 -289.738754) (xy 272.855932 -289.701333) (xy 272.89978 -289.669963)
			(xy 272.947728 -289.645311) (xy 272.998755 -289.627903) (xy 273.051773 -289.61811) (xy 273.105652 -289.616141)
			(xy 273.159243 -289.622038) (xy 273.211404 -289.635674) (xy 273.261024 -289.656761) (xy 273.307045 -289.684847)
			(xy 273.348487 -289.719335) (xy 273.384465 -289.759489) (xy 273.414213 -289.804453) (xy 273.437098 -289.85327)
			(xy 273.45263 -289.904899) (xy 273.46048 -289.958239) (xy 273.460972 -289.985196) (xy 280.266663 -289.985196)
			(xy 280.270598 -289.931425) (xy 280.282321 -289.878801) (xy 280.301581 -289.828444) (xy 280.327967 -289.781427)
			(xy 280.360919 -289.738754) (xy 280.399732 -289.701333) (xy 280.44358 -289.669963) (xy 280.491528 -289.645311)
			(xy 280.542555 -289.627903) (xy 280.595573 -289.61811) (xy 280.649452 -289.616141) (xy 280.703043 -289.622038)
			(xy 280.755204 -289.635674) (xy 280.804824 -289.656761) (xy 280.850845 -289.684847) (xy 280.892287 -289.719335)
			(xy 280.928265 -289.759489) (xy 280.958013 -289.804453) (xy 280.980898 -289.85327) (xy 280.99643 -289.904899)
			(xy 281.00428 -289.958239) (xy 281.004772 -289.985196) (xy 287.810717 -289.985196) (xy 287.814652 -289.931425)
			(xy 287.826375 -289.878801) (xy 287.845635 -289.828444) (xy 287.872021 -289.781427) (xy 287.904973 -289.738754)
			(xy 287.943786 -289.701333) (xy 287.987634 -289.669963) (xy 288.035582 -289.645311) (xy 288.086609 -289.627903)
			(xy 288.139627 -289.61811) (xy 288.193506 -289.616141) (xy 288.247097 -289.622038) (xy 288.299258 -289.635674)
			(xy 288.348878 -289.656761) (xy 288.394899 -289.684847) (xy 288.436341 -289.719335) (xy 288.472319 -289.759489)
			(xy 288.502067 -289.804453) (xy 288.524952 -289.85327) (xy 288.540484 -289.904899) (xy 288.548334 -289.958239)
			(xy 288.548826 -289.985196) (xy 288.548334 -290.012153) (xy 288.540484 -290.065493) (xy 288.524952 -290.117122)
			(xy 288.502067 -290.165939) (xy 288.472319 -290.210903) (xy 288.436341 -290.251057) (xy 288.394899 -290.285545)
			(xy 288.348878 -290.313631) (xy 288.299258 -290.334718) (xy 288.247097 -290.348354) (xy 288.193506 -290.354251)
			(xy 288.139627 -290.352282) (xy 288.086609 -290.342489) (xy 288.035582 -290.325081) (xy 287.987634 -290.300429)
			(xy 287.943786 -290.269059) (xy 287.904973 -290.231638) (xy 287.872021 -290.188965) (xy 287.845635 -290.141948)
			(xy 287.826375 -290.091591) (xy 287.814652 -290.038967) (xy 287.810717 -289.985196) (xy 281.004772 -289.985196)
			(xy 281.00428 -290.012153) (xy 280.99643 -290.065493) (xy 280.980898 -290.117122) (xy 280.958013 -290.165939)
			(xy 280.928265 -290.210903) (xy 280.892287 -290.251057) (xy 280.850845 -290.285545) (xy 280.804824 -290.313631)
			(xy 280.755204 -290.334718) (xy 280.703043 -290.348354) (xy 280.649452 -290.354251) (xy 280.595573 -290.352282)
			(xy 280.542555 -290.342489) (xy 280.491528 -290.325081) (xy 280.44358 -290.300429) (xy 280.399732 -290.269059)
			(xy 280.360919 -290.231638) (xy 280.327967 -290.188965) (xy 280.301581 -290.141948) (xy 280.282321 -290.091591)
			(xy 280.270598 -290.038967) (xy 280.266663 -289.985196) (xy 273.460972 -289.985196) (xy 273.46048 -290.012153)
			(xy 273.45263 -290.065493) (xy 273.437098 -290.117122) (xy 273.414213 -290.165939) (xy 273.384465 -290.210903)
			(xy 273.348487 -290.251057) (xy 273.307045 -290.285545) (xy 273.261024 -290.313631) (xy 273.211404 -290.334718)
			(xy 273.159243 -290.348354) (xy 273.105652 -290.354251) (xy 273.051773 -290.352282) (xy 272.998755 -290.342489)
			(xy 272.947728 -290.325081) (xy 272.89978 -290.300429) (xy 272.855932 -290.269059) (xy 272.817119 -290.231638)
			(xy 272.784167 -290.188965) (xy 272.757781 -290.141948) (xy 272.738521 -290.091591) (xy 272.726798 -290.038967)
			(xy 272.722863 -289.985196) (xy 265.916918 -289.985196) (xy 265.916426 -290.012153) (xy 265.908576 -290.065493)
			(xy 265.893044 -290.117122) (xy 265.870159 -290.165939) (xy 265.840411 -290.210903) (xy 265.804433 -290.251057)
			(xy 265.762991 -290.285545) (xy 265.71697 -290.313631) (xy 265.66735 -290.334718) (xy 265.615189 -290.348354)
			(xy 265.561598 -290.354251) (xy 265.507719 -290.352282) (xy 265.454701 -290.342489) (xy 265.403674 -290.325081)
			(xy 265.355726 -290.300429) (xy 265.311878 -290.269059) (xy 265.273065 -290.231638) (xy 265.240113 -290.188965)
			(xy 265.213727 -290.141948) (xy 265.194467 -290.091591) (xy 265.182744 -290.038967) (xy 265.178809 -289.985196)
			(xy 264.143998 -289.985196) (xy 264.143998 -290.83508) (xy 269.278877 -290.83508) (xy 269.282812 -290.781309)
			(xy 269.294535 -290.728685) (xy 269.313795 -290.678328) (xy 269.340181 -290.631311) (xy 269.373133 -290.588638)
			(xy 269.411946 -290.551217) (xy 269.455794 -290.519847) (xy 269.503742 -290.495195) (xy 269.554769 -290.477787)
			(xy 269.607787 -290.467994) (xy 269.661666 -290.466025) (xy 269.715257 -290.471922) (xy 269.767418 -290.485558)
			(xy 269.817038 -290.506645) (xy 269.863059 -290.534731) (xy 269.904501 -290.569219) (xy 269.940479 -290.609373)
			(xy 269.970227 -290.654337) (xy 269.993112 -290.703154) (xy 270.008644 -290.754783) (xy 270.016494 -290.808123)
			(xy 270.016986 -290.83508) (xy 276.822931 -290.83508) (xy 276.826866 -290.781309) (xy 276.838589 -290.728685)
			(xy 276.857849 -290.678328) (xy 276.884235 -290.631311) (xy 276.917187 -290.588638) (xy 276.956 -290.551217)
			(xy 276.999848 -290.519847) (xy 277.047796 -290.495195) (xy 277.098823 -290.477787) (xy 277.151841 -290.467994)
			(xy 277.20572 -290.466025) (xy 277.259311 -290.471922) (xy 277.311472 -290.485558) (xy 277.361092 -290.506645)
			(xy 277.407113 -290.534731) (xy 277.448555 -290.569219) (xy 277.484533 -290.609373) (xy 277.514281 -290.654337)
			(xy 277.537166 -290.703154) (xy 277.552698 -290.754783) (xy 277.560548 -290.808123) (xy 277.56104 -290.83508)
			(xy 284.366731 -290.83508) (xy 284.370666 -290.781309) (xy 284.382389 -290.728685) (xy 284.401649 -290.678328)
			(xy 284.428035 -290.631311) (xy 284.460987 -290.588638) (xy 284.4998 -290.551217) (xy 284.543648 -290.519847)
			(xy 284.591596 -290.495195) (xy 284.642623 -290.477787) (xy 284.695641 -290.467994) (xy 284.74952 -290.466025)
			(xy 284.803111 -290.471922) (xy 284.855272 -290.485558) (xy 284.904892 -290.506645) (xy 284.950913 -290.534731)
			(xy 284.992355 -290.569219) (xy 285.028333 -290.609373) (xy 285.058081 -290.654337) (xy 285.080966 -290.703154)
			(xy 285.096498 -290.754783) (xy 285.104348 -290.808123) (xy 285.10484 -290.83508) (xy 291.910785 -290.83508)
			(xy 291.91472 -290.781309) (xy 291.926443 -290.728685) (xy 291.945703 -290.678328) (xy 291.972089 -290.631311)
			(xy 292.005041 -290.588638) (xy 292.043854 -290.551217) (xy 292.087702 -290.519847) (xy 292.13565 -290.495195)
			(xy 292.186677 -290.477787) (xy 292.239695 -290.467994) (xy 292.293574 -290.466025) (xy 292.347165 -290.471922)
			(xy 292.399326 -290.485558) (xy 292.448946 -290.506645) (xy 292.494967 -290.534731) (xy 292.536409 -290.569219)
			(xy 292.572387 -290.609373) (xy 292.602135 -290.654337) (xy 292.62502 -290.703154) (xy 292.640552 -290.754783)
			(xy 292.648402 -290.808123) (xy 292.648894 -290.83508) (xy 292.648402 -290.862037) (xy 292.640552 -290.915377)
			(xy 292.62502 -290.967006) (xy 292.602135 -291.015823) (xy 292.572387 -291.060787) (xy 292.536409 -291.100941)
			(xy 292.494967 -291.135429) (xy 292.448946 -291.163515) (xy 292.399326 -291.184602) (xy 292.347165 -291.198238)
			(xy 292.293574 -291.204135) (xy 292.239695 -291.202166) (xy 292.186677 -291.192373) (xy 292.13565 -291.174965)
			(xy 292.087702 -291.150313) (xy 292.043854 -291.118943) (xy 292.005041 -291.081522) (xy 291.972089 -291.038849)
			(xy 291.945703 -290.991832) (xy 291.926443 -290.941475) (xy 291.91472 -290.888851) (xy 291.910785 -290.83508)
			(xy 285.10484 -290.83508) (xy 285.104348 -290.862037) (xy 285.096498 -290.915377) (xy 285.080966 -290.967006)
			(xy 285.058081 -291.015823) (xy 285.028333 -291.060787) (xy 284.992355 -291.100941) (xy 284.950913 -291.135429)
			(xy 284.904892 -291.163515) (xy 284.855272 -291.184602) (xy 284.803111 -291.198238) (xy 284.74952 -291.204135)
			(xy 284.695641 -291.202166) (xy 284.642623 -291.192373) (xy 284.591596 -291.174965) (xy 284.543648 -291.150313)
			(xy 284.4998 -291.118943) (xy 284.460987 -291.081522) (xy 284.428035 -291.038849) (xy 284.401649 -290.991832)
			(xy 284.382389 -290.941475) (xy 284.370666 -290.888851) (xy 284.366731 -290.83508) (xy 277.56104 -290.83508)
			(xy 277.560548 -290.862037) (xy 277.552698 -290.915377) (xy 277.537166 -290.967006) (xy 277.514281 -291.015823)
			(xy 277.484533 -291.060787) (xy 277.448555 -291.100941) (xy 277.407113 -291.135429) (xy 277.361092 -291.163515)
			(xy 277.311472 -291.184602) (xy 277.259311 -291.198238) (xy 277.20572 -291.204135) (xy 277.151841 -291.202166)
			(xy 277.098823 -291.192373) (xy 277.047796 -291.174965) (xy 276.999848 -291.150313) (xy 276.956 -291.118943)
			(xy 276.917187 -291.081522) (xy 276.884235 -291.038849) (xy 276.857849 -290.991832) (xy 276.838589 -290.941475)
			(xy 276.826866 -290.888851) (xy 276.822931 -290.83508) (xy 270.016986 -290.83508) (xy 270.016494 -290.862037)
			(xy 270.008644 -290.915377) (xy 269.993112 -290.967006) (xy 269.970227 -291.015823) (xy 269.940479 -291.060787)
			(xy 269.904501 -291.100941) (xy 269.863059 -291.135429) (xy 269.817038 -291.163515) (xy 269.767418 -291.184602)
			(xy 269.715257 -291.198238) (xy 269.661666 -291.204135) (xy 269.607787 -291.202166) (xy 269.554769 -291.192373)
			(xy 269.503742 -291.174965) (xy 269.455794 -291.150313) (xy 269.411946 -291.118943) (xy 269.373133 -291.081522)
			(xy 269.340181 -291.038849) (xy 269.313795 -290.991832) (xy 269.294535 -290.941475) (xy 269.282812 -290.888851)
			(xy 269.278877 -290.83508) (xy 264.143998 -290.83508) (xy 264.143998 -291.684964) (xy 265.178809 -291.684964)
			(xy 265.182744 -291.631193) (xy 265.194467 -291.578569) (xy 265.213727 -291.528212) (xy 265.240113 -291.481195)
			(xy 265.273065 -291.438522) (xy 265.311878 -291.401101) (xy 265.355726 -291.369731) (xy 265.403674 -291.345079)
			(xy 265.454701 -291.327671) (xy 265.507719 -291.317878) (xy 265.561598 -291.315909) (xy 265.615189 -291.321806)
			(xy 265.66735 -291.335442) (xy 265.71697 -291.356529) (xy 265.762991 -291.384615) (xy 265.804433 -291.419103)
			(xy 265.840411 -291.459257) (xy 265.870159 -291.504221) (xy 265.893044 -291.553038) (xy 265.908576 -291.604667)
			(xy 265.916426 -291.658007) (xy 265.916918 -291.684964) (xy 272.722863 -291.684964) (xy 272.726798 -291.631193)
			(xy 272.738521 -291.578569) (xy 272.757781 -291.528212) (xy 272.784167 -291.481195) (xy 272.817119 -291.438522)
			(xy 272.855932 -291.401101) (xy 272.89978 -291.369731) (xy 272.947728 -291.345079) (xy 272.998755 -291.327671)
			(xy 273.051773 -291.317878) (xy 273.105652 -291.315909) (xy 273.159243 -291.321806) (xy 273.211404 -291.335442)
			(xy 273.261024 -291.356529) (xy 273.307045 -291.384615) (xy 273.348487 -291.419103) (xy 273.384465 -291.459257)
			(xy 273.414213 -291.504221) (xy 273.437098 -291.553038) (xy 273.45263 -291.604667) (xy 273.46048 -291.658007)
			(xy 273.460972 -291.684964) (xy 280.266663 -291.684964) (xy 280.270598 -291.631193) (xy 280.282321 -291.578569)
			(xy 280.301581 -291.528212) (xy 280.327967 -291.481195) (xy 280.360919 -291.438522) (xy 280.399732 -291.401101)
			(xy 280.44358 -291.369731) (xy 280.491528 -291.345079) (xy 280.542555 -291.327671) (xy 280.595573 -291.317878)
			(xy 280.649452 -291.315909) (xy 280.703043 -291.321806) (xy 280.755204 -291.335442) (xy 280.804824 -291.356529)
			(xy 280.850845 -291.384615) (xy 280.892287 -291.419103) (xy 280.928265 -291.459257) (xy 280.958013 -291.504221)
			(xy 280.980898 -291.553038) (xy 280.99643 -291.604667) (xy 281.00428 -291.658007) (xy 281.004772 -291.684964)
			(xy 287.810717 -291.684964) (xy 287.814652 -291.631193) (xy 287.826375 -291.578569) (xy 287.845635 -291.528212)
			(xy 287.872021 -291.481195) (xy 287.904973 -291.438522) (xy 287.943786 -291.401101) (xy 287.987634 -291.369731)
			(xy 288.035582 -291.345079) (xy 288.086609 -291.327671) (xy 288.139627 -291.317878) (xy 288.193506 -291.315909)
			(xy 288.247097 -291.321806) (xy 288.299258 -291.335442) (xy 288.348878 -291.356529) (xy 288.394899 -291.384615)
			(xy 288.436341 -291.419103) (xy 288.472319 -291.459257) (xy 288.502067 -291.504221) (xy 288.524952 -291.553038)
			(xy 288.540484 -291.604667) (xy 288.548334 -291.658007) (xy 288.548826 -291.684964) (xy 288.548334 -291.711921)
			(xy 288.540484 -291.765261) (xy 288.524952 -291.81689) (xy 288.502067 -291.865707) (xy 288.472319 -291.910671)
			(xy 288.436341 -291.950825) (xy 288.394899 -291.985313) (xy 288.348878 -292.013399) (xy 288.299258 -292.034486)
			(xy 288.247097 -292.048122) (xy 288.193506 -292.054019) (xy 288.139627 -292.05205) (xy 288.086609 -292.042257)
			(xy 288.035582 -292.024849) (xy 287.987634 -292.000197) (xy 287.943786 -291.968827) (xy 287.904973 -291.931406)
			(xy 287.872021 -291.888733) (xy 287.845635 -291.841716) (xy 287.826375 -291.791359) (xy 287.814652 -291.738735)
			(xy 287.810717 -291.684964) (xy 281.004772 -291.684964) (xy 281.00428 -291.711921) (xy 280.99643 -291.765261)
			(xy 280.980898 -291.81689) (xy 280.958013 -291.865707) (xy 280.928265 -291.910671) (xy 280.892287 -291.950825)
			(xy 280.850845 -291.985313) (xy 280.804824 -292.013399) (xy 280.755204 -292.034486) (xy 280.703043 -292.048122)
			(xy 280.649452 -292.054019) (xy 280.595573 -292.05205) (xy 280.542555 -292.042257) (xy 280.491528 -292.024849)
			(xy 280.44358 -292.000197) (xy 280.399732 -291.968827) (xy 280.360919 -291.931406) (xy 280.327967 -291.888733)
			(xy 280.301581 -291.841716) (xy 280.282321 -291.791359) (xy 280.270598 -291.738735) (xy 280.266663 -291.684964)
			(xy 273.460972 -291.684964) (xy 273.46048 -291.711921) (xy 273.45263 -291.765261) (xy 273.437098 -291.81689)
			(xy 273.414213 -291.865707) (xy 273.384465 -291.910671) (xy 273.348487 -291.950825) (xy 273.307045 -291.985313)
			(xy 273.261024 -292.013399) (xy 273.211404 -292.034486) (xy 273.159243 -292.048122) (xy 273.105652 -292.054019)
			(xy 273.051773 -292.05205) (xy 272.998755 -292.042257) (xy 272.947728 -292.024849) (xy 272.89978 -292.000197)
			(xy 272.855932 -291.968827) (xy 272.817119 -291.931406) (xy 272.784167 -291.888733) (xy 272.757781 -291.841716)
			(xy 272.738521 -291.791359) (xy 272.726798 -291.738735) (xy 272.722863 -291.684964) (xy 265.916918 -291.684964)
			(xy 265.916426 -291.711921) (xy 265.908576 -291.765261) (xy 265.893044 -291.81689) (xy 265.870159 -291.865707)
			(xy 265.840411 -291.910671) (xy 265.804433 -291.950825) (xy 265.762991 -291.985313) (xy 265.71697 -292.013399)
			(xy 265.66735 -292.034486) (xy 265.615189 -292.048122) (xy 265.561598 -292.054019) (xy 265.507719 -292.05205)
			(xy 265.454701 -292.042257) (xy 265.403674 -292.024849) (xy 265.355726 -292.000197) (xy 265.311878 -291.968827)
			(xy 265.273065 -291.931406) (xy 265.240113 -291.888733) (xy 265.213727 -291.841716) (xy 265.194467 -291.791359)
			(xy 265.182744 -291.738735) (xy 265.178809 -291.684964) (xy 264.143998 -291.684964) (xy 264.143998 -292.535102)
			(xy 269.278877 -292.535102) (xy 269.282812 -292.481331) (xy 269.294535 -292.428707) (xy 269.313795 -292.37835)
			(xy 269.340181 -292.331333) (xy 269.373133 -292.28866) (xy 269.411946 -292.251239) (xy 269.455794 -292.219869)
			(xy 269.503742 -292.195217) (xy 269.554769 -292.177809) (xy 269.607787 -292.168016) (xy 269.661666 -292.166047)
			(xy 269.715257 -292.171944) (xy 269.767418 -292.18558) (xy 269.817038 -292.206667) (xy 269.863059 -292.234753)
			(xy 269.904501 -292.269241) (xy 269.940479 -292.309395) (xy 269.970227 -292.354359) (xy 269.993112 -292.403176)
			(xy 270.008644 -292.454805) (xy 270.016494 -292.508145) (xy 270.016986 -292.535102) (xy 276.822931 -292.535102)
			(xy 276.826866 -292.481331) (xy 276.838589 -292.428707) (xy 276.857849 -292.37835) (xy 276.884235 -292.331333)
			(xy 276.917187 -292.28866) (xy 276.956 -292.251239) (xy 276.999848 -292.219869) (xy 277.047796 -292.195217)
			(xy 277.098823 -292.177809) (xy 277.151841 -292.168016) (xy 277.20572 -292.166047) (xy 277.259311 -292.171944)
			(xy 277.311472 -292.18558) (xy 277.361092 -292.206667) (xy 277.407113 -292.234753) (xy 277.448555 -292.269241)
			(xy 277.484533 -292.309395) (xy 277.514281 -292.354359) (xy 277.537166 -292.403176) (xy 277.552698 -292.454805)
			(xy 277.560548 -292.508145) (xy 277.56104 -292.535102) (xy 284.366731 -292.535102) (xy 284.370666 -292.481331)
			(xy 284.382389 -292.428707) (xy 284.401649 -292.37835) (xy 284.428035 -292.331333) (xy 284.460987 -292.28866)
			(xy 284.4998 -292.251239) (xy 284.543648 -292.219869) (xy 284.591596 -292.195217) (xy 284.642623 -292.177809)
			(xy 284.695641 -292.168016) (xy 284.74952 -292.166047) (xy 284.803111 -292.171944) (xy 284.855272 -292.18558)
			(xy 284.904892 -292.206667) (xy 284.950913 -292.234753) (xy 284.992355 -292.269241) (xy 285.028333 -292.309395)
			(xy 285.058081 -292.354359) (xy 285.080966 -292.403176) (xy 285.096498 -292.454805) (xy 285.104348 -292.508145)
			(xy 285.10484 -292.535102) (xy 291.910785 -292.535102) (xy 291.91472 -292.481331) (xy 291.926443 -292.428707)
			(xy 291.945703 -292.37835) (xy 291.972089 -292.331333) (xy 292.005041 -292.28866) (xy 292.043854 -292.251239)
			(xy 292.087702 -292.219869) (xy 292.13565 -292.195217) (xy 292.186677 -292.177809) (xy 292.239695 -292.168016)
			(xy 292.293574 -292.166047) (xy 292.347165 -292.171944) (xy 292.399326 -292.18558) (xy 292.448946 -292.206667)
			(xy 292.494967 -292.234753) (xy 292.536409 -292.269241) (xy 292.572387 -292.309395) (xy 292.602135 -292.354359)
			(xy 292.62502 -292.403176) (xy 292.640552 -292.454805) (xy 292.648402 -292.508145) (xy 292.648894 -292.535102)
			(xy 292.648402 -292.562059) (xy 292.640552 -292.615399) (xy 292.62502 -292.667028) (xy 292.602135 -292.715845)
			(xy 292.572387 -292.760809) (xy 292.536409 -292.800963) (xy 292.494967 -292.835451) (xy 292.448946 -292.863537)
			(xy 292.399326 -292.884624) (xy 292.347165 -292.89826) (xy 292.293574 -292.904157) (xy 292.239695 -292.902188)
			(xy 292.186677 -292.892395) (xy 292.13565 -292.874987) (xy 292.087702 -292.850335) (xy 292.043854 -292.818965)
			(xy 292.005041 -292.781544) (xy 291.972089 -292.738871) (xy 291.945703 -292.691854) (xy 291.926443 -292.641497)
			(xy 291.91472 -292.588873) (xy 291.910785 -292.535102) (xy 285.10484 -292.535102) (xy 285.104348 -292.562059)
			(xy 285.096498 -292.615399) (xy 285.080966 -292.667028) (xy 285.058081 -292.715845) (xy 285.028333 -292.760809)
			(xy 284.992355 -292.800963) (xy 284.950913 -292.835451) (xy 284.904892 -292.863537) (xy 284.855272 -292.884624)
			(xy 284.803111 -292.89826) (xy 284.74952 -292.904157) (xy 284.695641 -292.902188) (xy 284.642623 -292.892395)
			(xy 284.591596 -292.874987) (xy 284.543648 -292.850335) (xy 284.4998 -292.818965) (xy 284.460987 -292.781544)
			(xy 284.428035 -292.738871) (xy 284.401649 -292.691854) (xy 284.382389 -292.641497) (xy 284.370666 -292.588873)
			(xy 284.366731 -292.535102) (xy 277.56104 -292.535102) (xy 277.560548 -292.562059) (xy 277.552698 -292.615399)
			(xy 277.537166 -292.667028) (xy 277.514281 -292.715845) (xy 277.484533 -292.760809) (xy 277.448555 -292.800963)
			(xy 277.407113 -292.835451) (xy 277.361092 -292.863537) (xy 277.311472 -292.884624) (xy 277.259311 -292.89826)
			(xy 277.20572 -292.904157) (xy 277.151841 -292.902188) (xy 277.098823 -292.892395) (xy 277.047796 -292.874987)
			(xy 276.999848 -292.850335) (xy 276.956 -292.818965) (xy 276.917187 -292.781544) (xy 276.884235 -292.738871)
			(xy 276.857849 -292.691854) (xy 276.838589 -292.641497) (xy 276.826866 -292.588873) (xy 276.822931 -292.535102)
			(xy 270.016986 -292.535102) (xy 270.016494 -292.562059) (xy 270.008644 -292.615399) (xy 269.993112 -292.667028)
			(xy 269.970227 -292.715845) (xy 269.940479 -292.760809) (xy 269.904501 -292.800963) (xy 269.863059 -292.835451)
			(xy 269.817038 -292.863537) (xy 269.767418 -292.884624) (xy 269.715257 -292.89826) (xy 269.661666 -292.904157)
			(xy 269.607787 -292.902188) (xy 269.554769 -292.892395) (xy 269.503742 -292.874987) (xy 269.455794 -292.850335)
			(xy 269.411946 -292.818965) (xy 269.373133 -292.781544) (xy 269.340181 -292.738871) (xy 269.313795 -292.691854)
			(xy 269.294535 -292.641497) (xy 269.282812 -292.588873) (xy 269.278877 -292.535102) (xy 264.143998 -292.535102)
			(xy 264.143998 -293.384986) (xy 265.178809 -293.384986) (xy 265.182744 -293.331215) (xy 265.194467 -293.278591)
			(xy 265.213727 -293.228234) (xy 265.240113 -293.181217) (xy 265.273065 -293.138544) (xy 265.311878 -293.101123)
			(xy 265.355726 -293.069753) (xy 265.403674 -293.045101) (xy 265.454701 -293.027693) (xy 265.507719 -293.0179)
			(xy 265.561598 -293.015931) (xy 265.615189 -293.021828) (xy 265.66735 -293.035464) (xy 265.71697 -293.056551)
			(xy 265.762991 -293.084637) (xy 265.804433 -293.119125) (xy 265.840411 -293.159279) (xy 265.870159 -293.204243)
			(xy 265.893044 -293.25306) (xy 265.908576 -293.304689) (xy 265.916426 -293.358029) (xy 265.916918 -293.384986)
			(xy 272.722863 -293.384986) (xy 272.726798 -293.331215) (xy 272.738521 -293.278591) (xy 272.757781 -293.228234)
			(xy 272.784167 -293.181217) (xy 272.817119 -293.138544) (xy 272.855932 -293.101123) (xy 272.89978 -293.069753)
			(xy 272.947728 -293.045101) (xy 272.998755 -293.027693) (xy 273.051773 -293.0179) (xy 273.105652 -293.015931)
			(xy 273.159243 -293.021828) (xy 273.211404 -293.035464) (xy 273.261024 -293.056551) (xy 273.307045 -293.084637)
			(xy 273.348487 -293.119125) (xy 273.384465 -293.159279) (xy 273.414213 -293.204243) (xy 273.437098 -293.25306)
			(xy 273.45263 -293.304689) (xy 273.46048 -293.358029) (xy 273.460972 -293.384986) (xy 280.266663 -293.384986)
			(xy 280.270598 -293.331215) (xy 280.282321 -293.278591) (xy 280.301581 -293.228234) (xy 280.327967 -293.181217)
			(xy 280.360919 -293.138544) (xy 280.399732 -293.101123) (xy 280.44358 -293.069753) (xy 280.491528 -293.045101)
			(xy 280.542555 -293.027693) (xy 280.595573 -293.0179) (xy 280.649452 -293.015931) (xy 280.703043 -293.021828)
			(xy 280.755204 -293.035464) (xy 280.804824 -293.056551) (xy 280.850845 -293.084637) (xy 280.892287 -293.119125)
			(xy 280.928265 -293.159279) (xy 280.958013 -293.204243) (xy 280.980898 -293.25306) (xy 280.99643 -293.304689)
			(xy 281.00428 -293.358029) (xy 281.004772 -293.384986) (xy 287.810717 -293.384986) (xy 287.814652 -293.331215)
			(xy 287.826375 -293.278591) (xy 287.845635 -293.228234) (xy 287.872021 -293.181217) (xy 287.904973 -293.138544)
			(xy 287.943786 -293.101123) (xy 287.987634 -293.069753) (xy 288.035582 -293.045101) (xy 288.086609 -293.027693)
			(xy 288.139627 -293.0179) (xy 288.193506 -293.015931) (xy 288.247097 -293.021828) (xy 288.299258 -293.035464)
			(xy 288.348878 -293.056551) (xy 288.394899 -293.084637) (xy 288.436341 -293.119125) (xy 288.472319 -293.159279)
			(xy 288.502067 -293.204243) (xy 288.524952 -293.25306) (xy 288.540484 -293.304689) (xy 288.548334 -293.358029)
			(xy 288.548826 -293.384986) (xy 288.548334 -293.411943) (xy 288.540484 -293.465283) (xy 288.524952 -293.516912)
			(xy 288.502067 -293.565729) (xy 288.472319 -293.610693) (xy 288.436341 -293.650847) (xy 288.394899 -293.685335)
			(xy 288.348878 -293.713421) (xy 288.299258 -293.734508) (xy 288.247097 -293.748144) (xy 288.193506 -293.754041)
			(xy 288.139627 -293.752072) (xy 288.086609 -293.742279) (xy 288.035582 -293.724871) (xy 287.987634 -293.700219)
			(xy 287.943786 -293.668849) (xy 287.904973 -293.631428) (xy 287.872021 -293.588755) (xy 287.845635 -293.541738)
			(xy 287.826375 -293.491381) (xy 287.814652 -293.438757) (xy 287.810717 -293.384986) (xy 281.004772 -293.384986)
			(xy 281.00428 -293.411943) (xy 280.99643 -293.465283) (xy 280.980898 -293.516912) (xy 280.958013 -293.565729)
			(xy 280.928265 -293.610693) (xy 280.892287 -293.650847) (xy 280.850845 -293.685335) (xy 280.804824 -293.713421)
			(xy 280.755204 -293.734508) (xy 280.703043 -293.748144) (xy 280.649452 -293.754041) (xy 280.595573 -293.752072)
			(xy 280.542555 -293.742279) (xy 280.491528 -293.724871) (xy 280.44358 -293.700219) (xy 280.399732 -293.668849)
			(xy 280.360919 -293.631428) (xy 280.327967 -293.588755) (xy 280.301581 -293.541738) (xy 280.282321 -293.491381)
			(xy 280.270598 -293.438757) (xy 280.266663 -293.384986) (xy 273.460972 -293.384986) (xy 273.46048 -293.411943)
			(xy 273.45263 -293.465283) (xy 273.437098 -293.516912) (xy 273.414213 -293.565729) (xy 273.384465 -293.610693)
			(xy 273.348487 -293.650847) (xy 273.307045 -293.685335) (xy 273.261024 -293.713421) (xy 273.211404 -293.734508)
			(xy 273.159243 -293.748144) (xy 273.105652 -293.754041) (xy 273.051773 -293.752072) (xy 272.998755 -293.742279)
			(xy 272.947728 -293.724871) (xy 272.89978 -293.700219) (xy 272.855932 -293.668849) (xy 272.817119 -293.631428)
			(xy 272.784167 -293.588755) (xy 272.757781 -293.541738) (xy 272.738521 -293.491381) (xy 272.726798 -293.438757)
			(xy 272.722863 -293.384986) (xy 265.916918 -293.384986) (xy 265.916426 -293.411943) (xy 265.908576 -293.465283)
			(xy 265.893044 -293.516912) (xy 265.870159 -293.565729) (xy 265.840411 -293.610693) (xy 265.804433 -293.650847)
			(xy 265.762991 -293.685335) (xy 265.71697 -293.713421) (xy 265.66735 -293.734508) (xy 265.615189 -293.748144)
			(xy 265.561598 -293.754041) (xy 265.507719 -293.752072) (xy 265.454701 -293.742279) (xy 265.403674 -293.724871)
			(xy 265.355726 -293.700219) (xy 265.311878 -293.668849) (xy 265.273065 -293.631428) (xy 265.240113 -293.588755)
			(xy 265.213727 -293.541738) (xy 265.194467 -293.491381) (xy 265.182744 -293.438757) (xy 265.178809 -293.384986)
			(xy 264.143998 -293.384986) (xy 264.143998 -294.235124) (xy 269.278877 -294.235124) (xy 269.282812 -294.181353)
			(xy 269.294535 -294.128729) (xy 269.313795 -294.078372) (xy 269.340181 -294.031355) (xy 269.373133 -293.988682)
			(xy 269.411946 -293.951261) (xy 269.455794 -293.919891) (xy 269.503742 -293.895239) (xy 269.554769 -293.877831)
			(xy 269.607787 -293.868038) (xy 269.661666 -293.866069) (xy 269.715257 -293.871966) (xy 269.767418 -293.885602)
			(xy 269.817038 -293.906689) (xy 269.863059 -293.934775) (xy 269.904501 -293.969263) (xy 269.940479 -294.009417)
			(xy 269.970227 -294.054381) (xy 269.993112 -294.103198) (xy 270.008644 -294.154827) (xy 270.016494 -294.208167)
			(xy 270.016986 -294.235124) (xy 276.822931 -294.235124) (xy 276.826866 -294.181353) (xy 276.838589 -294.128729)
			(xy 276.857849 -294.078372) (xy 276.884235 -294.031355) (xy 276.917187 -293.988682) (xy 276.956 -293.951261)
			(xy 276.999848 -293.919891) (xy 277.047796 -293.895239) (xy 277.098823 -293.877831) (xy 277.151841 -293.868038)
			(xy 277.20572 -293.866069) (xy 277.259311 -293.871966) (xy 277.311472 -293.885602) (xy 277.361092 -293.906689)
			(xy 277.407113 -293.934775) (xy 277.448555 -293.969263) (xy 277.484533 -294.009417) (xy 277.514281 -294.054381)
			(xy 277.537166 -294.103198) (xy 277.552698 -294.154827) (xy 277.560548 -294.208167) (xy 277.56104 -294.235124)
			(xy 284.366731 -294.235124) (xy 284.370666 -294.181353) (xy 284.382389 -294.128729) (xy 284.401649 -294.078372)
			(xy 284.428035 -294.031355) (xy 284.460987 -293.988682) (xy 284.4998 -293.951261) (xy 284.543648 -293.919891)
			(xy 284.591596 -293.895239) (xy 284.642623 -293.877831) (xy 284.695641 -293.868038) (xy 284.74952 -293.866069)
			(xy 284.803111 -293.871966) (xy 284.855272 -293.885602) (xy 284.904892 -293.906689) (xy 284.950913 -293.934775)
			(xy 284.992355 -293.969263) (xy 285.028333 -294.009417) (xy 285.058081 -294.054381) (xy 285.080966 -294.103198)
			(xy 285.096498 -294.154827) (xy 285.104348 -294.208167) (xy 285.10484 -294.235124) (xy 291.910785 -294.235124)
			(xy 291.91472 -294.181353) (xy 291.926443 -294.128729) (xy 291.945703 -294.078372) (xy 291.972089 -294.031355)
			(xy 292.005041 -293.988682) (xy 292.043854 -293.951261) (xy 292.087702 -293.919891) (xy 292.13565 -293.895239)
			(xy 292.186677 -293.877831) (xy 292.239695 -293.868038) (xy 292.293574 -293.866069) (xy 292.347165 -293.871966)
			(xy 292.399326 -293.885602) (xy 292.448946 -293.906689) (xy 292.494967 -293.934775) (xy 292.536409 -293.969263)
			(xy 292.572387 -294.009417) (xy 292.602135 -294.054381) (xy 292.62502 -294.103198) (xy 292.640552 -294.154827)
			(xy 292.648402 -294.208167) (xy 292.648894 -294.235124) (xy 292.648402 -294.262081) (xy 292.640552 -294.315421)
			(xy 292.62502 -294.36705) (xy 292.602135 -294.415867) (xy 292.572387 -294.460831) (xy 292.536409 -294.500985)
			(xy 292.494967 -294.535473) (xy 292.448946 -294.563559) (xy 292.399326 -294.584646) (xy 292.347165 -294.598282)
			(xy 292.293574 -294.604179) (xy 292.239695 -294.60221) (xy 292.186677 -294.592417) (xy 292.13565 -294.575009)
			(xy 292.087702 -294.550357) (xy 292.043854 -294.518987) (xy 292.005041 -294.481566) (xy 291.972089 -294.438893)
			(xy 291.945703 -294.391876) (xy 291.926443 -294.341519) (xy 291.91472 -294.288895) (xy 291.910785 -294.235124)
			(xy 285.10484 -294.235124) (xy 285.104348 -294.262081) (xy 285.096498 -294.315421) (xy 285.080966 -294.36705)
			(xy 285.058081 -294.415867) (xy 285.028333 -294.460831) (xy 284.992355 -294.500985) (xy 284.950913 -294.535473)
			(xy 284.904892 -294.563559) (xy 284.855272 -294.584646) (xy 284.803111 -294.598282) (xy 284.74952 -294.604179)
			(xy 284.695641 -294.60221) (xy 284.642623 -294.592417) (xy 284.591596 -294.575009) (xy 284.543648 -294.550357)
			(xy 284.4998 -294.518987) (xy 284.460987 -294.481566) (xy 284.428035 -294.438893) (xy 284.401649 -294.391876)
			(xy 284.382389 -294.341519) (xy 284.370666 -294.288895) (xy 284.366731 -294.235124) (xy 277.56104 -294.235124)
			(xy 277.560548 -294.262081) (xy 277.552698 -294.315421) (xy 277.537166 -294.36705) (xy 277.514281 -294.415867)
			(xy 277.484533 -294.460831) (xy 277.448555 -294.500985) (xy 277.407113 -294.535473) (xy 277.361092 -294.563559)
			(xy 277.311472 -294.584646) (xy 277.259311 -294.598282) (xy 277.20572 -294.604179) (xy 277.151841 -294.60221)
			(xy 277.098823 -294.592417) (xy 277.047796 -294.575009) (xy 276.999848 -294.550357) (xy 276.956 -294.518987)
			(xy 276.917187 -294.481566) (xy 276.884235 -294.438893) (xy 276.857849 -294.391876) (xy 276.838589 -294.341519)
			(xy 276.826866 -294.288895) (xy 276.822931 -294.235124) (xy 270.016986 -294.235124) (xy 270.016494 -294.262081)
			(xy 270.008644 -294.315421) (xy 269.993112 -294.36705) (xy 269.970227 -294.415867) (xy 269.940479 -294.460831)
			(xy 269.904501 -294.500985) (xy 269.863059 -294.535473) (xy 269.817038 -294.563559) (xy 269.767418 -294.584646)
			(xy 269.715257 -294.598282) (xy 269.661666 -294.604179) (xy 269.607787 -294.60221) (xy 269.554769 -294.592417)
			(xy 269.503742 -294.575009) (xy 269.455794 -294.550357) (xy 269.411946 -294.518987) (xy 269.373133 -294.481566)
			(xy 269.340181 -294.438893) (xy 269.313795 -294.391876) (xy 269.294535 -294.341519) (xy 269.282812 -294.288895)
			(xy 269.278877 -294.235124) (xy 264.143998 -294.235124) (xy 264.143998 -295.085008) (xy 265.178809 -295.085008)
			(xy 265.182744 -295.031237) (xy 265.194467 -294.978613) (xy 265.213727 -294.928256) (xy 265.240113 -294.881239)
			(xy 265.273065 -294.838566) (xy 265.311878 -294.801145) (xy 265.355726 -294.769775) (xy 265.403674 -294.745123)
			(xy 265.454701 -294.727715) (xy 265.507719 -294.717922) (xy 265.561598 -294.715953) (xy 265.615189 -294.72185)
			(xy 265.66735 -294.735486) (xy 265.71697 -294.756573) (xy 265.762991 -294.784659) (xy 265.804433 -294.819147)
			(xy 265.840411 -294.859301) (xy 265.870159 -294.904265) (xy 265.893044 -294.953082) (xy 265.908576 -295.004711)
			(xy 265.916426 -295.058051) (xy 265.916918 -295.085008) (xy 269.278877 -295.085008) (xy 269.282812 -295.031237)
			(xy 269.294535 -294.978613) (xy 269.313795 -294.928256) (xy 269.340181 -294.881239) (xy 269.373133 -294.838566)
			(xy 269.411946 -294.801145) (xy 269.455794 -294.769775) (xy 269.503742 -294.745123) (xy 269.554769 -294.727715)
			(xy 269.607787 -294.717922) (xy 269.661666 -294.715953) (xy 269.715257 -294.72185) (xy 269.767418 -294.735486)
			(xy 269.817038 -294.756573) (xy 269.863059 -294.784659) (xy 269.904501 -294.819147) (xy 269.940479 -294.859301)
			(xy 269.970227 -294.904265) (xy 269.993112 -294.953082) (xy 270.008644 -295.004711) (xy 270.016494 -295.058051)
			(xy 270.016986 -295.085008) (xy 272.722863 -295.085008) (xy 272.726798 -295.031237) (xy 272.738521 -294.978613)
			(xy 272.757781 -294.928256) (xy 272.784167 -294.881239) (xy 272.817119 -294.838566) (xy 272.855932 -294.801145)
			(xy 272.89978 -294.769775) (xy 272.947728 -294.745123) (xy 272.998755 -294.727715) (xy 273.051773 -294.717922)
			(xy 273.105652 -294.715953) (xy 273.159243 -294.72185) (xy 273.211404 -294.735486) (xy 273.261024 -294.756573)
			(xy 273.307045 -294.784659) (xy 273.348487 -294.819147) (xy 273.384465 -294.859301) (xy 273.414213 -294.904265)
			(xy 273.437098 -294.953082) (xy 273.45263 -295.004711) (xy 273.46048 -295.058051) (xy 273.460972 -295.085008)
			(xy 276.822931 -295.085008) (xy 276.826866 -295.031237) (xy 276.838589 -294.978613) (xy 276.857849 -294.928256)
			(xy 276.884235 -294.881239) (xy 276.917187 -294.838566) (xy 276.956 -294.801145) (xy 276.999848 -294.769775)
			(xy 277.047796 -294.745123) (xy 277.098823 -294.727715) (xy 277.151841 -294.717922) (xy 277.20572 -294.715953)
			(xy 277.259311 -294.72185) (xy 277.311472 -294.735486) (xy 277.361092 -294.756573) (xy 277.407113 -294.784659)
			(xy 277.448555 -294.819147) (xy 277.484533 -294.859301) (xy 277.514281 -294.904265) (xy 277.537166 -294.953082)
			(xy 277.552698 -295.004711) (xy 277.560548 -295.058051) (xy 277.56104 -295.085008) (xy 280.266663 -295.085008)
			(xy 280.270598 -295.031237) (xy 280.282321 -294.978613) (xy 280.301581 -294.928256) (xy 280.327967 -294.881239)
			(xy 280.360919 -294.838566) (xy 280.399732 -294.801145) (xy 280.44358 -294.769775) (xy 280.491528 -294.745123)
			(xy 280.542555 -294.727715) (xy 280.595573 -294.717922) (xy 280.649452 -294.715953) (xy 280.703043 -294.72185)
			(xy 280.755204 -294.735486) (xy 280.804824 -294.756573) (xy 280.850845 -294.784659) (xy 280.892287 -294.819147)
			(xy 280.928265 -294.859301) (xy 280.958013 -294.904265) (xy 280.980898 -294.953082) (xy 280.99643 -295.004711)
			(xy 281.00428 -295.058051) (xy 281.004772 -295.085008) (xy 284.366731 -295.085008) (xy 284.370666 -295.031237)
			(xy 284.382389 -294.978613) (xy 284.401649 -294.928256) (xy 284.428035 -294.881239) (xy 284.460987 -294.838566)
			(xy 284.4998 -294.801145) (xy 284.543648 -294.769775) (xy 284.591596 -294.745123) (xy 284.642623 -294.727715)
			(xy 284.695641 -294.717922) (xy 284.74952 -294.715953) (xy 284.803111 -294.72185) (xy 284.855272 -294.735486)
			(xy 284.904892 -294.756573) (xy 284.950913 -294.784659) (xy 284.992355 -294.819147) (xy 285.028333 -294.859301)
			(xy 285.058081 -294.904265) (xy 285.080966 -294.953082) (xy 285.096498 -295.004711) (xy 285.104348 -295.058051)
			(xy 285.10484 -295.085008) (xy 287.810717 -295.085008) (xy 287.814652 -295.031237) (xy 287.826375 -294.978613)
			(xy 287.845635 -294.928256) (xy 287.872021 -294.881239) (xy 287.904973 -294.838566) (xy 287.943786 -294.801145)
			(xy 287.987634 -294.769775) (xy 288.035582 -294.745123) (xy 288.086609 -294.727715) (xy 288.139627 -294.717922)
			(xy 288.193506 -294.715953) (xy 288.247097 -294.72185) (xy 288.299258 -294.735486) (xy 288.348878 -294.756573)
			(xy 288.394899 -294.784659) (xy 288.436341 -294.819147) (xy 288.472319 -294.859301) (xy 288.502067 -294.904265)
			(xy 288.524952 -294.953082) (xy 288.540484 -295.004711) (xy 288.548334 -295.058051) (xy 288.548826 -295.085008)
			(xy 291.910785 -295.085008) (xy 291.91472 -295.031237) (xy 291.926443 -294.978613) (xy 291.945703 -294.928256)
			(xy 291.972089 -294.881239) (xy 292.005041 -294.838566) (xy 292.043854 -294.801145) (xy 292.087702 -294.769775)
			(xy 292.13565 -294.745123) (xy 292.186677 -294.727715) (xy 292.239695 -294.717922) (xy 292.293574 -294.715953)
			(xy 292.347165 -294.72185) (xy 292.399326 -294.735486) (xy 292.448946 -294.756573) (xy 292.494967 -294.784659)
			(xy 292.536409 -294.819147) (xy 292.572387 -294.859301) (xy 292.602135 -294.904265) (xy 292.62502 -294.953082)
			(xy 292.640552 -295.004711) (xy 292.648402 -295.058051) (xy 292.648894 -295.085008) (xy 292.648402 -295.111965)
			(xy 292.640552 -295.165305) (xy 292.62502 -295.216934) (xy 292.602135 -295.265751) (xy 292.572387 -295.310715)
			(xy 292.536409 -295.350869) (xy 292.494967 -295.385357) (xy 292.448946 -295.413443) (xy 292.399326 -295.43453)
			(xy 292.347165 -295.448166) (xy 292.293574 -295.454063) (xy 292.239695 -295.452094) (xy 292.186677 -295.442301)
			(xy 292.13565 -295.424893) (xy 292.087702 -295.400241) (xy 292.043854 -295.368871) (xy 292.005041 -295.33145)
			(xy 291.972089 -295.288777) (xy 291.945703 -295.24176) (xy 291.926443 -295.191403) (xy 291.91472 -295.138779)
			(xy 291.910785 -295.085008) (xy 288.548826 -295.085008) (xy 288.548334 -295.111965) (xy 288.540484 -295.165305)
			(xy 288.524952 -295.216934) (xy 288.502067 -295.265751) (xy 288.472319 -295.310715) (xy 288.436341 -295.350869)
			(xy 288.394899 -295.385357) (xy 288.348878 -295.413443) (xy 288.299258 -295.43453) (xy 288.247097 -295.448166)
			(xy 288.193506 -295.454063) (xy 288.139627 -295.452094) (xy 288.086609 -295.442301) (xy 288.035582 -295.424893)
			(xy 287.987634 -295.400241) (xy 287.943786 -295.368871) (xy 287.904973 -295.33145) (xy 287.872021 -295.288777)
			(xy 287.845635 -295.24176) (xy 287.826375 -295.191403) (xy 287.814652 -295.138779) (xy 287.810717 -295.085008)
			(xy 285.10484 -295.085008) (xy 285.104348 -295.111965) (xy 285.096498 -295.165305) (xy 285.080966 -295.216934)
			(xy 285.058081 -295.265751) (xy 285.028333 -295.310715) (xy 284.992355 -295.350869) (xy 284.950913 -295.385357)
			(xy 284.904892 -295.413443) (xy 284.855272 -295.43453) (xy 284.803111 -295.448166) (xy 284.74952 -295.454063)
			(xy 284.695641 -295.452094) (xy 284.642623 -295.442301) (xy 284.591596 -295.424893) (xy 284.543648 -295.400241)
			(xy 284.4998 -295.368871) (xy 284.460987 -295.33145) (xy 284.428035 -295.288777) (xy 284.401649 -295.24176)
			(xy 284.382389 -295.191403) (xy 284.370666 -295.138779) (xy 284.366731 -295.085008) (xy 281.004772 -295.085008)
			(xy 281.00428 -295.111965) (xy 280.99643 -295.165305) (xy 280.980898 -295.216934) (xy 280.958013 -295.265751)
			(xy 280.928265 -295.310715) (xy 280.892287 -295.350869) (xy 280.850845 -295.385357) (xy 280.804824 -295.413443)
			(xy 280.755204 -295.43453) (xy 280.703043 -295.448166) (xy 280.649452 -295.454063) (xy 280.595573 -295.452094)
			(xy 280.542555 -295.442301) (xy 280.491528 -295.424893) (xy 280.44358 -295.400241) (xy 280.399732 -295.368871)
			(xy 280.360919 -295.33145) (xy 280.327967 -295.288777) (xy 280.301581 -295.24176) (xy 280.282321 -295.191403)
			(xy 280.270598 -295.138779) (xy 280.266663 -295.085008) (xy 277.56104 -295.085008) (xy 277.560548 -295.111965)
			(xy 277.552698 -295.165305) (xy 277.537166 -295.216934) (xy 277.514281 -295.265751) (xy 277.484533 -295.310715)
			(xy 277.448555 -295.350869) (xy 277.407113 -295.385357) (xy 277.361092 -295.413443) (xy 277.311472 -295.43453)
			(xy 277.259311 -295.448166) (xy 277.20572 -295.454063) (xy 277.151841 -295.452094) (xy 277.098823 -295.442301)
			(xy 277.047796 -295.424893) (xy 276.999848 -295.400241) (xy 276.956 -295.368871) (xy 276.917187 -295.33145)
			(xy 276.884235 -295.288777) (xy 276.857849 -295.24176) (xy 276.838589 -295.191403) (xy 276.826866 -295.138779)
			(xy 276.822931 -295.085008) (xy 273.460972 -295.085008) (xy 273.46048 -295.111965) (xy 273.45263 -295.165305)
			(xy 273.437098 -295.216934) (xy 273.414213 -295.265751) (xy 273.384465 -295.310715) (xy 273.348487 -295.350869)
			(xy 273.307045 -295.385357) (xy 273.261024 -295.413443) (xy 273.211404 -295.43453) (xy 273.159243 -295.448166)
			(xy 273.105652 -295.454063) (xy 273.051773 -295.452094) (xy 272.998755 -295.442301) (xy 272.947728 -295.424893)
			(xy 272.89978 -295.400241) (xy 272.855932 -295.368871) (xy 272.817119 -295.33145) (xy 272.784167 -295.288777)
			(xy 272.757781 -295.24176) (xy 272.738521 -295.191403) (xy 272.726798 -295.138779) (xy 272.722863 -295.085008)
			(xy 270.016986 -295.085008) (xy 270.016494 -295.111965) (xy 270.008644 -295.165305) (xy 269.993112 -295.216934)
			(xy 269.970227 -295.265751) (xy 269.940479 -295.310715) (xy 269.904501 -295.350869) (xy 269.863059 -295.385357)
			(xy 269.817038 -295.413443) (xy 269.767418 -295.43453) (xy 269.715257 -295.448166) (xy 269.661666 -295.454063)
			(xy 269.607787 -295.452094) (xy 269.554769 -295.442301) (xy 269.503742 -295.424893) (xy 269.455794 -295.400241)
			(xy 269.411946 -295.368871) (xy 269.373133 -295.33145) (xy 269.340181 -295.288777) (xy 269.313795 -295.24176)
			(xy 269.294535 -295.191403) (xy 269.282812 -295.138779) (xy 269.278877 -295.085008) (xy 265.916918 -295.085008)
			(xy 265.916426 -295.111965) (xy 265.908576 -295.165305) (xy 265.893044 -295.216934) (xy 265.870159 -295.265751)
			(xy 265.840411 -295.310715) (xy 265.804433 -295.350869) (xy 265.762991 -295.385357) (xy 265.71697 -295.413443)
			(xy 265.66735 -295.43453) (xy 265.615189 -295.448166) (xy 265.561598 -295.454063) (xy 265.507719 -295.452094)
			(xy 265.454701 -295.442301) (xy 265.403674 -295.424893) (xy 265.355726 -295.400241) (xy 265.311878 -295.368871)
			(xy 265.273065 -295.33145) (xy 265.240113 -295.288777) (xy 265.213727 -295.24176) (xy 265.194467 -295.191403)
			(xy 265.182744 -295.138779) (xy 265.178809 -295.085008) (xy 264.143998 -295.085008) (xy 264.143998 -295.935146)
			(xy 265.178809 -295.935146) (xy 265.182744 -295.881375) (xy 265.194467 -295.828751) (xy 265.213727 -295.778394)
			(xy 265.240113 -295.731377) (xy 265.273065 -295.688704) (xy 265.311878 -295.651283) (xy 265.355726 -295.619913)
			(xy 265.403674 -295.595261) (xy 265.454701 -295.577853) (xy 265.507719 -295.56806) (xy 265.561598 -295.566091)
			(xy 265.615189 -295.571988) (xy 265.66735 -295.585624) (xy 265.71697 -295.606711) (xy 265.762991 -295.634797)
			(xy 265.804433 -295.669285) (xy 265.840411 -295.709439) (xy 265.870159 -295.754403) (xy 265.893044 -295.80322)
			(xy 265.908576 -295.854849) (xy 265.916426 -295.908189) (xy 265.916918 -295.935146) (xy 272.722863 -295.935146)
			(xy 272.726798 -295.881375) (xy 272.738521 -295.828751) (xy 272.757781 -295.778394) (xy 272.784167 -295.731377)
			(xy 272.817119 -295.688704) (xy 272.855932 -295.651283) (xy 272.89978 -295.619913) (xy 272.947728 -295.595261)
			(xy 272.998755 -295.577853) (xy 273.051773 -295.56806) (xy 273.105652 -295.566091) (xy 273.159243 -295.571988)
			(xy 273.211404 -295.585624) (xy 273.261024 -295.606711) (xy 273.307045 -295.634797) (xy 273.348487 -295.669285)
			(xy 273.384465 -295.709439) (xy 273.414213 -295.754403) (xy 273.437098 -295.80322) (xy 273.45263 -295.854849)
			(xy 273.46048 -295.908189) (xy 273.460972 -295.935146) (xy 280.266663 -295.935146) (xy 280.270598 -295.881375)
			(xy 280.282321 -295.828751) (xy 280.301581 -295.778394) (xy 280.327967 -295.731377) (xy 280.360919 -295.688704)
			(xy 280.399732 -295.651283) (xy 280.44358 -295.619913) (xy 280.491528 -295.595261) (xy 280.542555 -295.577853)
			(xy 280.595573 -295.56806) (xy 280.649452 -295.566091) (xy 280.703043 -295.571988) (xy 280.755204 -295.585624)
			(xy 280.804824 -295.606711) (xy 280.850845 -295.634797) (xy 280.892287 -295.669285) (xy 280.928265 -295.709439)
			(xy 280.958013 -295.754403) (xy 280.980898 -295.80322) (xy 280.99643 -295.854849) (xy 281.00428 -295.908189)
			(xy 281.004772 -295.935146) (xy 287.810717 -295.935146) (xy 287.814652 -295.881375) (xy 287.826375 -295.828751)
			(xy 287.845635 -295.778394) (xy 287.872021 -295.731377) (xy 287.904973 -295.688704) (xy 287.943786 -295.651283)
			(xy 287.987634 -295.619913) (xy 288.035582 -295.595261) (xy 288.086609 -295.577853) (xy 288.139627 -295.56806)
			(xy 288.193506 -295.566091) (xy 288.247097 -295.571988) (xy 288.299258 -295.585624) (xy 288.348878 -295.606711)
			(xy 288.394899 -295.634797) (xy 288.436341 -295.669285) (xy 288.472319 -295.709439) (xy 288.502067 -295.754403)
			(xy 288.524952 -295.80322) (xy 288.540484 -295.854849) (xy 288.548334 -295.908189) (xy 288.548826 -295.935146)
			(xy 288.548334 -295.962103) (xy 288.540484 -296.015443) (xy 288.524952 -296.067072) (xy 288.502067 -296.115889)
			(xy 288.472319 -296.160853) (xy 288.436341 -296.201007) (xy 288.394899 -296.235495) (xy 288.348878 -296.263581)
			(xy 288.299258 -296.284668) (xy 288.247097 -296.298304) (xy 288.193506 -296.304201) (xy 288.139627 -296.302232)
			(xy 288.086609 -296.292439) (xy 288.035582 -296.275031) (xy 287.987634 -296.250379) (xy 287.943786 -296.219009)
			(xy 287.904973 -296.181588) (xy 287.872021 -296.138915) (xy 287.845635 -296.091898) (xy 287.826375 -296.041541)
			(xy 287.814652 -295.988917) (xy 287.810717 -295.935146) (xy 281.004772 -295.935146) (xy 281.00428 -295.962103)
			(xy 280.99643 -296.015443) (xy 280.980898 -296.067072) (xy 280.958013 -296.115889) (xy 280.928265 -296.160853)
			(xy 280.892287 -296.201007) (xy 280.850845 -296.235495) (xy 280.804824 -296.263581) (xy 280.755204 -296.284668)
			(xy 280.703043 -296.298304) (xy 280.649452 -296.304201) (xy 280.595573 -296.302232) (xy 280.542555 -296.292439)
			(xy 280.491528 -296.275031) (xy 280.44358 -296.250379) (xy 280.399732 -296.219009) (xy 280.360919 -296.181588)
			(xy 280.327967 -296.138915) (xy 280.301581 -296.091898) (xy 280.282321 -296.041541) (xy 280.270598 -295.988917)
			(xy 280.266663 -295.935146) (xy 273.460972 -295.935146) (xy 273.46048 -295.962103) (xy 273.45263 -296.015443)
			(xy 273.437098 -296.067072) (xy 273.414213 -296.115889) (xy 273.384465 -296.160853) (xy 273.348487 -296.201007)
			(xy 273.307045 -296.235495) (xy 273.261024 -296.263581) (xy 273.211404 -296.284668) (xy 273.159243 -296.298304)
			(xy 273.105652 -296.304201) (xy 273.051773 -296.302232) (xy 272.998755 -296.292439) (xy 272.947728 -296.275031)
			(xy 272.89978 -296.250379) (xy 272.855932 -296.219009) (xy 272.817119 -296.181588) (xy 272.784167 -296.138915)
			(xy 272.757781 -296.091898) (xy 272.738521 -296.041541) (xy 272.726798 -295.988917) (xy 272.722863 -295.935146)
			(xy 265.916918 -295.935146) (xy 265.916426 -295.962103) (xy 265.908576 -296.015443) (xy 265.893044 -296.067072)
			(xy 265.870159 -296.115889) (xy 265.840411 -296.160853) (xy 265.804433 -296.201007) (xy 265.762991 -296.235495)
			(xy 265.71697 -296.263581) (xy 265.66735 -296.284668) (xy 265.615189 -296.298304) (xy 265.561598 -296.304201)
			(xy 265.507719 -296.302232) (xy 265.454701 -296.292439) (xy 265.403674 -296.275031) (xy 265.355726 -296.250379)
			(xy 265.311878 -296.219009) (xy 265.273065 -296.181588) (xy 265.240113 -296.138915) (xy 265.213727 -296.091898)
			(xy 265.194467 -296.041541) (xy 265.182744 -295.988917) (xy 265.178809 -295.935146) (xy 264.143998 -295.935146)
			(xy 264.143998 -296.78503) (xy 269.278877 -296.78503) (xy 269.282812 -296.731259) (xy 269.294535 -296.678635)
			(xy 269.313795 -296.628278) (xy 269.340181 -296.581261) (xy 269.373133 -296.538588) (xy 269.411946 -296.501167)
			(xy 269.455794 -296.469797) (xy 269.503742 -296.445145) (xy 269.554769 -296.427737) (xy 269.607787 -296.417944)
			(xy 269.661666 -296.415975) (xy 269.715257 -296.421872) (xy 269.767418 -296.435508) (xy 269.817038 -296.456595)
			(xy 269.863059 -296.484681) (xy 269.904501 -296.519169) (xy 269.940479 -296.559323) (xy 269.970227 -296.604287)
			(xy 269.993112 -296.653104) (xy 270.008644 -296.704733) (xy 270.016494 -296.758073) (xy 270.016986 -296.78503)
			(xy 276.822931 -296.78503) (xy 276.826866 -296.731259) (xy 276.838589 -296.678635) (xy 276.857849 -296.628278)
			(xy 276.884235 -296.581261) (xy 276.917187 -296.538588) (xy 276.956 -296.501167) (xy 276.999848 -296.469797)
			(xy 277.047796 -296.445145) (xy 277.098823 -296.427737) (xy 277.151841 -296.417944) (xy 277.20572 -296.415975)
			(xy 277.259311 -296.421872) (xy 277.311472 -296.435508) (xy 277.361092 -296.456595) (xy 277.407113 -296.484681)
			(xy 277.448555 -296.519169) (xy 277.484533 -296.559323) (xy 277.514281 -296.604287) (xy 277.537166 -296.653104)
			(xy 277.552698 -296.704733) (xy 277.560548 -296.758073) (xy 277.56104 -296.78503) (xy 284.366731 -296.78503)
			(xy 284.370666 -296.731259) (xy 284.382389 -296.678635) (xy 284.401649 -296.628278) (xy 284.428035 -296.581261)
			(xy 284.460987 -296.538588) (xy 284.4998 -296.501167) (xy 284.543648 -296.469797) (xy 284.591596 -296.445145)
			(xy 284.642623 -296.427737) (xy 284.695641 -296.417944) (xy 284.74952 -296.415975) (xy 284.803111 -296.421872)
			(xy 284.855272 -296.435508) (xy 284.904892 -296.456595) (xy 284.950913 -296.484681) (xy 284.992355 -296.519169)
			(xy 285.028333 -296.559323) (xy 285.058081 -296.604287) (xy 285.080966 -296.653104) (xy 285.096498 -296.704733)
			(xy 285.104348 -296.758073) (xy 285.10484 -296.78503) (xy 291.910785 -296.78503) (xy 291.91472 -296.731259)
			(xy 291.926443 -296.678635) (xy 291.945703 -296.628278) (xy 291.972089 -296.581261) (xy 292.005041 -296.538588)
			(xy 292.043854 -296.501167) (xy 292.087702 -296.469797) (xy 292.13565 -296.445145) (xy 292.186677 -296.427737)
			(xy 292.239695 -296.417944) (xy 292.293574 -296.415975) (xy 292.347165 -296.421872) (xy 292.399326 -296.435508)
			(xy 292.448946 -296.456595) (xy 292.494967 -296.484681) (xy 292.536409 -296.519169) (xy 292.572387 -296.559323)
			(xy 292.602135 -296.604287) (xy 292.62502 -296.653104) (xy 292.640552 -296.704733) (xy 292.648402 -296.758073)
			(xy 292.648894 -296.78503) (xy 292.648402 -296.811987) (xy 292.640552 -296.865327) (xy 292.62502 -296.916956)
			(xy 292.602135 -296.965773) (xy 292.572387 -297.010737) (xy 292.536409 -297.050891) (xy 292.494967 -297.085379)
			(xy 292.448946 -297.113465) (xy 292.399326 -297.134552) (xy 292.347165 -297.148188) (xy 292.293574 -297.154085)
			(xy 292.239695 -297.152116) (xy 292.186677 -297.142323) (xy 292.13565 -297.124915) (xy 292.087702 -297.100263)
			(xy 292.043854 -297.068893) (xy 292.005041 -297.031472) (xy 291.972089 -296.988799) (xy 291.945703 -296.941782)
			(xy 291.926443 -296.891425) (xy 291.91472 -296.838801) (xy 291.910785 -296.78503) (xy 285.10484 -296.78503)
			(xy 285.104348 -296.811987) (xy 285.096498 -296.865327) (xy 285.080966 -296.916956) (xy 285.058081 -296.965773)
			(xy 285.028333 -297.010737) (xy 284.992355 -297.050891) (xy 284.950913 -297.085379) (xy 284.904892 -297.113465)
			(xy 284.855272 -297.134552) (xy 284.803111 -297.148188) (xy 284.74952 -297.154085) (xy 284.695641 -297.152116)
			(xy 284.642623 -297.142323) (xy 284.591596 -297.124915) (xy 284.543648 -297.100263) (xy 284.4998 -297.068893)
			(xy 284.460987 -297.031472) (xy 284.428035 -296.988799) (xy 284.401649 -296.941782) (xy 284.382389 -296.891425)
			(xy 284.370666 -296.838801) (xy 284.366731 -296.78503) (xy 277.56104 -296.78503) (xy 277.560548 -296.811987)
			(xy 277.552698 -296.865327) (xy 277.537166 -296.916956) (xy 277.514281 -296.965773) (xy 277.484533 -297.010737)
			(xy 277.448555 -297.050891) (xy 277.407113 -297.085379) (xy 277.361092 -297.113465) (xy 277.311472 -297.134552)
			(xy 277.259311 -297.148188) (xy 277.20572 -297.154085) (xy 277.151841 -297.152116) (xy 277.098823 -297.142323)
			(xy 277.047796 -297.124915) (xy 276.999848 -297.100263) (xy 276.956 -297.068893) (xy 276.917187 -297.031472)
			(xy 276.884235 -296.988799) (xy 276.857849 -296.941782) (xy 276.838589 -296.891425) (xy 276.826866 -296.838801)
			(xy 276.822931 -296.78503) (xy 270.016986 -296.78503) (xy 270.016494 -296.811987) (xy 270.008644 -296.865327)
			(xy 269.993112 -296.916956) (xy 269.970227 -296.965773) (xy 269.940479 -297.010737) (xy 269.904501 -297.050891)
			(xy 269.863059 -297.085379) (xy 269.817038 -297.113465) (xy 269.767418 -297.134552) (xy 269.715257 -297.148188)
			(xy 269.661666 -297.154085) (xy 269.607787 -297.152116) (xy 269.554769 -297.142323) (xy 269.503742 -297.124915)
			(xy 269.455794 -297.100263) (xy 269.411946 -297.068893) (xy 269.373133 -297.031472) (xy 269.340181 -296.988799)
			(xy 269.313795 -296.941782) (xy 269.294535 -296.891425) (xy 269.282812 -296.838801) (xy 269.278877 -296.78503)
			(xy 264.143998 -296.78503) (xy 264.143998 -297.635168) (xy 265.178809 -297.635168) (xy 265.182744 -297.581397)
			(xy 265.194467 -297.528773) (xy 265.213727 -297.478416) (xy 265.240113 -297.431399) (xy 265.273065 -297.388726)
			(xy 265.311878 -297.351305) (xy 265.355726 -297.319935) (xy 265.403674 -297.295283) (xy 265.454701 -297.277875)
			(xy 265.507719 -297.268082) (xy 265.561598 -297.266113) (xy 265.615189 -297.27201) (xy 265.66735 -297.285646)
			(xy 265.71697 -297.306733) (xy 265.762991 -297.334819) (xy 265.804433 -297.369307) (xy 265.840411 -297.409461)
			(xy 265.870159 -297.454425) (xy 265.893044 -297.503242) (xy 265.908576 -297.554871) (xy 265.916426 -297.608211)
			(xy 265.916918 -297.635168) (xy 272.722863 -297.635168) (xy 272.726798 -297.581397) (xy 272.738521 -297.528773)
			(xy 272.757781 -297.478416) (xy 272.784167 -297.431399) (xy 272.817119 -297.388726) (xy 272.855932 -297.351305)
			(xy 272.89978 -297.319935) (xy 272.947728 -297.295283) (xy 272.998755 -297.277875) (xy 273.051773 -297.268082)
			(xy 273.105652 -297.266113) (xy 273.159243 -297.27201) (xy 273.211404 -297.285646) (xy 273.261024 -297.306733)
			(xy 273.307045 -297.334819) (xy 273.348487 -297.369307) (xy 273.384465 -297.409461) (xy 273.414213 -297.454425)
			(xy 273.437098 -297.503242) (xy 273.45263 -297.554871) (xy 273.46048 -297.608211) (xy 273.460972 -297.635168)
			(xy 280.266663 -297.635168) (xy 280.270598 -297.581397) (xy 280.282321 -297.528773) (xy 280.301581 -297.478416)
			(xy 280.327967 -297.431399) (xy 280.360919 -297.388726) (xy 280.399732 -297.351305) (xy 280.44358 -297.319935)
			(xy 280.491528 -297.295283) (xy 280.542555 -297.277875) (xy 280.595573 -297.268082) (xy 280.649452 -297.266113)
			(xy 280.703043 -297.27201) (xy 280.755204 -297.285646) (xy 280.804824 -297.306733) (xy 280.850845 -297.334819)
			(xy 280.892287 -297.369307) (xy 280.928265 -297.409461) (xy 280.958013 -297.454425) (xy 280.980898 -297.503242)
			(xy 280.99643 -297.554871) (xy 281.00428 -297.608211) (xy 281.004772 -297.635168) (xy 287.810717 -297.635168)
			(xy 287.814652 -297.581397) (xy 287.826375 -297.528773) (xy 287.845635 -297.478416) (xy 287.872021 -297.431399)
			(xy 287.904973 -297.388726) (xy 287.943786 -297.351305) (xy 287.987634 -297.319935) (xy 288.035582 -297.295283)
			(xy 288.086609 -297.277875) (xy 288.139627 -297.268082) (xy 288.193506 -297.266113) (xy 288.247097 -297.27201)
			(xy 288.299258 -297.285646) (xy 288.348878 -297.306733) (xy 288.394899 -297.334819) (xy 288.436341 -297.369307)
			(xy 288.472319 -297.409461) (xy 288.502067 -297.454425) (xy 288.524952 -297.503242) (xy 288.540484 -297.554871)
			(xy 288.548334 -297.608211) (xy 288.548826 -297.635168) (xy 288.548334 -297.662125) (xy 288.540484 -297.715465)
			(xy 288.524952 -297.767094) (xy 288.502067 -297.815911) (xy 288.472319 -297.860875) (xy 288.436341 -297.901029)
			(xy 288.394899 -297.935517) (xy 288.348878 -297.963603) (xy 288.299258 -297.98469) (xy 288.247097 -297.998326)
			(xy 288.193506 -298.004223) (xy 288.139627 -298.002254) (xy 288.086609 -297.992461) (xy 288.035582 -297.975053)
			(xy 287.987634 -297.950401) (xy 287.943786 -297.919031) (xy 287.904973 -297.88161) (xy 287.872021 -297.838937)
			(xy 287.845635 -297.79192) (xy 287.826375 -297.741563) (xy 287.814652 -297.688939) (xy 287.810717 -297.635168)
			(xy 281.004772 -297.635168) (xy 281.00428 -297.662125) (xy 280.99643 -297.715465) (xy 280.980898 -297.767094)
			(xy 280.958013 -297.815911) (xy 280.928265 -297.860875) (xy 280.892287 -297.901029) (xy 280.850845 -297.935517)
			(xy 280.804824 -297.963603) (xy 280.755204 -297.98469) (xy 280.703043 -297.998326) (xy 280.649452 -298.004223)
			(xy 280.595573 -298.002254) (xy 280.542555 -297.992461) (xy 280.491528 -297.975053) (xy 280.44358 -297.950401)
			(xy 280.399732 -297.919031) (xy 280.360919 -297.88161) (xy 280.327967 -297.838937) (xy 280.301581 -297.79192)
			(xy 280.282321 -297.741563) (xy 280.270598 -297.688939) (xy 280.266663 -297.635168) (xy 273.460972 -297.635168)
			(xy 273.46048 -297.662125) (xy 273.45263 -297.715465) (xy 273.437098 -297.767094) (xy 273.414213 -297.815911)
			(xy 273.384465 -297.860875) (xy 273.348487 -297.901029) (xy 273.307045 -297.935517) (xy 273.261024 -297.963603)
			(xy 273.211404 -297.98469) (xy 273.159243 -297.998326) (xy 273.105652 -298.004223) (xy 273.051773 -298.002254)
			(xy 272.998755 -297.992461) (xy 272.947728 -297.975053) (xy 272.89978 -297.950401) (xy 272.855932 -297.919031)
			(xy 272.817119 -297.88161) (xy 272.784167 -297.838937) (xy 272.757781 -297.79192) (xy 272.738521 -297.741563)
			(xy 272.726798 -297.688939) (xy 272.722863 -297.635168) (xy 265.916918 -297.635168) (xy 265.916426 -297.662125)
			(xy 265.908576 -297.715465) (xy 265.893044 -297.767094) (xy 265.870159 -297.815911) (xy 265.840411 -297.860875)
			(xy 265.804433 -297.901029) (xy 265.762991 -297.935517) (xy 265.71697 -297.963603) (xy 265.66735 -297.98469)
			(xy 265.615189 -297.998326) (xy 265.561598 -298.004223) (xy 265.507719 -298.002254) (xy 265.454701 -297.992461)
			(xy 265.403674 -297.975053) (xy 265.355726 -297.950401) (xy 265.311878 -297.919031) (xy 265.273065 -297.88161)
			(xy 265.240113 -297.838937) (xy 265.213727 -297.79192) (xy 265.194467 -297.741563) (xy 265.182744 -297.688939)
			(xy 265.178809 -297.635168) (xy 264.143998 -297.635168) (xy 264.143998 -298.485052) (xy 269.278877 -298.485052)
			(xy 269.282812 -298.431281) (xy 269.294535 -298.378657) (xy 269.313795 -298.3283) (xy 269.340181 -298.281283)
			(xy 269.373133 -298.23861) (xy 269.411946 -298.201189) (xy 269.455794 -298.169819) (xy 269.503742 -298.145167)
			(xy 269.554769 -298.127759) (xy 269.607787 -298.117966) (xy 269.661666 -298.115997) (xy 269.715257 -298.121894)
			(xy 269.767418 -298.13553) (xy 269.817038 -298.156617) (xy 269.863059 -298.184703) (xy 269.904501 -298.219191)
			(xy 269.940479 -298.259345) (xy 269.970227 -298.304309) (xy 269.993112 -298.353126) (xy 270.008644 -298.404755)
			(xy 270.016494 -298.458095) (xy 270.016986 -298.485052) (xy 276.822931 -298.485052) (xy 276.826866 -298.431281)
			(xy 276.838589 -298.378657) (xy 276.857849 -298.3283) (xy 276.884235 -298.281283) (xy 276.917187 -298.23861)
			(xy 276.956 -298.201189) (xy 276.999848 -298.169819) (xy 277.047796 -298.145167) (xy 277.098823 -298.127759)
			(xy 277.151841 -298.117966) (xy 277.20572 -298.115997) (xy 277.259311 -298.121894) (xy 277.311472 -298.13553)
			(xy 277.361092 -298.156617) (xy 277.407113 -298.184703) (xy 277.448555 -298.219191) (xy 277.484533 -298.259345)
			(xy 277.514281 -298.304309) (xy 277.537166 -298.353126) (xy 277.552698 -298.404755) (xy 277.560548 -298.458095)
			(xy 277.56104 -298.485052) (xy 284.366731 -298.485052) (xy 284.370666 -298.431281) (xy 284.382389 -298.378657)
			(xy 284.401649 -298.3283) (xy 284.428035 -298.281283) (xy 284.460987 -298.23861) (xy 284.4998 -298.201189)
			(xy 284.543648 -298.169819) (xy 284.591596 -298.145167) (xy 284.642623 -298.127759) (xy 284.695641 -298.117966)
			(xy 284.74952 -298.115997) (xy 284.803111 -298.121894) (xy 284.855272 -298.13553) (xy 284.904892 -298.156617)
			(xy 284.950913 -298.184703) (xy 284.992355 -298.219191) (xy 285.028333 -298.259345) (xy 285.058081 -298.304309)
			(xy 285.080966 -298.353126) (xy 285.096498 -298.404755) (xy 285.104348 -298.458095) (xy 285.10484 -298.485052)
			(xy 291.910785 -298.485052) (xy 291.91472 -298.431281) (xy 291.926443 -298.378657) (xy 291.945703 -298.3283)
			(xy 291.972089 -298.281283) (xy 292.005041 -298.23861) (xy 292.043854 -298.201189) (xy 292.087702 -298.169819)
			(xy 292.13565 -298.145167) (xy 292.186677 -298.127759) (xy 292.239695 -298.117966) (xy 292.293574 -298.115997)
			(xy 292.347165 -298.121894) (xy 292.399326 -298.13553) (xy 292.448946 -298.156617) (xy 292.494967 -298.184703)
			(xy 292.536409 -298.219191) (xy 292.572387 -298.259345) (xy 292.602135 -298.304309) (xy 292.62502 -298.353126)
			(xy 292.640552 -298.404755) (xy 292.648402 -298.458095) (xy 292.648894 -298.485052) (xy 292.648402 -298.512009)
			(xy 292.640552 -298.565349) (xy 292.62502 -298.616978) (xy 292.602135 -298.665795) (xy 292.572387 -298.710759)
			(xy 292.536409 -298.750913) (xy 292.494967 -298.785401) (xy 292.448946 -298.813487) (xy 292.399326 -298.834574)
			(xy 292.347165 -298.84821) (xy 292.293574 -298.854107) (xy 292.239695 -298.852138) (xy 292.186677 -298.842345)
			(xy 292.13565 -298.824937) (xy 292.087702 -298.800285) (xy 292.043854 -298.768915) (xy 292.005041 -298.731494)
			(xy 291.972089 -298.688821) (xy 291.945703 -298.641804) (xy 291.926443 -298.591447) (xy 291.91472 -298.538823)
			(xy 291.910785 -298.485052) (xy 285.10484 -298.485052) (xy 285.104348 -298.512009) (xy 285.096498 -298.565349)
			(xy 285.080966 -298.616978) (xy 285.058081 -298.665795) (xy 285.028333 -298.710759) (xy 284.992355 -298.750913)
			(xy 284.950913 -298.785401) (xy 284.904892 -298.813487) (xy 284.855272 -298.834574) (xy 284.803111 -298.84821)
			(xy 284.74952 -298.854107) (xy 284.695641 -298.852138) (xy 284.642623 -298.842345) (xy 284.591596 -298.824937)
			(xy 284.543648 -298.800285) (xy 284.4998 -298.768915) (xy 284.460987 -298.731494) (xy 284.428035 -298.688821)
			(xy 284.401649 -298.641804) (xy 284.382389 -298.591447) (xy 284.370666 -298.538823) (xy 284.366731 -298.485052)
			(xy 277.56104 -298.485052) (xy 277.560548 -298.512009) (xy 277.552698 -298.565349) (xy 277.537166 -298.616978)
			(xy 277.514281 -298.665795) (xy 277.484533 -298.710759) (xy 277.448555 -298.750913) (xy 277.407113 -298.785401)
			(xy 277.361092 -298.813487) (xy 277.311472 -298.834574) (xy 277.259311 -298.84821) (xy 277.20572 -298.854107)
			(xy 277.151841 -298.852138) (xy 277.098823 -298.842345) (xy 277.047796 -298.824937) (xy 276.999848 -298.800285)
			(xy 276.956 -298.768915) (xy 276.917187 -298.731494) (xy 276.884235 -298.688821) (xy 276.857849 -298.641804)
			(xy 276.838589 -298.591447) (xy 276.826866 -298.538823) (xy 276.822931 -298.485052) (xy 270.016986 -298.485052)
			(xy 270.016494 -298.512009) (xy 270.008644 -298.565349) (xy 269.993112 -298.616978) (xy 269.970227 -298.665795)
			(xy 269.940479 -298.710759) (xy 269.904501 -298.750913) (xy 269.863059 -298.785401) (xy 269.817038 -298.813487)
			(xy 269.767418 -298.834574) (xy 269.715257 -298.84821) (xy 269.661666 -298.854107) (xy 269.607787 -298.852138)
			(xy 269.554769 -298.842345) (xy 269.503742 -298.824937) (xy 269.455794 -298.800285) (xy 269.411946 -298.768915)
			(xy 269.373133 -298.731494) (xy 269.340181 -298.688821) (xy 269.313795 -298.641804) (xy 269.294535 -298.591447)
			(xy 269.282812 -298.538823) (xy 269.278877 -298.485052) (xy 264.143998 -298.485052) (xy 264.143998 -299.33519)
			(xy 265.178809 -299.33519) (xy 265.182744 -299.281419) (xy 265.194467 -299.228795) (xy 265.213727 -299.178438)
			(xy 265.240113 -299.131421) (xy 265.273065 -299.088748) (xy 265.311878 -299.051327) (xy 265.355726 -299.019957)
			(xy 265.403674 -298.995305) (xy 265.454701 -298.977897) (xy 265.507719 -298.968104) (xy 265.561598 -298.966135)
			(xy 265.615189 -298.972032) (xy 265.66735 -298.985668) (xy 265.71697 -299.006755) (xy 265.762991 -299.034841)
			(xy 265.804433 -299.069329) (xy 265.840411 -299.109483) (xy 265.870159 -299.154447) (xy 265.893044 -299.203264)
			(xy 265.908576 -299.254893) (xy 265.916426 -299.308233) (xy 265.916918 -299.33519) (xy 272.722863 -299.33519)
			(xy 272.726798 -299.281419) (xy 272.738521 -299.228795) (xy 272.757781 -299.178438) (xy 272.784167 -299.131421)
			(xy 272.817119 -299.088748) (xy 272.855932 -299.051327) (xy 272.89978 -299.019957) (xy 272.947728 -298.995305)
			(xy 272.998755 -298.977897) (xy 273.051773 -298.968104) (xy 273.105652 -298.966135) (xy 273.159243 -298.972032)
			(xy 273.211404 -298.985668) (xy 273.261024 -299.006755) (xy 273.307045 -299.034841) (xy 273.348487 -299.069329)
			(xy 273.384465 -299.109483) (xy 273.414213 -299.154447) (xy 273.437098 -299.203264) (xy 273.45263 -299.254893)
			(xy 273.46048 -299.308233) (xy 273.460972 -299.33519) (xy 280.266663 -299.33519) (xy 280.270598 -299.281419)
			(xy 280.282321 -299.228795) (xy 280.301581 -299.178438) (xy 280.327967 -299.131421) (xy 280.360919 -299.088748)
			(xy 280.399732 -299.051327) (xy 280.44358 -299.019957) (xy 280.491528 -298.995305) (xy 280.542555 -298.977897)
			(xy 280.595573 -298.968104) (xy 280.649452 -298.966135) (xy 280.703043 -298.972032) (xy 280.755204 -298.985668)
			(xy 280.804824 -299.006755) (xy 280.850845 -299.034841) (xy 280.892287 -299.069329) (xy 280.928265 -299.109483)
			(xy 280.958013 -299.154447) (xy 280.980898 -299.203264) (xy 280.99643 -299.254893) (xy 281.00428 -299.308233)
			(xy 281.004772 -299.33519) (xy 287.810717 -299.33519) (xy 287.814652 -299.281419) (xy 287.826375 -299.228795)
			(xy 287.845635 -299.178438) (xy 287.872021 -299.131421) (xy 287.904973 -299.088748) (xy 287.943786 -299.051327)
			(xy 287.987634 -299.019957) (xy 288.035582 -298.995305) (xy 288.086609 -298.977897) (xy 288.139627 -298.968104)
			(xy 288.193506 -298.966135) (xy 288.247097 -298.972032) (xy 288.299258 -298.985668) (xy 288.348878 -299.006755)
			(xy 288.394899 -299.034841) (xy 288.436341 -299.069329) (xy 288.472319 -299.109483) (xy 288.502067 -299.154447)
			(xy 288.524952 -299.203264) (xy 288.540484 -299.254893) (xy 288.548334 -299.308233) (xy 288.548826 -299.33519)
			(xy 288.548334 -299.362147) (xy 288.540484 -299.415487) (xy 288.524952 -299.467116) (xy 288.502067 -299.515933)
			(xy 288.472319 -299.560897) (xy 288.436341 -299.601051) (xy 288.394899 -299.635539) (xy 288.348878 -299.663625)
			(xy 288.299258 -299.684712) (xy 288.247097 -299.698348) (xy 288.193506 -299.704245) (xy 288.139627 -299.702276)
			(xy 288.086609 -299.692483) (xy 288.035582 -299.675075) (xy 287.987634 -299.650423) (xy 287.943786 -299.619053)
			(xy 287.904973 -299.581632) (xy 287.872021 -299.538959) (xy 287.845635 -299.491942) (xy 287.826375 -299.441585)
			(xy 287.814652 -299.388961) (xy 287.810717 -299.33519) (xy 281.004772 -299.33519) (xy 281.00428 -299.362147)
			(xy 280.99643 -299.415487) (xy 280.980898 -299.467116) (xy 280.958013 -299.515933) (xy 280.928265 -299.560897)
			(xy 280.892287 -299.601051) (xy 280.850845 -299.635539) (xy 280.804824 -299.663625) (xy 280.755204 -299.684712)
			(xy 280.703043 -299.698348) (xy 280.649452 -299.704245) (xy 280.595573 -299.702276) (xy 280.542555 -299.692483)
			(xy 280.491528 -299.675075) (xy 280.44358 -299.650423) (xy 280.399732 -299.619053) (xy 280.360919 -299.581632)
			(xy 280.327967 -299.538959) (xy 280.301581 -299.491942) (xy 280.282321 -299.441585) (xy 280.270598 -299.388961)
			(xy 280.266663 -299.33519) (xy 273.460972 -299.33519) (xy 273.46048 -299.362147) (xy 273.45263 -299.415487)
			(xy 273.437098 -299.467116) (xy 273.414213 -299.515933) (xy 273.384465 -299.560897) (xy 273.348487 -299.601051)
			(xy 273.307045 -299.635539) (xy 273.261024 -299.663625) (xy 273.211404 -299.684712) (xy 273.159243 -299.698348)
			(xy 273.105652 -299.704245) (xy 273.051773 -299.702276) (xy 272.998755 -299.692483) (xy 272.947728 -299.675075)
			(xy 272.89978 -299.650423) (xy 272.855932 -299.619053) (xy 272.817119 -299.581632) (xy 272.784167 -299.538959)
			(xy 272.757781 -299.491942) (xy 272.738521 -299.441585) (xy 272.726798 -299.388961) (xy 272.722863 -299.33519)
			(xy 265.916918 -299.33519) (xy 265.916426 -299.362147) (xy 265.908576 -299.415487) (xy 265.893044 -299.467116)
			(xy 265.870159 -299.515933) (xy 265.840411 -299.560897) (xy 265.804433 -299.601051) (xy 265.762991 -299.635539)
			(xy 265.71697 -299.663625) (xy 265.66735 -299.684712) (xy 265.615189 -299.698348) (xy 265.561598 -299.704245)
			(xy 265.507719 -299.702276) (xy 265.454701 -299.692483) (xy 265.403674 -299.675075) (xy 265.355726 -299.650423)
			(xy 265.311878 -299.619053) (xy 265.273065 -299.581632) (xy 265.240113 -299.538959) (xy 265.213727 -299.491942)
			(xy 265.194467 -299.441585) (xy 265.182744 -299.388961) (xy 265.178809 -299.33519) (xy 264.143998 -299.33519)
			(xy 264.143998 -300.185074) (xy 269.278877 -300.185074) (xy 269.282812 -300.131303) (xy 269.294535 -300.078679)
			(xy 269.313795 -300.028322) (xy 269.340181 -299.981305) (xy 269.373133 -299.938632) (xy 269.411946 -299.901211)
			(xy 269.455794 -299.869841) (xy 269.503742 -299.845189) (xy 269.554769 -299.827781) (xy 269.607787 -299.817988)
			(xy 269.661666 -299.816019) (xy 269.715257 -299.821916) (xy 269.767418 -299.835552) (xy 269.817038 -299.856639)
			(xy 269.863059 -299.884725) (xy 269.904501 -299.919213) (xy 269.940479 -299.959367) (xy 269.970227 -300.004331)
			(xy 269.993112 -300.053148) (xy 270.008644 -300.104777) (xy 270.016494 -300.158117) (xy 270.016986 -300.185074)
			(xy 276.822931 -300.185074) (xy 276.826866 -300.131303) (xy 276.838589 -300.078679) (xy 276.857849 -300.028322)
			(xy 276.884235 -299.981305) (xy 276.917187 -299.938632) (xy 276.956 -299.901211) (xy 276.999848 -299.869841)
			(xy 277.047796 -299.845189) (xy 277.098823 -299.827781) (xy 277.151841 -299.817988) (xy 277.20572 -299.816019)
			(xy 277.259311 -299.821916) (xy 277.311472 -299.835552) (xy 277.361092 -299.856639) (xy 277.407113 -299.884725)
			(xy 277.448555 -299.919213) (xy 277.484533 -299.959367) (xy 277.514281 -300.004331) (xy 277.537166 -300.053148)
			(xy 277.552698 -300.104777) (xy 277.560548 -300.158117) (xy 277.56104 -300.185074) (xy 284.366731 -300.185074)
			(xy 284.370666 -300.131303) (xy 284.382389 -300.078679) (xy 284.401649 -300.028322) (xy 284.428035 -299.981305)
			(xy 284.460987 -299.938632) (xy 284.4998 -299.901211) (xy 284.543648 -299.869841) (xy 284.591596 -299.845189)
			(xy 284.642623 -299.827781) (xy 284.695641 -299.817988) (xy 284.74952 -299.816019) (xy 284.803111 -299.821916)
			(xy 284.855272 -299.835552) (xy 284.904892 -299.856639) (xy 284.950913 -299.884725) (xy 284.992355 -299.919213)
			(xy 285.028333 -299.959367) (xy 285.058081 -300.004331) (xy 285.080966 -300.053148) (xy 285.096498 -300.104777)
			(xy 285.104348 -300.158117) (xy 285.10484 -300.185074) (xy 291.910785 -300.185074) (xy 291.91472 -300.131303)
			(xy 291.926443 -300.078679) (xy 291.945703 -300.028322) (xy 291.972089 -299.981305) (xy 292.005041 -299.938632)
			(xy 292.043854 -299.901211) (xy 292.087702 -299.869841) (xy 292.13565 -299.845189) (xy 292.186677 -299.827781)
			(xy 292.239695 -299.817988) (xy 292.293574 -299.816019) (xy 292.347165 -299.821916) (xy 292.399326 -299.835552)
			(xy 292.448946 -299.856639) (xy 292.494967 -299.884725) (xy 292.536409 -299.919213) (xy 292.572387 -299.959367)
			(xy 292.602135 -300.004331) (xy 292.62502 -300.053148) (xy 292.640552 -300.104777) (xy 292.648402 -300.158117)
			(xy 292.648894 -300.185074) (xy 292.648402 -300.212031) (xy 292.640552 -300.265371) (xy 292.62502 -300.317)
			(xy 292.602135 -300.365817) (xy 292.572387 -300.410781) (xy 292.536409 -300.450935) (xy 292.494967 -300.485423)
			(xy 292.448946 -300.513509) (xy 292.399326 -300.534596) (xy 292.347165 -300.548232) (xy 292.293574 -300.554129)
			(xy 292.239695 -300.55216) (xy 292.186677 -300.542367) (xy 292.13565 -300.524959) (xy 292.087702 -300.500307)
			(xy 292.043854 -300.468937) (xy 292.005041 -300.431516) (xy 291.972089 -300.388843) (xy 291.945703 -300.341826)
			(xy 291.926443 -300.291469) (xy 291.91472 -300.238845) (xy 291.910785 -300.185074) (xy 285.10484 -300.185074)
			(xy 285.104348 -300.212031) (xy 285.096498 -300.265371) (xy 285.080966 -300.317) (xy 285.058081 -300.365817)
			(xy 285.028333 -300.410781) (xy 284.992355 -300.450935) (xy 284.950913 -300.485423) (xy 284.904892 -300.513509)
			(xy 284.855272 -300.534596) (xy 284.803111 -300.548232) (xy 284.74952 -300.554129) (xy 284.695641 -300.55216)
			(xy 284.642623 -300.542367) (xy 284.591596 -300.524959) (xy 284.543648 -300.500307) (xy 284.4998 -300.468937)
			(xy 284.460987 -300.431516) (xy 284.428035 -300.388843) (xy 284.401649 -300.341826) (xy 284.382389 -300.291469)
			(xy 284.370666 -300.238845) (xy 284.366731 -300.185074) (xy 277.56104 -300.185074) (xy 277.560548 -300.212031)
			(xy 277.552698 -300.265371) (xy 277.537166 -300.317) (xy 277.514281 -300.365817) (xy 277.484533 -300.410781)
			(xy 277.448555 -300.450935) (xy 277.407113 -300.485423) (xy 277.361092 -300.513509) (xy 277.311472 -300.534596)
			(xy 277.259311 -300.548232) (xy 277.20572 -300.554129) (xy 277.151841 -300.55216) (xy 277.098823 -300.542367)
			(xy 277.047796 -300.524959) (xy 276.999848 -300.500307) (xy 276.956 -300.468937) (xy 276.917187 -300.431516)
			(xy 276.884235 -300.388843) (xy 276.857849 -300.341826) (xy 276.838589 -300.291469) (xy 276.826866 -300.238845)
			(xy 276.822931 -300.185074) (xy 270.016986 -300.185074) (xy 270.016494 -300.212031) (xy 270.008644 -300.265371)
			(xy 269.993112 -300.317) (xy 269.970227 -300.365817) (xy 269.940479 -300.410781) (xy 269.904501 -300.450935)
			(xy 269.863059 -300.485423) (xy 269.817038 -300.513509) (xy 269.767418 -300.534596) (xy 269.715257 -300.548232)
			(xy 269.661666 -300.554129) (xy 269.607787 -300.55216) (xy 269.554769 -300.542367) (xy 269.503742 -300.524959)
			(xy 269.455794 -300.500307) (xy 269.411946 -300.468937) (xy 269.373133 -300.431516) (xy 269.340181 -300.388843)
			(xy 269.313795 -300.341826) (xy 269.294535 -300.291469) (xy 269.282812 -300.238845) (xy 269.278877 -300.185074)
			(xy 264.143998 -300.185074) (xy 264.143998 -301.034958) (xy 265.178809 -301.034958) (xy 265.182744 -300.981187)
			(xy 265.194467 -300.928563) (xy 265.213727 -300.878206) (xy 265.240113 -300.831189) (xy 265.273065 -300.788516)
			(xy 265.311878 -300.751095) (xy 265.355726 -300.719725) (xy 265.403674 -300.695073) (xy 265.454701 -300.677665)
			(xy 265.507719 -300.667872) (xy 265.561598 -300.665903) (xy 265.615189 -300.6718) (xy 265.66735 -300.685436)
			(xy 265.71697 -300.706523) (xy 265.762991 -300.734609) (xy 265.804433 -300.769097) (xy 265.840411 -300.809251)
			(xy 265.870159 -300.854215) (xy 265.893044 -300.903032) (xy 265.908576 -300.954661) (xy 265.916426 -301.008001)
			(xy 265.916918 -301.034958) (xy 272.722863 -301.034958) (xy 272.726798 -300.981187) (xy 272.738521 -300.928563)
			(xy 272.757781 -300.878206) (xy 272.784167 -300.831189) (xy 272.817119 -300.788516) (xy 272.855932 -300.751095)
			(xy 272.89978 -300.719725) (xy 272.947728 -300.695073) (xy 272.998755 -300.677665) (xy 273.051773 -300.667872)
			(xy 273.105652 -300.665903) (xy 273.159243 -300.6718) (xy 273.211404 -300.685436) (xy 273.261024 -300.706523)
			(xy 273.307045 -300.734609) (xy 273.348487 -300.769097) (xy 273.384465 -300.809251) (xy 273.414213 -300.854215)
			(xy 273.437098 -300.903032) (xy 273.45263 -300.954661) (xy 273.46048 -301.008001) (xy 273.460972 -301.034958)
			(xy 280.266663 -301.034958) (xy 280.270598 -300.981187) (xy 280.282321 -300.928563) (xy 280.301581 -300.878206)
			(xy 280.327967 -300.831189) (xy 280.360919 -300.788516) (xy 280.399732 -300.751095) (xy 280.44358 -300.719725)
			(xy 280.491528 -300.695073) (xy 280.542555 -300.677665) (xy 280.595573 -300.667872) (xy 280.649452 -300.665903)
			(xy 280.703043 -300.6718) (xy 280.755204 -300.685436) (xy 280.804824 -300.706523) (xy 280.850845 -300.734609)
			(xy 280.892287 -300.769097) (xy 280.928265 -300.809251) (xy 280.958013 -300.854215) (xy 280.980898 -300.903032)
			(xy 280.99643 -300.954661) (xy 281.00428 -301.008001) (xy 281.004772 -301.034958) (xy 287.810717 -301.034958)
			(xy 287.814652 -300.981187) (xy 287.826375 -300.928563) (xy 287.845635 -300.878206) (xy 287.872021 -300.831189)
			(xy 287.904973 -300.788516) (xy 287.943786 -300.751095) (xy 287.987634 -300.719725) (xy 288.035582 -300.695073)
			(xy 288.086609 -300.677665) (xy 288.139627 -300.667872) (xy 288.193506 -300.665903) (xy 288.247097 -300.6718)
			(xy 288.299258 -300.685436) (xy 288.348878 -300.706523) (xy 288.394899 -300.734609) (xy 288.436341 -300.769097)
			(xy 288.472319 -300.809251) (xy 288.502067 -300.854215) (xy 288.524952 -300.903032) (xy 288.540484 -300.954661)
			(xy 288.548334 -301.008001) (xy 288.548826 -301.034958) (xy 288.548334 -301.061915) (xy 288.540484 -301.115255)
			(xy 288.524952 -301.166884) (xy 288.502067 -301.215701) (xy 288.472319 -301.260665) (xy 288.436341 -301.300819)
			(xy 288.394899 -301.335307) (xy 288.348878 -301.363393) (xy 288.299258 -301.38448) (xy 288.247097 -301.398116)
			(xy 288.193506 -301.404013) (xy 288.139627 -301.402044) (xy 288.086609 -301.392251) (xy 288.035582 -301.374843)
			(xy 287.987634 -301.350191) (xy 287.943786 -301.318821) (xy 287.904973 -301.2814) (xy 287.872021 -301.238727)
			(xy 287.845635 -301.19171) (xy 287.826375 -301.141353) (xy 287.814652 -301.088729) (xy 287.810717 -301.034958)
			(xy 281.004772 -301.034958) (xy 281.00428 -301.061915) (xy 280.99643 -301.115255) (xy 280.980898 -301.166884)
			(xy 280.958013 -301.215701) (xy 280.928265 -301.260665) (xy 280.892287 -301.300819) (xy 280.850845 -301.335307)
			(xy 280.804824 -301.363393) (xy 280.755204 -301.38448) (xy 280.703043 -301.398116) (xy 280.649452 -301.404013)
			(xy 280.595573 -301.402044) (xy 280.542555 -301.392251) (xy 280.491528 -301.374843) (xy 280.44358 -301.350191)
			(xy 280.399732 -301.318821) (xy 280.360919 -301.2814) (xy 280.327967 -301.238727) (xy 280.301581 -301.19171)
			(xy 280.282321 -301.141353) (xy 280.270598 -301.088729) (xy 280.266663 -301.034958) (xy 273.460972 -301.034958)
			(xy 273.46048 -301.061915) (xy 273.45263 -301.115255) (xy 273.437098 -301.166884) (xy 273.414213 -301.215701)
			(xy 273.384465 -301.260665) (xy 273.348487 -301.300819) (xy 273.307045 -301.335307) (xy 273.261024 -301.363393)
			(xy 273.211404 -301.38448) (xy 273.159243 -301.398116) (xy 273.105652 -301.404013) (xy 273.051773 -301.402044)
			(xy 272.998755 -301.392251) (xy 272.947728 -301.374843) (xy 272.89978 -301.350191) (xy 272.855932 -301.318821)
			(xy 272.817119 -301.2814) (xy 272.784167 -301.238727) (xy 272.757781 -301.19171) (xy 272.738521 -301.141353)
			(xy 272.726798 -301.088729) (xy 272.722863 -301.034958) (xy 265.916918 -301.034958) (xy 265.916426 -301.061915)
			(xy 265.908576 -301.115255) (xy 265.893044 -301.166884) (xy 265.870159 -301.215701) (xy 265.840411 -301.260665)
			(xy 265.804433 -301.300819) (xy 265.762991 -301.335307) (xy 265.71697 -301.363393) (xy 265.66735 -301.38448)
			(xy 265.615189 -301.398116) (xy 265.561598 -301.404013) (xy 265.507719 -301.402044) (xy 265.454701 -301.392251)
			(xy 265.403674 -301.374843) (xy 265.355726 -301.350191) (xy 265.311878 -301.318821) (xy 265.273065 -301.2814)
			(xy 265.240113 -301.238727) (xy 265.213727 -301.19171) (xy 265.194467 -301.141353) (xy 265.182744 -301.088729)
			(xy 265.178809 -301.034958) (xy 264.143998 -301.034958) (xy 264.143998 -301.885096) (xy 269.278877 -301.885096)
			(xy 269.282812 -301.831325) (xy 269.294535 -301.778701) (xy 269.313795 -301.728344) (xy 269.340181 -301.681327)
			(xy 269.373133 -301.638654) (xy 269.411946 -301.601233) (xy 269.455794 -301.569863) (xy 269.503742 -301.545211)
			(xy 269.554769 -301.527803) (xy 269.607787 -301.51801) (xy 269.661666 -301.516041) (xy 269.715257 -301.521938)
			(xy 269.767418 -301.535574) (xy 269.817038 -301.556661) (xy 269.863059 -301.584747) (xy 269.904501 -301.619235)
			(xy 269.940479 -301.659389) (xy 269.970227 -301.704353) (xy 269.993112 -301.75317) (xy 270.008644 -301.804799)
			(xy 270.016494 -301.858139) (xy 270.016986 -301.885096) (xy 276.822931 -301.885096) (xy 276.826866 -301.831325)
			(xy 276.838589 -301.778701) (xy 276.857849 -301.728344) (xy 276.884235 -301.681327) (xy 276.917187 -301.638654)
			(xy 276.956 -301.601233) (xy 276.999848 -301.569863) (xy 277.047796 -301.545211) (xy 277.098823 -301.527803)
			(xy 277.151841 -301.51801) (xy 277.20572 -301.516041) (xy 277.259311 -301.521938) (xy 277.311472 -301.535574)
			(xy 277.361092 -301.556661) (xy 277.407113 -301.584747) (xy 277.448555 -301.619235) (xy 277.484533 -301.659389)
			(xy 277.514281 -301.704353) (xy 277.537166 -301.75317) (xy 277.552698 -301.804799) (xy 277.560548 -301.858139)
			(xy 277.56104 -301.885096) (xy 284.366731 -301.885096) (xy 284.370666 -301.831325) (xy 284.382389 -301.778701)
			(xy 284.401649 -301.728344) (xy 284.428035 -301.681327) (xy 284.460987 -301.638654) (xy 284.4998 -301.601233)
			(xy 284.543648 -301.569863) (xy 284.591596 -301.545211) (xy 284.642623 -301.527803) (xy 284.695641 -301.51801)
			(xy 284.74952 -301.516041) (xy 284.803111 -301.521938) (xy 284.855272 -301.535574) (xy 284.904892 -301.556661)
			(xy 284.950913 -301.584747) (xy 284.992355 -301.619235) (xy 285.028333 -301.659389) (xy 285.058081 -301.704353)
			(xy 285.080966 -301.75317) (xy 285.096498 -301.804799) (xy 285.104348 -301.858139) (xy 285.10484 -301.885096)
			(xy 291.910785 -301.885096) (xy 291.91472 -301.831325) (xy 291.926443 -301.778701) (xy 291.945703 -301.728344)
			(xy 291.972089 -301.681327) (xy 292.005041 -301.638654) (xy 292.043854 -301.601233) (xy 292.087702 -301.569863)
			(xy 292.13565 -301.545211) (xy 292.186677 -301.527803) (xy 292.239695 -301.51801) (xy 292.293574 -301.516041)
			(xy 292.347165 -301.521938) (xy 292.399326 -301.535574) (xy 292.448946 -301.556661) (xy 292.494967 -301.584747)
			(xy 292.536409 -301.619235) (xy 292.572387 -301.659389) (xy 292.602135 -301.704353) (xy 292.62502 -301.75317)
			(xy 292.640552 -301.804799) (xy 292.648402 -301.858139) (xy 292.648894 -301.885096) (xy 292.648402 -301.912053)
			(xy 292.640552 -301.965393) (xy 292.62502 -302.017022) (xy 292.602135 -302.065839) (xy 292.572387 -302.110803)
			(xy 292.536409 -302.150957) (xy 292.494967 -302.185445) (xy 292.448946 -302.213531) (xy 292.399326 -302.234618)
			(xy 292.347165 -302.248254) (xy 292.293574 -302.254151) (xy 292.239695 -302.252182) (xy 292.186677 -302.242389)
			(xy 292.13565 -302.224981) (xy 292.087702 -302.200329) (xy 292.043854 -302.168959) (xy 292.005041 -302.131538)
			(xy 291.972089 -302.088865) (xy 291.945703 -302.041848) (xy 291.926443 -301.991491) (xy 291.91472 -301.938867)
			(xy 291.910785 -301.885096) (xy 285.10484 -301.885096) (xy 285.104348 -301.912053) (xy 285.096498 -301.965393)
			(xy 285.080966 -302.017022) (xy 285.058081 -302.065839) (xy 285.028333 -302.110803) (xy 284.992355 -302.150957)
			(xy 284.950913 -302.185445) (xy 284.904892 -302.213531) (xy 284.855272 -302.234618) (xy 284.803111 -302.248254)
			(xy 284.74952 -302.254151) (xy 284.695641 -302.252182) (xy 284.642623 -302.242389) (xy 284.591596 -302.224981)
			(xy 284.543648 -302.200329) (xy 284.4998 -302.168959) (xy 284.460987 -302.131538) (xy 284.428035 -302.088865)
			(xy 284.401649 -302.041848) (xy 284.382389 -301.991491) (xy 284.370666 -301.938867) (xy 284.366731 -301.885096)
			(xy 277.56104 -301.885096) (xy 277.560548 -301.912053) (xy 277.552698 -301.965393) (xy 277.537166 -302.017022)
			(xy 277.514281 -302.065839) (xy 277.484533 -302.110803) (xy 277.448555 -302.150957) (xy 277.407113 -302.185445)
			(xy 277.361092 -302.213531) (xy 277.311472 -302.234618) (xy 277.259311 -302.248254) (xy 277.20572 -302.254151)
			(xy 277.151841 -302.252182) (xy 277.098823 -302.242389) (xy 277.047796 -302.224981) (xy 276.999848 -302.200329)
			(xy 276.956 -302.168959) (xy 276.917187 -302.131538) (xy 276.884235 -302.088865) (xy 276.857849 -302.041848)
			(xy 276.838589 -301.991491) (xy 276.826866 -301.938867) (xy 276.822931 -301.885096) (xy 270.016986 -301.885096)
			(xy 270.016494 -301.912053) (xy 270.008644 -301.965393) (xy 269.993112 -302.017022) (xy 269.970227 -302.065839)
			(xy 269.940479 -302.110803) (xy 269.904501 -302.150957) (xy 269.863059 -302.185445) (xy 269.817038 -302.213531)
			(xy 269.767418 -302.234618) (xy 269.715257 -302.248254) (xy 269.661666 -302.254151) (xy 269.607787 -302.252182)
			(xy 269.554769 -302.242389) (xy 269.503742 -302.224981) (xy 269.455794 -302.200329) (xy 269.411946 -302.168959)
			(xy 269.373133 -302.131538) (xy 269.340181 -302.088865) (xy 269.313795 -302.041848) (xy 269.294535 -301.991491)
			(xy 269.282812 -301.938867) (xy 269.278877 -301.885096) (xy 264.143998 -301.885096) (xy 264.143998 -302.73498)
			(xy 265.178809 -302.73498) (xy 265.182744 -302.681209) (xy 265.194467 -302.628585) (xy 265.213727 -302.578228)
			(xy 265.240113 -302.531211) (xy 265.273065 -302.488538) (xy 265.311878 -302.451117) (xy 265.355726 -302.419747)
			(xy 265.403674 -302.395095) (xy 265.454701 -302.377687) (xy 265.507719 -302.367894) (xy 265.561598 -302.365925)
			(xy 265.615189 -302.371822) (xy 265.66735 -302.385458) (xy 265.71697 -302.406545) (xy 265.762991 -302.434631)
			(xy 265.804433 -302.469119) (xy 265.840411 -302.509273) (xy 265.870159 -302.554237) (xy 265.893044 -302.603054)
			(xy 265.908576 -302.654683) (xy 265.916426 -302.708023) (xy 265.916918 -302.73498) (xy 272.722863 -302.73498)
			(xy 272.726798 -302.681209) (xy 272.738521 -302.628585) (xy 272.757781 -302.578228) (xy 272.784167 -302.531211)
			(xy 272.817119 -302.488538) (xy 272.855932 -302.451117) (xy 272.89978 -302.419747) (xy 272.947728 -302.395095)
			(xy 272.998755 -302.377687) (xy 273.051773 -302.367894) (xy 273.105652 -302.365925) (xy 273.159243 -302.371822)
			(xy 273.211404 -302.385458) (xy 273.261024 -302.406545) (xy 273.307045 -302.434631) (xy 273.348487 -302.469119)
			(xy 273.384465 -302.509273) (xy 273.414213 -302.554237) (xy 273.437098 -302.603054) (xy 273.45263 -302.654683)
			(xy 273.46048 -302.708023) (xy 273.460972 -302.73498) (xy 280.266663 -302.73498) (xy 280.270598 -302.681209)
			(xy 280.282321 -302.628585) (xy 280.301581 -302.578228) (xy 280.327967 -302.531211) (xy 280.360919 -302.488538)
			(xy 280.399732 -302.451117) (xy 280.44358 -302.419747) (xy 280.491528 -302.395095) (xy 280.542555 -302.377687)
			(xy 280.595573 -302.367894) (xy 280.649452 -302.365925) (xy 280.703043 -302.371822) (xy 280.755204 -302.385458)
			(xy 280.804824 -302.406545) (xy 280.850845 -302.434631) (xy 280.892287 -302.469119) (xy 280.928265 -302.509273)
			(xy 280.958013 -302.554237) (xy 280.980898 -302.603054) (xy 280.99643 -302.654683) (xy 281.00428 -302.708023)
			(xy 281.004772 -302.73498) (xy 287.810717 -302.73498) (xy 287.814652 -302.681209) (xy 287.826375 -302.628585)
			(xy 287.845635 -302.578228) (xy 287.872021 -302.531211) (xy 287.904973 -302.488538) (xy 287.943786 -302.451117)
			(xy 287.987634 -302.419747) (xy 288.035582 -302.395095) (xy 288.086609 -302.377687) (xy 288.139627 -302.367894)
			(xy 288.193506 -302.365925) (xy 288.247097 -302.371822) (xy 288.299258 -302.385458) (xy 288.348878 -302.406545)
			(xy 288.394899 -302.434631) (xy 288.436341 -302.469119) (xy 288.472319 -302.509273) (xy 288.502067 -302.554237)
			(xy 288.524952 -302.603054) (xy 288.540484 -302.654683) (xy 288.548334 -302.708023) (xy 288.548826 -302.73498)
			(xy 288.548334 -302.761937) (xy 288.540484 -302.815277) (xy 288.524952 -302.866906) (xy 288.502067 -302.915723)
			(xy 288.472319 -302.960687) (xy 288.436341 -303.000841) (xy 288.394899 -303.035329) (xy 288.348878 -303.063415)
			(xy 288.299258 -303.084502) (xy 288.247097 -303.098138) (xy 288.193506 -303.104035) (xy 288.139627 -303.102066)
			(xy 288.086609 -303.092273) (xy 288.035582 -303.074865) (xy 287.987634 -303.050213) (xy 287.943786 -303.018843)
			(xy 287.904973 -302.981422) (xy 287.872021 -302.938749) (xy 287.845635 -302.891732) (xy 287.826375 -302.841375)
			(xy 287.814652 -302.788751) (xy 287.810717 -302.73498) (xy 281.004772 -302.73498) (xy 281.00428 -302.761937)
			(xy 280.99643 -302.815277) (xy 280.980898 -302.866906) (xy 280.958013 -302.915723) (xy 280.928265 -302.960687)
			(xy 280.892287 -303.000841) (xy 280.850845 -303.035329) (xy 280.804824 -303.063415) (xy 280.755204 -303.084502)
			(xy 280.703043 -303.098138) (xy 280.649452 -303.104035) (xy 280.595573 -303.102066) (xy 280.542555 -303.092273)
			(xy 280.491528 -303.074865) (xy 280.44358 -303.050213) (xy 280.399732 -303.018843) (xy 280.360919 -302.981422)
			(xy 280.327967 -302.938749) (xy 280.301581 -302.891732) (xy 280.282321 -302.841375) (xy 280.270598 -302.788751)
			(xy 280.266663 -302.73498) (xy 273.460972 -302.73498) (xy 273.46048 -302.761937) (xy 273.45263 -302.815277)
			(xy 273.437098 -302.866906) (xy 273.414213 -302.915723) (xy 273.384465 -302.960687) (xy 273.348487 -303.000841)
			(xy 273.307045 -303.035329) (xy 273.261024 -303.063415) (xy 273.211404 -303.084502) (xy 273.159243 -303.098138)
			(xy 273.105652 -303.104035) (xy 273.051773 -303.102066) (xy 272.998755 -303.092273) (xy 272.947728 -303.074865)
			(xy 272.89978 -303.050213) (xy 272.855932 -303.018843) (xy 272.817119 -302.981422) (xy 272.784167 -302.938749)
			(xy 272.757781 -302.891732) (xy 272.738521 -302.841375) (xy 272.726798 -302.788751) (xy 272.722863 -302.73498)
			(xy 265.916918 -302.73498) (xy 265.916426 -302.761937) (xy 265.908576 -302.815277) (xy 265.893044 -302.866906)
			(xy 265.870159 -302.915723) (xy 265.840411 -302.960687) (xy 265.804433 -303.000841) (xy 265.762991 -303.035329)
			(xy 265.71697 -303.063415) (xy 265.66735 -303.084502) (xy 265.615189 -303.098138) (xy 265.561598 -303.104035)
			(xy 265.507719 -303.102066) (xy 265.454701 -303.092273) (xy 265.403674 -303.074865) (xy 265.355726 -303.050213)
			(xy 265.311878 -303.018843) (xy 265.273065 -302.981422) (xy 265.240113 -302.938749) (xy 265.213727 -302.891732)
			(xy 265.194467 -302.841375) (xy 265.182744 -302.788751) (xy 265.178809 -302.73498) (xy 264.143998 -302.73498)
			(xy 264.143998 -303.585118) (xy 269.278877 -303.585118) (xy 269.282812 -303.531347) (xy 269.294535 -303.478723)
			(xy 269.313795 -303.428366) (xy 269.340181 -303.381349) (xy 269.373133 -303.338676) (xy 269.411946 -303.301255)
			(xy 269.455794 -303.269885) (xy 269.503742 -303.245233) (xy 269.554769 -303.227825) (xy 269.607787 -303.218032)
			(xy 269.661666 -303.216063) (xy 269.715257 -303.22196) (xy 269.767418 -303.235596) (xy 269.817038 -303.256683)
			(xy 269.863059 -303.284769) (xy 269.904501 -303.319257) (xy 269.940479 -303.359411) (xy 269.970227 -303.404375)
			(xy 269.993112 -303.453192) (xy 270.008644 -303.504821) (xy 270.016494 -303.558161) (xy 270.016986 -303.585118)
			(xy 276.822931 -303.585118) (xy 276.826866 -303.531347) (xy 276.838589 -303.478723) (xy 276.857849 -303.428366)
			(xy 276.884235 -303.381349) (xy 276.917187 -303.338676) (xy 276.956 -303.301255) (xy 276.999848 -303.269885)
			(xy 277.047796 -303.245233) (xy 277.098823 -303.227825) (xy 277.151841 -303.218032) (xy 277.20572 -303.216063)
			(xy 277.259311 -303.22196) (xy 277.311472 -303.235596) (xy 277.361092 -303.256683) (xy 277.407113 -303.284769)
			(xy 277.448555 -303.319257) (xy 277.484533 -303.359411) (xy 277.514281 -303.404375) (xy 277.537166 -303.453192)
			(xy 277.552698 -303.504821) (xy 277.560548 -303.558161) (xy 277.56104 -303.585118) (xy 284.366731 -303.585118)
			(xy 284.370666 -303.531347) (xy 284.382389 -303.478723) (xy 284.401649 -303.428366) (xy 284.428035 -303.381349)
			(xy 284.460987 -303.338676) (xy 284.4998 -303.301255) (xy 284.543648 -303.269885) (xy 284.591596 -303.245233)
			(xy 284.642623 -303.227825) (xy 284.695641 -303.218032) (xy 284.74952 -303.216063) (xy 284.803111 -303.22196)
			(xy 284.855272 -303.235596) (xy 284.904892 -303.256683) (xy 284.950913 -303.284769) (xy 284.992355 -303.319257)
			(xy 285.028333 -303.359411) (xy 285.058081 -303.404375) (xy 285.080966 -303.453192) (xy 285.096498 -303.504821)
			(xy 285.104348 -303.558161) (xy 285.10484 -303.585118) (xy 291.910785 -303.585118) (xy 291.91472 -303.531347)
			(xy 291.926443 -303.478723) (xy 291.945703 -303.428366) (xy 291.972089 -303.381349) (xy 292.005041 -303.338676)
			(xy 292.043854 -303.301255) (xy 292.087702 -303.269885) (xy 292.13565 -303.245233) (xy 292.186677 -303.227825)
			(xy 292.239695 -303.218032) (xy 292.293574 -303.216063) (xy 292.347165 -303.22196) (xy 292.399326 -303.235596)
			(xy 292.448946 -303.256683) (xy 292.494967 -303.284769) (xy 292.536409 -303.319257) (xy 292.572387 -303.359411)
			(xy 292.602135 -303.404375) (xy 292.62502 -303.453192) (xy 292.640552 -303.504821) (xy 292.648402 -303.558161)
			(xy 292.648894 -303.585118) (xy 292.648402 -303.612075) (xy 292.640552 -303.665415) (xy 292.62502 -303.717044)
			(xy 292.602135 -303.765861) (xy 292.572387 -303.810825) (xy 292.536409 -303.850979) (xy 292.494967 -303.885467)
			(xy 292.448946 -303.913553) (xy 292.399326 -303.93464) (xy 292.347165 -303.948276) (xy 292.293574 -303.954173)
			(xy 292.239695 -303.952204) (xy 292.186677 -303.942411) (xy 292.13565 -303.925003) (xy 292.087702 -303.900351)
			(xy 292.043854 -303.868981) (xy 292.005041 -303.83156) (xy 291.972089 -303.788887) (xy 291.945703 -303.74187)
			(xy 291.926443 -303.691513) (xy 291.91472 -303.638889) (xy 291.910785 -303.585118) (xy 285.10484 -303.585118)
			(xy 285.104348 -303.612075) (xy 285.096498 -303.665415) (xy 285.080966 -303.717044) (xy 285.058081 -303.765861)
			(xy 285.028333 -303.810825) (xy 284.992355 -303.850979) (xy 284.950913 -303.885467) (xy 284.904892 -303.913553)
			(xy 284.855272 -303.93464) (xy 284.803111 -303.948276) (xy 284.74952 -303.954173) (xy 284.695641 -303.952204)
			(xy 284.642623 -303.942411) (xy 284.591596 -303.925003) (xy 284.543648 -303.900351) (xy 284.4998 -303.868981)
			(xy 284.460987 -303.83156) (xy 284.428035 -303.788887) (xy 284.401649 -303.74187) (xy 284.382389 -303.691513)
			(xy 284.370666 -303.638889) (xy 284.366731 -303.585118) (xy 277.56104 -303.585118) (xy 277.560548 -303.612075)
			(xy 277.552698 -303.665415) (xy 277.537166 -303.717044) (xy 277.514281 -303.765861) (xy 277.484533 -303.810825)
			(xy 277.448555 -303.850979) (xy 277.407113 -303.885467) (xy 277.361092 -303.913553) (xy 277.311472 -303.93464)
			(xy 277.259311 -303.948276) (xy 277.20572 -303.954173) (xy 277.151841 -303.952204) (xy 277.098823 -303.942411)
			(xy 277.047796 -303.925003) (xy 276.999848 -303.900351) (xy 276.956 -303.868981) (xy 276.917187 -303.83156)
			(xy 276.884235 -303.788887) (xy 276.857849 -303.74187) (xy 276.838589 -303.691513) (xy 276.826866 -303.638889)
			(xy 276.822931 -303.585118) (xy 270.016986 -303.585118) (xy 270.016494 -303.612075) (xy 270.008644 -303.665415)
			(xy 269.993112 -303.717044) (xy 269.970227 -303.765861) (xy 269.940479 -303.810825) (xy 269.904501 -303.850979)
			(xy 269.863059 -303.885467) (xy 269.817038 -303.913553) (xy 269.767418 -303.93464) (xy 269.715257 -303.948276)
			(xy 269.661666 -303.954173) (xy 269.607787 -303.952204) (xy 269.554769 -303.942411) (xy 269.503742 -303.925003)
			(xy 269.455794 -303.900351) (xy 269.411946 -303.868981) (xy 269.373133 -303.83156) (xy 269.340181 -303.788887)
			(xy 269.313795 -303.74187) (xy 269.294535 -303.691513) (xy 269.282812 -303.638889) (xy 269.278877 -303.585118)
			(xy 264.143998 -303.585118) (xy 264.143998 -304.435002) (xy 265.178809 -304.435002) (xy 265.182744 -304.381231)
			(xy 265.194467 -304.328607) (xy 265.213727 -304.27825) (xy 265.240113 -304.231233) (xy 265.273065 -304.18856)
			(xy 265.311878 -304.151139) (xy 265.355726 -304.119769) (xy 265.403674 -304.095117) (xy 265.454701 -304.077709)
			(xy 265.507719 -304.067916) (xy 265.561598 -304.065947) (xy 265.615189 -304.071844) (xy 265.66735 -304.08548)
			(xy 265.71697 -304.106567) (xy 265.762991 -304.134653) (xy 265.804433 -304.169141) (xy 265.840411 -304.209295)
			(xy 265.870159 -304.254259) (xy 265.893044 -304.303076) (xy 265.908576 -304.354705) (xy 265.916426 -304.408045)
			(xy 265.916918 -304.435002) (xy 269.278877 -304.435002) (xy 269.282812 -304.381231) (xy 269.294535 -304.328607)
			(xy 269.313795 -304.27825) (xy 269.340181 -304.231233) (xy 269.373133 -304.18856) (xy 269.411946 -304.151139)
			(xy 269.455794 -304.119769) (xy 269.503742 -304.095117) (xy 269.554769 -304.077709) (xy 269.607787 -304.067916)
			(xy 269.661666 -304.065947) (xy 269.715257 -304.071844) (xy 269.767418 -304.08548) (xy 269.817038 -304.106567)
			(xy 269.863059 -304.134653) (xy 269.904501 -304.169141) (xy 269.940479 -304.209295) (xy 269.970227 -304.254259)
			(xy 269.993112 -304.303076) (xy 270.008644 -304.354705) (xy 270.016494 -304.408045) (xy 270.016986 -304.435002)
			(xy 272.722863 -304.435002) (xy 272.726798 -304.381231) (xy 272.738521 -304.328607) (xy 272.757781 -304.27825)
			(xy 272.784167 -304.231233) (xy 272.817119 -304.18856) (xy 272.855932 -304.151139) (xy 272.89978 -304.119769)
			(xy 272.947728 -304.095117) (xy 272.998755 -304.077709) (xy 273.051773 -304.067916) (xy 273.105652 -304.065947)
			(xy 273.159243 -304.071844) (xy 273.211404 -304.08548) (xy 273.261024 -304.106567) (xy 273.307045 -304.134653)
			(xy 273.348487 -304.169141) (xy 273.384465 -304.209295) (xy 273.414213 -304.254259) (xy 273.437098 -304.303076)
			(xy 273.45263 -304.354705) (xy 273.46048 -304.408045) (xy 273.460972 -304.435002) (xy 276.822931 -304.435002)
			(xy 276.826866 -304.381231) (xy 276.838589 -304.328607) (xy 276.857849 -304.27825) (xy 276.884235 -304.231233)
			(xy 276.917187 -304.18856) (xy 276.956 -304.151139) (xy 276.999848 -304.119769) (xy 277.047796 -304.095117)
			(xy 277.098823 -304.077709) (xy 277.151841 -304.067916) (xy 277.20572 -304.065947) (xy 277.259311 -304.071844)
			(xy 277.311472 -304.08548) (xy 277.361092 -304.106567) (xy 277.407113 -304.134653) (xy 277.448555 -304.169141)
			(xy 277.484533 -304.209295) (xy 277.514281 -304.254259) (xy 277.537166 -304.303076) (xy 277.552698 -304.354705)
			(xy 277.560548 -304.408045) (xy 277.56104 -304.435002) (xy 280.266663 -304.435002) (xy 280.270598 -304.381231)
			(xy 280.282321 -304.328607) (xy 280.301581 -304.27825) (xy 280.327967 -304.231233) (xy 280.360919 -304.18856)
			(xy 280.399732 -304.151139) (xy 280.44358 -304.119769) (xy 280.491528 -304.095117) (xy 280.542555 -304.077709)
			(xy 280.595573 -304.067916) (xy 280.649452 -304.065947) (xy 280.703043 -304.071844) (xy 280.755204 -304.08548)
			(xy 280.804824 -304.106567) (xy 280.850845 -304.134653) (xy 280.892287 -304.169141) (xy 280.928265 -304.209295)
			(xy 280.958013 -304.254259) (xy 280.980898 -304.303076) (xy 280.99643 -304.354705) (xy 281.00428 -304.408045)
			(xy 281.004772 -304.435002) (xy 284.366731 -304.435002) (xy 284.370666 -304.381231) (xy 284.382389 -304.328607)
			(xy 284.401649 -304.27825) (xy 284.428035 -304.231233) (xy 284.460987 -304.18856) (xy 284.4998 -304.151139)
			(xy 284.543648 -304.119769) (xy 284.591596 -304.095117) (xy 284.642623 -304.077709) (xy 284.695641 -304.067916)
			(xy 284.74952 -304.065947) (xy 284.803111 -304.071844) (xy 284.855272 -304.08548) (xy 284.904892 -304.106567)
			(xy 284.950913 -304.134653) (xy 284.992355 -304.169141) (xy 285.028333 -304.209295) (xy 285.058081 -304.254259)
			(xy 285.080966 -304.303076) (xy 285.096498 -304.354705) (xy 285.104348 -304.408045) (xy 285.10484 -304.435002)
			(xy 287.810717 -304.435002) (xy 287.814652 -304.381231) (xy 287.826375 -304.328607) (xy 287.845635 -304.27825)
			(xy 287.872021 -304.231233) (xy 287.904973 -304.18856) (xy 287.943786 -304.151139) (xy 287.987634 -304.119769)
			(xy 288.035582 -304.095117) (xy 288.086609 -304.077709) (xy 288.139627 -304.067916) (xy 288.193506 -304.065947)
			(xy 288.247097 -304.071844) (xy 288.299258 -304.08548) (xy 288.348878 -304.106567) (xy 288.394899 -304.134653)
			(xy 288.436341 -304.169141) (xy 288.472319 -304.209295) (xy 288.502067 -304.254259) (xy 288.524952 -304.303076)
			(xy 288.540484 -304.354705) (xy 288.548334 -304.408045) (xy 288.548826 -304.435002) (xy 291.910785 -304.435002)
			(xy 291.91472 -304.381231) (xy 291.926443 -304.328607) (xy 291.945703 -304.27825) (xy 291.972089 -304.231233)
			(xy 292.005041 -304.18856) (xy 292.043854 -304.151139) (xy 292.087702 -304.119769) (xy 292.13565 -304.095117)
			(xy 292.186677 -304.077709) (xy 292.239695 -304.067916) (xy 292.293574 -304.065947) (xy 292.347165 -304.071844)
			(xy 292.399326 -304.08548) (xy 292.448946 -304.106567) (xy 292.494967 -304.134653) (xy 292.536409 -304.169141)
			(xy 292.572387 -304.209295) (xy 292.602135 -304.254259) (xy 292.62502 -304.303076) (xy 292.640552 -304.354705)
			(xy 292.648402 -304.408045) (xy 292.648894 -304.435002) (xy 292.648402 -304.461959) (xy 292.640552 -304.515299)
			(xy 292.62502 -304.566928) (xy 292.602135 -304.615745) (xy 292.572387 -304.660709) (xy 292.536409 -304.700863)
			(xy 292.494967 -304.735351) (xy 292.448946 -304.763437) (xy 292.399326 -304.784524) (xy 292.347165 -304.79816)
			(xy 292.293574 -304.804057) (xy 292.239695 -304.802088) (xy 292.186677 -304.792295) (xy 292.13565 -304.774887)
			(xy 292.087702 -304.750235) (xy 292.043854 -304.718865) (xy 292.005041 -304.681444) (xy 291.972089 -304.638771)
			(xy 291.945703 -304.591754) (xy 291.926443 -304.541397) (xy 291.91472 -304.488773) (xy 291.910785 -304.435002)
			(xy 288.548826 -304.435002) (xy 288.548334 -304.461959) (xy 288.540484 -304.515299) (xy 288.524952 -304.566928)
			(xy 288.502067 -304.615745) (xy 288.472319 -304.660709) (xy 288.436341 -304.700863) (xy 288.394899 -304.735351)
			(xy 288.348878 -304.763437) (xy 288.299258 -304.784524) (xy 288.247097 -304.79816) (xy 288.193506 -304.804057)
			(xy 288.139627 -304.802088) (xy 288.086609 -304.792295) (xy 288.035582 -304.774887) (xy 287.987634 -304.750235)
			(xy 287.943786 -304.718865) (xy 287.904973 -304.681444) (xy 287.872021 -304.638771) (xy 287.845635 -304.591754)
			(xy 287.826375 -304.541397) (xy 287.814652 -304.488773) (xy 287.810717 -304.435002) (xy 285.10484 -304.435002)
			(xy 285.104348 -304.461959) (xy 285.096498 -304.515299) (xy 285.080966 -304.566928) (xy 285.058081 -304.615745)
			(xy 285.028333 -304.660709) (xy 284.992355 -304.700863) (xy 284.950913 -304.735351) (xy 284.904892 -304.763437)
			(xy 284.855272 -304.784524) (xy 284.803111 -304.79816) (xy 284.74952 -304.804057) (xy 284.695641 -304.802088)
			(xy 284.642623 -304.792295) (xy 284.591596 -304.774887) (xy 284.543648 -304.750235) (xy 284.4998 -304.718865)
			(xy 284.460987 -304.681444) (xy 284.428035 -304.638771) (xy 284.401649 -304.591754) (xy 284.382389 -304.541397)
			(xy 284.370666 -304.488773) (xy 284.366731 -304.435002) (xy 281.004772 -304.435002) (xy 281.00428 -304.461959)
			(xy 280.99643 -304.515299) (xy 280.980898 -304.566928) (xy 280.958013 -304.615745) (xy 280.928265 -304.660709)
			(xy 280.892287 -304.700863) (xy 280.850845 -304.735351) (xy 280.804824 -304.763437) (xy 280.755204 -304.784524)
			(xy 280.703043 -304.79816) (xy 280.649452 -304.804057) (xy 280.595573 -304.802088) (xy 280.542555 -304.792295)
			(xy 280.491528 -304.774887) (xy 280.44358 -304.750235) (xy 280.399732 -304.718865) (xy 280.360919 -304.681444)
			(xy 280.327967 -304.638771) (xy 280.301581 -304.591754) (xy 280.282321 -304.541397) (xy 280.270598 -304.488773)
			(xy 280.266663 -304.435002) (xy 277.56104 -304.435002) (xy 277.560548 -304.461959) (xy 277.552698 -304.515299)
			(xy 277.537166 -304.566928) (xy 277.514281 -304.615745) (xy 277.484533 -304.660709) (xy 277.448555 -304.700863)
			(xy 277.407113 -304.735351) (xy 277.361092 -304.763437) (xy 277.311472 -304.784524) (xy 277.259311 -304.79816)
			(xy 277.20572 -304.804057) (xy 277.151841 -304.802088) (xy 277.098823 -304.792295) (xy 277.047796 -304.774887)
			(xy 276.999848 -304.750235) (xy 276.956 -304.718865) (xy 276.917187 -304.681444) (xy 276.884235 -304.638771)
			(xy 276.857849 -304.591754) (xy 276.838589 -304.541397) (xy 276.826866 -304.488773) (xy 276.822931 -304.435002)
			(xy 273.460972 -304.435002) (xy 273.46048 -304.461959) (xy 273.45263 -304.515299) (xy 273.437098 -304.566928)
			(xy 273.414213 -304.615745) (xy 273.384465 -304.660709) (xy 273.348487 -304.700863) (xy 273.307045 -304.735351)
			(xy 273.261024 -304.763437) (xy 273.211404 -304.784524) (xy 273.159243 -304.79816) (xy 273.105652 -304.804057)
			(xy 273.051773 -304.802088) (xy 272.998755 -304.792295) (xy 272.947728 -304.774887) (xy 272.89978 -304.750235)
			(xy 272.855932 -304.718865) (xy 272.817119 -304.681444) (xy 272.784167 -304.638771) (xy 272.757781 -304.591754)
			(xy 272.738521 -304.541397) (xy 272.726798 -304.488773) (xy 272.722863 -304.435002) (xy 270.016986 -304.435002)
			(xy 270.016494 -304.461959) (xy 270.008644 -304.515299) (xy 269.993112 -304.566928) (xy 269.970227 -304.615745)
			(xy 269.940479 -304.660709) (xy 269.904501 -304.700863) (xy 269.863059 -304.735351) (xy 269.817038 -304.763437)
			(xy 269.767418 -304.784524) (xy 269.715257 -304.79816) (xy 269.661666 -304.804057) (xy 269.607787 -304.802088)
			(xy 269.554769 -304.792295) (xy 269.503742 -304.774887) (xy 269.455794 -304.750235) (xy 269.411946 -304.718865)
			(xy 269.373133 -304.681444) (xy 269.340181 -304.638771) (xy 269.313795 -304.591754) (xy 269.294535 -304.541397)
			(xy 269.282812 -304.488773) (xy 269.278877 -304.435002) (xy 265.916918 -304.435002) (xy 265.916426 -304.461959)
			(xy 265.908576 -304.515299) (xy 265.893044 -304.566928) (xy 265.870159 -304.615745) (xy 265.840411 -304.660709)
			(xy 265.804433 -304.700863) (xy 265.762991 -304.735351) (xy 265.71697 -304.763437) (xy 265.66735 -304.784524)
			(xy 265.615189 -304.79816) (xy 265.561598 -304.804057) (xy 265.507719 -304.802088) (xy 265.454701 -304.792295)
			(xy 265.403674 -304.774887) (xy 265.355726 -304.750235) (xy 265.311878 -304.718865) (xy 265.273065 -304.681444)
			(xy 265.240113 -304.638771) (xy 265.213727 -304.591754) (xy 265.194467 -304.541397) (xy 265.182744 -304.488773)
			(xy 265.178809 -304.435002) (xy 264.143998 -304.435002) (xy 264.143998 -305.28514) (xy 265.178809 -305.28514)
			(xy 265.182744 -305.231369) (xy 265.194467 -305.178745) (xy 265.213727 -305.128388) (xy 265.240113 -305.081371)
			(xy 265.273065 -305.038698) (xy 265.311878 -305.001277) (xy 265.355726 -304.969907) (xy 265.403674 -304.945255)
			(xy 265.454701 -304.927847) (xy 265.507719 -304.918054) (xy 265.561598 -304.916085) (xy 265.615189 -304.921982)
			(xy 265.66735 -304.935618) (xy 265.71697 -304.956705) (xy 265.762991 -304.984791) (xy 265.804433 -305.019279)
			(xy 265.840411 -305.059433) (xy 265.870159 -305.104397) (xy 265.893044 -305.153214) (xy 265.908576 -305.204843)
			(xy 265.916426 -305.258183) (xy 265.916918 -305.28514) (xy 272.722863 -305.28514) (xy 272.726798 -305.231369)
			(xy 272.738521 -305.178745) (xy 272.757781 -305.128388) (xy 272.784167 -305.081371) (xy 272.817119 -305.038698)
			(xy 272.855932 -305.001277) (xy 272.89978 -304.969907) (xy 272.947728 -304.945255) (xy 272.998755 -304.927847)
			(xy 273.051773 -304.918054) (xy 273.105652 -304.916085) (xy 273.159243 -304.921982) (xy 273.211404 -304.935618)
			(xy 273.261024 -304.956705) (xy 273.307045 -304.984791) (xy 273.348487 -305.019279) (xy 273.384465 -305.059433)
			(xy 273.414213 -305.104397) (xy 273.437098 -305.153214) (xy 273.45263 -305.204843) (xy 273.46048 -305.258183)
			(xy 273.460972 -305.28514) (xy 280.266663 -305.28514) (xy 280.270598 -305.231369) (xy 280.282321 -305.178745)
			(xy 280.301581 -305.128388) (xy 280.327967 -305.081371) (xy 280.360919 -305.038698) (xy 280.399732 -305.001277)
			(xy 280.44358 -304.969907) (xy 280.491528 -304.945255) (xy 280.542555 -304.927847) (xy 280.595573 -304.918054)
			(xy 280.649452 -304.916085) (xy 280.703043 -304.921982) (xy 280.755204 -304.935618) (xy 280.804824 -304.956705)
			(xy 280.850845 -304.984791) (xy 280.892287 -305.019279) (xy 280.928265 -305.059433) (xy 280.958013 -305.104397)
			(xy 280.980898 -305.153214) (xy 280.99643 -305.204843) (xy 281.00428 -305.258183) (xy 281.004772 -305.28514)
			(xy 287.810717 -305.28514) (xy 287.814652 -305.231369) (xy 287.826375 -305.178745) (xy 287.845635 -305.128388)
			(xy 287.872021 -305.081371) (xy 287.904973 -305.038698) (xy 287.943786 -305.001277) (xy 287.987634 -304.969907)
			(xy 288.035582 -304.945255) (xy 288.086609 -304.927847) (xy 288.139627 -304.918054) (xy 288.193506 -304.916085)
			(xy 288.247097 -304.921982) (xy 288.299258 -304.935618) (xy 288.348878 -304.956705) (xy 288.394899 -304.984791)
			(xy 288.436341 -305.019279) (xy 288.472319 -305.059433) (xy 288.502067 -305.104397) (xy 288.524952 -305.153214)
			(xy 288.540484 -305.204843) (xy 288.548334 -305.258183) (xy 288.548826 -305.28514) (xy 288.548334 -305.312097)
			(xy 288.540484 -305.365437) (xy 288.524952 -305.417066) (xy 288.502067 -305.465883) (xy 288.472319 -305.510847)
			(xy 288.436341 -305.551001) (xy 288.394899 -305.585489) (xy 288.348878 -305.613575) (xy 288.299258 -305.634662)
			(xy 288.247097 -305.648298) (xy 288.193506 -305.654195) (xy 288.139627 -305.652226) (xy 288.086609 -305.642433)
			(xy 288.035582 -305.625025) (xy 287.987634 -305.600373) (xy 287.943786 -305.569003) (xy 287.904973 -305.531582)
			(xy 287.872021 -305.488909) (xy 287.845635 -305.441892) (xy 287.826375 -305.391535) (xy 287.814652 -305.338911)
			(xy 287.810717 -305.28514) (xy 281.004772 -305.28514) (xy 281.00428 -305.312097) (xy 280.99643 -305.365437)
			(xy 280.980898 -305.417066) (xy 280.958013 -305.465883) (xy 280.928265 -305.510847) (xy 280.892287 -305.551001)
			(xy 280.850845 -305.585489) (xy 280.804824 -305.613575) (xy 280.755204 -305.634662) (xy 280.703043 -305.648298)
			(xy 280.649452 -305.654195) (xy 280.595573 -305.652226) (xy 280.542555 -305.642433) (xy 280.491528 -305.625025)
			(xy 280.44358 -305.600373) (xy 280.399732 -305.569003) (xy 280.360919 -305.531582) (xy 280.327967 -305.488909)
			(xy 280.301581 -305.441892) (xy 280.282321 -305.391535) (xy 280.270598 -305.338911) (xy 280.266663 -305.28514)
			(xy 273.460972 -305.28514) (xy 273.46048 -305.312097) (xy 273.45263 -305.365437) (xy 273.437098 -305.417066)
			(xy 273.414213 -305.465883) (xy 273.384465 -305.510847) (xy 273.348487 -305.551001) (xy 273.307045 -305.585489)
			(xy 273.261024 -305.613575) (xy 273.211404 -305.634662) (xy 273.159243 -305.648298) (xy 273.105652 -305.654195)
			(xy 273.051773 -305.652226) (xy 272.998755 -305.642433) (xy 272.947728 -305.625025) (xy 272.89978 -305.600373)
			(xy 272.855932 -305.569003) (xy 272.817119 -305.531582) (xy 272.784167 -305.488909) (xy 272.757781 -305.441892)
			(xy 272.738521 -305.391535) (xy 272.726798 -305.338911) (xy 272.722863 -305.28514) (xy 265.916918 -305.28514)
			(xy 265.916426 -305.312097) (xy 265.908576 -305.365437) (xy 265.893044 -305.417066) (xy 265.870159 -305.465883)
			(xy 265.840411 -305.510847) (xy 265.804433 -305.551001) (xy 265.762991 -305.585489) (xy 265.71697 -305.613575)
			(xy 265.66735 -305.634662) (xy 265.615189 -305.648298) (xy 265.561598 -305.654195) (xy 265.507719 -305.652226)
			(xy 265.454701 -305.642433) (xy 265.403674 -305.625025) (xy 265.355726 -305.600373) (xy 265.311878 -305.569003)
			(xy 265.273065 -305.531582) (xy 265.240113 -305.488909) (xy 265.213727 -305.441892) (xy 265.194467 -305.391535)
			(xy 265.182744 -305.338911) (xy 265.178809 -305.28514) (xy 264.143998 -305.28514) (xy 264.143998 -306.135024)
			(xy 269.278877 -306.135024) (xy 269.282812 -306.081253) (xy 269.294535 -306.028629) (xy 269.313795 -305.978272)
			(xy 269.340181 -305.931255) (xy 269.373133 -305.888582) (xy 269.411946 -305.851161) (xy 269.455794 -305.819791)
			(xy 269.503742 -305.795139) (xy 269.554769 -305.777731) (xy 269.607787 -305.767938) (xy 269.661666 -305.765969)
			(xy 269.715257 -305.771866) (xy 269.767418 -305.785502) (xy 269.817038 -305.806589) (xy 269.863059 -305.834675)
			(xy 269.904501 -305.869163) (xy 269.940479 -305.909317) (xy 269.970227 -305.954281) (xy 269.993112 -306.003098)
			(xy 270.008644 -306.054727) (xy 270.016494 -306.108067) (xy 270.016986 -306.135024) (xy 276.822931 -306.135024)
			(xy 276.826866 -306.081253) (xy 276.838589 -306.028629) (xy 276.857849 -305.978272) (xy 276.884235 -305.931255)
			(xy 276.917187 -305.888582) (xy 276.956 -305.851161) (xy 276.999848 -305.819791) (xy 277.047796 -305.795139)
			(xy 277.098823 -305.777731) (xy 277.151841 -305.767938) (xy 277.20572 -305.765969) (xy 277.259311 -305.771866)
			(xy 277.311472 -305.785502) (xy 277.361092 -305.806589) (xy 277.407113 -305.834675) (xy 277.448555 -305.869163)
			(xy 277.484533 -305.909317) (xy 277.514281 -305.954281) (xy 277.537166 -306.003098) (xy 277.552698 -306.054727)
			(xy 277.560548 -306.108067) (xy 277.56104 -306.135024) (xy 284.366731 -306.135024) (xy 284.370666 -306.081253)
			(xy 284.382389 -306.028629) (xy 284.401649 -305.978272) (xy 284.428035 -305.931255) (xy 284.460987 -305.888582)
			(xy 284.4998 -305.851161) (xy 284.543648 -305.819791) (xy 284.591596 -305.795139) (xy 284.642623 -305.777731)
			(xy 284.695641 -305.767938) (xy 284.74952 -305.765969) (xy 284.803111 -305.771866) (xy 284.855272 -305.785502)
			(xy 284.904892 -305.806589) (xy 284.950913 -305.834675) (xy 284.992355 -305.869163) (xy 285.028333 -305.909317)
			(xy 285.058081 -305.954281) (xy 285.080966 -306.003098) (xy 285.096498 -306.054727) (xy 285.104348 -306.108067)
			(xy 285.10484 -306.135024) (xy 291.910785 -306.135024) (xy 291.91472 -306.081253) (xy 291.926443 -306.028629)
			(xy 291.945703 -305.978272) (xy 291.972089 -305.931255) (xy 292.005041 -305.888582) (xy 292.043854 -305.851161)
			(xy 292.087702 -305.819791) (xy 292.13565 -305.795139) (xy 292.186677 -305.777731) (xy 292.239695 -305.767938)
			(xy 292.293574 -305.765969) (xy 292.347165 -305.771866) (xy 292.399326 -305.785502) (xy 292.448946 -305.806589)
			(xy 292.494967 -305.834675) (xy 292.536409 -305.869163) (xy 292.572387 -305.909317) (xy 292.602135 -305.954281)
			(xy 292.62502 -306.003098) (xy 292.640552 -306.054727) (xy 292.648402 -306.108067) (xy 292.648894 -306.135024)
			(xy 292.648402 -306.161981) (xy 292.640552 -306.215321) (xy 292.62502 -306.26695) (xy 292.602135 -306.315767)
			(xy 292.572387 -306.360731) (xy 292.536409 -306.400885) (xy 292.494967 -306.435373) (xy 292.448946 -306.463459)
			(xy 292.399326 -306.484546) (xy 292.347165 -306.498182) (xy 292.293574 -306.504079) (xy 292.239695 -306.50211)
			(xy 292.186677 -306.492317) (xy 292.13565 -306.474909) (xy 292.087702 -306.450257) (xy 292.043854 -306.418887)
			(xy 292.005041 -306.381466) (xy 291.972089 -306.338793) (xy 291.945703 -306.291776) (xy 291.926443 -306.241419)
			(xy 291.91472 -306.188795) (xy 291.910785 -306.135024) (xy 285.10484 -306.135024) (xy 285.104348 -306.161981)
			(xy 285.096498 -306.215321) (xy 285.080966 -306.26695) (xy 285.058081 -306.315767) (xy 285.028333 -306.360731)
			(xy 284.992355 -306.400885) (xy 284.950913 -306.435373) (xy 284.904892 -306.463459) (xy 284.855272 -306.484546)
			(xy 284.803111 -306.498182) (xy 284.74952 -306.504079) (xy 284.695641 -306.50211) (xy 284.642623 -306.492317)
			(xy 284.591596 -306.474909) (xy 284.543648 -306.450257) (xy 284.4998 -306.418887) (xy 284.460987 -306.381466)
			(xy 284.428035 -306.338793) (xy 284.401649 -306.291776) (xy 284.382389 -306.241419) (xy 284.370666 -306.188795)
			(xy 284.366731 -306.135024) (xy 277.56104 -306.135024) (xy 277.560548 -306.161981) (xy 277.552698 -306.215321)
			(xy 277.537166 -306.26695) (xy 277.514281 -306.315767) (xy 277.484533 -306.360731) (xy 277.448555 -306.400885)
			(xy 277.407113 -306.435373) (xy 277.361092 -306.463459) (xy 277.311472 -306.484546) (xy 277.259311 -306.498182)
			(xy 277.20572 -306.504079) (xy 277.151841 -306.50211) (xy 277.098823 -306.492317) (xy 277.047796 -306.474909)
			(xy 276.999848 -306.450257) (xy 276.956 -306.418887) (xy 276.917187 -306.381466) (xy 276.884235 -306.338793)
			(xy 276.857849 -306.291776) (xy 276.838589 -306.241419) (xy 276.826866 -306.188795) (xy 276.822931 -306.135024)
			(xy 270.016986 -306.135024) (xy 270.016494 -306.161981) (xy 270.008644 -306.215321) (xy 269.993112 -306.26695)
			(xy 269.970227 -306.315767) (xy 269.940479 -306.360731) (xy 269.904501 -306.400885) (xy 269.863059 -306.435373)
			(xy 269.817038 -306.463459) (xy 269.767418 -306.484546) (xy 269.715257 -306.498182) (xy 269.661666 -306.504079)
			(xy 269.607787 -306.50211) (xy 269.554769 -306.492317) (xy 269.503742 -306.474909) (xy 269.455794 -306.450257)
			(xy 269.411946 -306.418887) (xy 269.373133 -306.381466) (xy 269.340181 -306.338793) (xy 269.313795 -306.291776)
			(xy 269.294535 -306.241419) (xy 269.282812 -306.188795) (xy 269.278877 -306.135024) (xy 264.143998 -306.135024)
			(xy 264.143998 -306.985162) (xy 265.178809 -306.985162) (xy 265.182744 -306.931391) (xy 265.194467 -306.878767)
			(xy 265.213727 -306.82841) (xy 265.240113 -306.781393) (xy 265.273065 -306.73872) (xy 265.311878 -306.701299)
			(xy 265.355726 -306.669929) (xy 265.403674 -306.645277) (xy 265.454701 -306.627869) (xy 265.507719 -306.618076)
			(xy 265.561598 -306.616107) (xy 265.615189 -306.622004) (xy 265.66735 -306.63564) (xy 265.71697 -306.656727)
			(xy 265.762991 -306.684813) (xy 265.804433 -306.719301) (xy 265.840411 -306.759455) (xy 265.870159 -306.804419)
			(xy 265.893044 -306.853236) (xy 265.908576 -306.904865) (xy 265.916426 -306.958205) (xy 265.916918 -306.985162)
			(xy 272.722863 -306.985162) (xy 272.726798 -306.931391) (xy 272.738521 -306.878767) (xy 272.757781 -306.82841)
			(xy 272.784167 -306.781393) (xy 272.817119 -306.73872) (xy 272.855932 -306.701299) (xy 272.89978 -306.669929)
			(xy 272.947728 -306.645277) (xy 272.998755 -306.627869) (xy 273.051773 -306.618076) (xy 273.105652 -306.616107)
			(xy 273.159243 -306.622004) (xy 273.211404 -306.63564) (xy 273.261024 -306.656727) (xy 273.307045 -306.684813)
			(xy 273.348487 -306.719301) (xy 273.384465 -306.759455) (xy 273.414213 -306.804419) (xy 273.437098 -306.853236)
			(xy 273.45263 -306.904865) (xy 273.46048 -306.958205) (xy 273.460972 -306.985162) (xy 280.266663 -306.985162)
			(xy 280.270598 -306.931391) (xy 280.282321 -306.878767) (xy 280.301581 -306.82841) (xy 280.327967 -306.781393)
			(xy 280.360919 -306.73872) (xy 280.399732 -306.701299) (xy 280.44358 -306.669929) (xy 280.491528 -306.645277)
			(xy 280.542555 -306.627869) (xy 280.595573 -306.618076) (xy 280.649452 -306.616107) (xy 280.703043 -306.622004)
			(xy 280.755204 -306.63564) (xy 280.804824 -306.656727) (xy 280.850845 -306.684813) (xy 280.892287 -306.719301)
			(xy 280.928265 -306.759455) (xy 280.958013 -306.804419) (xy 280.980898 -306.853236) (xy 280.99643 -306.904865)
			(xy 281.00428 -306.958205) (xy 281.004772 -306.985162) (xy 287.810717 -306.985162) (xy 287.814652 -306.931391)
			(xy 287.826375 -306.878767) (xy 287.845635 -306.82841) (xy 287.872021 -306.781393) (xy 287.904973 -306.73872)
			(xy 287.943786 -306.701299) (xy 287.987634 -306.669929) (xy 288.035582 -306.645277) (xy 288.086609 -306.627869)
			(xy 288.139627 -306.618076) (xy 288.193506 -306.616107) (xy 288.247097 -306.622004) (xy 288.299258 -306.63564)
			(xy 288.348878 -306.656727) (xy 288.394899 -306.684813) (xy 288.436341 -306.719301) (xy 288.472319 -306.759455)
			(xy 288.502067 -306.804419) (xy 288.524952 -306.853236) (xy 288.540484 -306.904865) (xy 288.548334 -306.958205)
			(xy 288.548826 -306.985162) (xy 288.548334 -307.012119) (xy 288.540484 -307.065459) (xy 288.524952 -307.117088)
			(xy 288.502067 -307.165905) (xy 288.472319 -307.210869) (xy 288.436341 -307.251023) (xy 288.394899 -307.285511)
			(xy 288.348878 -307.313597) (xy 288.299258 -307.334684) (xy 288.247097 -307.34832) (xy 288.193506 -307.354217)
			(xy 288.139627 -307.352248) (xy 288.086609 -307.342455) (xy 288.035582 -307.325047) (xy 287.987634 -307.300395)
			(xy 287.943786 -307.269025) (xy 287.904973 -307.231604) (xy 287.872021 -307.188931) (xy 287.845635 -307.141914)
			(xy 287.826375 -307.091557) (xy 287.814652 -307.038933) (xy 287.810717 -306.985162) (xy 281.004772 -306.985162)
			(xy 281.00428 -307.012119) (xy 280.99643 -307.065459) (xy 280.980898 -307.117088) (xy 280.958013 -307.165905)
			(xy 280.928265 -307.210869) (xy 280.892287 -307.251023) (xy 280.850845 -307.285511) (xy 280.804824 -307.313597)
			(xy 280.755204 -307.334684) (xy 280.703043 -307.34832) (xy 280.649452 -307.354217) (xy 280.595573 -307.352248)
			(xy 280.542555 -307.342455) (xy 280.491528 -307.325047) (xy 280.44358 -307.300395) (xy 280.399732 -307.269025)
			(xy 280.360919 -307.231604) (xy 280.327967 -307.188931) (xy 280.301581 -307.141914) (xy 280.282321 -307.091557)
			(xy 280.270598 -307.038933) (xy 280.266663 -306.985162) (xy 273.460972 -306.985162) (xy 273.46048 -307.012119)
			(xy 273.45263 -307.065459) (xy 273.437098 -307.117088) (xy 273.414213 -307.165905) (xy 273.384465 -307.210869)
			(xy 273.348487 -307.251023) (xy 273.307045 -307.285511) (xy 273.261024 -307.313597) (xy 273.211404 -307.334684)
			(xy 273.159243 -307.34832) (xy 273.105652 -307.354217) (xy 273.051773 -307.352248) (xy 272.998755 -307.342455)
			(xy 272.947728 -307.325047) (xy 272.89978 -307.300395) (xy 272.855932 -307.269025) (xy 272.817119 -307.231604)
			(xy 272.784167 -307.188931) (xy 272.757781 -307.141914) (xy 272.738521 -307.091557) (xy 272.726798 -307.038933)
			(xy 272.722863 -306.985162) (xy 265.916918 -306.985162) (xy 265.916426 -307.012119) (xy 265.908576 -307.065459)
			(xy 265.893044 -307.117088) (xy 265.870159 -307.165905) (xy 265.840411 -307.210869) (xy 265.804433 -307.251023)
			(xy 265.762991 -307.285511) (xy 265.71697 -307.313597) (xy 265.66735 -307.334684) (xy 265.615189 -307.34832)
			(xy 265.561598 -307.354217) (xy 265.507719 -307.352248) (xy 265.454701 -307.342455) (xy 265.403674 -307.325047)
			(xy 265.355726 -307.300395) (xy 265.311878 -307.269025) (xy 265.273065 -307.231604) (xy 265.240113 -307.188931)
			(xy 265.213727 -307.141914) (xy 265.194467 -307.091557) (xy 265.182744 -307.038933) (xy 265.178809 -306.985162)
			(xy 264.143998 -306.985162) (xy 264.143998 -307.835046) (xy 269.278877 -307.835046) (xy 269.282812 -307.781275)
			(xy 269.294535 -307.728651) (xy 269.313795 -307.678294) (xy 269.340181 -307.631277) (xy 269.373133 -307.588604)
			(xy 269.411946 -307.551183) (xy 269.455794 -307.519813) (xy 269.503742 -307.495161) (xy 269.554769 -307.477753)
			(xy 269.607787 -307.46796) (xy 269.661666 -307.465991) (xy 269.715257 -307.471888) (xy 269.767418 -307.485524)
			(xy 269.817038 -307.506611) (xy 269.863059 -307.534697) (xy 269.904501 -307.569185) (xy 269.940479 -307.609339)
			(xy 269.970227 -307.654303) (xy 269.993112 -307.70312) (xy 270.008644 -307.754749) (xy 270.016494 -307.808089)
			(xy 270.016986 -307.835046) (xy 276.822931 -307.835046) (xy 276.826866 -307.781275) (xy 276.838589 -307.728651)
			(xy 276.857849 -307.678294) (xy 276.884235 -307.631277) (xy 276.917187 -307.588604) (xy 276.956 -307.551183)
			(xy 276.999848 -307.519813) (xy 277.047796 -307.495161) (xy 277.098823 -307.477753) (xy 277.151841 -307.46796)
			(xy 277.20572 -307.465991) (xy 277.259311 -307.471888) (xy 277.311472 -307.485524) (xy 277.361092 -307.506611)
			(xy 277.407113 -307.534697) (xy 277.448555 -307.569185) (xy 277.484533 -307.609339) (xy 277.514281 -307.654303)
			(xy 277.537166 -307.70312) (xy 277.552698 -307.754749) (xy 277.560548 -307.808089) (xy 277.56104 -307.835046)
			(xy 284.366731 -307.835046) (xy 284.370666 -307.781275) (xy 284.382389 -307.728651) (xy 284.401649 -307.678294)
			(xy 284.428035 -307.631277) (xy 284.460987 -307.588604) (xy 284.4998 -307.551183) (xy 284.543648 -307.519813)
			(xy 284.591596 -307.495161) (xy 284.642623 -307.477753) (xy 284.695641 -307.46796) (xy 284.74952 -307.465991)
			(xy 284.803111 -307.471888) (xy 284.855272 -307.485524) (xy 284.904892 -307.506611) (xy 284.950913 -307.534697)
			(xy 284.992355 -307.569185) (xy 285.028333 -307.609339) (xy 285.058081 -307.654303) (xy 285.080966 -307.70312)
			(xy 285.096498 -307.754749) (xy 285.104348 -307.808089) (xy 285.10484 -307.835046) (xy 291.910785 -307.835046)
			(xy 291.91472 -307.781275) (xy 291.926443 -307.728651) (xy 291.945703 -307.678294) (xy 291.972089 -307.631277)
			(xy 292.005041 -307.588604) (xy 292.043854 -307.551183) (xy 292.087702 -307.519813) (xy 292.13565 -307.495161)
			(xy 292.186677 -307.477753) (xy 292.239695 -307.46796) (xy 292.293574 -307.465991) (xy 292.347165 -307.471888)
			(xy 292.399326 -307.485524) (xy 292.448946 -307.506611) (xy 292.494967 -307.534697) (xy 292.536409 -307.569185)
			(xy 292.572387 -307.609339) (xy 292.602135 -307.654303) (xy 292.62502 -307.70312) (xy 292.640552 -307.754749)
			(xy 292.648402 -307.808089) (xy 292.648894 -307.835046) (xy 292.648402 -307.862003) (xy 292.640552 -307.915343)
			(xy 292.62502 -307.966972) (xy 292.602135 -308.015789) (xy 292.572387 -308.060753) (xy 292.536409 -308.100907)
			(xy 292.494967 -308.135395) (xy 292.448946 -308.163481) (xy 292.399326 -308.184568) (xy 292.347165 -308.198204)
			(xy 292.293574 -308.204101) (xy 292.239695 -308.202132) (xy 292.186677 -308.192339) (xy 292.13565 -308.174931)
			(xy 292.087702 -308.150279) (xy 292.043854 -308.118909) (xy 292.005041 -308.081488) (xy 291.972089 -308.038815)
			(xy 291.945703 -307.991798) (xy 291.926443 -307.941441) (xy 291.91472 -307.888817) (xy 291.910785 -307.835046)
			(xy 285.10484 -307.835046) (xy 285.104348 -307.862003) (xy 285.096498 -307.915343) (xy 285.080966 -307.966972)
			(xy 285.058081 -308.015789) (xy 285.028333 -308.060753) (xy 284.992355 -308.100907) (xy 284.950913 -308.135395)
			(xy 284.904892 -308.163481) (xy 284.855272 -308.184568) (xy 284.803111 -308.198204) (xy 284.74952 -308.204101)
			(xy 284.695641 -308.202132) (xy 284.642623 -308.192339) (xy 284.591596 -308.174931) (xy 284.543648 -308.150279)
			(xy 284.4998 -308.118909) (xy 284.460987 -308.081488) (xy 284.428035 -308.038815) (xy 284.401649 -307.991798)
			(xy 284.382389 -307.941441) (xy 284.370666 -307.888817) (xy 284.366731 -307.835046) (xy 277.56104 -307.835046)
			(xy 277.560548 -307.862003) (xy 277.552698 -307.915343) (xy 277.537166 -307.966972) (xy 277.514281 -308.015789)
			(xy 277.484533 -308.060753) (xy 277.448555 -308.100907) (xy 277.407113 -308.135395) (xy 277.361092 -308.163481)
			(xy 277.311472 -308.184568) (xy 277.259311 -308.198204) (xy 277.20572 -308.204101) (xy 277.151841 -308.202132)
			(xy 277.098823 -308.192339) (xy 277.047796 -308.174931) (xy 276.999848 -308.150279) (xy 276.956 -308.118909)
			(xy 276.917187 -308.081488) (xy 276.884235 -308.038815) (xy 276.857849 -307.991798) (xy 276.838589 -307.941441)
			(xy 276.826866 -307.888817) (xy 276.822931 -307.835046) (xy 270.016986 -307.835046) (xy 270.016494 -307.862003)
			(xy 270.008644 -307.915343) (xy 269.993112 -307.966972) (xy 269.970227 -308.015789) (xy 269.940479 -308.060753)
			(xy 269.904501 -308.100907) (xy 269.863059 -308.135395) (xy 269.817038 -308.163481) (xy 269.767418 -308.184568)
			(xy 269.715257 -308.198204) (xy 269.661666 -308.204101) (xy 269.607787 -308.202132) (xy 269.554769 -308.192339)
			(xy 269.503742 -308.174931) (xy 269.455794 -308.150279) (xy 269.411946 -308.118909) (xy 269.373133 -308.081488)
			(xy 269.340181 -308.038815) (xy 269.313795 -307.991798) (xy 269.294535 -307.941441) (xy 269.282812 -307.888817)
			(xy 269.278877 -307.835046) (xy 264.143998 -307.835046) (xy 264.143998 -308.685184) (xy 265.178809 -308.685184)
			(xy 265.182744 -308.631413) (xy 265.194467 -308.578789) (xy 265.213727 -308.528432) (xy 265.240113 -308.481415)
			(xy 265.273065 -308.438742) (xy 265.311878 -308.401321) (xy 265.355726 -308.369951) (xy 265.403674 -308.345299)
			(xy 265.454701 -308.327891) (xy 265.507719 -308.318098) (xy 265.561598 -308.316129) (xy 265.615189 -308.322026)
			(xy 265.66735 -308.335662) (xy 265.71697 -308.356749) (xy 265.762991 -308.384835) (xy 265.804433 -308.419323)
			(xy 265.840411 -308.459477) (xy 265.870159 -308.504441) (xy 265.893044 -308.553258) (xy 265.908576 -308.604887)
			(xy 265.916426 -308.658227) (xy 265.916918 -308.685184) (xy 272.722863 -308.685184) (xy 272.726798 -308.631413)
			(xy 272.738521 -308.578789) (xy 272.757781 -308.528432) (xy 272.784167 -308.481415) (xy 272.817119 -308.438742)
			(xy 272.855932 -308.401321) (xy 272.89978 -308.369951) (xy 272.947728 -308.345299) (xy 272.998755 -308.327891)
			(xy 273.051773 -308.318098) (xy 273.105652 -308.316129) (xy 273.159243 -308.322026) (xy 273.211404 -308.335662)
			(xy 273.261024 -308.356749) (xy 273.307045 -308.384835) (xy 273.348487 -308.419323) (xy 273.384465 -308.459477)
			(xy 273.414213 -308.504441) (xy 273.437098 -308.553258) (xy 273.45263 -308.604887) (xy 273.46048 -308.658227)
			(xy 273.460972 -308.685184) (xy 280.266663 -308.685184) (xy 280.270598 -308.631413) (xy 280.282321 -308.578789)
			(xy 280.301581 -308.528432) (xy 280.327967 -308.481415) (xy 280.360919 -308.438742) (xy 280.399732 -308.401321)
			(xy 280.44358 -308.369951) (xy 280.491528 -308.345299) (xy 280.542555 -308.327891) (xy 280.595573 -308.318098)
			(xy 280.649452 -308.316129) (xy 280.703043 -308.322026) (xy 280.755204 -308.335662) (xy 280.804824 -308.356749)
			(xy 280.850845 -308.384835) (xy 280.892287 -308.419323) (xy 280.928265 -308.459477) (xy 280.958013 -308.504441)
			(xy 280.980898 -308.553258) (xy 280.99643 -308.604887) (xy 281.00428 -308.658227) (xy 281.004772 -308.685184)
			(xy 287.810717 -308.685184) (xy 287.814652 -308.631413) (xy 287.826375 -308.578789) (xy 287.845635 -308.528432)
			(xy 287.872021 -308.481415) (xy 287.904973 -308.438742) (xy 287.943786 -308.401321) (xy 287.987634 -308.369951)
			(xy 288.035582 -308.345299) (xy 288.086609 -308.327891) (xy 288.139627 -308.318098) (xy 288.193506 -308.316129)
			(xy 288.247097 -308.322026) (xy 288.299258 -308.335662) (xy 288.348878 -308.356749) (xy 288.394899 -308.384835)
			(xy 288.436341 -308.419323) (xy 288.472319 -308.459477) (xy 288.502067 -308.504441) (xy 288.524952 -308.553258)
			(xy 288.540484 -308.604887) (xy 288.548334 -308.658227) (xy 288.548826 -308.685184) (xy 288.548334 -308.712141)
			(xy 288.540484 -308.765481) (xy 288.524952 -308.81711) (xy 288.502067 -308.865927) (xy 288.472319 -308.910891)
			(xy 288.436341 -308.951045) (xy 288.394899 -308.985533) (xy 288.348878 -309.013619) (xy 288.299258 -309.034706)
			(xy 288.247097 -309.048342) (xy 288.193506 -309.054239) (xy 288.139627 -309.05227) (xy 288.086609 -309.042477)
			(xy 288.035582 -309.025069) (xy 287.987634 -309.000417) (xy 287.943786 -308.969047) (xy 287.904973 -308.931626)
			(xy 287.872021 -308.888953) (xy 287.845635 -308.841936) (xy 287.826375 -308.791579) (xy 287.814652 -308.738955)
			(xy 287.810717 -308.685184) (xy 281.004772 -308.685184) (xy 281.00428 -308.712141) (xy 280.99643 -308.765481)
			(xy 280.980898 -308.81711) (xy 280.958013 -308.865927) (xy 280.928265 -308.910891) (xy 280.892287 -308.951045)
			(xy 280.850845 -308.985533) (xy 280.804824 -309.013619) (xy 280.755204 -309.034706) (xy 280.703043 -309.048342)
			(xy 280.649452 -309.054239) (xy 280.595573 -309.05227) (xy 280.542555 -309.042477) (xy 280.491528 -309.025069)
			(xy 280.44358 -309.000417) (xy 280.399732 -308.969047) (xy 280.360919 -308.931626) (xy 280.327967 -308.888953)
			(xy 280.301581 -308.841936) (xy 280.282321 -308.791579) (xy 280.270598 -308.738955) (xy 280.266663 -308.685184)
			(xy 273.460972 -308.685184) (xy 273.46048 -308.712141) (xy 273.45263 -308.765481) (xy 273.437098 -308.81711)
			(xy 273.414213 -308.865927) (xy 273.384465 -308.910891) (xy 273.348487 -308.951045) (xy 273.307045 -308.985533)
			(xy 273.261024 -309.013619) (xy 273.211404 -309.034706) (xy 273.159243 -309.048342) (xy 273.105652 -309.054239)
			(xy 273.051773 -309.05227) (xy 272.998755 -309.042477) (xy 272.947728 -309.025069) (xy 272.89978 -309.000417)
			(xy 272.855932 -308.969047) (xy 272.817119 -308.931626) (xy 272.784167 -308.888953) (xy 272.757781 -308.841936)
			(xy 272.738521 -308.791579) (xy 272.726798 -308.738955) (xy 272.722863 -308.685184) (xy 265.916918 -308.685184)
			(xy 265.916426 -308.712141) (xy 265.908576 -308.765481) (xy 265.893044 -308.81711) (xy 265.870159 -308.865927)
			(xy 265.840411 -308.910891) (xy 265.804433 -308.951045) (xy 265.762991 -308.985533) (xy 265.71697 -309.013619)
			(xy 265.66735 -309.034706) (xy 265.615189 -309.048342) (xy 265.561598 -309.054239) (xy 265.507719 -309.05227)
			(xy 265.454701 -309.042477) (xy 265.403674 -309.025069) (xy 265.355726 -309.000417) (xy 265.311878 -308.969047)
			(xy 265.273065 -308.931626) (xy 265.240113 -308.888953) (xy 265.213727 -308.841936) (xy 265.194467 -308.791579)
			(xy 265.182744 -308.738955) (xy 265.178809 -308.685184) (xy 264.143998 -308.685184) (xy 264.143998 -309.535068)
			(xy 269.278877 -309.535068) (xy 269.282812 -309.481297) (xy 269.294535 -309.428673) (xy 269.313795 -309.378316)
			(xy 269.340181 -309.331299) (xy 269.373133 -309.288626) (xy 269.411946 -309.251205) (xy 269.455794 -309.219835)
			(xy 269.503742 -309.195183) (xy 269.554769 -309.177775) (xy 269.607787 -309.167982) (xy 269.661666 -309.166013)
			(xy 269.715257 -309.17191) (xy 269.767418 -309.185546) (xy 269.817038 -309.206633) (xy 269.863059 -309.234719)
			(xy 269.904501 -309.269207) (xy 269.940479 -309.309361) (xy 269.970227 -309.354325) (xy 269.993112 -309.403142)
			(xy 270.008644 -309.454771) (xy 270.016494 -309.508111) (xy 270.016986 -309.535068) (xy 276.822931 -309.535068)
			(xy 276.826866 -309.481297) (xy 276.838589 -309.428673) (xy 276.857849 -309.378316) (xy 276.884235 -309.331299)
			(xy 276.917187 -309.288626) (xy 276.956 -309.251205) (xy 276.999848 -309.219835) (xy 277.047796 -309.195183)
			(xy 277.098823 -309.177775) (xy 277.151841 -309.167982) (xy 277.20572 -309.166013) (xy 277.259311 -309.17191)
			(xy 277.311472 -309.185546) (xy 277.361092 -309.206633) (xy 277.407113 -309.234719) (xy 277.448555 -309.269207)
			(xy 277.484533 -309.309361) (xy 277.514281 -309.354325) (xy 277.537166 -309.403142) (xy 277.552698 -309.454771)
			(xy 277.560548 -309.508111) (xy 277.56104 -309.535068) (xy 284.366731 -309.535068) (xy 284.370666 -309.481297)
			(xy 284.382389 -309.428673) (xy 284.401649 -309.378316) (xy 284.428035 -309.331299) (xy 284.460987 -309.288626)
			(xy 284.4998 -309.251205) (xy 284.543648 -309.219835) (xy 284.591596 -309.195183) (xy 284.642623 -309.177775)
			(xy 284.695641 -309.167982) (xy 284.74952 -309.166013) (xy 284.803111 -309.17191) (xy 284.855272 -309.185546)
			(xy 284.904892 -309.206633) (xy 284.950913 -309.234719) (xy 284.992355 -309.269207) (xy 285.028333 -309.309361)
			(xy 285.058081 -309.354325) (xy 285.080966 -309.403142) (xy 285.096498 -309.454771) (xy 285.104348 -309.508111)
			(xy 285.10484 -309.535068) (xy 291.910785 -309.535068) (xy 291.91472 -309.481297) (xy 291.926443 -309.428673)
			(xy 291.945703 -309.378316) (xy 291.972089 -309.331299) (xy 292.005041 -309.288626) (xy 292.043854 -309.251205)
			(xy 292.087702 -309.219835) (xy 292.13565 -309.195183) (xy 292.186677 -309.177775) (xy 292.239695 -309.167982)
			(xy 292.293574 -309.166013) (xy 292.347165 -309.17191) (xy 292.399326 -309.185546) (xy 292.448946 -309.206633)
			(xy 292.494967 -309.234719) (xy 292.536409 -309.269207) (xy 292.572387 -309.309361) (xy 292.602135 -309.354325)
			(xy 292.62502 -309.403142) (xy 292.640552 -309.454771) (xy 292.648402 -309.508111) (xy 292.648894 -309.535068)
			(xy 292.648402 -309.562025) (xy 292.640552 -309.615365) (xy 292.62502 -309.666994) (xy 292.602135 -309.715811)
			(xy 292.572387 -309.760775) (xy 292.536409 -309.800929) (xy 292.494967 -309.835417) (xy 292.448946 -309.863503)
			(xy 292.399326 -309.88459) (xy 292.347165 -309.898226) (xy 292.293574 -309.904123) (xy 292.239695 -309.902154)
			(xy 292.186677 -309.892361) (xy 292.13565 -309.874953) (xy 292.087702 -309.850301) (xy 292.043854 -309.818931)
			(xy 292.005041 -309.78151) (xy 291.972089 -309.738837) (xy 291.945703 -309.69182) (xy 291.926443 -309.641463)
			(xy 291.91472 -309.588839) (xy 291.910785 -309.535068) (xy 285.10484 -309.535068) (xy 285.104348 -309.562025)
			(xy 285.096498 -309.615365) (xy 285.080966 -309.666994) (xy 285.058081 -309.715811) (xy 285.028333 -309.760775)
			(xy 284.992355 -309.800929) (xy 284.950913 -309.835417) (xy 284.904892 -309.863503) (xy 284.855272 -309.88459)
			(xy 284.803111 -309.898226) (xy 284.74952 -309.904123) (xy 284.695641 -309.902154) (xy 284.642623 -309.892361)
			(xy 284.591596 -309.874953) (xy 284.543648 -309.850301) (xy 284.4998 -309.818931) (xy 284.460987 -309.78151)
			(xy 284.428035 -309.738837) (xy 284.401649 -309.69182) (xy 284.382389 -309.641463) (xy 284.370666 -309.588839)
			(xy 284.366731 -309.535068) (xy 277.56104 -309.535068) (xy 277.560548 -309.562025) (xy 277.552698 -309.615365)
			(xy 277.537166 -309.666994) (xy 277.514281 -309.715811) (xy 277.484533 -309.760775) (xy 277.448555 -309.800929)
			(xy 277.407113 -309.835417) (xy 277.361092 -309.863503) (xy 277.311472 -309.88459) (xy 277.259311 -309.898226)
			(xy 277.20572 -309.904123) (xy 277.151841 -309.902154) (xy 277.098823 -309.892361) (xy 277.047796 -309.874953)
			(xy 276.999848 -309.850301) (xy 276.956 -309.818931) (xy 276.917187 -309.78151) (xy 276.884235 -309.738837)
			(xy 276.857849 -309.69182) (xy 276.838589 -309.641463) (xy 276.826866 -309.588839) (xy 276.822931 -309.535068)
			(xy 270.016986 -309.535068) (xy 270.016494 -309.562025) (xy 270.008644 -309.615365) (xy 269.993112 -309.666994)
			(xy 269.970227 -309.715811) (xy 269.940479 -309.760775) (xy 269.904501 -309.800929) (xy 269.863059 -309.835417)
			(xy 269.817038 -309.863503) (xy 269.767418 -309.88459) (xy 269.715257 -309.898226) (xy 269.661666 -309.904123)
			(xy 269.607787 -309.902154) (xy 269.554769 -309.892361) (xy 269.503742 -309.874953) (xy 269.455794 -309.850301)
			(xy 269.411946 -309.818931) (xy 269.373133 -309.78151) (xy 269.340181 -309.738837) (xy 269.313795 -309.69182)
			(xy 269.294535 -309.641463) (xy 269.282812 -309.588839) (xy 269.278877 -309.535068) (xy 264.143998 -309.535068)
			(xy 264.143998 -310.384952) (xy 265.178809 -310.384952) (xy 265.182744 -310.331181) (xy 265.194467 -310.278557)
			(xy 265.213727 -310.2282) (xy 265.240113 -310.181183) (xy 265.273065 -310.13851) (xy 265.311878 -310.101089)
			(xy 265.355726 -310.069719) (xy 265.403674 -310.045067) (xy 265.454701 -310.027659) (xy 265.507719 -310.017866)
			(xy 265.561598 -310.015897) (xy 265.615189 -310.021794) (xy 265.66735 -310.03543) (xy 265.71697 -310.056517)
			(xy 265.762991 -310.084603) (xy 265.804433 -310.119091) (xy 265.840411 -310.159245) (xy 265.870159 -310.204209)
			(xy 265.893044 -310.253026) (xy 265.908576 -310.304655) (xy 265.916426 -310.357995) (xy 265.916918 -310.384952)
			(xy 272.722863 -310.384952) (xy 272.726798 -310.331181) (xy 272.738521 -310.278557) (xy 272.757781 -310.2282)
			(xy 272.784167 -310.181183) (xy 272.817119 -310.13851) (xy 272.855932 -310.101089) (xy 272.89978 -310.069719)
			(xy 272.947728 -310.045067) (xy 272.998755 -310.027659) (xy 273.051773 -310.017866) (xy 273.105652 -310.015897)
			(xy 273.159243 -310.021794) (xy 273.211404 -310.03543) (xy 273.261024 -310.056517) (xy 273.307045 -310.084603)
			(xy 273.348487 -310.119091) (xy 273.384465 -310.159245) (xy 273.414213 -310.204209) (xy 273.437098 -310.253026)
			(xy 273.45263 -310.304655) (xy 273.46048 -310.357995) (xy 273.460972 -310.384952) (xy 280.266663 -310.384952)
			(xy 280.270598 -310.331181) (xy 280.282321 -310.278557) (xy 280.301581 -310.2282) (xy 280.327967 -310.181183)
			(xy 280.360919 -310.13851) (xy 280.399732 -310.101089) (xy 280.44358 -310.069719) (xy 280.491528 -310.045067)
			(xy 280.542555 -310.027659) (xy 280.595573 -310.017866) (xy 280.649452 -310.015897) (xy 280.703043 -310.021794)
			(xy 280.755204 -310.03543) (xy 280.804824 -310.056517) (xy 280.850845 -310.084603) (xy 280.892287 -310.119091)
			(xy 280.928265 -310.159245) (xy 280.958013 -310.204209) (xy 280.980898 -310.253026) (xy 280.99643 -310.304655)
			(xy 281.00428 -310.357995) (xy 281.004772 -310.384952) (xy 287.810717 -310.384952) (xy 287.814652 -310.331181)
			(xy 287.826375 -310.278557) (xy 287.845635 -310.2282) (xy 287.872021 -310.181183) (xy 287.904973 -310.13851)
			(xy 287.943786 -310.101089) (xy 287.987634 -310.069719) (xy 288.035582 -310.045067) (xy 288.086609 -310.027659)
			(xy 288.139627 -310.017866) (xy 288.193506 -310.015897) (xy 288.247097 -310.021794) (xy 288.299258 -310.03543)
			(xy 288.348878 -310.056517) (xy 288.394899 -310.084603) (xy 288.436341 -310.119091) (xy 288.472319 -310.159245)
			(xy 288.502067 -310.204209) (xy 288.524952 -310.253026) (xy 288.540484 -310.304655) (xy 288.548334 -310.357995)
			(xy 288.548826 -310.384952) (xy 288.548334 -310.411909) (xy 288.540484 -310.465249) (xy 288.524952 -310.516878)
			(xy 288.502067 -310.565695) (xy 288.472319 -310.610659) (xy 288.436341 -310.650813) (xy 288.394899 -310.685301)
			(xy 288.348878 -310.713387) (xy 288.299258 -310.734474) (xy 288.247097 -310.74811) (xy 288.193506 -310.754007)
			(xy 288.139627 -310.752038) (xy 288.086609 -310.742245) (xy 288.035582 -310.724837) (xy 287.987634 -310.700185)
			(xy 287.943786 -310.668815) (xy 287.904973 -310.631394) (xy 287.872021 -310.588721) (xy 287.845635 -310.541704)
			(xy 287.826375 -310.491347) (xy 287.814652 -310.438723) (xy 287.810717 -310.384952) (xy 281.004772 -310.384952)
			(xy 281.00428 -310.411909) (xy 280.99643 -310.465249) (xy 280.980898 -310.516878) (xy 280.958013 -310.565695)
			(xy 280.928265 -310.610659) (xy 280.892287 -310.650813) (xy 280.850845 -310.685301) (xy 280.804824 -310.713387)
			(xy 280.755204 -310.734474) (xy 280.703043 -310.74811) (xy 280.649452 -310.754007) (xy 280.595573 -310.752038)
			(xy 280.542555 -310.742245) (xy 280.491528 -310.724837) (xy 280.44358 -310.700185) (xy 280.399732 -310.668815)
			(xy 280.360919 -310.631394) (xy 280.327967 -310.588721) (xy 280.301581 -310.541704) (xy 280.282321 -310.491347)
			(xy 280.270598 -310.438723) (xy 280.266663 -310.384952) (xy 273.460972 -310.384952) (xy 273.46048 -310.411909)
			(xy 273.45263 -310.465249) (xy 273.437098 -310.516878) (xy 273.414213 -310.565695) (xy 273.384465 -310.610659)
			(xy 273.348487 -310.650813) (xy 273.307045 -310.685301) (xy 273.261024 -310.713387) (xy 273.211404 -310.734474)
			(xy 273.159243 -310.74811) (xy 273.105652 -310.754007) (xy 273.051773 -310.752038) (xy 272.998755 -310.742245)
			(xy 272.947728 -310.724837) (xy 272.89978 -310.700185) (xy 272.855932 -310.668815) (xy 272.817119 -310.631394)
			(xy 272.784167 -310.588721) (xy 272.757781 -310.541704) (xy 272.738521 -310.491347) (xy 272.726798 -310.438723)
			(xy 272.722863 -310.384952) (xy 265.916918 -310.384952) (xy 265.916426 -310.411909) (xy 265.908576 -310.465249)
			(xy 265.893044 -310.516878) (xy 265.870159 -310.565695) (xy 265.840411 -310.610659) (xy 265.804433 -310.650813)
			(xy 265.762991 -310.685301) (xy 265.71697 -310.713387) (xy 265.66735 -310.734474) (xy 265.615189 -310.74811)
			(xy 265.561598 -310.754007) (xy 265.507719 -310.752038) (xy 265.454701 -310.742245) (xy 265.403674 -310.724837)
			(xy 265.355726 -310.700185) (xy 265.311878 -310.668815) (xy 265.273065 -310.631394) (xy 265.240113 -310.588721)
			(xy 265.213727 -310.541704) (xy 265.194467 -310.491347) (xy 265.182744 -310.438723) (xy 265.178809 -310.384952)
			(xy 264.143998 -310.384952) (xy 264.143998 -311.23509) (xy 269.278877 -311.23509) (xy 269.282812 -311.181319)
			(xy 269.294535 -311.128695) (xy 269.313795 -311.078338) (xy 269.340181 -311.031321) (xy 269.373133 -310.988648)
			(xy 269.411946 -310.951227) (xy 269.455794 -310.919857) (xy 269.503742 -310.895205) (xy 269.554769 -310.877797)
			(xy 269.607787 -310.868004) (xy 269.661666 -310.866035) (xy 269.715257 -310.871932) (xy 269.767418 -310.885568)
			(xy 269.817038 -310.906655) (xy 269.863059 -310.934741) (xy 269.904501 -310.969229) (xy 269.940479 -311.009383)
			(xy 269.970227 -311.054347) (xy 269.993112 -311.103164) (xy 270.008644 -311.154793) (xy 270.016494 -311.208133)
			(xy 270.016986 -311.23509) (xy 276.822931 -311.23509) (xy 276.826866 -311.181319) (xy 276.838589 -311.128695)
			(xy 276.857849 -311.078338) (xy 276.884235 -311.031321) (xy 276.917187 -310.988648) (xy 276.956 -310.951227)
			(xy 276.999848 -310.919857) (xy 277.047796 -310.895205) (xy 277.098823 -310.877797) (xy 277.151841 -310.868004)
			(xy 277.20572 -310.866035) (xy 277.259311 -310.871932) (xy 277.311472 -310.885568) (xy 277.361092 -310.906655)
			(xy 277.407113 -310.934741) (xy 277.448555 -310.969229) (xy 277.484533 -311.009383) (xy 277.514281 -311.054347)
			(xy 277.537166 -311.103164) (xy 277.552698 -311.154793) (xy 277.560548 -311.208133) (xy 277.56104 -311.23509)
			(xy 284.366731 -311.23509) (xy 284.370666 -311.181319) (xy 284.382389 -311.128695) (xy 284.401649 -311.078338)
			(xy 284.428035 -311.031321) (xy 284.460987 -310.988648) (xy 284.4998 -310.951227) (xy 284.543648 -310.919857)
			(xy 284.591596 -310.895205) (xy 284.642623 -310.877797) (xy 284.695641 -310.868004) (xy 284.74952 -310.866035)
			(xy 284.803111 -310.871932) (xy 284.855272 -310.885568) (xy 284.904892 -310.906655) (xy 284.950913 -310.934741)
			(xy 284.992355 -310.969229) (xy 285.028333 -311.009383) (xy 285.058081 -311.054347) (xy 285.080966 -311.103164)
			(xy 285.096498 -311.154793) (xy 285.104348 -311.208133) (xy 285.10484 -311.23509) (xy 291.910785 -311.23509)
			(xy 291.91472 -311.181319) (xy 291.926443 -311.128695) (xy 291.945703 -311.078338) (xy 291.972089 -311.031321)
			(xy 292.005041 -310.988648) (xy 292.043854 -310.951227) (xy 292.087702 -310.919857) (xy 292.13565 -310.895205)
			(xy 292.186677 -310.877797) (xy 292.239695 -310.868004) (xy 292.293574 -310.866035) (xy 292.347165 -310.871932)
			(xy 292.399326 -310.885568) (xy 292.448946 -310.906655) (xy 292.494967 -310.934741) (xy 292.536409 -310.969229)
			(xy 292.572387 -311.009383) (xy 292.602135 -311.054347) (xy 292.62502 -311.103164) (xy 292.640552 -311.154793)
			(xy 292.648402 -311.208133) (xy 292.648894 -311.23509) (xy 292.648402 -311.262047) (xy 292.640552 -311.315387)
			(xy 292.62502 -311.367016) (xy 292.602135 -311.415833) (xy 292.572387 -311.460797) (xy 292.536409 -311.500951)
			(xy 292.494967 -311.535439) (xy 292.448946 -311.563525) (xy 292.399326 -311.584612) (xy 292.347165 -311.598248)
			(xy 292.293574 -311.604145) (xy 292.239695 -311.602176) (xy 292.186677 -311.592383) (xy 292.13565 -311.574975)
			(xy 292.087702 -311.550323) (xy 292.043854 -311.518953) (xy 292.005041 -311.481532) (xy 291.972089 -311.438859)
			(xy 291.945703 -311.391842) (xy 291.926443 -311.341485) (xy 291.91472 -311.288861) (xy 291.910785 -311.23509)
			(xy 285.10484 -311.23509) (xy 285.104348 -311.262047) (xy 285.096498 -311.315387) (xy 285.080966 -311.367016)
			(xy 285.058081 -311.415833) (xy 285.028333 -311.460797) (xy 284.992355 -311.500951) (xy 284.950913 -311.535439)
			(xy 284.904892 -311.563525) (xy 284.855272 -311.584612) (xy 284.803111 -311.598248) (xy 284.74952 -311.604145)
			(xy 284.695641 -311.602176) (xy 284.642623 -311.592383) (xy 284.591596 -311.574975) (xy 284.543648 -311.550323)
			(xy 284.4998 -311.518953) (xy 284.460987 -311.481532) (xy 284.428035 -311.438859) (xy 284.401649 -311.391842)
			(xy 284.382389 -311.341485) (xy 284.370666 -311.288861) (xy 284.366731 -311.23509) (xy 277.56104 -311.23509)
			(xy 277.560548 -311.262047) (xy 277.552698 -311.315387) (xy 277.537166 -311.367016) (xy 277.514281 -311.415833)
			(xy 277.484533 -311.460797) (xy 277.448555 -311.500951) (xy 277.407113 -311.535439) (xy 277.361092 -311.563525)
			(xy 277.311472 -311.584612) (xy 277.259311 -311.598248) (xy 277.20572 -311.604145) (xy 277.151841 -311.602176)
			(xy 277.098823 -311.592383) (xy 277.047796 -311.574975) (xy 276.999848 -311.550323) (xy 276.956 -311.518953)
			(xy 276.917187 -311.481532) (xy 276.884235 -311.438859) (xy 276.857849 -311.391842) (xy 276.838589 -311.341485)
			(xy 276.826866 -311.288861) (xy 276.822931 -311.23509) (xy 270.016986 -311.23509) (xy 270.016494 -311.262047)
			(xy 270.008644 -311.315387) (xy 269.993112 -311.367016) (xy 269.970227 -311.415833) (xy 269.940479 -311.460797)
			(xy 269.904501 -311.500951) (xy 269.863059 -311.535439) (xy 269.817038 -311.563525) (xy 269.767418 -311.584612)
			(xy 269.715257 -311.598248) (xy 269.661666 -311.604145) (xy 269.607787 -311.602176) (xy 269.554769 -311.592383)
			(xy 269.503742 -311.574975) (xy 269.455794 -311.550323) (xy 269.411946 -311.518953) (xy 269.373133 -311.481532)
			(xy 269.340181 -311.438859) (xy 269.313795 -311.391842) (xy 269.294535 -311.341485) (xy 269.282812 -311.288861)
			(xy 269.278877 -311.23509) (xy 264.143998 -311.23509) (xy 264.143998 -312.084974) (xy 265.178809 -312.084974)
			(xy 265.182744 -312.031203) (xy 265.194467 -311.978579) (xy 265.213727 -311.928222) (xy 265.240113 -311.881205)
			(xy 265.273065 -311.838532) (xy 265.311878 -311.801111) (xy 265.355726 -311.769741) (xy 265.403674 -311.745089)
			(xy 265.454701 -311.727681) (xy 265.507719 -311.717888) (xy 265.561598 -311.715919) (xy 265.615189 -311.721816)
			(xy 265.66735 -311.735452) (xy 265.71697 -311.756539) (xy 265.762991 -311.784625) (xy 265.804433 -311.819113)
			(xy 265.840411 -311.859267) (xy 265.870159 -311.904231) (xy 265.893044 -311.953048) (xy 265.908576 -312.004677)
			(xy 265.916426 -312.058017) (xy 265.916918 -312.084974) (xy 272.722863 -312.084974) (xy 272.726798 -312.031203)
			(xy 272.738521 -311.978579) (xy 272.757781 -311.928222) (xy 272.784167 -311.881205) (xy 272.817119 -311.838532)
			(xy 272.855932 -311.801111) (xy 272.89978 -311.769741) (xy 272.947728 -311.745089) (xy 272.998755 -311.727681)
			(xy 273.051773 -311.717888) (xy 273.105652 -311.715919) (xy 273.159243 -311.721816) (xy 273.211404 -311.735452)
			(xy 273.261024 -311.756539) (xy 273.307045 -311.784625) (xy 273.348487 -311.819113) (xy 273.384465 -311.859267)
			(xy 273.414213 -311.904231) (xy 273.437098 -311.953048) (xy 273.45263 -312.004677) (xy 273.46048 -312.058017)
			(xy 273.460972 -312.084974) (xy 280.266663 -312.084974) (xy 280.270598 -312.031203) (xy 280.282321 -311.978579)
			(xy 280.301581 -311.928222) (xy 280.327967 -311.881205) (xy 280.360919 -311.838532) (xy 280.399732 -311.801111)
			(xy 280.44358 -311.769741) (xy 280.491528 -311.745089) (xy 280.542555 -311.727681) (xy 280.595573 -311.717888)
			(xy 280.649452 -311.715919) (xy 280.703043 -311.721816) (xy 280.755204 -311.735452) (xy 280.804824 -311.756539)
			(xy 280.850845 -311.784625) (xy 280.892287 -311.819113) (xy 280.928265 -311.859267) (xy 280.958013 -311.904231)
			(xy 280.980898 -311.953048) (xy 280.99643 -312.004677) (xy 281.00428 -312.058017) (xy 281.004772 -312.084974)
			(xy 287.810717 -312.084974) (xy 287.814652 -312.031203) (xy 287.826375 -311.978579) (xy 287.845635 -311.928222)
			(xy 287.872021 -311.881205) (xy 287.904973 -311.838532) (xy 287.943786 -311.801111) (xy 287.987634 -311.769741)
			(xy 288.035582 -311.745089) (xy 288.086609 -311.727681) (xy 288.139627 -311.717888) (xy 288.193506 -311.715919)
			(xy 288.247097 -311.721816) (xy 288.299258 -311.735452) (xy 288.348878 -311.756539) (xy 288.394899 -311.784625)
			(xy 288.436341 -311.819113) (xy 288.472319 -311.859267) (xy 288.502067 -311.904231) (xy 288.524952 -311.953048)
			(xy 288.540484 -312.004677) (xy 288.548334 -312.058017) (xy 288.548826 -312.084974) (xy 288.548334 -312.111931)
			(xy 288.540484 -312.165271) (xy 288.524952 -312.2169) (xy 288.502067 -312.265717) (xy 288.472319 -312.310681)
			(xy 288.436341 -312.350835) (xy 288.394899 -312.385323) (xy 288.348878 -312.413409) (xy 288.299258 -312.434496)
			(xy 288.247097 -312.448132) (xy 288.193506 -312.454029) (xy 288.139627 -312.45206) (xy 288.086609 -312.442267)
			(xy 288.035582 -312.424859) (xy 287.987634 -312.400207) (xy 287.943786 -312.368837) (xy 287.904973 -312.331416)
			(xy 287.872021 -312.288743) (xy 287.845635 -312.241726) (xy 287.826375 -312.191369) (xy 287.814652 -312.138745)
			(xy 287.810717 -312.084974) (xy 281.004772 -312.084974) (xy 281.00428 -312.111931) (xy 280.99643 -312.165271)
			(xy 280.980898 -312.2169) (xy 280.958013 -312.265717) (xy 280.928265 -312.310681) (xy 280.892287 -312.350835)
			(xy 280.850845 -312.385323) (xy 280.804824 -312.413409) (xy 280.755204 -312.434496) (xy 280.703043 -312.448132)
			(xy 280.649452 -312.454029) (xy 280.595573 -312.45206) (xy 280.542555 -312.442267) (xy 280.491528 -312.424859)
			(xy 280.44358 -312.400207) (xy 280.399732 -312.368837) (xy 280.360919 -312.331416) (xy 280.327967 -312.288743)
			(xy 280.301581 -312.241726) (xy 280.282321 -312.191369) (xy 280.270598 -312.138745) (xy 280.266663 -312.084974)
			(xy 273.460972 -312.084974) (xy 273.46048 -312.111931) (xy 273.45263 -312.165271) (xy 273.437098 -312.2169)
			(xy 273.414213 -312.265717) (xy 273.384465 -312.310681) (xy 273.348487 -312.350835) (xy 273.307045 -312.385323)
			(xy 273.261024 -312.413409) (xy 273.211404 -312.434496) (xy 273.159243 -312.448132) (xy 273.105652 -312.454029)
			(xy 273.051773 -312.45206) (xy 272.998755 -312.442267) (xy 272.947728 -312.424859) (xy 272.89978 -312.400207)
			(xy 272.855932 -312.368837) (xy 272.817119 -312.331416) (xy 272.784167 -312.288743) (xy 272.757781 -312.241726)
			(xy 272.738521 -312.191369) (xy 272.726798 -312.138745) (xy 272.722863 -312.084974) (xy 265.916918 -312.084974)
			(xy 265.916426 -312.111931) (xy 265.908576 -312.165271) (xy 265.893044 -312.2169) (xy 265.870159 -312.265717)
			(xy 265.840411 -312.310681) (xy 265.804433 -312.350835) (xy 265.762991 -312.385323) (xy 265.71697 -312.413409)
			(xy 265.66735 -312.434496) (xy 265.615189 -312.448132) (xy 265.561598 -312.454029) (xy 265.507719 -312.45206)
			(xy 265.454701 -312.442267) (xy 265.403674 -312.424859) (xy 265.355726 -312.400207) (xy 265.311878 -312.368837)
			(xy 265.273065 -312.331416) (xy 265.240113 -312.288743) (xy 265.213727 -312.241726) (xy 265.194467 -312.191369)
			(xy 265.182744 -312.138745) (xy 265.178809 -312.084974) (xy 264.143998 -312.084974) (xy 264.143998 -312.935112)
			(xy 269.278877 -312.935112) (xy 269.282812 -312.881341) (xy 269.294535 -312.828717) (xy 269.313795 -312.77836)
			(xy 269.340181 -312.731343) (xy 269.373133 -312.68867) (xy 269.411946 -312.651249) (xy 269.455794 -312.619879)
			(xy 269.503742 -312.595227) (xy 269.554769 -312.577819) (xy 269.607787 -312.568026) (xy 269.661666 -312.566057)
			(xy 269.715257 -312.571954) (xy 269.767418 -312.58559) (xy 269.817038 -312.606677) (xy 269.863059 -312.634763)
			(xy 269.904501 -312.669251) (xy 269.940479 -312.709405) (xy 269.970227 -312.754369) (xy 269.993112 -312.803186)
			(xy 270.008644 -312.854815) (xy 270.016494 -312.908155) (xy 270.016986 -312.935112) (xy 276.822931 -312.935112)
			(xy 276.826866 -312.881341) (xy 276.838589 -312.828717) (xy 276.857849 -312.77836) (xy 276.884235 -312.731343)
			(xy 276.917187 -312.68867) (xy 276.956 -312.651249) (xy 276.999848 -312.619879) (xy 277.047796 -312.595227)
			(xy 277.098823 -312.577819) (xy 277.151841 -312.568026) (xy 277.20572 -312.566057) (xy 277.259311 -312.571954)
			(xy 277.311472 -312.58559) (xy 277.361092 -312.606677) (xy 277.407113 -312.634763) (xy 277.448555 -312.669251)
			(xy 277.484533 -312.709405) (xy 277.514281 -312.754369) (xy 277.537166 -312.803186) (xy 277.552698 -312.854815)
			(xy 277.560548 -312.908155) (xy 277.56104 -312.935112) (xy 284.366731 -312.935112) (xy 284.370666 -312.881341)
			(xy 284.382389 -312.828717) (xy 284.401649 -312.77836) (xy 284.428035 -312.731343) (xy 284.460987 -312.68867)
			(xy 284.4998 -312.651249) (xy 284.543648 -312.619879) (xy 284.591596 -312.595227) (xy 284.642623 -312.577819)
			(xy 284.695641 -312.568026) (xy 284.74952 -312.566057) (xy 284.803111 -312.571954) (xy 284.855272 -312.58559)
			(xy 284.904892 -312.606677) (xy 284.950913 -312.634763) (xy 284.992355 -312.669251) (xy 285.028333 -312.709405)
			(xy 285.058081 -312.754369) (xy 285.080966 -312.803186) (xy 285.096498 -312.854815) (xy 285.104348 -312.908155)
			(xy 285.10484 -312.935112) (xy 291.910785 -312.935112) (xy 291.91472 -312.881341) (xy 291.926443 -312.828717)
			(xy 291.945703 -312.77836) (xy 291.972089 -312.731343) (xy 292.005041 -312.68867) (xy 292.043854 -312.651249)
			(xy 292.087702 -312.619879) (xy 292.13565 -312.595227) (xy 292.186677 -312.577819) (xy 292.239695 -312.568026)
			(xy 292.293574 -312.566057) (xy 292.347165 -312.571954) (xy 292.399326 -312.58559) (xy 292.448946 -312.606677)
			(xy 292.494967 -312.634763) (xy 292.536409 -312.669251) (xy 292.572387 -312.709405) (xy 292.602135 -312.754369)
			(xy 292.62502 -312.803186) (xy 292.640552 -312.854815) (xy 292.648402 -312.908155) (xy 292.648894 -312.935112)
			(xy 292.648402 -312.962069) (xy 292.640552 -313.015409) (xy 292.62502 -313.067038) (xy 292.602135 -313.115855)
			(xy 292.572387 -313.160819) (xy 292.536409 -313.200973) (xy 292.494967 -313.235461) (xy 292.448946 -313.263547)
			(xy 292.399326 -313.284634) (xy 292.347165 -313.29827) (xy 292.293574 -313.304167) (xy 292.239695 -313.302198)
			(xy 292.186677 -313.292405) (xy 292.13565 -313.274997) (xy 292.087702 -313.250345) (xy 292.043854 -313.218975)
			(xy 292.005041 -313.181554) (xy 291.972089 -313.138881) (xy 291.945703 -313.091864) (xy 291.926443 -313.041507)
			(xy 291.91472 -312.988883) (xy 291.910785 -312.935112) (xy 285.10484 -312.935112) (xy 285.104348 -312.962069)
			(xy 285.096498 -313.015409) (xy 285.080966 -313.067038) (xy 285.058081 -313.115855) (xy 285.028333 -313.160819)
			(xy 284.992355 -313.200973) (xy 284.950913 -313.235461) (xy 284.904892 -313.263547) (xy 284.855272 -313.284634)
			(xy 284.803111 -313.29827) (xy 284.74952 -313.304167) (xy 284.695641 -313.302198) (xy 284.642623 -313.292405)
			(xy 284.591596 -313.274997) (xy 284.543648 -313.250345) (xy 284.4998 -313.218975) (xy 284.460987 -313.181554)
			(xy 284.428035 -313.138881) (xy 284.401649 -313.091864) (xy 284.382389 -313.041507) (xy 284.370666 -312.988883)
			(xy 284.366731 -312.935112) (xy 277.56104 -312.935112) (xy 277.560548 -312.962069) (xy 277.552698 -313.015409)
			(xy 277.537166 -313.067038) (xy 277.514281 -313.115855) (xy 277.484533 -313.160819) (xy 277.448555 -313.200973)
			(xy 277.407113 -313.235461) (xy 277.361092 -313.263547) (xy 277.311472 -313.284634) (xy 277.259311 -313.29827)
			(xy 277.20572 -313.304167) (xy 277.151841 -313.302198) (xy 277.098823 -313.292405) (xy 277.047796 -313.274997)
			(xy 276.999848 -313.250345) (xy 276.956 -313.218975) (xy 276.917187 -313.181554) (xy 276.884235 -313.138881)
			(xy 276.857849 -313.091864) (xy 276.838589 -313.041507) (xy 276.826866 -312.988883) (xy 276.822931 -312.935112)
			(xy 270.016986 -312.935112) (xy 270.016494 -312.962069) (xy 270.008644 -313.015409) (xy 269.993112 -313.067038)
			(xy 269.970227 -313.115855) (xy 269.940479 -313.160819) (xy 269.904501 -313.200973) (xy 269.863059 -313.235461)
			(xy 269.817038 -313.263547) (xy 269.767418 -313.284634) (xy 269.715257 -313.29827) (xy 269.661666 -313.304167)
			(xy 269.607787 -313.302198) (xy 269.554769 -313.292405) (xy 269.503742 -313.274997) (xy 269.455794 -313.250345)
			(xy 269.411946 -313.218975) (xy 269.373133 -313.181554) (xy 269.340181 -313.138881) (xy 269.313795 -313.091864)
			(xy 269.294535 -313.041507) (xy 269.282812 -312.988883) (xy 269.278877 -312.935112) (xy 264.143998 -312.935112)
			(xy 264.143998 -313.784996) (xy 265.178809 -313.784996) (xy 265.182744 -313.731225) (xy 265.194467 -313.678601)
			(xy 265.213727 -313.628244) (xy 265.240113 -313.581227) (xy 265.273065 -313.538554) (xy 265.311878 -313.501133)
			(xy 265.355726 -313.469763) (xy 265.403674 -313.445111) (xy 265.454701 -313.427703) (xy 265.507719 -313.41791)
			(xy 265.561598 -313.415941) (xy 265.615189 -313.421838) (xy 265.66735 -313.435474) (xy 265.71697 -313.456561)
			(xy 265.762991 -313.484647) (xy 265.804433 -313.519135) (xy 265.840411 -313.559289) (xy 265.870159 -313.604253)
			(xy 265.893044 -313.65307) (xy 265.908576 -313.704699) (xy 265.916426 -313.758039) (xy 265.916918 -313.784996)
			(xy 269.278877 -313.784996) (xy 269.282812 -313.731225) (xy 269.294535 -313.678601) (xy 269.313795 -313.628244)
			(xy 269.340181 -313.581227) (xy 269.373133 -313.538554) (xy 269.411946 -313.501133) (xy 269.455794 -313.469763)
			(xy 269.503742 -313.445111) (xy 269.554769 -313.427703) (xy 269.607787 -313.41791) (xy 269.661666 -313.415941)
			(xy 269.715257 -313.421838) (xy 269.767418 -313.435474) (xy 269.817038 -313.456561) (xy 269.863059 -313.484647)
			(xy 269.904501 -313.519135) (xy 269.940479 -313.559289) (xy 269.970227 -313.604253) (xy 269.993112 -313.65307)
			(xy 270.008644 -313.704699) (xy 270.016494 -313.758039) (xy 270.016986 -313.784996) (xy 272.722863 -313.784996)
			(xy 272.726798 -313.731225) (xy 272.738521 -313.678601) (xy 272.757781 -313.628244) (xy 272.784167 -313.581227)
			(xy 272.817119 -313.538554) (xy 272.855932 -313.501133) (xy 272.89978 -313.469763) (xy 272.947728 -313.445111)
			(xy 272.998755 -313.427703) (xy 273.051773 -313.41791) (xy 273.105652 -313.415941) (xy 273.159243 -313.421838)
			(xy 273.211404 -313.435474) (xy 273.261024 -313.456561) (xy 273.307045 -313.484647) (xy 273.348487 -313.519135)
			(xy 273.384465 -313.559289) (xy 273.414213 -313.604253) (xy 273.437098 -313.65307) (xy 273.45263 -313.704699)
			(xy 273.46048 -313.758039) (xy 273.460972 -313.784996) (xy 276.822931 -313.784996) (xy 276.826866 -313.731225)
			(xy 276.838589 -313.678601) (xy 276.857849 -313.628244) (xy 276.884235 -313.581227) (xy 276.917187 -313.538554)
			(xy 276.956 -313.501133) (xy 276.999848 -313.469763) (xy 277.047796 -313.445111) (xy 277.098823 -313.427703)
			(xy 277.151841 -313.41791) (xy 277.20572 -313.415941) (xy 277.259311 -313.421838) (xy 277.311472 -313.435474)
			(xy 277.361092 -313.456561) (xy 277.407113 -313.484647) (xy 277.448555 -313.519135) (xy 277.484533 -313.559289)
			(xy 277.514281 -313.604253) (xy 277.537166 -313.65307) (xy 277.552698 -313.704699) (xy 277.560548 -313.758039)
			(xy 277.56104 -313.784996) (xy 280.266663 -313.784996) (xy 280.270598 -313.731225) (xy 280.282321 -313.678601)
			(xy 280.301581 -313.628244) (xy 280.327967 -313.581227) (xy 280.360919 -313.538554) (xy 280.399732 -313.501133)
			(xy 280.44358 -313.469763) (xy 280.491528 -313.445111) (xy 280.542555 -313.427703) (xy 280.595573 -313.41791)
			(xy 280.649452 -313.415941) (xy 280.703043 -313.421838) (xy 280.755204 -313.435474) (xy 280.804824 -313.456561)
			(xy 280.850845 -313.484647) (xy 280.892287 -313.519135) (xy 280.928265 -313.559289) (xy 280.958013 -313.604253)
			(xy 280.980898 -313.65307) (xy 280.99643 -313.704699) (xy 281.00428 -313.758039) (xy 281.004772 -313.784996)
			(xy 284.366731 -313.784996) (xy 284.370666 -313.731225) (xy 284.382389 -313.678601) (xy 284.401649 -313.628244)
			(xy 284.428035 -313.581227) (xy 284.460987 -313.538554) (xy 284.4998 -313.501133) (xy 284.543648 -313.469763)
			(xy 284.591596 -313.445111) (xy 284.642623 -313.427703) (xy 284.695641 -313.41791) (xy 284.74952 -313.415941)
			(xy 284.803111 -313.421838) (xy 284.855272 -313.435474) (xy 284.904892 -313.456561) (xy 284.950913 -313.484647)
			(xy 284.992355 -313.519135) (xy 285.028333 -313.559289) (xy 285.058081 -313.604253) (xy 285.080966 -313.65307)
			(xy 285.096498 -313.704699) (xy 285.104348 -313.758039) (xy 285.10484 -313.784996) (xy 287.810717 -313.784996)
			(xy 287.814652 -313.731225) (xy 287.826375 -313.678601) (xy 287.845635 -313.628244) (xy 287.872021 -313.581227)
			(xy 287.904973 -313.538554) (xy 287.943786 -313.501133) (xy 287.987634 -313.469763) (xy 288.035582 -313.445111)
			(xy 288.086609 -313.427703) (xy 288.139627 -313.41791) (xy 288.193506 -313.415941) (xy 288.247097 -313.421838)
			(xy 288.299258 -313.435474) (xy 288.348878 -313.456561) (xy 288.394899 -313.484647) (xy 288.436341 -313.519135)
			(xy 288.472319 -313.559289) (xy 288.502067 -313.604253) (xy 288.524952 -313.65307) (xy 288.540484 -313.704699)
			(xy 288.548334 -313.758039) (xy 288.548826 -313.784996) (xy 291.910785 -313.784996) (xy 291.91472 -313.731225)
			(xy 291.926443 -313.678601) (xy 291.945703 -313.628244) (xy 291.972089 -313.581227) (xy 292.005041 -313.538554)
			(xy 292.043854 -313.501133) (xy 292.087702 -313.469763) (xy 292.13565 -313.445111) (xy 292.186677 -313.427703)
			(xy 292.239695 -313.41791) (xy 292.293574 -313.415941) (xy 292.347165 -313.421838) (xy 292.399326 -313.435474)
			(xy 292.448946 -313.456561) (xy 292.494967 -313.484647) (xy 292.536409 -313.519135) (xy 292.572387 -313.559289)
			(xy 292.602135 -313.604253) (xy 292.62502 -313.65307) (xy 292.640552 -313.704699) (xy 292.648402 -313.758039)
			(xy 292.648894 -313.784996) (xy 292.648402 -313.811953) (xy 292.640552 -313.865293) (xy 292.62502 -313.916922)
			(xy 292.602135 -313.965739) (xy 292.572387 -314.010703) (xy 292.536409 -314.050857) (xy 292.494967 -314.085345)
			(xy 292.448946 -314.113431) (xy 292.399326 -314.134518) (xy 292.347165 -314.148154) (xy 292.293574 -314.154051)
			(xy 292.239695 -314.152082) (xy 292.186677 -314.142289) (xy 292.13565 -314.124881) (xy 292.087702 -314.100229)
			(xy 292.043854 -314.068859) (xy 292.005041 -314.031438) (xy 291.972089 -313.988765) (xy 291.945703 -313.941748)
			(xy 291.926443 -313.891391) (xy 291.91472 -313.838767) (xy 291.910785 -313.784996) (xy 288.548826 -313.784996)
			(xy 288.548334 -313.811953) (xy 288.540484 -313.865293) (xy 288.524952 -313.916922) (xy 288.502067 -313.965739)
			(xy 288.472319 -314.010703) (xy 288.436341 -314.050857) (xy 288.394899 -314.085345) (xy 288.348878 -314.113431)
			(xy 288.299258 -314.134518) (xy 288.247097 -314.148154) (xy 288.193506 -314.154051) (xy 288.139627 -314.152082)
			(xy 288.086609 -314.142289) (xy 288.035582 -314.124881) (xy 287.987634 -314.100229) (xy 287.943786 -314.068859)
			(xy 287.904973 -314.031438) (xy 287.872021 -313.988765) (xy 287.845635 -313.941748) (xy 287.826375 -313.891391)
			(xy 287.814652 -313.838767) (xy 287.810717 -313.784996) (xy 285.10484 -313.784996) (xy 285.104348 -313.811953)
			(xy 285.096498 -313.865293) (xy 285.080966 -313.916922) (xy 285.058081 -313.965739) (xy 285.028333 -314.010703)
			(xy 284.992355 -314.050857) (xy 284.950913 -314.085345) (xy 284.904892 -314.113431) (xy 284.855272 -314.134518)
			(xy 284.803111 -314.148154) (xy 284.74952 -314.154051) (xy 284.695641 -314.152082) (xy 284.642623 -314.142289)
			(xy 284.591596 -314.124881) (xy 284.543648 -314.100229) (xy 284.4998 -314.068859) (xy 284.460987 -314.031438)
			(xy 284.428035 -313.988765) (xy 284.401649 -313.941748) (xy 284.382389 -313.891391) (xy 284.370666 -313.838767)
			(xy 284.366731 -313.784996) (xy 281.004772 -313.784996) (xy 281.00428 -313.811953) (xy 280.99643 -313.865293)
			(xy 280.980898 -313.916922) (xy 280.958013 -313.965739) (xy 280.928265 -314.010703) (xy 280.892287 -314.050857)
			(xy 280.850845 -314.085345) (xy 280.804824 -314.113431) (xy 280.755204 -314.134518) (xy 280.703043 -314.148154)
			(xy 280.649452 -314.154051) (xy 280.595573 -314.152082) (xy 280.542555 -314.142289) (xy 280.491528 -314.124881)
			(xy 280.44358 -314.100229) (xy 280.399732 -314.068859) (xy 280.360919 -314.031438) (xy 280.327967 -313.988765)
			(xy 280.301581 -313.941748) (xy 280.282321 -313.891391) (xy 280.270598 -313.838767) (xy 280.266663 -313.784996)
			(xy 277.56104 -313.784996) (xy 277.560548 -313.811953) (xy 277.552698 -313.865293) (xy 277.537166 -313.916922)
			(xy 277.514281 -313.965739) (xy 277.484533 -314.010703) (xy 277.448555 -314.050857) (xy 277.407113 -314.085345)
			(xy 277.361092 -314.113431) (xy 277.311472 -314.134518) (xy 277.259311 -314.148154) (xy 277.20572 -314.154051)
			(xy 277.151841 -314.152082) (xy 277.098823 -314.142289) (xy 277.047796 -314.124881) (xy 276.999848 -314.100229)
			(xy 276.956 -314.068859) (xy 276.917187 -314.031438) (xy 276.884235 -313.988765) (xy 276.857849 -313.941748)
			(xy 276.838589 -313.891391) (xy 276.826866 -313.838767) (xy 276.822931 -313.784996) (xy 273.460972 -313.784996)
			(xy 273.46048 -313.811953) (xy 273.45263 -313.865293) (xy 273.437098 -313.916922) (xy 273.414213 -313.965739)
			(xy 273.384465 -314.010703) (xy 273.348487 -314.050857) (xy 273.307045 -314.085345) (xy 273.261024 -314.113431)
			(xy 273.211404 -314.134518) (xy 273.159243 -314.148154) (xy 273.105652 -314.154051) (xy 273.051773 -314.152082)
			(xy 272.998755 -314.142289) (xy 272.947728 -314.124881) (xy 272.89978 -314.100229) (xy 272.855932 -314.068859)
			(xy 272.817119 -314.031438) (xy 272.784167 -313.988765) (xy 272.757781 -313.941748) (xy 272.738521 -313.891391)
			(xy 272.726798 -313.838767) (xy 272.722863 -313.784996) (xy 270.016986 -313.784996) (xy 270.016494 -313.811953)
			(xy 270.008644 -313.865293) (xy 269.993112 -313.916922) (xy 269.970227 -313.965739) (xy 269.940479 -314.010703)
			(xy 269.904501 -314.050857) (xy 269.863059 -314.085345) (xy 269.817038 -314.113431) (xy 269.767418 -314.134518)
			(xy 269.715257 -314.148154) (xy 269.661666 -314.154051) (xy 269.607787 -314.152082) (xy 269.554769 -314.142289)
			(xy 269.503742 -314.124881) (xy 269.455794 -314.100229) (xy 269.411946 -314.068859) (xy 269.373133 -314.031438)
			(xy 269.340181 -313.988765) (xy 269.313795 -313.941748) (xy 269.294535 -313.891391) (xy 269.282812 -313.838767)
			(xy 269.278877 -313.784996) (xy 265.916918 -313.784996) (xy 265.916426 -313.811953) (xy 265.908576 -313.865293)
			(xy 265.893044 -313.916922) (xy 265.870159 -313.965739) (xy 265.840411 -314.010703) (xy 265.804433 -314.050857)
			(xy 265.762991 -314.085345) (xy 265.71697 -314.113431) (xy 265.66735 -314.134518) (xy 265.615189 -314.148154)
			(xy 265.561598 -314.154051) (xy 265.507719 -314.152082) (xy 265.454701 -314.142289) (xy 265.403674 -314.124881)
			(xy 265.355726 -314.100229) (xy 265.311878 -314.068859) (xy 265.273065 -314.031438) (xy 265.240113 -313.988765)
			(xy 265.213727 -313.941748) (xy 265.194467 -313.891391) (xy 265.182744 -313.838767) (xy 265.178809 -313.784996)
			(xy 264.143998 -313.784996) (xy 264.143998 -314.635134) (xy 265.178809 -314.635134) (xy 265.182744 -314.581363)
			(xy 265.194467 -314.528739) (xy 265.213727 -314.478382) (xy 265.240113 -314.431365) (xy 265.273065 -314.388692)
			(xy 265.311878 -314.351271) (xy 265.355726 -314.319901) (xy 265.403674 -314.295249) (xy 265.454701 -314.277841)
			(xy 265.507719 -314.268048) (xy 265.561598 -314.266079) (xy 265.615189 -314.271976) (xy 265.66735 -314.285612)
			(xy 265.71697 -314.306699) (xy 265.762991 -314.334785) (xy 265.804433 -314.369273) (xy 265.840411 -314.409427)
			(xy 265.870159 -314.454391) (xy 265.893044 -314.503208) (xy 265.908576 -314.554837) (xy 265.916426 -314.608177)
			(xy 265.916918 -314.635134) (xy 272.722863 -314.635134) (xy 272.726798 -314.581363) (xy 272.738521 -314.528739)
			(xy 272.757781 -314.478382) (xy 272.784167 -314.431365) (xy 272.817119 -314.388692) (xy 272.855932 -314.351271)
			(xy 272.89978 -314.319901) (xy 272.947728 -314.295249) (xy 272.998755 -314.277841) (xy 273.051773 -314.268048)
			(xy 273.105652 -314.266079) (xy 273.159243 -314.271976) (xy 273.211404 -314.285612) (xy 273.261024 -314.306699)
			(xy 273.307045 -314.334785) (xy 273.348487 -314.369273) (xy 273.384465 -314.409427) (xy 273.414213 -314.454391)
			(xy 273.437098 -314.503208) (xy 273.45263 -314.554837) (xy 273.46048 -314.608177) (xy 273.460972 -314.635134)
			(xy 280.266663 -314.635134) (xy 280.270598 -314.581363) (xy 280.282321 -314.528739) (xy 280.301581 -314.478382)
			(xy 280.327967 -314.431365) (xy 280.360919 -314.388692) (xy 280.399732 -314.351271) (xy 280.44358 -314.319901)
			(xy 280.491528 -314.295249) (xy 280.542555 -314.277841) (xy 280.595573 -314.268048) (xy 280.649452 -314.266079)
			(xy 280.703043 -314.271976) (xy 280.755204 -314.285612) (xy 280.804824 -314.306699) (xy 280.850845 -314.334785)
			(xy 280.892287 -314.369273) (xy 280.928265 -314.409427) (xy 280.958013 -314.454391) (xy 280.980898 -314.503208)
			(xy 280.99643 -314.554837) (xy 281.00428 -314.608177) (xy 281.004772 -314.635134) (xy 287.810717 -314.635134)
			(xy 287.814652 -314.581363) (xy 287.826375 -314.528739) (xy 287.845635 -314.478382) (xy 287.872021 -314.431365)
			(xy 287.904973 -314.388692) (xy 287.943786 -314.351271) (xy 287.987634 -314.319901) (xy 288.035582 -314.295249)
			(xy 288.086609 -314.277841) (xy 288.139627 -314.268048) (xy 288.193506 -314.266079) (xy 288.247097 -314.271976)
			(xy 288.299258 -314.285612) (xy 288.348878 -314.306699) (xy 288.394899 -314.334785) (xy 288.436341 -314.369273)
			(xy 288.472319 -314.409427) (xy 288.502067 -314.454391) (xy 288.524952 -314.503208) (xy 288.540484 -314.554837)
			(xy 288.548334 -314.608177) (xy 288.548826 -314.635134) (xy 288.548334 -314.662091) (xy 288.540484 -314.715431)
			(xy 288.524952 -314.76706) (xy 288.502067 -314.815877) (xy 288.472319 -314.860841) (xy 288.436341 -314.900995)
			(xy 288.394899 -314.935483) (xy 288.348878 -314.963569) (xy 288.299258 -314.984656) (xy 288.247097 -314.998292)
			(xy 288.193506 -315.004189) (xy 288.139627 -315.00222) (xy 288.086609 -314.992427) (xy 288.035582 -314.975019)
			(xy 287.987634 -314.950367) (xy 287.943786 -314.918997) (xy 287.904973 -314.881576) (xy 287.872021 -314.838903)
			(xy 287.845635 -314.791886) (xy 287.826375 -314.741529) (xy 287.814652 -314.688905) (xy 287.810717 -314.635134)
			(xy 281.004772 -314.635134) (xy 281.00428 -314.662091) (xy 280.99643 -314.715431) (xy 280.980898 -314.76706)
			(xy 280.958013 -314.815877) (xy 280.928265 -314.860841) (xy 280.892287 -314.900995) (xy 280.850845 -314.935483)
			(xy 280.804824 -314.963569) (xy 280.755204 -314.984656) (xy 280.703043 -314.998292) (xy 280.649452 -315.004189)
			(xy 280.595573 -315.00222) (xy 280.542555 -314.992427) (xy 280.491528 -314.975019) (xy 280.44358 -314.950367)
			(xy 280.399732 -314.918997) (xy 280.360919 -314.881576) (xy 280.327967 -314.838903) (xy 280.301581 -314.791886)
			(xy 280.282321 -314.741529) (xy 280.270598 -314.688905) (xy 280.266663 -314.635134) (xy 273.460972 -314.635134)
			(xy 273.46048 -314.662091) (xy 273.45263 -314.715431) (xy 273.437098 -314.76706) (xy 273.414213 -314.815877)
			(xy 273.384465 -314.860841) (xy 273.348487 -314.900995) (xy 273.307045 -314.935483) (xy 273.261024 -314.963569)
			(xy 273.211404 -314.984656) (xy 273.159243 -314.998292) (xy 273.105652 -315.004189) (xy 273.051773 -315.00222)
			(xy 272.998755 -314.992427) (xy 272.947728 -314.975019) (xy 272.89978 -314.950367) (xy 272.855932 -314.918997)
			(xy 272.817119 -314.881576) (xy 272.784167 -314.838903) (xy 272.757781 -314.791886) (xy 272.738521 -314.741529)
			(xy 272.726798 -314.688905) (xy 272.722863 -314.635134) (xy 265.916918 -314.635134) (xy 265.916426 -314.662091)
			(xy 265.908576 -314.715431) (xy 265.893044 -314.76706) (xy 265.870159 -314.815877) (xy 265.840411 -314.860841)
			(xy 265.804433 -314.900995) (xy 265.762991 -314.935483) (xy 265.71697 -314.963569) (xy 265.66735 -314.984656)
			(xy 265.615189 -314.998292) (xy 265.561598 -315.004189) (xy 265.507719 -315.00222) (xy 265.454701 -314.992427)
			(xy 265.403674 -314.975019) (xy 265.355726 -314.950367) (xy 265.311878 -314.918997) (xy 265.273065 -314.881576)
			(xy 265.240113 -314.838903) (xy 265.213727 -314.791886) (xy 265.194467 -314.741529) (xy 265.182744 -314.688905)
			(xy 265.178809 -314.635134) (xy 264.143998 -314.635134) (xy 264.143998 -315.485018) (xy 269.278877 -315.485018)
			(xy 269.282812 -315.431247) (xy 269.294535 -315.378623) (xy 269.313795 -315.328266) (xy 269.340181 -315.281249)
			(xy 269.373133 -315.238576) (xy 269.411946 -315.201155) (xy 269.455794 -315.169785) (xy 269.503742 -315.145133)
			(xy 269.554769 -315.127725) (xy 269.607787 -315.117932) (xy 269.661666 -315.115963) (xy 269.715257 -315.12186)
			(xy 269.767418 -315.135496) (xy 269.817038 -315.156583) (xy 269.863059 -315.184669) (xy 269.904501 -315.219157)
			(xy 269.940479 -315.259311) (xy 269.970227 -315.304275) (xy 269.993112 -315.353092) (xy 270.008644 -315.404721)
			(xy 270.016494 -315.458061) (xy 270.016986 -315.485018) (xy 276.822931 -315.485018) (xy 276.826866 -315.431247)
			(xy 276.838589 -315.378623) (xy 276.857849 -315.328266) (xy 276.884235 -315.281249) (xy 276.917187 -315.238576)
			(xy 276.956 -315.201155) (xy 276.999848 -315.169785) (xy 277.047796 -315.145133) (xy 277.098823 -315.127725)
			(xy 277.151841 -315.117932) (xy 277.20572 -315.115963) (xy 277.259311 -315.12186) (xy 277.311472 -315.135496)
			(xy 277.361092 -315.156583) (xy 277.407113 -315.184669) (xy 277.448555 -315.219157) (xy 277.484533 -315.259311)
			(xy 277.514281 -315.304275) (xy 277.537166 -315.353092) (xy 277.552698 -315.404721) (xy 277.560548 -315.458061)
			(xy 277.56104 -315.485018) (xy 284.366731 -315.485018) (xy 284.370666 -315.431247) (xy 284.382389 -315.378623)
			(xy 284.401649 -315.328266) (xy 284.428035 -315.281249) (xy 284.460987 -315.238576) (xy 284.4998 -315.201155)
			(xy 284.543648 -315.169785) (xy 284.591596 -315.145133) (xy 284.642623 -315.127725) (xy 284.695641 -315.117932)
			(xy 284.74952 -315.115963) (xy 284.803111 -315.12186) (xy 284.855272 -315.135496) (xy 284.904892 -315.156583)
			(xy 284.950913 -315.184669) (xy 284.992355 -315.219157) (xy 285.028333 -315.259311) (xy 285.058081 -315.304275)
			(xy 285.080966 -315.353092) (xy 285.096498 -315.404721) (xy 285.104348 -315.458061) (xy 285.10484 -315.485018)
			(xy 291.910785 -315.485018) (xy 291.91472 -315.431247) (xy 291.926443 -315.378623) (xy 291.945703 -315.328266)
			(xy 291.972089 -315.281249) (xy 292.005041 -315.238576) (xy 292.043854 -315.201155) (xy 292.087702 -315.169785)
			(xy 292.13565 -315.145133) (xy 292.186677 -315.127725) (xy 292.239695 -315.117932) (xy 292.293574 -315.115963)
			(xy 292.347165 -315.12186) (xy 292.399326 -315.135496) (xy 292.448946 -315.156583) (xy 292.494967 -315.184669)
			(xy 292.536409 -315.219157) (xy 292.572387 -315.259311) (xy 292.602135 -315.304275) (xy 292.62502 -315.353092)
			(xy 292.640552 -315.404721) (xy 292.648402 -315.458061) (xy 292.648894 -315.485018) (xy 292.648402 -315.511975)
			(xy 292.640552 -315.565315) (xy 292.62502 -315.616944) (xy 292.602135 -315.665761) (xy 292.572387 -315.710725)
			(xy 292.536409 -315.750879) (xy 292.494967 -315.785367) (xy 292.448946 -315.813453) (xy 292.399326 -315.83454)
			(xy 292.347165 -315.848176) (xy 292.293574 -315.854073) (xy 292.239695 -315.852104) (xy 292.186677 -315.842311)
			(xy 292.13565 -315.824903) (xy 292.087702 -315.800251) (xy 292.043854 -315.768881) (xy 292.005041 -315.73146)
			(xy 291.972089 -315.688787) (xy 291.945703 -315.64177) (xy 291.926443 -315.591413) (xy 291.91472 -315.538789)
			(xy 291.910785 -315.485018) (xy 285.10484 -315.485018) (xy 285.104348 -315.511975) (xy 285.096498 -315.565315)
			(xy 285.080966 -315.616944) (xy 285.058081 -315.665761) (xy 285.028333 -315.710725) (xy 284.992355 -315.750879)
			(xy 284.950913 -315.785367) (xy 284.904892 -315.813453) (xy 284.855272 -315.83454) (xy 284.803111 -315.848176)
			(xy 284.74952 -315.854073) (xy 284.695641 -315.852104) (xy 284.642623 -315.842311) (xy 284.591596 -315.824903)
			(xy 284.543648 -315.800251) (xy 284.4998 -315.768881) (xy 284.460987 -315.73146) (xy 284.428035 -315.688787)
			(xy 284.401649 -315.64177) (xy 284.382389 -315.591413) (xy 284.370666 -315.538789) (xy 284.366731 -315.485018)
			(xy 277.56104 -315.485018) (xy 277.560548 -315.511975) (xy 277.552698 -315.565315) (xy 277.537166 -315.616944)
			(xy 277.514281 -315.665761) (xy 277.484533 -315.710725) (xy 277.448555 -315.750879) (xy 277.407113 -315.785367)
			(xy 277.361092 -315.813453) (xy 277.311472 -315.83454) (xy 277.259311 -315.848176) (xy 277.20572 -315.854073)
			(xy 277.151841 -315.852104) (xy 277.098823 -315.842311) (xy 277.047796 -315.824903) (xy 276.999848 -315.800251)
			(xy 276.956 -315.768881) (xy 276.917187 -315.73146) (xy 276.884235 -315.688787) (xy 276.857849 -315.64177)
			(xy 276.838589 -315.591413) (xy 276.826866 -315.538789) (xy 276.822931 -315.485018) (xy 270.016986 -315.485018)
			(xy 270.016494 -315.511975) (xy 270.008644 -315.565315) (xy 269.993112 -315.616944) (xy 269.970227 -315.665761)
			(xy 269.940479 -315.710725) (xy 269.904501 -315.750879) (xy 269.863059 -315.785367) (xy 269.817038 -315.813453)
			(xy 269.767418 -315.83454) (xy 269.715257 -315.848176) (xy 269.661666 -315.854073) (xy 269.607787 -315.852104)
			(xy 269.554769 -315.842311) (xy 269.503742 -315.824903) (xy 269.455794 -315.800251) (xy 269.411946 -315.768881)
			(xy 269.373133 -315.73146) (xy 269.340181 -315.688787) (xy 269.313795 -315.64177) (xy 269.294535 -315.591413)
			(xy 269.282812 -315.538789) (xy 269.278877 -315.485018) (xy 264.143998 -315.485018) (xy 264.143998 -316.335156)
			(xy 265.178809 -316.335156) (xy 265.182744 -316.281385) (xy 265.194467 -316.228761) (xy 265.213727 -316.178404)
			(xy 265.240113 -316.131387) (xy 265.273065 -316.088714) (xy 265.311878 -316.051293) (xy 265.355726 -316.019923)
			(xy 265.403674 -315.995271) (xy 265.454701 -315.977863) (xy 265.507719 -315.96807) (xy 265.561598 -315.966101)
			(xy 265.615189 -315.971998) (xy 265.66735 -315.985634) (xy 265.71697 -316.006721) (xy 265.762991 -316.034807)
			(xy 265.804433 -316.069295) (xy 265.840411 -316.109449) (xy 265.870159 -316.154413) (xy 265.893044 -316.20323)
			(xy 265.908576 -316.254859) (xy 265.916426 -316.308199) (xy 265.916918 -316.335156) (xy 272.722863 -316.335156)
			(xy 272.726798 -316.281385) (xy 272.738521 -316.228761) (xy 272.757781 -316.178404) (xy 272.784167 -316.131387)
			(xy 272.817119 -316.088714) (xy 272.855932 -316.051293) (xy 272.89978 -316.019923) (xy 272.947728 -315.995271)
			(xy 272.998755 -315.977863) (xy 273.051773 -315.96807) (xy 273.105652 -315.966101) (xy 273.159243 -315.971998)
			(xy 273.211404 -315.985634) (xy 273.261024 -316.006721) (xy 273.307045 -316.034807) (xy 273.348487 -316.069295)
			(xy 273.384465 -316.109449) (xy 273.414213 -316.154413) (xy 273.437098 -316.20323) (xy 273.45263 -316.254859)
			(xy 273.46048 -316.308199) (xy 273.460972 -316.335156) (xy 280.266663 -316.335156) (xy 280.270598 -316.281385)
			(xy 280.282321 -316.228761) (xy 280.301581 -316.178404) (xy 280.327967 -316.131387) (xy 280.360919 -316.088714)
			(xy 280.399732 -316.051293) (xy 280.44358 -316.019923) (xy 280.491528 -315.995271) (xy 280.542555 -315.977863)
			(xy 280.595573 -315.96807) (xy 280.649452 -315.966101) (xy 280.703043 -315.971998) (xy 280.755204 -315.985634)
			(xy 280.804824 -316.006721) (xy 280.850845 -316.034807) (xy 280.892287 -316.069295) (xy 280.928265 -316.109449)
			(xy 280.958013 -316.154413) (xy 280.980898 -316.20323) (xy 280.99643 -316.254859) (xy 281.00428 -316.308199)
			(xy 281.004772 -316.335156) (xy 287.810717 -316.335156) (xy 287.814652 -316.281385) (xy 287.826375 -316.228761)
			(xy 287.845635 -316.178404) (xy 287.872021 -316.131387) (xy 287.904973 -316.088714) (xy 287.943786 -316.051293)
			(xy 287.987634 -316.019923) (xy 288.035582 -315.995271) (xy 288.086609 -315.977863) (xy 288.139627 -315.96807)
			(xy 288.193506 -315.966101) (xy 288.247097 -315.971998) (xy 288.299258 -315.985634) (xy 288.348878 -316.006721)
			(xy 288.394899 -316.034807) (xy 288.436341 -316.069295) (xy 288.472319 -316.109449) (xy 288.502067 -316.154413)
			(xy 288.524952 -316.20323) (xy 288.540484 -316.254859) (xy 288.548334 -316.308199) (xy 288.548826 -316.335156)
			(xy 288.548334 -316.362113) (xy 288.540484 -316.415453) (xy 288.524952 -316.467082) (xy 288.502067 -316.515899)
			(xy 288.472319 -316.560863) (xy 288.436341 -316.601017) (xy 288.394899 -316.635505) (xy 288.348878 -316.663591)
			(xy 288.299258 -316.684678) (xy 288.247097 -316.698314) (xy 288.193506 -316.704211) (xy 288.139627 -316.702242)
			(xy 288.086609 -316.692449) (xy 288.035582 -316.675041) (xy 287.987634 -316.650389) (xy 287.943786 -316.619019)
			(xy 287.904973 -316.581598) (xy 287.872021 -316.538925) (xy 287.845635 -316.491908) (xy 287.826375 -316.441551)
			(xy 287.814652 -316.388927) (xy 287.810717 -316.335156) (xy 281.004772 -316.335156) (xy 281.00428 -316.362113)
			(xy 280.99643 -316.415453) (xy 280.980898 -316.467082) (xy 280.958013 -316.515899) (xy 280.928265 -316.560863)
			(xy 280.892287 -316.601017) (xy 280.850845 -316.635505) (xy 280.804824 -316.663591) (xy 280.755204 -316.684678)
			(xy 280.703043 -316.698314) (xy 280.649452 -316.704211) (xy 280.595573 -316.702242) (xy 280.542555 -316.692449)
			(xy 280.491528 -316.675041) (xy 280.44358 -316.650389) (xy 280.399732 -316.619019) (xy 280.360919 -316.581598)
			(xy 280.327967 -316.538925) (xy 280.301581 -316.491908) (xy 280.282321 -316.441551) (xy 280.270598 -316.388927)
			(xy 280.266663 -316.335156) (xy 273.460972 -316.335156) (xy 273.46048 -316.362113) (xy 273.45263 -316.415453)
			(xy 273.437098 -316.467082) (xy 273.414213 -316.515899) (xy 273.384465 -316.560863) (xy 273.348487 -316.601017)
			(xy 273.307045 -316.635505) (xy 273.261024 -316.663591) (xy 273.211404 -316.684678) (xy 273.159243 -316.698314)
			(xy 273.105652 -316.704211) (xy 273.051773 -316.702242) (xy 272.998755 -316.692449) (xy 272.947728 -316.675041)
			(xy 272.89978 -316.650389) (xy 272.855932 -316.619019) (xy 272.817119 -316.581598) (xy 272.784167 -316.538925)
			(xy 272.757781 -316.491908) (xy 272.738521 -316.441551) (xy 272.726798 -316.388927) (xy 272.722863 -316.335156)
			(xy 265.916918 -316.335156) (xy 265.916426 -316.362113) (xy 265.908576 -316.415453) (xy 265.893044 -316.467082)
			(xy 265.870159 -316.515899) (xy 265.840411 -316.560863) (xy 265.804433 -316.601017) (xy 265.762991 -316.635505)
			(xy 265.71697 -316.663591) (xy 265.66735 -316.684678) (xy 265.615189 -316.698314) (xy 265.561598 -316.704211)
			(xy 265.507719 -316.702242) (xy 265.454701 -316.692449) (xy 265.403674 -316.675041) (xy 265.355726 -316.650389)
			(xy 265.311878 -316.619019) (xy 265.273065 -316.581598) (xy 265.240113 -316.538925) (xy 265.213727 -316.491908)
			(xy 265.194467 -316.441551) (xy 265.182744 -316.388927) (xy 265.178809 -316.335156) (xy 264.143998 -316.335156)
			(xy 264.143998 -317.18504) (xy 269.278877 -317.18504) (xy 269.282812 -317.131269) (xy 269.294535 -317.078645)
			(xy 269.313795 -317.028288) (xy 269.340181 -316.981271) (xy 269.373133 -316.938598) (xy 269.411946 -316.901177)
			(xy 269.455794 -316.869807) (xy 269.503742 -316.845155) (xy 269.554769 -316.827747) (xy 269.607787 -316.817954)
			(xy 269.661666 -316.815985) (xy 269.715257 -316.821882) (xy 269.767418 -316.835518) (xy 269.817038 -316.856605)
			(xy 269.863059 -316.884691) (xy 269.904501 -316.919179) (xy 269.940479 -316.959333) (xy 269.970227 -317.004297)
			(xy 269.993112 -317.053114) (xy 270.008644 -317.104743) (xy 270.016494 -317.158083) (xy 270.016986 -317.18504)
			(xy 276.822931 -317.18504) (xy 276.826866 -317.131269) (xy 276.838589 -317.078645) (xy 276.857849 -317.028288)
			(xy 276.884235 -316.981271) (xy 276.917187 -316.938598) (xy 276.956 -316.901177) (xy 276.999848 -316.869807)
			(xy 277.047796 -316.845155) (xy 277.098823 -316.827747) (xy 277.151841 -316.817954) (xy 277.20572 -316.815985)
			(xy 277.259311 -316.821882) (xy 277.311472 -316.835518) (xy 277.361092 -316.856605) (xy 277.407113 -316.884691)
			(xy 277.448555 -316.919179) (xy 277.484533 -316.959333) (xy 277.514281 -317.004297) (xy 277.537166 -317.053114)
			(xy 277.552698 -317.104743) (xy 277.560548 -317.158083) (xy 277.56104 -317.18504) (xy 284.366731 -317.18504)
			(xy 284.370666 -317.131269) (xy 284.382389 -317.078645) (xy 284.401649 -317.028288) (xy 284.428035 -316.981271)
			(xy 284.460987 -316.938598) (xy 284.4998 -316.901177) (xy 284.543648 -316.869807) (xy 284.591596 -316.845155)
			(xy 284.642623 -316.827747) (xy 284.695641 -316.817954) (xy 284.74952 -316.815985) (xy 284.803111 -316.821882)
			(xy 284.855272 -316.835518) (xy 284.904892 -316.856605) (xy 284.950913 -316.884691) (xy 284.992355 -316.919179)
			(xy 285.028333 -316.959333) (xy 285.058081 -317.004297) (xy 285.080966 -317.053114) (xy 285.096498 -317.104743)
			(xy 285.104348 -317.158083) (xy 285.10484 -317.18504) (xy 291.910785 -317.18504) (xy 291.91472 -317.131269)
			(xy 291.926443 -317.078645) (xy 291.945703 -317.028288) (xy 291.972089 -316.981271) (xy 292.005041 -316.938598)
			(xy 292.043854 -316.901177) (xy 292.087702 -316.869807) (xy 292.13565 -316.845155) (xy 292.186677 -316.827747)
			(xy 292.239695 -316.817954) (xy 292.293574 -316.815985) (xy 292.347165 -316.821882) (xy 292.399326 -316.835518)
			(xy 292.448946 -316.856605) (xy 292.494967 -316.884691) (xy 292.536409 -316.919179) (xy 292.572387 -316.959333)
			(xy 292.602135 -317.004297) (xy 292.62502 -317.053114) (xy 292.640552 -317.104743) (xy 292.648402 -317.158083)
			(xy 292.648894 -317.18504) (xy 292.648402 -317.211997) (xy 292.640552 -317.265337) (xy 292.62502 -317.316966)
			(xy 292.602135 -317.365783) (xy 292.572387 -317.410747) (xy 292.536409 -317.450901) (xy 292.494967 -317.485389)
			(xy 292.448946 -317.513475) (xy 292.399326 -317.534562) (xy 292.347165 -317.548198) (xy 292.293574 -317.554095)
			(xy 292.239695 -317.552126) (xy 292.186677 -317.542333) (xy 292.13565 -317.524925) (xy 292.087702 -317.500273)
			(xy 292.043854 -317.468903) (xy 292.005041 -317.431482) (xy 291.972089 -317.388809) (xy 291.945703 -317.341792)
			(xy 291.926443 -317.291435) (xy 291.91472 -317.238811) (xy 291.910785 -317.18504) (xy 285.10484 -317.18504)
			(xy 285.104348 -317.211997) (xy 285.096498 -317.265337) (xy 285.080966 -317.316966) (xy 285.058081 -317.365783)
			(xy 285.028333 -317.410747) (xy 284.992355 -317.450901) (xy 284.950913 -317.485389) (xy 284.904892 -317.513475)
			(xy 284.855272 -317.534562) (xy 284.803111 -317.548198) (xy 284.74952 -317.554095) (xy 284.695641 -317.552126)
			(xy 284.642623 -317.542333) (xy 284.591596 -317.524925) (xy 284.543648 -317.500273) (xy 284.4998 -317.468903)
			(xy 284.460987 -317.431482) (xy 284.428035 -317.388809) (xy 284.401649 -317.341792) (xy 284.382389 -317.291435)
			(xy 284.370666 -317.238811) (xy 284.366731 -317.18504) (xy 277.56104 -317.18504) (xy 277.560548 -317.211997)
			(xy 277.552698 -317.265337) (xy 277.537166 -317.316966) (xy 277.514281 -317.365783) (xy 277.484533 -317.410747)
			(xy 277.448555 -317.450901) (xy 277.407113 -317.485389) (xy 277.361092 -317.513475) (xy 277.311472 -317.534562)
			(xy 277.259311 -317.548198) (xy 277.20572 -317.554095) (xy 277.151841 -317.552126) (xy 277.098823 -317.542333)
			(xy 277.047796 -317.524925) (xy 276.999848 -317.500273) (xy 276.956 -317.468903) (xy 276.917187 -317.431482)
			(xy 276.884235 -317.388809) (xy 276.857849 -317.341792) (xy 276.838589 -317.291435) (xy 276.826866 -317.238811)
			(xy 276.822931 -317.18504) (xy 270.016986 -317.18504) (xy 270.016494 -317.211997) (xy 270.008644 -317.265337)
			(xy 269.993112 -317.316966) (xy 269.970227 -317.365783) (xy 269.940479 -317.410747) (xy 269.904501 -317.450901)
			(xy 269.863059 -317.485389) (xy 269.817038 -317.513475) (xy 269.767418 -317.534562) (xy 269.715257 -317.548198)
			(xy 269.661666 -317.554095) (xy 269.607787 -317.552126) (xy 269.554769 -317.542333) (xy 269.503742 -317.524925)
			(xy 269.455794 -317.500273) (xy 269.411946 -317.468903) (xy 269.373133 -317.431482) (xy 269.340181 -317.388809)
			(xy 269.313795 -317.341792) (xy 269.294535 -317.291435) (xy 269.282812 -317.238811) (xy 269.278877 -317.18504)
			(xy 264.143998 -317.18504) (xy 264.143998 -318.035178) (xy 265.178809 -318.035178) (xy 265.182744 -317.981407)
			(xy 265.194467 -317.928783) (xy 265.213727 -317.878426) (xy 265.240113 -317.831409) (xy 265.273065 -317.788736)
			(xy 265.311878 -317.751315) (xy 265.355726 -317.719945) (xy 265.403674 -317.695293) (xy 265.454701 -317.677885)
			(xy 265.507719 -317.668092) (xy 265.561598 -317.666123) (xy 265.615189 -317.67202) (xy 265.66735 -317.685656)
			(xy 265.71697 -317.706743) (xy 265.762991 -317.734829) (xy 265.804433 -317.769317) (xy 265.840411 -317.809471)
			(xy 265.870159 -317.854435) (xy 265.893044 -317.903252) (xy 265.908576 -317.954881) (xy 265.916426 -318.008221)
			(xy 265.916918 -318.035178) (xy 272.722863 -318.035178) (xy 272.726798 -317.981407) (xy 272.738521 -317.928783)
			(xy 272.757781 -317.878426) (xy 272.784167 -317.831409) (xy 272.817119 -317.788736) (xy 272.855932 -317.751315)
			(xy 272.89978 -317.719945) (xy 272.947728 -317.695293) (xy 272.998755 -317.677885) (xy 273.051773 -317.668092)
			(xy 273.105652 -317.666123) (xy 273.159243 -317.67202) (xy 273.211404 -317.685656) (xy 273.261024 -317.706743)
			(xy 273.307045 -317.734829) (xy 273.348487 -317.769317) (xy 273.384465 -317.809471) (xy 273.414213 -317.854435)
			(xy 273.437098 -317.903252) (xy 273.45263 -317.954881) (xy 273.46048 -318.008221) (xy 273.460972 -318.035178)
			(xy 280.266663 -318.035178) (xy 280.270598 -317.981407) (xy 280.282321 -317.928783) (xy 280.301581 -317.878426)
			(xy 280.327967 -317.831409) (xy 280.360919 -317.788736) (xy 280.399732 -317.751315) (xy 280.44358 -317.719945)
			(xy 280.491528 -317.695293) (xy 280.542555 -317.677885) (xy 280.595573 -317.668092) (xy 280.649452 -317.666123)
			(xy 280.703043 -317.67202) (xy 280.755204 -317.685656) (xy 280.804824 -317.706743) (xy 280.850845 -317.734829)
			(xy 280.892287 -317.769317) (xy 280.928265 -317.809471) (xy 280.958013 -317.854435) (xy 280.980898 -317.903252)
			(xy 280.99643 -317.954881) (xy 281.00428 -318.008221) (xy 281.004772 -318.035178) (xy 287.810717 -318.035178)
			(xy 287.814652 -317.981407) (xy 287.826375 -317.928783) (xy 287.845635 -317.878426) (xy 287.872021 -317.831409)
			(xy 287.904973 -317.788736) (xy 287.943786 -317.751315) (xy 287.987634 -317.719945) (xy 288.035582 -317.695293)
			(xy 288.086609 -317.677885) (xy 288.139627 -317.668092) (xy 288.193506 -317.666123) (xy 288.247097 -317.67202)
			(xy 288.299258 -317.685656) (xy 288.348878 -317.706743) (xy 288.394899 -317.734829) (xy 288.436341 -317.769317)
			(xy 288.472319 -317.809471) (xy 288.502067 -317.854435) (xy 288.524952 -317.903252) (xy 288.540484 -317.954881)
			(xy 288.548334 -318.008221) (xy 288.548826 -318.035178) (xy 288.548334 -318.062135) (xy 288.540484 -318.115475)
			(xy 288.524952 -318.167104) (xy 288.502067 -318.215921) (xy 288.472319 -318.260885) (xy 288.436341 -318.301039)
			(xy 288.394899 -318.335527) (xy 288.348878 -318.363613) (xy 288.299258 -318.3847) (xy 288.247097 -318.398336)
			(xy 288.193506 -318.404233) (xy 288.139627 -318.402264) (xy 288.086609 -318.392471) (xy 288.035582 -318.375063)
			(xy 287.987634 -318.350411) (xy 287.943786 -318.319041) (xy 287.904973 -318.28162) (xy 287.872021 -318.238947)
			(xy 287.845635 -318.19193) (xy 287.826375 -318.141573) (xy 287.814652 -318.088949) (xy 287.810717 -318.035178)
			(xy 281.004772 -318.035178) (xy 281.00428 -318.062135) (xy 280.99643 -318.115475) (xy 280.980898 -318.167104)
			(xy 280.958013 -318.215921) (xy 280.928265 -318.260885) (xy 280.892287 -318.301039) (xy 280.850845 -318.335527)
			(xy 280.804824 -318.363613) (xy 280.755204 -318.3847) (xy 280.703043 -318.398336) (xy 280.649452 -318.404233)
			(xy 280.595573 -318.402264) (xy 280.542555 -318.392471) (xy 280.491528 -318.375063) (xy 280.44358 -318.350411)
			(xy 280.399732 -318.319041) (xy 280.360919 -318.28162) (xy 280.327967 -318.238947) (xy 280.301581 -318.19193)
			(xy 280.282321 -318.141573) (xy 280.270598 -318.088949) (xy 280.266663 -318.035178) (xy 273.460972 -318.035178)
			(xy 273.46048 -318.062135) (xy 273.45263 -318.115475) (xy 273.437098 -318.167104) (xy 273.414213 -318.215921)
			(xy 273.384465 -318.260885) (xy 273.348487 -318.301039) (xy 273.307045 -318.335527) (xy 273.261024 -318.363613)
			(xy 273.211404 -318.3847) (xy 273.159243 -318.398336) (xy 273.105652 -318.404233) (xy 273.051773 -318.402264)
			(xy 272.998755 -318.392471) (xy 272.947728 -318.375063) (xy 272.89978 -318.350411) (xy 272.855932 -318.319041)
			(xy 272.817119 -318.28162) (xy 272.784167 -318.238947) (xy 272.757781 -318.19193) (xy 272.738521 -318.141573)
			(xy 272.726798 -318.088949) (xy 272.722863 -318.035178) (xy 265.916918 -318.035178) (xy 265.916426 -318.062135)
			(xy 265.908576 -318.115475) (xy 265.893044 -318.167104) (xy 265.870159 -318.215921) (xy 265.840411 -318.260885)
			(xy 265.804433 -318.301039) (xy 265.762991 -318.335527) (xy 265.71697 -318.363613) (xy 265.66735 -318.3847)
			(xy 265.615189 -318.398336) (xy 265.561598 -318.404233) (xy 265.507719 -318.402264) (xy 265.454701 -318.392471)
			(xy 265.403674 -318.375063) (xy 265.355726 -318.350411) (xy 265.311878 -318.319041) (xy 265.273065 -318.28162)
			(xy 265.240113 -318.238947) (xy 265.213727 -318.19193) (xy 265.194467 -318.141573) (xy 265.182744 -318.088949)
			(xy 265.178809 -318.035178) (xy 264.143998 -318.035178) (xy 264.143998 -318.367664) (xy 264.144433 -318.377729)
			(xy 264.152163 -318.396317) (xy 264.158984 -318.403732) (xy 264.810748 -319.055496) (xy 264.818149 -319.062335)
			(xy 264.836747 -319.070053) (xy 264.846816 -319.070482)
		)
		(stroke
			(width 0)
			(type solid)
		)
		(fill yes)
		(layer "B.Cu")
		(net "GND")
	)
	(gr_poly
		(pts
			(xy 45.125132 -319.633092) (xy 45.135199 -319.632663) (xy 45.153795 -319.624939) (xy 45.1612 -319.618106)
			(xy 45.794168 -318.985138) (xy 45.801008 -318.977738) (xy 45.808725 -318.959139) (xy 45.809154 -318.94907)
			(xy 45.809154 -244.512846) (xy 45.808749 -244.502968) (xy 45.801203 -244.48471) (xy 45.787242 -244.470732)
			(xy 45.768994 -244.463163) (xy 45.759116 -244.462808) (xy 45.649896 -244.462808) (xy 45.639826 -244.462385)
			(xy 45.621222 -244.45467) (xy 45.613828 -244.447822) (xy 45.596302 -244.430296) (xy 45.593404 -244.427509)
			(xy 45.586899 -244.422783) (xy 45.583348 -244.420898) (xy 45.571918 -244.415056) (xy 45.571664 -244.414802)
			(xy 45.565314 -244.411754) (xy 45.55998 -244.40896) (xy 45.542454 -244.404388) (xy 45.529754 -244.402864)
			(xy 45.12437 -244.402864) (xy 45.114575 -244.403378) (xy 45.096488 -244.410916) (xy 45.082629 -244.424769)
			(xy 45.075082 -244.442853) (xy 45.074586 -244.452648) (xy 45.074586 -244.462808) (xy 44.806616 -244.462808)
			(xy 44.787107 -244.462354) (xy 44.748682 -244.455564) (xy 44.711996 -244.442269) (xy 44.678142 -244.422865)
			(xy 44.662852 -244.410738) (xy 44.656248 -244.405404) (xy 44.632372 -244.396514) (xy 44.628084 -244.394996)
			(xy 44.61914 -244.39334) (xy 44.614592 -244.393212) (xy 44.55795 -244.393212) (xy 44.54398 -244.395244)
			(xy 44.53763 -244.397022) (xy 44.531534 -244.400578) (xy 44.53128 -244.400832) (xy 44.509549 -244.413475)
			(xy 44.463396 -244.433413) (xy 44.414967 -244.446915) (xy 44.365156 -244.453729) (xy 44.340018 -244.454172)
			(xy 44.312418 -244.453683) (xy 44.257835 -244.445458) (xy 44.205087 -244.42919) (xy 44.155353 -244.405242)
			(xy 44.109744 -244.374148) (xy 44.069279 -244.336604) (xy 44.034862 -244.293448) (xy 44.007261 -244.245644)
			(xy 43.987094 -244.194261) (xy 43.974811 -244.140445) (xy 43.970685 -244.0854) (xy 43.974811 -244.030355)
			(xy 43.987094 -243.976539) (xy 44.007261 -243.925156) (xy 44.034862 -243.877352) (xy 44.069279 -243.834196)
			(xy 44.109744 -243.796652) (xy 44.155353 -243.765558) (xy 44.205087 -243.74161) (xy 44.257835 -243.725342)
			(xy 44.312418 -243.717117) (xy 44.340018 -243.716556) (xy 44.365159 -243.716958) (xy 44.414981 -243.723748)
			(xy 44.463415 -243.737254) (xy 44.509561 -243.757225) (xy 44.53128 -243.769896) (xy 44.531534 -243.77015)
			(xy 44.53763 -243.773706) (xy 44.54398 -243.775484) (xy 44.55795 -243.777516) (xy 44.614592 -243.777516)
			(xy 44.619139 -243.77739) (xy 44.628082 -243.775727) (xy 44.632372 -243.774214) (xy 44.656248 -243.765324)
			(xy 44.662852 -243.75999) (xy 44.678132 -243.747851) (xy 44.711997 -243.728464) (xy 44.748684 -243.71517)
			(xy 44.787107 -243.708363) (xy 44.806616 -243.70792) (xy 45.02404 -243.70792) (xy 45.034107 -243.708351)
			(xy 45.052699 -243.716078) (xy 45.060108 -243.722906) (xy 45.074586 -243.737384) (xy 45.074586 -243.738654)
			(xy 45.088556 -243.752878) (xy 45.095957 -243.759718) (xy 45.114555 -243.767435) (xy 45.124624 -243.767864)
			(xy 45.529754 -243.767864) (xy 45.542454 -243.76634) (xy 45.560234 -243.761768) (xy 45.565568 -243.758974)
			(xy 45.571664 -243.755672) (xy 45.571918 -243.755418) (xy 45.579931 -243.750781) (xy 45.592242 -243.736971)
			(xy 45.59889 -243.719707) (xy 45.59935 -243.71046) (xy 45.59935 -243.70792) (xy 45.759116 -243.70792)
			(xy 45.768983 -243.707503) (xy 45.787214 -243.699945) (xy 45.801164 -243.685985) (xy 45.80871 -243.66775)
			(xy 45.809154 -243.657882) (xy 45.809154 -198.757794) (xy 45.808733 -198.747777) (xy 45.80106 -198.72927)
			(xy 45.786886 -198.715111) (xy 45.768372 -198.707457) (xy 45.758354 -198.706994) (xy 44.752006 -198.706994)
			(xy 44.736927 -198.707539) (xy 44.708085 -198.71635) (xy 44.683076 -198.733203) (xy 44.664082 -198.756628)
			(xy 44.652762 -198.784581) (xy 44.650104 -198.814621) (xy 44.65634 -198.844127) (xy 44.663106 -198.857616)
			(xy 44.677479 -198.885025) (xy 44.697859 -198.943458) (xy 44.708194 -199.004474) (xy 44.708826 -199.035416)
			(xy 44.70831 -199.063016) (xy 44.700083 -199.117599) (xy 44.683813 -199.170346) (xy 44.659863 -199.220079)
			(xy 44.628768 -199.265686) (xy 44.591223 -199.30615) (xy 44.548066 -199.340567) (xy 44.500262 -199.368166)
			(xy 44.448878 -199.388333) (xy 44.395063 -199.400616) (xy 44.340018 -199.404741) (xy 44.284973 -199.400616)
			(xy 44.231158 -199.388333) (xy 44.179774 -199.368166) (xy 44.13197 -199.340567) (xy 44.088813 -199.30615)
			(xy 44.051268 -199.265686) (xy 44.020173 -199.220079) (xy 43.996223 -199.170346) (xy 43.979953 -199.117599)
			(xy 43.971726 -199.063016) (xy 43.97121 -199.035416) (xy 43.971841 -199.004473) (xy 43.982173 -198.943456)
			(xy 44.002551 -198.885022) (xy 44.01693 -198.857616) (xy 44.023725 -198.844146) (xy 44.029927 -198.814637)
			(xy 44.027248 -198.784602) (xy 44.015922 -198.756657) (xy 43.996933 -198.733232) (xy 43.971936 -198.716368)
			(xy 43.943106 -198.707532) (xy 43.92803 -198.706994) (xy 37.207952 -198.706994) (xy 37.192868 -198.707533)
			(xy 37.164013 -198.716336) (xy 37.138992 -198.733188) (xy 37.119988 -198.756618) (xy 37.108663 -198.784579)
			(xy 37.106005 -198.814629) (xy 37.112246 -198.844144) (xy 37.119052 -198.857616) (xy 37.133427 -198.885024)
			(xy 37.15381 -198.943457) (xy 37.164146 -199.004473) (xy 37.164772 -199.035416) (xy 37.164256 -199.063016)
			(xy 37.156029 -199.117599) (xy 37.139759 -199.170346) (xy 37.115809 -199.220079) (xy 37.084714 -199.265686)
			(xy 37.047169 -199.30615) (xy 37.004012 -199.340567) (xy 36.956208 -199.368166) (xy 36.904824 -199.388333)
			(xy 36.851009 -199.400616) (xy 36.795964 -199.404741) (xy 36.740919 -199.400616) (xy 36.687104 -199.388333)
			(xy 36.63572 -199.368166) (xy 36.587916 -199.340567) (xy 36.544759 -199.30615) (xy 36.507214 -199.265686)
			(xy 36.476119 -199.220079) (xy 36.452169 -199.170346) (xy 36.435899 -199.117599) (xy 36.427672 -199.063016)
			(xy 36.427156 -199.035416) (xy 36.427787 -199.004473) (xy 36.438118 -198.943456) (xy 36.458493 -198.88502)
			(xy 36.472876 -198.857616) (xy 36.479673 -198.844149) (xy 36.485879 -198.814643) (xy 36.483201 -198.784611)
			(xy 36.471873 -198.756669) (xy 36.452882 -198.73325) (xy 36.427882 -198.716395) (xy 36.399051 -198.707572)
			(xy 36.383976 -198.706994) (xy 29.664152 -198.706994) (xy 29.649068 -198.707533) (xy 29.620213 -198.716336)
			(xy 29.595192 -198.733188) (xy 29.576188 -198.756618) (xy 29.564863 -198.784579) (xy 29.562205 -198.814629)
			(xy 29.568446 -198.844144) (xy 29.575252 -198.857616) (xy 29.589627 -198.885024) (xy 29.61001 -198.943457)
			(xy 29.620346 -199.004473) (xy 29.620972 -199.035416) (xy 29.620456 -199.063016) (xy 29.612229 -199.117599)
			(xy 29.595959 -199.170346) (xy 29.572009 -199.220079) (xy 29.540914 -199.265686) (xy 29.503369 -199.30615)
			(xy 29.460212 -199.340567) (xy 29.412408 -199.368166) (xy 29.361024 -199.388333) (xy 29.307209 -199.400616)
			(xy 29.252164 -199.404741) (xy 29.197119 -199.400616) (xy 29.143304 -199.388333) (xy 29.09192 -199.368166)
			(xy 29.044116 -199.340567) (xy 29.000959 -199.30615) (xy 28.963414 -199.265686) (xy 28.932319 -199.220079)
			(xy 28.908369 -199.170346) (xy 28.892099 -199.117599) (xy 28.883872 -199.063016) (xy 28.883356 -199.035416)
			(xy 28.883987 -199.004473) (xy 28.894318 -198.943456) (xy 28.914693 -198.88502) (xy 28.929076 -198.857616)
			(xy 28.935873 -198.844149) (xy 28.942079 -198.814643) (xy 28.939401 -198.784611) (xy 28.928073 -198.756669)
			(xy 28.909082 -198.73325) (xy 28.884082 -198.716395) (xy 28.855251 -198.707572) (xy 28.840176 -198.706994)
			(xy 22.120098 -198.706994) (xy 22.10502 -198.707541) (xy 22.07618 -198.716352) (xy 22.051173 -198.733205)
			(xy 22.032181 -198.75663) (xy 22.020862 -198.784581) (xy 22.018204 -198.81462) (xy 22.024438 -198.844124)
			(xy 22.031198 -198.857616) (xy 22.045571 -198.885025) (xy 22.065952 -198.943458) (xy 22.076287 -199.004473)
			(xy 22.076918 -199.035416) (xy 22.076402 -199.063016) (xy 22.068175 -199.117599) (xy 22.051905 -199.170346)
			(xy 22.027955 -199.220079) (xy 21.99686 -199.265686) (xy 21.959315 -199.30615) (xy 21.916158 -199.340567)
			(xy 21.868354 -199.368166) (xy 21.81697 -199.388333) (xy 21.763155 -199.400616) (xy 21.70811 -199.404741)
			(xy 21.653065 -199.400616) (xy 21.59925 -199.388333) (xy 21.547866 -199.368166) (xy 21.500062 -199.340567)
			(xy 21.456905 -199.30615) (xy 21.41936 -199.265686) (xy 21.388265 -199.220079) (xy 21.364315 -199.170346)
			(xy 21.348045 -199.117599) (xy 21.339818 -199.063016) (xy 21.339302 -199.035416) (xy 21.339933 -199.004473)
			(xy 21.350265 -198.943456) (xy 21.370642 -198.885022) (xy 21.385022 -198.857616) (xy 21.391817 -198.844146)
			(xy 21.39802 -198.814638) (xy 21.395341 -198.784604) (xy 21.384014 -198.756658) (xy 21.365026 -198.733235)
			(xy 21.340028 -198.716372) (xy 21.311198 -198.707538) (xy 21.296122 -198.706994) (xy 20.185634 -198.706994)
			(xy 18.577052 -197.098412) (xy 18.371312 -197.098412) (xy 16.145002 -197.098412) (xy 16.139984 -197.098509)
			(xy 16.130136 -197.100438) (xy 16.125444 -197.102222) (xy 16.116554 -197.106032) (xy 16.116554 -198.185278)
			(xy 17.238741 -198.185278) (xy 17.242676 -198.131507) (xy 17.254399 -198.078883) (xy 17.273659 -198.028526)
			(xy 17.300045 -197.981509) (xy 17.332997 -197.938836) (xy 17.37181 -197.901415) (xy 17.415658 -197.870045)
			(xy 17.463606 -197.845393) (xy 17.514633 -197.827985) (xy 17.567651 -197.818192) (xy 17.62153 -197.816223)
			(xy 17.675121 -197.82212) (xy 17.727282 -197.835756) (xy 17.776902 -197.856843) (xy 17.822923 -197.884929)
			(xy 17.864365 -197.919417) (xy 17.900343 -197.959571) (xy 17.930091 -198.004535) (xy 17.952976 -198.053352)
			(xy 17.968508 -198.104981) (xy 17.976358 -198.158321) (xy 17.97685 -198.185278) (xy 17.976358 -198.212235)
			(xy 17.968508 -198.265575) (xy 17.952976 -198.317204) (xy 17.930091 -198.366021) (xy 17.900343 -198.410985)
			(xy 17.864365 -198.451139) (xy 17.822923 -198.485627) (xy 17.776902 -198.513713) (xy 17.727282 -198.5348)
			(xy 17.675121 -198.548436) (xy 17.62153 -198.554333) (xy 17.567651 -198.552364) (xy 17.514633 -198.542571)
			(xy 17.463606 -198.525163) (xy 17.415658 -198.500511) (xy 17.37181 -198.469141) (xy 17.332997 -198.43172)
			(xy 17.300045 -198.389047) (xy 17.273659 -198.34203) (xy 17.254399 -198.291673) (xy 17.242676 -198.239049)
			(xy 17.238741 -198.185278) (xy 16.116554 -198.185278) (xy 16.116554 -199.8853) (xy 17.238741 -199.8853)
			(xy 17.242676 -199.831529) (xy 17.254399 -199.778905) (xy 17.273659 -199.728548) (xy 17.300045 -199.681531)
			(xy 17.332997 -199.638858) (xy 17.37181 -199.601437) (xy 17.415658 -199.570067) (xy 17.463606 -199.545415)
			(xy 17.514633 -199.528007) (xy 17.567651 -199.518214) (xy 17.62153 -199.516245) (xy 17.675121 -199.522142)
			(xy 17.727282 -199.535778) (xy 17.776902 -199.556865) (xy 17.822923 -199.584951) (xy 17.864365 -199.619439)
			(xy 17.900343 -199.659593) (xy 17.930091 -199.704557) (xy 17.952976 -199.753374) (xy 17.968508 -199.805003)
			(xy 17.976358 -199.858343) (xy 17.97685 -199.8853) (xy 24.782795 -199.8853) (xy 24.78673 -199.831529)
			(xy 24.798453 -199.778905) (xy 24.817713 -199.728548) (xy 24.844099 -199.681531) (xy 24.877051 -199.638858)
			(xy 24.915864 -199.601437) (xy 24.959712 -199.570067) (xy 25.00766 -199.545415) (xy 25.058687 -199.528007)
			(xy 25.111705 -199.518214) (xy 25.165584 -199.516245) (xy 25.219175 -199.522142) (xy 25.271336 -199.535778)
			(xy 25.320956 -199.556865) (xy 25.366977 -199.584951) (xy 25.408419 -199.619439) (xy 25.444397 -199.659593)
			(xy 25.474145 -199.704557) (xy 25.49703 -199.753374) (xy 25.512562 -199.805003) (xy 25.520412 -199.858343)
			(xy 25.520904 -199.8853) (xy 32.326595 -199.8853) (xy 32.33053 -199.831529) (xy 32.342253 -199.778905)
			(xy 32.361513 -199.728548) (xy 32.387899 -199.681531) (xy 32.420851 -199.638858) (xy 32.459664 -199.601437)
			(xy 32.503512 -199.570067) (xy 32.55146 -199.545415) (xy 32.602487 -199.528007) (xy 32.655505 -199.518214)
			(xy 32.709384 -199.516245) (xy 32.762975 -199.522142) (xy 32.815136 -199.535778) (xy 32.864756 -199.556865)
			(xy 32.910777 -199.584951) (xy 32.952219 -199.619439) (xy 32.988197 -199.659593) (xy 33.017945 -199.704557)
			(xy 33.04083 -199.753374) (xy 33.056362 -199.805003) (xy 33.064212 -199.858343) (xy 33.064704 -199.8853)
			(xy 39.870649 -199.8853) (xy 39.874584 -199.831529) (xy 39.886307 -199.778905) (xy 39.905567 -199.728548)
			(xy 39.931953 -199.681531) (xy 39.964905 -199.638858) (xy 40.003718 -199.601437) (xy 40.047566 -199.570067)
			(xy 40.095514 -199.545415) (xy 40.146541 -199.528007) (xy 40.199559 -199.518214) (xy 40.253438 -199.516245)
			(xy 40.307029 -199.522142) (xy 40.35919 -199.535778) (xy 40.40881 -199.556865) (xy 40.454831 -199.584951)
			(xy 40.496273 -199.619439) (xy 40.532251 -199.659593) (xy 40.561999 -199.704557) (xy 40.584884 -199.753374)
			(xy 40.600416 -199.805003) (xy 40.608266 -199.858343) (xy 40.608758 -199.8853) (xy 40.608266 -199.912257)
			(xy 40.600416 -199.965597) (xy 40.584884 -200.017226) (xy 40.561999 -200.066043) (xy 40.532251 -200.111007)
			(xy 40.496273 -200.151161) (xy 40.454831 -200.185649) (xy 40.40881 -200.213735) (xy 40.35919 -200.234822)
			(xy 40.307029 -200.248458) (xy 40.253438 -200.254355) (xy 40.199559 -200.252386) (xy 40.146541 -200.242593)
			(xy 40.095514 -200.225185) (xy 40.047566 -200.200533) (xy 40.003718 -200.169163) (xy 39.964905 -200.131742)
			(xy 39.931953 -200.089069) (xy 39.905567 -200.042052) (xy 39.886307 -199.991695) (xy 39.874584 -199.939071)
			(xy 39.870649 -199.8853) (xy 33.064704 -199.8853) (xy 33.064212 -199.912257) (xy 33.056362 -199.965597)
			(xy 33.04083 -200.017226) (xy 33.017945 -200.066043) (xy 32.988197 -200.111007) (xy 32.952219 -200.151161)
			(xy 32.910777 -200.185649) (xy 32.864756 -200.213735) (xy 32.815136 -200.234822) (xy 32.762975 -200.248458)
			(xy 32.709384 -200.254355) (xy 32.655505 -200.252386) (xy 32.602487 -200.242593) (xy 32.55146 -200.225185)
			(xy 32.503512 -200.200533) (xy 32.459664 -200.169163) (xy 32.420851 -200.131742) (xy 32.387899 -200.089069)
			(xy 32.361513 -200.042052) (xy 32.342253 -199.991695) (xy 32.33053 -199.939071) (xy 32.326595 -199.8853)
			(xy 25.520904 -199.8853) (xy 25.520412 -199.912257) (xy 25.512562 -199.965597) (xy 25.49703 -200.017226)
			(xy 25.474145 -200.066043) (xy 25.444397 -200.111007) (xy 25.408419 -200.151161) (xy 25.366977 -200.185649)
			(xy 25.320956 -200.213735) (xy 25.271336 -200.234822) (xy 25.219175 -200.248458) (xy 25.165584 -200.254355)
			(xy 25.111705 -200.252386) (xy 25.058687 -200.242593) (xy 25.00766 -200.225185) (xy 24.959712 -200.200533)
			(xy 24.915864 -200.169163) (xy 24.877051 -200.131742) (xy 24.844099 -200.089069) (xy 24.817713 -200.042052)
			(xy 24.798453 -199.991695) (xy 24.78673 -199.939071) (xy 24.782795 -199.8853) (xy 17.97685 -199.8853)
			(xy 17.976358 -199.912257) (xy 17.968508 -199.965597) (xy 17.952976 -200.017226) (xy 17.930091 -200.066043)
			(xy 17.900343 -200.111007) (xy 17.864365 -200.151161) (xy 17.822923 -200.185649) (xy 17.776902 -200.213735)
			(xy 17.727282 -200.234822) (xy 17.675121 -200.248458) (xy 17.62153 -200.254355) (xy 17.567651 -200.252386)
			(xy 17.514633 -200.242593) (xy 17.463606 -200.225185) (xy 17.415658 -200.200533) (xy 17.37181 -200.169163)
			(xy 17.332997 -200.131742) (xy 17.300045 -200.089069) (xy 17.273659 -200.042052) (xy 17.254399 -199.991695)
			(xy 17.242676 -199.939071) (xy 17.238741 -199.8853) (xy 16.116554 -199.8853) (xy 16.116554 -200.735438)
			(xy 21.338809 -200.735438) (xy 21.342744 -200.681667) (xy 21.354467 -200.629043) (xy 21.373727 -200.578686)
			(xy 21.400113 -200.531669) (xy 21.433065 -200.488996) (xy 21.471878 -200.451575) (xy 21.515726 -200.420205)
			(xy 21.563674 -200.395553) (xy 21.614701 -200.378145) (xy 21.667719 -200.368352) (xy 21.721598 -200.366383)
			(xy 21.775189 -200.37228) (xy 21.82735 -200.385916) (xy 21.87697 -200.407003) (xy 21.922991 -200.435089)
			(xy 21.964433 -200.469577) (xy 22.000411 -200.509731) (xy 22.030159 -200.554695) (xy 22.053044 -200.603512)
			(xy 22.068576 -200.655141) (xy 22.076426 -200.708481) (xy 22.076918 -200.735438) (xy 28.882863 -200.735438)
			(xy 28.886798 -200.681667) (xy 28.898521 -200.629043) (xy 28.917781 -200.578686) (xy 28.944167 -200.531669)
			(xy 28.977119 -200.488996) (xy 29.015932 -200.451575) (xy 29.05978 -200.420205) (xy 29.107728 -200.395553)
			(xy 29.158755 -200.378145) (xy 29.211773 -200.368352) (xy 29.265652 -200.366383) (xy 29.319243 -200.37228)
			(xy 29.371404 -200.385916) (xy 29.421024 -200.407003) (xy 29.467045 -200.435089) (xy 29.508487 -200.469577)
			(xy 29.544465 -200.509731) (xy 29.574213 -200.554695) (xy 29.597098 -200.603512) (xy 29.61263 -200.655141)
			(xy 29.62048 -200.708481) (xy 29.620972 -200.735438) (xy 36.426663 -200.735438) (xy 36.430598 -200.681667)
			(xy 36.442321 -200.629043) (xy 36.461581 -200.578686) (xy 36.487967 -200.531669) (xy 36.520919 -200.488996)
			(xy 36.559732 -200.451575) (xy 36.60358 -200.420205) (xy 36.651528 -200.395553) (xy 36.702555 -200.378145)
			(xy 36.755573 -200.368352) (xy 36.809452 -200.366383) (xy 36.863043 -200.37228) (xy 36.915204 -200.385916)
			(xy 36.964824 -200.407003) (xy 37.010845 -200.435089) (xy 37.052287 -200.469577) (xy 37.088265 -200.509731)
			(xy 37.118013 -200.554695) (xy 37.140898 -200.603512) (xy 37.15643 -200.655141) (xy 37.16428 -200.708481)
			(xy 37.164772 -200.735438) (xy 43.970717 -200.735438) (xy 43.974652 -200.681667) (xy 43.986375 -200.629043)
			(xy 44.005635 -200.578686) (xy 44.032021 -200.531669) (xy 44.064973 -200.488996) (xy 44.103786 -200.451575)
			(xy 44.147634 -200.420205) (xy 44.195582 -200.395553) (xy 44.246609 -200.378145) (xy 44.299627 -200.368352)
			(xy 44.353506 -200.366383) (xy 44.407097 -200.37228) (xy 44.459258 -200.385916) (xy 44.508878 -200.407003)
			(xy 44.554899 -200.435089) (xy 44.596341 -200.469577) (xy 44.632319 -200.509731) (xy 44.662067 -200.554695)
			(xy 44.684952 -200.603512) (xy 44.700484 -200.655141) (xy 44.708334 -200.708481) (xy 44.708826 -200.735438)
			(xy 44.708334 -200.762395) (xy 44.700484 -200.815735) (xy 44.684952 -200.867364) (xy 44.662067 -200.916181)
			(xy 44.632319 -200.961145) (xy 44.596341 -201.001299) (xy 44.554899 -201.035787) (xy 44.508878 -201.063873)
			(xy 44.459258 -201.08496) (xy 44.407097 -201.098596) (xy 44.353506 -201.104493) (xy 44.299627 -201.102524)
			(xy 44.246609 -201.092731) (xy 44.195582 -201.075323) (xy 44.147634 -201.050671) (xy 44.103786 -201.019301)
			(xy 44.064973 -200.98188) (xy 44.032021 -200.939207) (xy 44.005635 -200.89219) (xy 43.986375 -200.841833)
			(xy 43.974652 -200.789209) (xy 43.970717 -200.735438) (xy 37.164772 -200.735438) (xy 37.16428 -200.762395)
			(xy 37.15643 -200.815735) (xy 37.140898 -200.867364) (xy 37.118013 -200.916181) (xy 37.088265 -200.961145)
			(xy 37.052287 -201.001299) (xy 37.010845 -201.035787) (xy 36.964824 -201.063873) (xy 36.915204 -201.08496)
			(xy 36.863043 -201.098596) (xy 36.809452 -201.104493) (xy 36.755573 -201.102524) (xy 36.702555 -201.092731)
			(xy 36.651528 -201.075323) (xy 36.60358 -201.050671) (xy 36.559732 -201.019301) (xy 36.520919 -200.98188)
			(xy 36.487967 -200.939207) (xy 36.461581 -200.89219) (xy 36.442321 -200.841833) (xy 36.430598 -200.789209)
			(xy 36.426663 -200.735438) (xy 29.620972 -200.735438) (xy 29.62048 -200.762395) (xy 29.61263 -200.815735)
			(xy 29.597098 -200.867364) (xy 29.574213 -200.916181) (xy 29.544465 -200.961145) (xy 29.508487 -201.001299)
			(xy 29.467045 -201.035787) (xy 29.421024 -201.063873) (xy 29.371404 -201.08496) (xy 29.319243 -201.098596)
			(xy 29.265652 -201.104493) (xy 29.211773 -201.102524) (xy 29.158755 -201.092731) (xy 29.107728 -201.075323)
			(xy 29.05978 -201.050671) (xy 29.015932 -201.019301) (xy 28.977119 -200.98188) (xy 28.944167 -200.939207)
			(xy 28.917781 -200.89219) (xy 28.898521 -200.841833) (xy 28.886798 -200.789209) (xy 28.882863 -200.735438)
			(xy 22.076918 -200.735438) (xy 22.076426 -200.762395) (xy 22.068576 -200.815735) (xy 22.053044 -200.867364)
			(xy 22.030159 -200.916181) (xy 22.000411 -200.961145) (xy 21.964433 -201.001299) (xy 21.922991 -201.035787)
			(xy 21.87697 -201.063873) (xy 21.82735 -201.08496) (xy 21.775189 -201.098596) (xy 21.721598 -201.104493)
			(xy 21.667719 -201.102524) (xy 21.614701 -201.092731) (xy 21.563674 -201.075323) (xy 21.515726 -201.050671)
			(xy 21.471878 -201.019301) (xy 21.433065 -200.98188) (xy 21.400113 -200.939207) (xy 21.373727 -200.89219)
			(xy 21.354467 -200.841833) (xy 21.342744 -200.789209) (xy 21.338809 -200.735438) (xy 16.116554 -200.735438)
			(xy 16.116554 -201.518774) (xy 16.116116 -201.528837) (xy 16.108378 -201.547418) (xy 16.101568 -201.554842)
			(xy 16.071088 -201.585322) (xy 17.238741 -201.585322) (xy 17.242676 -201.531551) (xy 17.254399 -201.478927)
			(xy 17.273659 -201.42857) (xy 17.300045 -201.381553) (xy 17.332997 -201.33888) (xy 17.37181 -201.301459)
			(xy 17.415658 -201.270089) (xy 17.463606 -201.245437) (xy 17.514633 -201.228029) (xy 17.567651 -201.218236)
			(xy 17.62153 -201.216267) (xy 17.675121 -201.222164) (xy 17.727282 -201.2358) (xy 17.776902 -201.256887)
			(xy 17.822923 -201.284973) (xy 17.864365 -201.319461) (xy 17.900343 -201.359615) (xy 17.930091 -201.404579)
			(xy 17.952976 -201.453396) (xy 17.968508 -201.505025) (xy 17.976358 -201.558365) (xy 17.97685 -201.585322)
			(xy 21.338809 -201.585322) (xy 21.342744 -201.531551) (xy 21.354467 -201.478927) (xy 21.373727 -201.42857)
			(xy 21.400113 -201.381553) (xy 21.433065 -201.33888) (xy 21.471878 -201.301459) (xy 21.515726 -201.270089)
			(xy 21.563674 -201.245437) (xy 21.614701 -201.228029) (xy 21.667719 -201.218236) (xy 21.721598 -201.216267)
			(xy 21.775189 -201.222164) (xy 21.82735 -201.2358) (xy 21.87697 -201.256887) (xy 21.922991 -201.284973)
			(xy 21.964433 -201.319461) (xy 22.000411 -201.359615) (xy 22.030159 -201.404579) (xy 22.053044 -201.453396)
			(xy 22.068576 -201.505025) (xy 22.076426 -201.558365) (xy 22.076918 -201.585322) (xy 24.782795 -201.585322)
			(xy 24.78673 -201.531551) (xy 24.798453 -201.478927) (xy 24.817713 -201.42857) (xy 24.844099 -201.381553)
			(xy 24.877051 -201.33888) (xy 24.915864 -201.301459) (xy 24.959712 -201.270089) (xy 25.00766 -201.245437)
			(xy 25.058687 -201.228029) (xy 25.111705 -201.218236) (xy 25.165584 -201.216267) (xy 25.219175 -201.222164)
			(xy 25.271336 -201.2358) (xy 25.320956 -201.256887) (xy 25.366977 -201.284973) (xy 25.408419 -201.319461)
			(xy 25.444397 -201.359615) (xy 25.474145 -201.404579) (xy 25.49703 -201.453396) (xy 25.512562 -201.505025)
			(xy 25.520412 -201.558365) (xy 25.520904 -201.585322) (xy 28.882863 -201.585322) (xy 28.886798 -201.531551)
			(xy 28.898521 -201.478927) (xy 28.917781 -201.42857) (xy 28.944167 -201.381553) (xy 28.977119 -201.33888)
			(xy 29.015932 -201.301459) (xy 29.05978 -201.270089) (xy 29.107728 -201.245437) (xy 29.158755 -201.228029)
			(xy 29.211773 -201.218236) (xy 29.265652 -201.216267) (xy 29.319243 -201.222164) (xy 29.371404 -201.2358)
			(xy 29.421024 -201.256887) (xy 29.467045 -201.284973) (xy 29.508487 -201.319461) (xy 29.544465 -201.359615)
			(xy 29.574213 -201.404579) (xy 29.597098 -201.453396) (xy 29.61263 -201.505025) (xy 29.62048 -201.558365)
			(xy 29.620972 -201.585322) (xy 32.326595 -201.585322) (xy 32.33053 -201.531551) (xy 32.342253 -201.478927)
			(xy 32.361513 -201.42857) (xy 32.387899 -201.381553) (xy 32.420851 -201.33888) (xy 32.459664 -201.301459)
			(xy 32.503512 -201.270089) (xy 32.55146 -201.245437) (xy 32.602487 -201.228029) (xy 32.655505 -201.218236)
			(xy 32.709384 -201.216267) (xy 32.762975 -201.222164) (xy 32.815136 -201.2358) (xy 32.864756 -201.256887)
			(xy 32.910777 -201.284973) (xy 32.952219 -201.319461) (xy 32.988197 -201.359615) (xy 33.017945 -201.404579)
			(xy 33.04083 -201.453396) (xy 33.056362 -201.505025) (xy 33.064212 -201.558365) (xy 33.064704 -201.585322)
			(xy 36.426663 -201.585322) (xy 36.430598 -201.531551) (xy 36.442321 -201.478927) (xy 36.461581 -201.42857)
			(xy 36.487967 -201.381553) (xy 36.520919 -201.33888) (xy 36.559732 -201.301459) (xy 36.60358 -201.270089)
			(xy 36.651528 -201.245437) (xy 36.702555 -201.228029) (xy 36.755573 -201.218236) (xy 36.809452 -201.216267)
			(xy 36.863043 -201.222164) (xy 36.915204 -201.2358) (xy 36.964824 -201.256887) (xy 37.010845 -201.284973)
			(xy 37.052287 -201.319461) (xy 37.088265 -201.359615) (xy 37.118013 -201.404579) (xy 37.140898 -201.453396)
			(xy 37.15643 -201.505025) (xy 37.16428 -201.558365) (xy 37.164772 -201.585322) (xy 39.870649 -201.585322)
			(xy 39.874584 -201.531551) (xy 39.886307 -201.478927) (xy 39.905567 -201.42857) (xy 39.931953 -201.381553)
			(xy 39.964905 -201.33888) (xy 40.003718 -201.301459) (xy 40.047566 -201.270089) (xy 40.095514 -201.245437)
			(xy 40.146541 -201.228029) (xy 40.199559 -201.218236) (xy 40.253438 -201.216267) (xy 40.307029 -201.222164)
			(xy 40.35919 -201.2358) (xy 40.40881 -201.256887) (xy 40.454831 -201.284973) (xy 40.496273 -201.319461)
			(xy 40.532251 -201.359615) (xy 40.561999 -201.404579) (xy 40.584884 -201.453396) (xy 40.600416 -201.505025)
			(xy 40.608266 -201.558365) (xy 40.608758 -201.585322) (xy 43.970717 -201.585322) (xy 43.974652 -201.531551)
			(xy 43.986375 -201.478927) (xy 44.005635 -201.42857) (xy 44.032021 -201.381553) (xy 44.064973 -201.33888)
			(xy 44.103786 -201.301459) (xy 44.147634 -201.270089) (xy 44.195582 -201.245437) (xy 44.246609 -201.228029)
			(xy 44.299627 -201.218236) (xy 44.353506 -201.216267) (xy 44.407097 -201.222164) (xy 44.459258 -201.2358)
			(xy 44.508878 -201.256887) (xy 44.554899 -201.284973) (xy 44.596341 -201.319461) (xy 44.632319 -201.359615)
			(xy 44.662067 -201.404579) (xy 44.684952 -201.453396) (xy 44.700484 -201.505025) (xy 44.708334 -201.558365)
			(xy 44.708826 -201.585322) (xy 44.708334 -201.612279) (xy 44.700484 -201.665619) (xy 44.684952 -201.717248)
			(xy 44.662067 -201.766065) (xy 44.632319 -201.811029) (xy 44.596341 -201.851183) (xy 44.554899 -201.885671)
			(xy 44.508878 -201.913757) (xy 44.459258 -201.934844) (xy 44.407097 -201.94848) (xy 44.353506 -201.954377)
			(xy 44.299627 -201.952408) (xy 44.246609 -201.942615) (xy 44.195582 -201.925207) (xy 44.147634 -201.900555)
			(xy 44.103786 -201.869185) (xy 44.064973 -201.831764) (xy 44.032021 -201.789091) (xy 44.005635 -201.742074)
			(xy 43.986375 -201.691717) (xy 43.974652 -201.639093) (xy 43.970717 -201.585322) (xy 40.608758 -201.585322)
			(xy 40.608266 -201.612279) (xy 40.600416 -201.665619) (xy 40.584884 -201.717248) (xy 40.561999 -201.766065)
			(xy 40.532251 -201.811029) (xy 40.496273 -201.851183) (xy 40.454831 -201.885671) (xy 40.40881 -201.913757)
			(xy 40.35919 -201.934844) (xy 40.307029 -201.94848) (xy 40.253438 -201.954377) (xy 40.199559 -201.952408)
			(xy 40.146541 -201.942615) (xy 40.095514 -201.925207) (xy 40.047566 -201.900555) (xy 40.003718 -201.869185)
			(xy 39.964905 -201.831764) (xy 39.931953 -201.789091) (xy 39.905567 -201.742074) (xy 39.886307 -201.691717)
			(xy 39.874584 -201.639093) (xy 39.870649 -201.585322) (xy 37.164772 -201.585322) (xy 37.16428 -201.612279)
			(xy 37.15643 -201.665619) (xy 37.140898 -201.717248) (xy 37.118013 -201.766065) (xy 37.088265 -201.811029)
			(xy 37.052287 -201.851183) (xy 37.010845 -201.885671) (xy 36.964824 -201.913757) (xy 36.915204 -201.934844)
			(xy 36.863043 -201.94848) (xy 36.809452 -201.954377) (xy 36.755573 -201.952408) (xy 36.702555 -201.942615)
			(xy 36.651528 -201.925207) (xy 36.60358 -201.900555) (xy 36.559732 -201.869185) (xy 36.520919 -201.831764)
			(xy 36.487967 -201.789091) (xy 36.461581 -201.742074) (xy 36.442321 -201.691717) (xy 36.430598 -201.639093)
			(xy 36.426663 -201.585322) (xy 33.064704 -201.585322) (xy 33.064212 -201.612279) (xy 33.056362 -201.665619)
			(xy 33.04083 -201.717248) (xy 33.017945 -201.766065) (xy 32.988197 -201.811029) (xy 32.952219 -201.851183)
			(xy 32.910777 -201.885671) (xy 32.864756 -201.913757) (xy 32.815136 -201.934844) (xy 32.762975 -201.94848)
			(xy 32.709384 -201.954377) (xy 32.655505 -201.952408) (xy 32.602487 -201.942615) (xy 32.55146 -201.925207)
			(xy 32.503512 -201.900555) (xy 32.459664 -201.869185) (xy 32.420851 -201.831764) (xy 32.387899 -201.789091)
			(xy 32.361513 -201.742074) (xy 32.342253 -201.691717) (xy 32.33053 -201.639093) (xy 32.326595 -201.585322)
			(xy 29.620972 -201.585322) (xy 29.62048 -201.612279) (xy 29.61263 -201.665619) (xy 29.597098 -201.717248)
			(xy 29.574213 -201.766065) (xy 29.544465 -201.811029) (xy 29.508487 -201.851183) (xy 29.467045 -201.885671)
			(xy 29.421024 -201.913757) (xy 29.371404 -201.934844) (xy 29.319243 -201.94848) (xy 29.265652 -201.954377)
			(xy 29.211773 -201.952408) (xy 29.158755 -201.942615) (xy 29.107728 -201.925207) (xy 29.05978 -201.900555)
			(xy 29.015932 -201.869185) (xy 28.977119 -201.831764) (xy 28.944167 -201.789091) (xy 28.917781 -201.742074)
			(xy 28.898521 -201.691717) (xy 28.886798 -201.639093) (xy 28.882863 -201.585322) (xy 25.520904 -201.585322)
			(xy 25.520412 -201.612279) (xy 25.512562 -201.665619) (xy 25.49703 -201.717248) (xy 25.474145 -201.766065)
			(xy 25.444397 -201.811029) (xy 25.408419 -201.851183) (xy 25.366977 -201.885671) (xy 25.320956 -201.913757)
			(xy 25.271336 -201.934844) (xy 25.219175 -201.94848) (xy 25.165584 -201.954377) (xy 25.111705 -201.952408)
			(xy 25.058687 -201.942615) (xy 25.00766 -201.925207) (xy 24.959712 -201.900555) (xy 24.915864 -201.869185)
			(xy 24.877051 -201.831764) (xy 24.844099 -201.789091) (xy 24.817713 -201.742074) (xy 24.798453 -201.691717)
			(xy 24.78673 -201.639093) (xy 24.782795 -201.585322) (xy 22.076918 -201.585322) (xy 22.076426 -201.612279)
			(xy 22.068576 -201.665619) (xy 22.053044 -201.717248) (xy 22.030159 -201.766065) (xy 22.000411 -201.811029)
			(xy 21.964433 -201.851183) (xy 21.922991 -201.885671) (xy 21.87697 -201.913757) (xy 21.82735 -201.934844)
			(xy 21.775189 -201.94848) (xy 21.721598 -201.954377) (xy 21.667719 -201.952408) (xy 21.614701 -201.942615)
			(xy 21.563674 -201.925207) (xy 21.515726 -201.900555) (xy 21.471878 -201.869185) (xy 21.433065 -201.831764)
			(xy 21.400113 -201.789091) (xy 21.373727 -201.742074) (xy 21.354467 -201.691717) (xy 21.342744 -201.639093)
			(xy 21.338809 -201.585322) (xy 17.97685 -201.585322) (xy 17.976358 -201.612279) (xy 17.968508 -201.665619)
			(xy 17.952976 -201.717248) (xy 17.930091 -201.766065) (xy 17.900343 -201.811029) (xy 17.864365 -201.851183)
			(xy 17.822923 -201.885671) (xy 17.776902 -201.913757) (xy 17.727282 -201.934844) (xy 17.675121 -201.94848)
			(xy 17.62153 -201.954377) (xy 17.567651 -201.952408) (xy 17.514633 -201.942615) (xy 17.463606 -201.925207)
			(xy 17.415658 -201.900555) (xy 17.37181 -201.869185) (xy 17.332997 -201.831764) (xy 17.300045 -201.789091)
			(xy 17.273659 -201.742074) (xy 17.254399 -201.691717) (xy 17.242676 -201.639093) (xy 17.238741 -201.585322)
			(xy 16.071088 -201.585322) (xy 15.61338 -202.04303) (xy 15.60653 -202.050426) (xy 15.598793 -202.069025)
			(xy 15.598394 -202.079098) (xy 15.598394 -202.435206) (xy 17.238741 -202.435206) (xy 17.242676 -202.381435)
			(xy 17.254399 -202.328811) (xy 17.273659 -202.278454) (xy 17.300045 -202.231437) (xy 17.332997 -202.188764)
			(xy 17.37181 -202.151343) (xy 17.415658 -202.119973) (xy 17.463606 -202.095321) (xy 17.514633 -202.077913)
			(xy 17.567651 -202.06812) (xy 17.62153 -202.066151) (xy 17.675121 -202.072048) (xy 17.727282 -202.085684)
			(xy 17.776902 -202.106771) (xy 17.822923 -202.134857) (xy 17.864365 -202.169345) (xy 17.900343 -202.209499)
			(xy 17.930091 -202.254463) (xy 17.952976 -202.30328) (xy 17.968508 -202.354909) (xy 17.976358 -202.408249)
			(xy 17.97685 -202.435206) (xy 24.782795 -202.435206) (xy 24.78673 -202.381435) (xy 24.798453 -202.328811)
			(xy 24.817713 -202.278454) (xy 24.844099 -202.231437) (xy 24.877051 -202.188764) (xy 24.915864 -202.151343)
			(xy 24.959712 -202.119973) (xy 25.00766 -202.095321) (xy 25.058687 -202.077913) (xy 25.111705 -202.06812)
			(xy 25.165584 -202.066151) (xy 25.219175 -202.072048) (xy 25.271336 -202.085684) (xy 25.320956 -202.106771)
			(xy 25.366977 -202.134857) (xy 25.408419 -202.169345) (xy 25.444397 -202.209499) (xy 25.474145 -202.254463)
			(xy 25.49703 -202.30328) (xy 25.512562 -202.354909) (xy 25.520412 -202.408249) (xy 25.520904 -202.435206)
			(xy 32.326595 -202.435206) (xy 32.33053 -202.381435) (xy 32.342253 -202.328811) (xy 32.361513 -202.278454)
			(xy 32.387899 -202.231437) (xy 32.420851 -202.188764) (xy 32.459664 -202.151343) (xy 32.503512 -202.119973)
			(xy 32.55146 -202.095321) (xy 32.602487 -202.077913) (xy 32.655505 -202.06812) (xy 32.709384 -202.066151)
			(xy 32.762975 -202.072048) (xy 32.815136 -202.085684) (xy 32.864756 -202.106771) (xy 32.910777 -202.134857)
			(xy 32.952219 -202.169345) (xy 32.988197 -202.209499) (xy 33.017945 -202.254463) (xy 33.04083 -202.30328)
			(xy 33.056362 -202.354909) (xy 33.064212 -202.408249) (xy 33.064704 -202.435206) (xy 39.870649 -202.435206)
			(xy 39.874584 -202.381435) (xy 39.886307 -202.328811) (xy 39.905567 -202.278454) (xy 39.931953 -202.231437)
			(xy 39.964905 -202.188764) (xy 40.003718 -202.151343) (xy 40.047566 -202.119973) (xy 40.095514 -202.095321)
			(xy 40.146541 -202.077913) (xy 40.199559 -202.06812) (xy 40.253438 -202.066151) (xy 40.307029 -202.072048)
			(xy 40.35919 -202.085684) (xy 40.40881 -202.106771) (xy 40.454831 -202.134857) (xy 40.496273 -202.169345)
			(xy 40.532251 -202.209499) (xy 40.561999 -202.254463) (xy 40.584884 -202.30328) (xy 40.600416 -202.354909)
			(xy 40.608266 -202.408249) (xy 40.608758 -202.435206) (xy 40.608266 -202.462163) (xy 40.600416 -202.515503)
			(xy 40.584884 -202.567132) (xy 40.561999 -202.615949) (xy 40.532251 -202.660913) (xy 40.496273 -202.701067)
			(xy 40.454831 -202.735555) (xy 40.40881 -202.763641) (xy 40.35919 -202.784728) (xy 40.307029 -202.798364)
			(xy 40.253438 -202.804261) (xy 40.199559 -202.802292) (xy 40.146541 -202.792499) (xy 40.095514 -202.775091)
			(xy 40.047566 -202.750439) (xy 40.003718 -202.719069) (xy 39.964905 -202.681648) (xy 39.931953 -202.638975)
			(xy 39.905567 -202.591958) (xy 39.886307 -202.541601) (xy 39.874584 -202.488977) (xy 39.870649 -202.435206)
			(xy 33.064704 -202.435206) (xy 33.064212 -202.462163) (xy 33.056362 -202.515503) (xy 33.04083 -202.567132)
			(xy 33.017945 -202.615949) (xy 32.988197 -202.660913) (xy 32.952219 -202.701067) (xy 32.910777 -202.735555)
			(xy 32.864756 -202.763641) (xy 32.815136 -202.784728) (xy 32.762975 -202.798364) (xy 32.709384 -202.804261)
			(xy 32.655505 -202.802292) (xy 32.602487 -202.792499) (xy 32.55146 -202.775091) (xy 32.503512 -202.750439)
			(xy 32.459664 -202.719069) (xy 32.420851 -202.681648) (xy 32.387899 -202.638975) (xy 32.361513 -202.591958)
			(xy 32.342253 -202.541601) (xy 32.33053 -202.488977) (xy 32.326595 -202.435206) (xy 25.520904 -202.435206)
			(xy 25.520412 -202.462163) (xy 25.512562 -202.515503) (xy 25.49703 -202.567132) (xy 25.474145 -202.615949)
			(xy 25.444397 -202.660913) (xy 25.408419 -202.701067) (xy 25.366977 -202.735555) (xy 25.320956 -202.763641)
			(xy 25.271336 -202.784728) (xy 25.219175 -202.798364) (xy 25.165584 -202.804261) (xy 25.111705 -202.802292)
			(xy 25.058687 -202.792499) (xy 25.00766 -202.775091) (xy 24.959712 -202.750439) (xy 24.915864 -202.719069)
			(xy 24.877051 -202.681648) (xy 24.844099 -202.638975) (xy 24.817713 -202.591958) (xy 24.798453 -202.541601)
			(xy 24.78673 -202.488977) (xy 24.782795 -202.435206) (xy 17.97685 -202.435206) (xy 17.976358 -202.462163)
			(xy 17.968508 -202.515503) (xy 17.952976 -202.567132) (xy 17.930091 -202.615949) (xy 17.900343 -202.660913)
			(xy 17.864365 -202.701067) (xy 17.822923 -202.735555) (xy 17.776902 -202.763641) (xy 17.727282 -202.784728)
			(xy 17.675121 -202.798364) (xy 17.62153 -202.804261) (xy 17.567651 -202.802292) (xy 17.514633 -202.792499)
			(xy 17.463606 -202.775091) (xy 17.415658 -202.750439) (xy 17.37181 -202.719069) (xy 17.332997 -202.681648)
			(xy 17.300045 -202.638975) (xy 17.273659 -202.591958) (xy 17.254399 -202.541601) (xy 17.242676 -202.488977)
			(xy 17.238741 -202.435206) (xy 15.598394 -202.435206) (xy 15.598394 -203.285344) (xy 21.338809 -203.285344)
			(xy 21.342744 -203.231573) (xy 21.354467 -203.178949) (xy 21.373727 -203.128592) (xy 21.400113 -203.081575)
			(xy 21.433065 -203.038902) (xy 21.471878 -203.001481) (xy 21.515726 -202.970111) (xy 21.563674 -202.945459)
			(xy 21.614701 -202.928051) (xy 21.667719 -202.918258) (xy 21.721598 -202.916289) (xy 21.775189 -202.922186)
			(xy 21.82735 -202.935822) (xy 21.87697 -202.956909) (xy 21.922991 -202.984995) (xy 21.964433 -203.019483)
			(xy 22.000411 -203.059637) (xy 22.030159 -203.104601) (xy 22.053044 -203.153418) (xy 22.068576 -203.205047)
			(xy 22.076426 -203.258387) (xy 22.076918 -203.285344) (xy 28.882863 -203.285344) (xy 28.886798 -203.231573)
			(xy 28.898521 -203.178949) (xy 28.917781 -203.128592) (xy 28.944167 -203.081575) (xy 28.977119 -203.038902)
			(xy 29.015932 -203.001481) (xy 29.05978 -202.970111) (xy 29.107728 -202.945459) (xy 29.158755 -202.928051)
			(xy 29.211773 -202.918258) (xy 29.265652 -202.916289) (xy 29.319243 -202.922186) (xy 29.371404 -202.935822)
			(xy 29.421024 -202.956909) (xy 29.467045 -202.984995) (xy 29.508487 -203.019483) (xy 29.544465 -203.059637)
			(xy 29.574213 -203.104601) (xy 29.597098 -203.153418) (xy 29.61263 -203.205047) (xy 29.62048 -203.258387)
			(xy 29.620972 -203.285344) (xy 36.426663 -203.285344) (xy 36.430598 -203.231573) (xy 36.442321 -203.178949)
			(xy 36.461581 -203.128592) (xy 36.487967 -203.081575) (xy 36.520919 -203.038902) (xy 36.559732 -203.001481)
			(xy 36.60358 -202.970111) (xy 36.651528 -202.945459) (xy 36.702555 -202.928051) (xy 36.755573 -202.918258)
			(xy 36.809452 -202.916289) (xy 36.863043 -202.922186) (xy 36.915204 -202.935822) (xy 36.964824 -202.956909)
			(xy 37.010845 -202.984995) (xy 37.052287 -203.019483) (xy 37.088265 -203.059637) (xy 37.118013 -203.104601)
			(xy 37.140898 -203.153418) (xy 37.15643 -203.205047) (xy 37.16428 -203.258387) (xy 37.164772 -203.285344)
			(xy 43.970717 -203.285344) (xy 43.974652 -203.231573) (xy 43.986375 -203.178949) (xy 44.005635 -203.128592)
			(xy 44.032021 -203.081575) (xy 44.064973 -203.038902) (xy 44.103786 -203.001481) (xy 44.147634 -202.970111)
			(xy 44.195582 -202.945459) (xy 44.246609 -202.928051) (xy 44.299627 -202.918258) (xy 44.353506 -202.916289)
			(xy 44.407097 -202.922186) (xy 44.459258 -202.935822) (xy 44.508878 -202.956909) (xy 44.554899 -202.984995)
			(xy 44.596341 -203.019483) (xy 44.632319 -203.059637) (xy 44.662067 -203.104601) (xy 44.684952 -203.153418)
			(xy 44.700484 -203.205047) (xy 44.708334 -203.258387) (xy 44.708826 -203.285344) (xy 44.708334 -203.312301)
			(xy 44.700484 -203.365641) (xy 44.684952 -203.41727) (xy 44.662067 -203.466087) (xy 44.632319 -203.511051)
			(xy 44.596341 -203.551205) (xy 44.554899 -203.585693) (xy 44.508878 -203.613779) (xy 44.459258 -203.634866)
			(xy 44.407097 -203.648502) (xy 44.353506 -203.654399) (xy 44.299627 -203.65243) (xy 44.246609 -203.642637)
			(xy 44.195582 -203.625229) (xy 44.147634 -203.600577) (xy 44.103786 -203.569207) (xy 44.064973 -203.531786)
			(xy 44.032021 -203.489113) (xy 44.005635 -203.442096) (xy 43.986375 -203.391739) (xy 43.974652 -203.339115)
			(xy 43.970717 -203.285344) (xy 37.164772 -203.285344) (xy 37.16428 -203.312301) (xy 37.15643 -203.365641)
			(xy 37.140898 -203.41727) (xy 37.118013 -203.466087) (xy 37.088265 -203.511051) (xy 37.052287 -203.551205)
			(xy 37.010845 -203.585693) (xy 36.964824 -203.613779) (xy 36.915204 -203.634866) (xy 36.863043 -203.648502)
			(xy 36.809452 -203.654399) (xy 36.755573 -203.65243) (xy 36.702555 -203.642637) (xy 36.651528 -203.625229)
			(xy 36.60358 -203.600577) (xy 36.559732 -203.569207) (xy 36.520919 -203.531786) (xy 36.487967 -203.489113)
			(xy 36.461581 -203.442096) (xy 36.442321 -203.391739) (xy 36.430598 -203.339115) (xy 36.426663 -203.285344)
			(xy 29.620972 -203.285344) (xy 29.62048 -203.312301) (xy 29.61263 -203.365641) (xy 29.597098 -203.41727)
			(xy 29.574213 -203.466087) (xy 29.544465 -203.511051) (xy 29.508487 -203.551205) (xy 29.467045 -203.585693)
			(xy 29.421024 -203.613779) (xy 29.371404 -203.634866) (xy 29.319243 -203.648502) (xy 29.265652 -203.654399)
			(xy 29.211773 -203.65243) (xy 29.158755 -203.642637) (xy 29.107728 -203.625229) (xy 29.05978 -203.600577)
			(xy 29.015932 -203.569207) (xy 28.977119 -203.531786) (xy 28.944167 -203.489113) (xy 28.917781 -203.442096)
			(xy 28.898521 -203.391739) (xy 28.886798 -203.339115) (xy 28.882863 -203.285344) (xy 22.076918 -203.285344)
			(xy 22.076426 -203.312301) (xy 22.068576 -203.365641) (xy 22.053044 -203.41727) (xy 22.030159 -203.466087)
			(xy 22.000411 -203.511051) (xy 21.964433 -203.551205) (xy 21.922991 -203.585693) (xy 21.87697 -203.613779)
			(xy 21.82735 -203.634866) (xy 21.775189 -203.648502) (xy 21.721598 -203.654399) (xy 21.667719 -203.65243)
			(xy 21.614701 -203.642637) (xy 21.563674 -203.625229) (xy 21.515726 -203.600577) (xy 21.471878 -203.569207)
			(xy 21.433065 -203.531786) (xy 21.400113 -203.489113) (xy 21.373727 -203.442096) (xy 21.354467 -203.391739)
			(xy 21.342744 -203.339115) (xy 21.338809 -203.285344) (xy 15.598394 -203.285344) (xy 15.598394 -204.135228)
			(xy 17.238741 -204.135228) (xy 17.242676 -204.081457) (xy 17.254399 -204.028833) (xy 17.273659 -203.978476)
			(xy 17.300045 -203.931459) (xy 17.332997 -203.888786) (xy 17.37181 -203.851365) (xy 17.415658 -203.819995)
			(xy 17.463606 -203.795343) (xy 17.514633 -203.777935) (xy 17.567651 -203.768142) (xy 17.62153 -203.766173)
			(xy 17.675121 -203.77207) (xy 17.727282 -203.785706) (xy 17.776902 -203.806793) (xy 17.822923 -203.834879)
			(xy 17.864365 -203.869367) (xy 17.900343 -203.909521) (xy 17.930091 -203.954485) (xy 17.952976 -204.003302)
			(xy 17.968508 -204.054931) (xy 17.976358 -204.108271) (xy 17.97685 -204.135228) (xy 24.782795 -204.135228)
			(xy 24.78673 -204.081457) (xy 24.798453 -204.028833) (xy 24.817713 -203.978476) (xy 24.844099 -203.931459)
			(xy 24.877051 -203.888786) (xy 24.915864 -203.851365) (xy 24.959712 -203.819995) (xy 25.00766 -203.795343)
			(xy 25.058687 -203.777935) (xy 25.111705 -203.768142) (xy 25.165584 -203.766173) (xy 25.219175 -203.77207)
			(xy 25.271336 -203.785706) (xy 25.320956 -203.806793) (xy 25.366977 -203.834879) (xy 25.408419 -203.869367)
			(xy 25.444397 -203.909521) (xy 25.474145 -203.954485) (xy 25.49703 -204.003302) (xy 25.512562 -204.054931)
			(xy 25.520412 -204.108271) (xy 25.520904 -204.135228) (xy 32.326595 -204.135228) (xy 32.33053 -204.081457)
			(xy 32.342253 -204.028833) (xy 32.361513 -203.978476) (xy 32.387899 -203.931459) (xy 32.420851 -203.888786)
			(xy 32.459664 -203.851365) (xy 32.503512 -203.819995) (xy 32.55146 -203.795343) (xy 32.602487 -203.777935)
			(xy 32.655505 -203.768142) (xy 32.709384 -203.766173) (xy 32.762975 -203.77207) (xy 32.815136 -203.785706)
			(xy 32.864756 -203.806793) (xy 32.910777 -203.834879) (xy 32.952219 -203.869367) (xy 32.988197 -203.909521)
			(xy 33.017945 -203.954485) (xy 33.04083 -204.003302) (xy 33.056362 -204.054931) (xy 33.064212 -204.108271)
			(xy 33.064704 -204.135228) (xy 39.870649 -204.135228) (xy 39.874584 -204.081457) (xy 39.886307 -204.028833)
			(xy 39.905567 -203.978476) (xy 39.931953 -203.931459) (xy 39.964905 -203.888786) (xy 40.003718 -203.851365)
			(xy 40.047566 -203.819995) (xy 40.095514 -203.795343) (xy 40.146541 -203.777935) (xy 40.199559 -203.768142)
			(xy 40.253438 -203.766173) (xy 40.307029 -203.77207) (xy 40.35919 -203.785706) (xy 40.40881 -203.806793)
			(xy 40.454831 -203.834879) (xy 40.496273 -203.869367) (xy 40.532251 -203.909521) (xy 40.561999 -203.954485)
			(xy 40.584884 -204.003302) (xy 40.600416 -204.054931) (xy 40.608266 -204.108271) (xy 40.608758 -204.135228)
			(xy 40.608266 -204.162185) (xy 40.600416 -204.215525) (xy 40.584884 -204.267154) (xy 40.561999 -204.315971)
			(xy 40.532251 -204.360935) (xy 40.496273 -204.401089) (xy 40.454831 -204.435577) (xy 40.40881 -204.463663)
			(xy 40.35919 -204.48475) (xy 40.307029 -204.498386) (xy 40.253438 -204.504283) (xy 40.199559 -204.502314)
			(xy 40.146541 -204.492521) (xy 40.095514 -204.475113) (xy 40.047566 -204.450461) (xy 40.003718 -204.419091)
			(xy 39.964905 -204.38167) (xy 39.931953 -204.338997) (xy 39.905567 -204.29198) (xy 39.886307 -204.241623)
			(xy 39.874584 -204.188999) (xy 39.870649 -204.135228) (xy 33.064704 -204.135228) (xy 33.064212 -204.162185)
			(xy 33.056362 -204.215525) (xy 33.04083 -204.267154) (xy 33.017945 -204.315971) (xy 32.988197 -204.360935)
			(xy 32.952219 -204.401089) (xy 32.910777 -204.435577) (xy 32.864756 -204.463663) (xy 32.815136 -204.48475)
			(xy 32.762975 -204.498386) (xy 32.709384 -204.504283) (xy 32.655505 -204.502314) (xy 32.602487 -204.492521)
			(xy 32.55146 -204.475113) (xy 32.503512 -204.450461) (xy 32.459664 -204.419091) (xy 32.420851 -204.38167)
			(xy 32.387899 -204.338997) (xy 32.361513 -204.29198) (xy 32.342253 -204.241623) (xy 32.33053 -204.188999)
			(xy 32.326595 -204.135228) (xy 25.520904 -204.135228) (xy 25.520412 -204.162185) (xy 25.512562 -204.215525)
			(xy 25.49703 -204.267154) (xy 25.474145 -204.315971) (xy 25.444397 -204.360935) (xy 25.408419 -204.401089)
			(xy 25.366977 -204.435577) (xy 25.320956 -204.463663) (xy 25.271336 -204.48475) (xy 25.219175 -204.498386)
			(xy 25.165584 -204.504283) (xy 25.111705 -204.502314) (xy 25.058687 -204.492521) (xy 25.00766 -204.475113)
			(xy 24.959712 -204.450461) (xy 24.915864 -204.419091) (xy 24.877051 -204.38167) (xy 24.844099 -204.338997)
			(xy 24.817713 -204.29198) (xy 24.798453 -204.241623) (xy 24.78673 -204.188999) (xy 24.782795 -204.135228)
			(xy 17.97685 -204.135228) (xy 17.976358 -204.162185) (xy 17.968508 -204.215525) (xy 17.952976 -204.267154)
			(xy 17.930091 -204.315971) (xy 17.900343 -204.360935) (xy 17.864365 -204.401089) (xy 17.822923 -204.435577)
			(xy 17.776902 -204.463663) (xy 17.727282 -204.48475) (xy 17.675121 -204.498386) (xy 17.62153 -204.504283)
			(xy 17.567651 -204.502314) (xy 17.514633 -204.492521) (xy 17.463606 -204.475113) (xy 17.415658 -204.450461)
			(xy 17.37181 -204.419091) (xy 17.332997 -204.38167) (xy 17.300045 -204.338997) (xy 17.273659 -204.29198)
			(xy 17.254399 -204.241623) (xy 17.242676 -204.188999) (xy 17.238741 -204.135228) (xy 15.598394 -204.135228)
			(xy 15.598394 -204.985366) (xy 21.338809 -204.985366) (xy 21.342744 -204.931595) (xy 21.354467 -204.878971)
			(xy 21.373727 -204.828614) (xy 21.400113 -204.781597) (xy 21.433065 -204.738924) (xy 21.471878 -204.701503)
			(xy 21.515726 -204.670133) (xy 21.563674 -204.645481) (xy 21.614701 -204.628073) (xy 21.667719 -204.61828)
			(xy 21.721598 -204.616311) (xy 21.775189 -204.622208) (xy 21.82735 -204.635844) (xy 21.87697 -204.656931)
			(xy 21.922991 -204.685017) (xy 21.964433 -204.719505) (xy 22.000411 -204.759659) (xy 22.030159 -204.804623)
			(xy 22.053044 -204.85344) (xy 22.068576 -204.905069) (xy 22.076426 -204.958409) (xy 22.076918 -204.985366)
			(xy 28.882863 -204.985366) (xy 28.886798 -204.931595) (xy 28.898521 -204.878971) (xy 28.917781 -204.828614)
			(xy 28.944167 -204.781597) (xy 28.977119 -204.738924) (xy 29.015932 -204.701503) (xy 29.05978 -204.670133)
			(xy 29.107728 -204.645481) (xy 29.158755 -204.628073) (xy 29.211773 -204.61828) (xy 29.265652 -204.616311)
			(xy 29.319243 -204.622208) (xy 29.371404 -204.635844) (xy 29.421024 -204.656931) (xy 29.467045 -204.685017)
			(xy 29.508487 -204.719505) (xy 29.544465 -204.759659) (xy 29.574213 -204.804623) (xy 29.597098 -204.85344)
			(xy 29.61263 -204.905069) (xy 29.62048 -204.958409) (xy 29.620972 -204.985366) (xy 36.426663 -204.985366)
			(xy 36.430598 -204.931595) (xy 36.442321 -204.878971) (xy 36.461581 -204.828614) (xy 36.487967 -204.781597)
			(xy 36.520919 -204.738924) (xy 36.559732 -204.701503) (xy 36.60358 -204.670133) (xy 36.651528 -204.645481)
			(xy 36.702555 -204.628073) (xy 36.755573 -204.61828) (xy 36.809452 -204.616311) (xy 36.863043 -204.622208)
			(xy 36.915204 -204.635844) (xy 36.964824 -204.656931) (xy 37.010845 -204.685017) (xy 37.052287 -204.719505)
			(xy 37.088265 -204.759659) (xy 37.118013 -204.804623) (xy 37.140898 -204.85344) (xy 37.15643 -204.905069)
			(xy 37.16428 -204.958409) (xy 37.164772 -204.985366) (xy 43.970717 -204.985366) (xy 43.974652 -204.931595)
			(xy 43.986375 -204.878971) (xy 44.005635 -204.828614) (xy 44.032021 -204.781597) (xy 44.064973 -204.738924)
			(xy 44.103786 -204.701503) (xy 44.147634 -204.670133) (xy 44.195582 -204.645481) (xy 44.246609 -204.628073)
			(xy 44.299627 -204.61828) (xy 44.353506 -204.616311) (xy 44.407097 -204.622208) (xy 44.459258 -204.635844)
			(xy 44.508878 -204.656931) (xy 44.554899 -204.685017) (xy 44.596341 -204.719505) (xy 44.632319 -204.759659)
			(xy 44.662067 -204.804623) (xy 44.684952 -204.85344) (xy 44.700484 -204.905069) (xy 44.708334 -204.958409)
			(xy 44.708826 -204.985366) (xy 44.708334 -205.012323) (xy 44.700484 -205.065663) (xy 44.684952 -205.117292)
			(xy 44.662067 -205.166109) (xy 44.632319 -205.211073) (xy 44.596341 -205.251227) (xy 44.554899 -205.285715)
			(xy 44.508878 -205.313801) (xy 44.459258 -205.334888) (xy 44.407097 -205.348524) (xy 44.353506 -205.354421)
			(xy 44.299627 -205.352452) (xy 44.246609 -205.342659) (xy 44.195582 -205.325251) (xy 44.147634 -205.300599)
			(xy 44.103786 -205.269229) (xy 44.064973 -205.231808) (xy 44.032021 -205.189135) (xy 44.005635 -205.142118)
			(xy 43.986375 -205.091761) (xy 43.974652 -205.039137) (xy 43.970717 -204.985366) (xy 37.164772 -204.985366)
			(xy 37.16428 -205.012323) (xy 37.15643 -205.065663) (xy 37.140898 -205.117292) (xy 37.118013 -205.166109)
			(xy 37.088265 -205.211073) (xy 37.052287 -205.251227) (xy 37.010845 -205.285715) (xy 36.964824 -205.313801)
			(xy 36.915204 -205.334888) (xy 36.863043 -205.348524) (xy 36.809452 -205.354421) (xy 36.755573 -205.352452)
			(xy 36.702555 -205.342659) (xy 36.651528 -205.325251) (xy 36.60358 -205.300599) (xy 36.559732 -205.269229)
			(xy 36.520919 -205.231808) (xy 36.487967 -205.189135) (xy 36.461581 -205.142118) (xy 36.442321 -205.091761)
			(xy 36.430598 -205.039137) (xy 36.426663 -204.985366) (xy 29.620972 -204.985366) (xy 29.62048 -205.012323)
			(xy 29.61263 -205.065663) (xy 29.597098 -205.117292) (xy 29.574213 -205.166109) (xy 29.544465 -205.211073)
			(xy 29.508487 -205.251227) (xy 29.467045 -205.285715) (xy 29.421024 -205.313801) (xy 29.371404 -205.334888)
			(xy 29.319243 -205.348524) (xy 29.265652 -205.354421) (xy 29.211773 -205.352452) (xy 29.158755 -205.342659)
			(xy 29.107728 -205.325251) (xy 29.05978 -205.300599) (xy 29.015932 -205.269229) (xy 28.977119 -205.231808)
			(xy 28.944167 -205.189135) (xy 28.917781 -205.142118) (xy 28.898521 -205.091761) (xy 28.886798 -205.039137)
			(xy 28.882863 -204.985366) (xy 22.076918 -204.985366) (xy 22.076426 -205.012323) (xy 22.068576 -205.065663)
			(xy 22.053044 -205.117292) (xy 22.030159 -205.166109) (xy 22.000411 -205.211073) (xy 21.964433 -205.251227)
			(xy 21.922991 -205.285715) (xy 21.87697 -205.313801) (xy 21.82735 -205.334888) (xy 21.775189 -205.348524)
			(xy 21.721598 -205.354421) (xy 21.667719 -205.352452) (xy 21.614701 -205.342659) (xy 21.563674 -205.325251)
			(xy 21.515726 -205.300599) (xy 21.471878 -205.269229) (xy 21.433065 -205.231808) (xy 21.400113 -205.189135)
			(xy 21.373727 -205.142118) (xy 21.354467 -205.091761) (xy 21.342744 -205.039137) (xy 21.338809 -204.985366)
			(xy 15.598394 -204.985366) (xy 15.598394 -205.83525) (xy 17.238741 -205.83525) (xy 17.242676 -205.781479)
			(xy 17.254399 -205.728855) (xy 17.273659 -205.678498) (xy 17.300045 -205.631481) (xy 17.332997 -205.588808)
			(xy 17.37181 -205.551387) (xy 17.415658 -205.520017) (xy 17.463606 -205.495365) (xy 17.514633 -205.477957)
			(xy 17.567651 -205.468164) (xy 17.62153 -205.466195) (xy 17.675121 -205.472092) (xy 17.727282 -205.485728)
			(xy 17.776902 -205.506815) (xy 17.822923 -205.534901) (xy 17.864365 -205.569389) (xy 17.900343 -205.609543)
			(xy 17.930091 -205.654507) (xy 17.952976 -205.703324) (xy 17.968508 -205.754953) (xy 17.976358 -205.808293)
			(xy 17.97685 -205.83525) (xy 24.782795 -205.83525) (xy 24.78673 -205.781479) (xy 24.798453 -205.728855)
			(xy 24.817713 -205.678498) (xy 24.844099 -205.631481) (xy 24.877051 -205.588808) (xy 24.915864 -205.551387)
			(xy 24.959712 -205.520017) (xy 25.00766 -205.495365) (xy 25.058687 -205.477957) (xy 25.111705 -205.468164)
			(xy 25.165584 -205.466195) (xy 25.219175 -205.472092) (xy 25.271336 -205.485728) (xy 25.320956 -205.506815)
			(xy 25.366977 -205.534901) (xy 25.408419 -205.569389) (xy 25.444397 -205.609543) (xy 25.474145 -205.654507)
			(xy 25.49703 -205.703324) (xy 25.512562 -205.754953) (xy 25.520412 -205.808293) (xy 25.520904 -205.83525)
			(xy 32.326595 -205.83525) (xy 32.33053 -205.781479) (xy 32.342253 -205.728855) (xy 32.361513 -205.678498)
			(xy 32.387899 -205.631481) (xy 32.420851 -205.588808) (xy 32.459664 -205.551387) (xy 32.503512 -205.520017)
			(xy 32.55146 -205.495365) (xy 32.602487 -205.477957) (xy 32.655505 -205.468164) (xy 32.709384 -205.466195)
			(xy 32.762975 -205.472092) (xy 32.815136 -205.485728) (xy 32.864756 -205.506815) (xy 32.910777 -205.534901)
			(xy 32.952219 -205.569389) (xy 32.988197 -205.609543) (xy 33.017945 -205.654507) (xy 33.04083 -205.703324)
			(xy 33.056362 -205.754953) (xy 33.064212 -205.808293) (xy 33.064704 -205.83525) (xy 39.870649 -205.83525)
			(xy 39.874584 -205.781479) (xy 39.886307 -205.728855) (xy 39.905567 -205.678498) (xy 39.931953 -205.631481)
			(xy 39.964905 -205.588808) (xy 40.003718 -205.551387) (xy 40.047566 -205.520017) (xy 40.095514 -205.495365)
			(xy 40.146541 -205.477957) (xy 40.199559 -205.468164) (xy 40.253438 -205.466195) (xy 40.307029 -205.472092)
			(xy 40.35919 -205.485728) (xy 40.40881 -205.506815) (xy 40.454831 -205.534901) (xy 40.496273 -205.569389)
			(xy 40.532251 -205.609543) (xy 40.561999 -205.654507) (xy 40.584884 -205.703324) (xy 40.600416 -205.754953)
			(xy 40.608266 -205.808293) (xy 40.608758 -205.83525) (xy 40.608266 -205.862207) (xy 40.600416 -205.915547)
			(xy 40.584884 -205.967176) (xy 40.561999 -206.015993) (xy 40.532251 -206.060957) (xy 40.496273 -206.101111)
			(xy 40.454831 -206.135599) (xy 40.40881 -206.163685) (xy 40.35919 -206.184772) (xy 40.307029 -206.198408)
			(xy 40.253438 -206.204305) (xy 40.199559 -206.202336) (xy 40.146541 -206.192543) (xy 40.095514 -206.175135)
			(xy 40.047566 -206.150483) (xy 40.003718 -206.119113) (xy 39.964905 -206.081692) (xy 39.931953 -206.039019)
			(xy 39.905567 -205.992002) (xy 39.886307 -205.941645) (xy 39.874584 -205.889021) (xy 39.870649 -205.83525)
			(xy 33.064704 -205.83525) (xy 33.064212 -205.862207) (xy 33.056362 -205.915547) (xy 33.04083 -205.967176)
			(xy 33.017945 -206.015993) (xy 32.988197 -206.060957) (xy 32.952219 -206.101111) (xy 32.910777 -206.135599)
			(xy 32.864756 -206.163685) (xy 32.815136 -206.184772) (xy 32.762975 -206.198408) (xy 32.709384 -206.204305)
			(xy 32.655505 -206.202336) (xy 32.602487 -206.192543) (xy 32.55146 -206.175135) (xy 32.503512 -206.150483)
			(xy 32.459664 -206.119113) (xy 32.420851 -206.081692) (xy 32.387899 -206.039019) (xy 32.361513 -205.992002)
			(xy 32.342253 -205.941645) (xy 32.33053 -205.889021) (xy 32.326595 -205.83525) (xy 25.520904 -205.83525)
			(xy 25.520412 -205.862207) (xy 25.512562 -205.915547) (xy 25.49703 -205.967176) (xy 25.474145 -206.015993)
			(xy 25.444397 -206.060957) (xy 25.408419 -206.101111) (xy 25.366977 -206.135599) (xy 25.320956 -206.163685)
			(xy 25.271336 -206.184772) (xy 25.219175 -206.198408) (xy 25.165584 -206.204305) (xy 25.111705 -206.202336)
			(xy 25.058687 -206.192543) (xy 25.00766 -206.175135) (xy 24.959712 -206.150483) (xy 24.915864 -206.119113)
			(xy 24.877051 -206.081692) (xy 24.844099 -206.039019) (xy 24.817713 -205.992002) (xy 24.798453 -205.941645)
			(xy 24.78673 -205.889021) (xy 24.782795 -205.83525) (xy 17.97685 -205.83525) (xy 17.976358 -205.862207)
			(xy 17.968508 -205.915547) (xy 17.952976 -205.967176) (xy 17.930091 -206.015993) (xy 17.900343 -206.060957)
			(xy 17.864365 -206.101111) (xy 17.822923 -206.135599) (xy 17.776902 -206.163685) (xy 17.727282 -206.184772)
			(xy 17.675121 -206.198408) (xy 17.62153 -206.204305) (xy 17.567651 -206.202336) (xy 17.514633 -206.192543)
			(xy 17.463606 -206.175135) (xy 17.415658 -206.150483) (xy 17.37181 -206.119113) (xy 17.332997 -206.081692)
			(xy 17.300045 -206.039019) (xy 17.273659 -205.992002) (xy 17.254399 -205.941645) (xy 17.242676 -205.889021)
			(xy 17.238741 -205.83525) (xy 15.598394 -205.83525) (xy 15.598394 -206.685388) (xy 21.338809 -206.685388)
			(xy 21.342744 -206.631617) (xy 21.354467 -206.578993) (xy 21.373727 -206.528636) (xy 21.400113 -206.481619)
			(xy 21.433065 -206.438946) (xy 21.471878 -206.401525) (xy 21.515726 -206.370155) (xy 21.563674 -206.345503)
			(xy 21.614701 -206.328095) (xy 21.667719 -206.318302) (xy 21.721598 -206.316333) (xy 21.775189 -206.32223)
			(xy 21.82735 -206.335866) (xy 21.87697 -206.356953) (xy 21.922991 -206.385039) (xy 21.964433 -206.419527)
			(xy 22.000411 -206.459681) (xy 22.030159 -206.504645) (xy 22.053044 -206.553462) (xy 22.068576 -206.605091)
			(xy 22.076426 -206.658431) (xy 22.076918 -206.685388) (xy 28.882863 -206.685388) (xy 28.886798 -206.631617)
			(xy 28.898521 -206.578993) (xy 28.917781 -206.528636) (xy 28.944167 -206.481619) (xy 28.977119 -206.438946)
			(xy 29.015932 -206.401525) (xy 29.05978 -206.370155) (xy 29.107728 -206.345503) (xy 29.158755 -206.328095)
			(xy 29.211773 -206.318302) (xy 29.265652 -206.316333) (xy 29.319243 -206.32223) (xy 29.371404 -206.335866)
			(xy 29.421024 -206.356953) (xy 29.467045 -206.385039) (xy 29.508487 -206.419527) (xy 29.544465 -206.459681)
			(xy 29.574213 -206.504645) (xy 29.597098 -206.553462) (xy 29.61263 -206.605091) (xy 29.62048 -206.658431)
			(xy 29.620972 -206.685388) (xy 36.426663 -206.685388) (xy 36.430598 -206.631617) (xy 36.442321 -206.578993)
			(xy 36.461581 -206.528636) (xy 36.487967 -206.481619) (xy 36.520919 -206.438946) (xy 36.559732 -206.401525)
			(xy 36.60358 -206.370155) (xy 36.651528 -206.345503) (xy 36.702555 -206.328095) (xy 36.755573 -206.318302)
			(xy 36.809452 -206.316333) (xy 36.863043 -206.32223) (xy 36.915204 -206.335866) (xy 36.964824 -206.356953)
			(xy 37.010845 -206.385039) (xy 37.052287 -206.419527) (xy 37.088265 -206.459681) (xy 37.118013 -206.504645)
			(xy 37.140898 -206.553462) (xy 37.15643 -206.605091) (xy 37.16428 -206.658431) (xy 37.164772 -206.685388)
			(xy 43.970717 -206.685388) (xy 43.974652 -206.631617) (xy 43.986375 -206.578993) (xy 44.005635 -206.528636)
			(xy 44.032021 -206.481619) (xy 44.064973 -206.438946) (xy 44.103786 -206.401525) (xy 44.147634 -206.370155)
			(xy 44.195582 -206.345503) (xy 44.246609 -206.328095) (xy 44.299627 -206.318302) (xy 44.353506 -206.316333)
			(xy 44.407097 -206.32223) (xy 44.459258 -206.335866) (xy 44.508878 -206.356953) (xy 44.554899 -206.385039)
			(xy 44.596341 -206.419527) (xy 44.632319 -206.459681) (xy 44.662067 -206.504645) (xy 44.684952 -206.553462)
			(xy 44.700484 -206.605091) (xy 44.708334 -206.658431) (xy 44.708826 -206.685388) (xy 44.708334 -206.712345)
			(xy 44.700484 -206.765685) (xy 44.684952 -206.817314) (xy 44.662067 -206.866131) (xy 44.632319 -206.911095)
			(xy 44.596341 -206.951249) (xy 44.554899 -206.985737) (xy 44.508878 -207.013823) (xy 44.459258 -207.03491)
			(xy 44.407097 -207.048546) (xy 44.353506 -207.054443) (xy 44.299627 -207.052474) (xy 44.246609 -207.042681)
			(xy 44.195582 -207.025273) (xy 44.147634 -207.000621) (xy 44.103786 -206.969251) (xy 44.064973 -206.93183)
			(xy 44.032021 -206.889157) (xy 44.005635 -206.84214) (xy 43.986375 -206.791783) (xy 43.974652 -206.739159)
			(xy 43.970717 -206.685388) (xy 37.164772 -206.685388) (xy 37.16428 -206.712345) (xy 37.15643 -206.765685)
			(xy 37.140898 -206.817314) (xy 37.118013 -206.866131) (xy 37.088265 -206.911095) (xy 37.052287 -206.951249)
			(xy 37.010845 -206.985737) (xy 36.964824 -207.013823) (xy 36.915204 -207.03491) (xy 36.863043 -207.048546)
			(xy 36.809452 -207.054443) (xy 36.755573 -207.052474) (xy 36.702555 -207.042681) (xy 36.651528 -207.025273)
			(xy 36.60358 -207.000621) (xy 36.559732 -206.969251) (xy 36.520919 -206.93183) (xy 36.487967 -206.889157)
			(xy 36.461581 -206.84214) (xy 36.442321 -206.791783) (xy 36.430598 -206.739159) (xy 36.426663 -206.685388)
			(xy 29.620972 -206.685388) (xy 29.62048 -206.712345) (xy 29.61263 -206.765685) (xy 29.597098 -206.817314)
			(xy 29.574213 -206.866131) (xy 29.544465 -206.911095) (xy 29.508487 -206.951249) (xy 29.467045 -206.985737)
			(xy 29.421024 -207.013823) (xy 29.371404 -207.03491) (xy 29.319243 -207.048546) (xy 29.265652 -207.054443)
			(xy 29.211773 -207.052474) (xy 29.158755 -207.042681) (xy 29.107728 -207.025273) (xy 29.05978 -207.000621)
			(xy 29.015932 -206.969251) (xy 28.977119 -206.93183) (xy 28.944167 -206.889157) (xy 28.917781 -206.84214)
			(xy 28.898521 -206.791783) (xy 28.886798 -206.739159) (xy 28.882863 -206.685388) (xy 22.076918 -206.685388)
			(xy 22.076426 -206.712345) (xy 22.068576 -206.765685) (xy 22.053044 -206.817314) (xy 22.030159 -206.866131)
			(xy 22.000411 -206.911095) (xy 21.964433 -206.951249) (xy 21.922991 -206.985737) (xy 21.87697 -207.013823)
			(xy 21.82735 -207.03491) (xy 21.775189 -207.048546) (xy 21.721598 -207.054443) (xy 21.667719 -207.052474)
			(xy 21.614701 -207.042681) (xy 21.563674 -207.025273) (xy 21.515726 -207.000621) (xy 21.471878 -206.969251)
			(xy 21.433065 -206.93183) (xy 21.400113 -206.889157) (xy 21.373727 -206.84214) (xy 21.354467 -206.791783)
			(xy 21.342744 -206.739159) (xy 21.338809 -206.685388) (xy 15.598394 -206.685388) (xy 15.598394 -207.535272)
			(xy 17.238741 -207.535272) (xy 17.242676 -207.481501) (xy 17.254399 -207.428877) (xy 17.273659 -207.37852)
			(xy 17.300045 -207.331503) (xy 17.332997 -207.28883) (xy 17.37181 -207.251409) (xy 17.415658 -207.220039)
			(xy 17.463606 -207.195387) (xy 17.514633 -207.177979) (xy 17.567651 -207.168186) (xy 17.62153 -207.166217)
			(xy 17.675121 -207.172114) (xy 17.727282 -207.18575) (xy 17.776902 -207.206837) (xy 17.822923 -207.234923)
			(xy 17.864365 -207.269411) (xy 17.900343 -207.309565) (xy 17.930091 -207.354529) (xy 17.952976 -207.403346)
			(xy 17.968508 -207.454975) (xy 17.976358 -207.508315) (xy 17.97685 -207.535272) (xy 24.782795 -207.535272)
			(xy 24.78673 -207.481501) (xy 24.798453 -207.428877) (xy 24.817713 -207.37852) (xy 24.844099 -207.331503)
			(xy 24.877051 -207.28883) (xy 24.915864 -207.251409) (xy 24.959712 -207.220039) (xy 25.00766 -207.195387)
			(xy 25.058687 -207.177979) (xy 25.111705 -207.168186) (xy 25.165584 -207.166217) (xy 25.219175 -207.172114)
			(xy 25.271336 -207.18575) (xy 25.320956 -207.206837) (xy 25.366977 -207.234923) (xy 25.408419 -207.269411)
			(xy 25.444397 -207.309565) (xy 25.474145 -207.354529) (xy 25.49703 -207.403346) (xy 25.512562 -207.454975)
			(xy 25.520412 -207.508315) (xy 25.520904 -207.535272) (xy 32.326595 -207.535272) (xy 32.33053 -207.481501)
			(xy 32.342253 -207.428877) (xy 32.361513 -207.37852) (xy 32.387899 -207.331503) (xy 32.420851 -207.28883)
			(xy 32.459664 -207.251409) (xy 32.503512 -207.220039) (xy 32.55146 -207.195387) (xy 32.602487 -207.177979)
			(xy 32.655505 -207.168186) (xy 32.709384 -207.166217) (xy 32.762975 -207.172114) (xy 32.815136 -207.18575)
			(xy 32.864756 -207.206837) (xy 32.910777 -207.234923) (xy 32.952219 -207.269411) (xy 32.988197 -207.309565)
			(xy 33.017945 -207.354529) (xy 33.04083 -207.403346) (xy 33.056362 -207.454975) (xy 33.064212 -207.508315)
			(xy 33.064704 -207.535272) (xy 39.870649 -207.535272) (xy 39.874584 -207.481501) (xy 39.886307 -207.428877)
			(xy 39.905567 -207.37852) (xy 39.931953 -207.331503) (xy 39.964905 -207.28883) (xy 40.003718 -207.251409)
			(xy 40.047566 -207.220039) (xy 40.095514 -207.195387) (xy 40.146541 -207.177979) (xy 40.199559 -207.168186)
			(xy 40.253438 -207.166217) (xy 40.307029 -207.172114) (xy 40.35919 -207.18575) (xy 40.40881 -207.206837)
			(xy 40.454831 -207.234923) (xy 40.496273 -207.269411) (xy 40.532251 -207.309565) (xy 40.561999 -207.354529)
			(xy 40.584884 -207.403346) (xy 40.600416 -207.454975) (xy 40.608266 -207.508315) (xy 40.608758 -207.535272)
			(xy 40.608266 -207.562229) (xy 40.600416 -207.615569) (xy 40.584884 -207.667198) (xy 40.561999 -207.716015)
			(xy 40.532251 -207.760979) (xy 40.496273 -207.801133) (xy 40.454831 -207.835621) (xy 40.40881 -207.863707)
			(xy 40.35919 -207.884794) (xy 40.307029 -207.89843) (xy 40.253438 -207.904327) (xy 40.199559 -207.902358)
			(xy 40.146541 -207.892565) (xy 40.095514 -207.875157) (xy 40.047566 -207.850505) (xy 40.003718 -207.819135)
			(xy 39.964905 -207.781714) (xy 39.931953 -207.739041) (xy 39.905567 -207.692024) (xy 39.886307 -207.641667)
			(xy 39.874584 -207.589043) (xy 39.870649 -207.535272) (xy 33.064704 -207.535272) (xy 33.064212 -207.562229)
			(xy 33.056362 -207.615569) (xy 33.04083 -207.667198) (xy 33.017945 -207.716015) (xy 32.988197 -207.760979)
			(xy 32.952219 -207.801133) (xy 32.910777 -207.835621) (xy 32.864756 -207.863707) (xy 32.815136 -207.884794)
			(xy 32.762975 -207.89843) (xy 32.709384 -207.904327) (xy 32.655505 -207.902358) (xy 32.602487 -207.892565)
			(xy 32.55146 -207.875157) (xy 32.503512 -207.850505) (xy 32.459664 -207.819135) (xy 32.420851 -207.781714)
			(xy 32.387899 -207.739041) (xy 32.361513 -207.692024) (xy 32.342253 -207.641667) (xy 32.33053 -207.589043)
			(xy 32.326595 -207.535272) (xy 25.520904 -207.535272) (xy 25.520412 -207.562229) (xy 25.512562 -207.615569)
			(xy 25.49703 -207.667198) (xy 25.474145 -207.716015) (xy 25.444397 -207.760979) (xy 25.408419 -207.801133)
			(xy 25.366977 -207.835621) (xy 25.320956 -207.863707) (xy 25.271336 -207.884794) (xy 25.219175 -207.89843)
			(xy 25.165584 -207.904327) (xy 25.111705 -207.902358) (xy 25.058687 -207.892565) (xy 25.00766 -207.875157)
			(xy 24.959712 -207.850505) (xy 24.915864 -207.819135) (xy 24.877051 -207.781714) (xy 24.844099 -207.739041)
			(xy 24.817713 -207.692024) (xy 24.798453 -207.641667) (xy 24.78673 -207.589043) (xy 24.782795 -207.535272)
			(xy 17.97685 -207.535272) (xy 17.976358 -207.562229) (xy 17.968508 -207.615569) (xy 17.952976 -207.667198)
			(xy 17.930091 -207.716015) (xy 17.900343 -207.760979) (xy 17.864365 -207.801133) (xy 17.822923 -207.835621)
			(xy 17.776902 -207.863707) (xy 17.727282 -207.884794) (xy 17.675121 -207.89843) (xy 17.62153 -207.904327)
			(xy 17.567651 -207.902358) (xy 17.514633 -207.892565) (xy 17.463606 -207.875157) (xy 17.415658 -207.850505)
			(xy 17.37181 -207.819135) (xy 17.332997 -207.781714) (xy 17.300045 -207.739041) (xy 17.273659 -207.692024)
			(xy 17.254399 -207.641667) (xy 17.242676 -207.589043) (xy 17.238741 -207.535272) (xy 15.598394 -207.535272)
			(xy 15.598394 -208.38541) (xy 21.338809 -208.38541) (xy 21.342744 -208.331639) (xy 21.354467 -208.279015)
			(xy 21.373727 -208.228658) (xy 21.400113 -208.181641) (xy 21.433065 -208.138968) (xy 21.471878 -208.101547)
			(xy 21.515726 -208.070177) (xy 21.563674 -208.045525) (xy 21.614701 -208.028117) (xy 21.667719 -208.018324)
			(xy 21.721598 -208.016355) (xy 21.775189 -208.022252) (xy 21.82735 -208.035888) (xy 21.87697 -208.056975)
			(xy 21.922991 -208.085061) (xy 21.964433 -208.119549) (xy 22.000411 -208.159703) (xy 22.030159 -208.204667)
			(xy 22.053044 -208.253484) (xy 22.068576 -208.305113) (xy 22.076426 -208.358453) (xy 22.076918 -208.38541)
			(xy 28.882863 -208.38541) (xy 28.886798 -208.331639) (xy 28.898521 -208.279015) (xy 28.917781 -208.228658)
			(xy 28.944167 -208.181641) (xy 28.977119 -208.138968) (xy 29.015932 -208.101547) (xy 29.05978 -208.070177)
			(xy 29.107728 -208.045525) (xy 29.158755 -208.028117) (xy 29.211773 -208.018324) (xy 29.265652 -208.016355)
			(xy 29.319243 -208.022252) (xy 29.371404 -208.035888) (xy 29.421024 -208.056975) (xy 29.467045 -208.085061)
			(xy 29.508487 -208.119549) (xy 29.544465 -208.159703) (xy 29.574213 -208.204667) (xy 29.597098 -208.253484)
			(xy 29.61263 -208.305113) (xy 29.62048 -208.358453) (xy 29.620972 -208.38541) (xy 36.426663 -208.38541)
			(xy 36.430598 -208.331639) (xy 36.442321 -208.279015) (xy 36.461581 -208.228658) (xy 36.487967 -208.181641)
			(xy 36.520919 -208.138968) (xy 36.559732 -208.101547) (xy 36.60358 -208.070177) (xy 36.651528 -208.045525)
			(xy 36.702555 -208.028117) (xy 36.755573 -208.018324) (xy 36.809452 -208.016355) (xy 36.863043 -208.022252)
			(xy 36.915204 -208.035888) (xy 36.964824 -208.056975) (xy 37.010845 -208.085061) (xy 37.052287 -208.119549)
			(xy 37.088265 -208.159703) (xy 37.118013 -208.204667) (xy 37.140898 -208.253484) (xy 37.15643 -208.305113)
			(xy 37.16428 -208.358453) (xy 37.164772 -208.38541) (xy 43.970717 -208.38541) (xy 43.974652 -208.331639)
			(xy 43.986375 -208.279015) (xy 44.005635 -208.228658) (xy 44.032021 -208.181641) (xy 44.064973 -208.138968)
			(xy 44.103786 -208.101547) (xy 44.147634 -208.070177) (xy 44.195582 -208.045525) (xy 44.246609 -208.028117)
			(xy 44.299627 -208.018324) (xy 44.353506 -208.016355) (xy 44.407097 -208.022252) (xy 44.459258 -208.035888)
			(xy 44.508878 -208.056975) (xy 44.554899 -208.085061) (xy 44.596341 -208.119549) (xy 44.632319 -208.159703)
			(xy 44.662067 -208.204667) (xy 44.684952 -208.253484) (xy 44.700484 -208.305113) (xy 44.708334 -208.358453)
			(xy 44.708826 -208.38541) (xy 44.708334 -208.412367) (xy 44.700484 -208.465707) (xy 44.684952 -208.517336)
			(xy 44.662067 -208.566153) (xy 44.632319 -208.611117) (xy 44.596341 -208.651271) (xy 44.554899 -208.685759)
			(xy 44.508878 -208.713845) (xy 44.459258 -208.734932) (xy 44.407097 -208.748568) (xy 44.353506 -208.754465)
			(xy 44.299627 -208.752496) (xy 44.246609 -208.742703) (xy 44.195582 -208.725295) (xy 44.147634 -208.700643)
			(xy 44.103786 -208.669273) (xy 44.064973 -208.631852) (xy 44.032021 -208.589179) (xy 44.005635 -208.542162)
			(xy 43.986375 -208.491805) (xy 43.974652 -208.439181) (xy 43.970717 -208.38541) (xy 37.164772 -208.38541)
			(xy 37.16428 -208.412367) (xy 37.15643 -208.465707) (xy 37.140898 -208.517336) (xy 37.118013 -208.566153)
			(xy 37.088265 -208.611117) (xy 37.052287 -208.651271) (xy 37.010845 -208.685759) (xy 36.964824 -208.713845)
			(xy 36.915204 -208.734932) (xy 36.863043 -208.748568) (xy 36.809452 -208.754465) (xy 36.755573 -208.752496)
			(xy 36.702555 -208.742703) (xy 36.651528 -208.725295) (xy 36.60358 -208.700643) (xy 36.559732 -208.669273)
			(xy 36.520919 -208.631852) (xy 36.487967 -208.589179) (xy 36.461581 -208.542162) (xy 36.442321 -208.491805)
			(xy 36.430598 -208.439181) (xy 36.426663 -208.38541) (xy 29.620972 -208.38541) (xy 29.62048 -208.412367)
			(xy 29.61263 -208.465707) (xy 29.597098 -208.517336) (xy 29.574213 -208.566153) (xy 29.544465 -208.611117)
			(xy 29.508487 -208.651271) (xy 29.467045 -208.685759) (xy 29.421024 -208.713845) (xy 29.371404 -208.734932)
			(xy 29.319243 -208.748568) (xy 29.265652 -208.754465) (xy 29.211773 -208.752496) (xy 29.158755 -208.742703)
			(xy 29.107728 -208.725295) (xy 29.05978 -208.700643) (xy 29.015932 -208.669273) (xy 28.977119 -208.631852)
			(xy 28.944167 -208.589179) (xy 28.917781 -208.542162) (xy 28.898521 -208.491805) (xy 28.886798 -208.439181)
			(xy 28.882863 -208.38541) (xy 22.076918 -208.38541) (xy 22.076426 -208.412367) (xy 22.068576 -208.465707)
			(xy 22.053044 -208.517336) (xy 22.030159 -208.566153) (xy 22.000411 -208.611117) (xy 21.964433 -208.651271)
			(xy 21.922991 -208.685759) (xy 21.87697 -208.713845) (xy 21.82735 -208.734932) (xy 21.775189 -208.748568)
			(xy 21.721598 -208.754465) (xy 21.667719 -208.752496) (xy 21.614701 -208.742703) (xy 21.563674 -208.725295)
			(xy 21.515726 -208.700643) (xy 21.471878 -208.669273) (xy 21.433065 -208.631852) (xy 21.400113 -208.589179)
			(xy 21.373727 -208.542162) (xy 21.354467 -208.491805) (xy 21.342744 -208.439181) (xy 21.338809 -208.38541)
			(xy 15.598394 -208.38541) (xy 15.598394 -209.235294) (xy 17.238741 -209.235294) (xy 17.242676 -209.181523)
			(xy 17.254399 -209.128899) (xy 17.273659 -209.078542) (xy 17.300045 -209.031525) (xy 17.332997 -208.988852)
			(xy 17.37181 -208.951431) (xy 17.415658 -208.920061) (xy 17.463606 -208.895409) (xy 17.514633 -208.878001)
			(xy 17.567651 -208.868208) (xy 17.62153 -208.866239) (xy 17.675121 -208.872136) (xy 17.727282 -208.885772)
			(xy 17.776902 -208.906859) (xy 17.822923 -208.934945) (xy 17.864365 -208.969433) (xy 17.900343 -209.009587)
			(xy 17.930091 -209.054551) (xy 17.952976 -209.103368) (xy 17.968508 -209.154997) (xy 17.976358 -209.208337)
			(xy 17.97685 -209.235294) (xy 24.782795 -209.235294) (xy 24.78673 -209.181523) (xy 24.798453 -209.128899)
			(xy 24.817713 -209.078542) (xy 24.844099 -209.031525) (xy 24.877051 -208.988852) (xy 24.915864 -208.951431)
			(xy 24.959712 -208.920061) (xy 25.00766 -208.895409) (xy 25.058687 -208.878001) (xy 25.111705 -208.868208)
			(xy 25.165584 -208.866239) (xy 25.219175 -208.872136) (xy 25.271336 -208.885772) (xy 25.320956 -208.906859)
			(xy 25.366977 -208.934945) (xy 25.408419 -208.969433) (xy 25.444397 -209.009587) (xy 25.474145 -209.054551)
			(xy 25.49703 -209.103368) (xy 25.512562 -209.154997) (xy 25.520412 -209.208337) (xy 25.520904 -209.235294)
			(xy 32.326595 -209.235294) (xy 32.33053 -209.181523) (xy 32.342253 -209.128899) (xy 32.361513 -209.078542)
			(xy 32.387899 -209.031525) (xy 32.420851 -208.988852) (xy 32.459664 -208.951431) (xy 32.503512 -208.920061)
			(xy 32.55146 -208.895409) (xy 32.602487 -208.878001) (xy 32.655505 -208.868208) (xy 32.709384 -208.866239)
			(xy 32.762975 -208.872136) (xy 32.815136 -208.885772) (xy 32.864756 -208.906859) (xy 32.910777 -208.934945)
			(xy 32.952219 -208.969433) (xy 32.988197 -209.009587) (xy 33.017945 -209.054551) (xy 33.04083 -209.103368)
			(xy 33.056362 -209.154997) (xy 33.064212 -209.208337) (xy 33.064704 -209.235294) (xy 39.870649 -209.235294)
			(xy 39.874584 -209.181523) (xy 39.886307 -209.128899) (xy 39.905567 -209.078542) (xy 39.931953 -209.031525)
			(xy 39.964905 -208.988852) (xy 40.003718 -208.951431) (xy 40.047566 -208.920061) (xy 40.095514 -208.895409)
			(xy 40.146541 -208.878001) (xy 40.199559 -208.868208) (xy 40.253438 -208.866239) (xy 40.307029 -208.872136)
			(xy 40.35919 -208.885772) (xy 40.40881 -208.906859) (xy 40.454831 -208.934945) (xy 40.496273 -208.969433)
			(xy 40.532251 -209.009587) (xy 40.561999 -209.054551) (xy 40.584884 -209.103368) (xy 40.600416 -209.154997)
			(xy 40.608266 -209.208337) (xy 40.608758 -209.235294) (xy 40.608266 -209.262251) (xy 40.600416 -209.315591)
			(xy 40.584884 -209.36722) (xy 40.561999 -209.416037) (xy 40.532251 -209.461001) (xy 40.496273 -209.501155)
			(xy 40.454831 -209.535643) (xy 40.40881 -209.563729) (xy 40.35919 -209.584816) (xy 40.307029 -209.598452)
			(xy 40.253438 -209.604349) (xy 40.199559 -209.60238) (xy 40.146541 -209.592587) (xy 40.095514 -209.575179)
			(xy 40.047566 -209.550527) (xy 40.003718 -209.519157) (xy 39.964905 -209.481736) (xy 39.931953 -209.439063)
			(xy 39.905567 -209.392046) (xy 39.886307 -209.341689) (xy 39.874584 -209.289065) (xy 39.870649 -209.235294)
			(xy 33.064704 -209.235294) (xy 33.064212 -209.262251) (xy 33.056362 -209.315591) (xy 33.04083 -209.36722)
			(xy 33.017945 -209.416037) (xy 32.988197 -209.461001) (xy 32.952219 -209.501155) (xy 32.910777 -209.535643)
			(xy 32.864756 -209.563729) (xy 32.815136 -209.584816) (xy 32.762975 -209.598452) (xy 32.709384 -209.604349)
			(xy 32.655505 -209.60238) (xy 32.602487 -209.592587) (xy 32.55146 -209.575179) (xy 32.503512 -209.550527)
			(xy 32.459664 -209.519157) (xy 32.420851 -209.481736) (xy 32.387899 -209.439063) (xy 32.361513 -209.392046)
			(xy 32.342253 -209.341689) (xy 32.33053 -209.289065) (xy 32.326595 -209.235294) (xy 25.520904 -209.235294)
			(xy 25.520412 -209.262251) (xy 25.512562 -209.315591) (xy 25.49703 -209.36722) (xy 25.474145 -209.416037)
			(xy 25.444397 -209.461001) (xy 25.408419 -209.501155) (xy 25.366977 -209.535643) (xy 25.320956 -209.563729)
			(xy 25.271336 -209.584816) (xy 25.219175 -209.598452) (xy 25.165584 -209.604349) (xy 25.111705 -209.60238)
			(xy 25.058687 -209.592587) (xy 25.00766 -209.575179) (xy 24.959712 -209.550527) (xy 24.915864 -209.519157)
			(xy 24.877051 -209.481736) (xy 24.844099 -209.439063) (xy 24.817713 -209.392046) (xy 24.798453 -209.341689)
			(xy 24.78673 -209.289065) (xy 24.782795 -209.235294) (xy 17.97685 -209.235294) (xy 17.976358 -209.262251)
			(xy 17.968508 -209.315591) (xy 17.952976 -209.36722) (xy 17.930091 -209.416037) (xy 17.900343 -209.461001)
			(xy 17.864365 -209.501155) (xy 17.822923 -209.535643) (xy 17.776902 -209.563729) (xy 17.727282 -209.584816)
			(xy 17.675121 -209.598452) (xy 17.62153 -209.604349) (xy 17.567651 -209.60238) (xy 17.514633 -209.592587)
			(xy 17.463606 -209.575179) (xy 17.415658 -209.550527) (xy 17.37181 -209.519157) (xy 17.332997 -209.481736)
			(xy 17.300045 -209.439063) (xy 17.273659 -209.392046) (xy 17.254399 -209.341689) (xy 17.242676 -209.289065)
			(xy 17.238741 -209.235294) (xy 15.598394 -209.235294) (xy 15.598394 -210.085432) (xy 21.338809 -210.085432)
			(xy 21.342744 -210.031661) (xy 21.354467 -209.979037) (xy 21.373727 -209.92868) (xy 21.400113 -209.881663)
			(xy 21.433065 -209.83899) (xy 21.471878 -209.801569) (xy 21.515726 -209.770199) (xy 21.563674 -209.745547)
			(xy 21.614701 -209.728139) (xy 21.667719 -209.718346) (xy 21.721598 -209.716377) (xy 21.775189 -209.722274)
			(xy 21.82735 -209.73591) (xy 21.87697 -209.756997) (xy 21.922991 -209.785083) (xy 21.964433 -209.819571)
			(xy 22.000411 -209.859725) (xy 22.030159 -209.904689) (xy 22.053044 -209.953506) (xy 22.068576 -210.005135)
			(xy 22.076426 -210.058475) (xy 22.076918 -210.085432) (xy 28.882863 -210.085432) (xy 28.886798 -210.031661)
			(xy 28.898521 -209.979037) (xy 28.917781 -209.92868) (xy 28.944167 -209.881663) (xy 28.977119 -209.83899)
			(xy 29.015932 -209.801569) (xy 29.05978 -209.770199) (xy 29.107728 -209.745547) (xy 29.158755 -209.728139)
			(xy 29.211773 -209.718346) (xy 29.265652 -209.716377) (xy 29.319243 -209.722274) (xy 29.371404 -209.73591)
			(xy 29.421024 -209.756997) (xy 29.467045 -209.785083) (xy 29.508487 -209.819571) (xy 29.544465 -209.859725)
			(xy 29.574213 -209.904689) (xy 29.597098 -209.953506) (xy 29.61263 -210.005135) (xy 29.62048 -210.058475)
			(xy 29.620972 -210.085432) (xy 36.426663 -210.085432) (xy 36.430598 -210.031661) (xy 36.442321 -209.979037)
			(xy 36.461581 -209.92868) (xy 36.487967 -209.881663) (xy 36.520919 -209.83899) (xy 36.559732 -209.801569)
			(xy 36.60358 -209.770199) (xy 36.651528 -209.745547) (xy 36.702555 -209.728139) (xy 36.755573 -209.718346)
			(xy 36.809452 -209.716377) (xy 36.863043 -209.722274) (xy 36.915204 -209.73591) (xy 36.964824 -209.756997)
			(xy 37.010845 -209.785083) (xy 37.052287 -209.819571) (xy 37.088265 -209.859725) (xy 37.118013 -209.904689)
			(xy 37.140898 -209.953506) (xy 37.15643 -210.005135) (xy 37.16428 -210.058475) (xy 37.164772 -210.085432)
			(xy 43.970717 -210.085432) (xy 43.974652 -210.031661) (xy 43.986375 -209.979037) (xy 44.005635 -209.92868)
			(xy 44.032021 -209.881663) (xy 44.064973 -209.83899) (xy 44.103786 -209.801569) (xy 44.147634 -209.770199)
			(xy 44.195582 -209.745547) (xy 44.246609 -209.728139) (xy 44.299627 -209.718346) (xy 44.353506 -209.716377)
			(xy 44.407097 -209.722274) (xy 44.459258 -209.73591) (xy 44.508878 -209.756997) (xy 44.554899 -209.785083)
			(xy 44.596341 -209.819571) (xy 44.632319 -209.859725) (xy 44.662067 -209.904689) (xy 44.684952 -209.953506)
			(xy 44.700484 -210.005135) (xy 44.708334 -210.058475) (xy 44.708826 -210.085432) (xy 44.708334 -210.112389)
			(xy 44.700484 -210.165729) (xy 44.684952 -210.217358) (xy 44.662067 -210.266175) (xy 44.632319 -210.311139)
			(xy 44.596341 -210.351293) (xy 44.554899 -210.385781) (xy 44.508878 -210.413867) (xy 44.459258 -210.434954)
			(xy 44.407097 -210.44859) (xy 44.353506 -210.454487) (xy 44.299627 -210.452518) (xy 44.246609 -210.442725)
			(xy 44.195582 -210.425317) (xy 44.147634 -210.400665) (xy 44.103786 -210.369295) (xy 44.064973 -210.331874)
			(xy 44.032021 -210.289201) (xy 44.005635 -210.242184) (xy 43.986375 -210.191827) (xy 43.974652 -210.139203)
			(xy 43.970717 -210.085432) (xy 37.164772 -210.085432) (xy 37.16428 -210.112389) (xy 37.15643 -210.165729)
			(xy 37.140898 -210.217358) (xy 37.118013 -210.266175) (xy 37.088265 -210.311139) (xy 37.052287 -210.351293)
			(xy 37.010845 -210.385781) (xy 36.964824 -210.413867) (xy 36.915204 -210.434954) (xy 36.863043 -210.44859)
			(xy 36.809452 -210.454487) (xy 36.755573 -210.452518) (xy 36.702555 -210.442725) (xy 36.651528 -210.425317)
			(xy 36.60358 -210.400665) (xy 36.559732 -210.369295) (xy 36.520919 -210.331874) (xy 36.487967 -210.289201)
			(xy 36.461581 -210.242184) (xy 36.442321 -210.191827) (xy 36.430598 -210.139203) (xy 36.426663 -210.085432)
			(xy 29.620972 -210.085432) (xy 29.62048 -210.112389) (xy 29.61263 -210.165729) (xy 29.597098 -210.217358)
			(xy 29.574213 -210.266175) (xy 29.544465 -210.311139) (xy 29.508487 -210.351293) (xy 29.467045 -210.385781)
			(xy 29.421024 -210.413867) (xy 29.371404 -210.434954) (xy 29.319243 -210.44859) (xy 29.265652 -210.454487)
			(xy 29.211773 -210.452518) (xy 29.158755 -210.442725) (xy 29.107728 -210.425317) (xy 29.05978 -210.400665)
			(xy 29.015932 -210.369295) (xy 28.977119 -210.331874) (xy 28.944167 -210.289201) (xy 28.917781 -210.242184)
			(xy 28.898521 -210.191827) (xy 28.886798 -210.139203) (xy 28.882863 -210.085432) (xy 22.076918 -210.085432)
			(xy 22.076426 -210.112389) (xy 22.068576 -210.165729) (xy 22.053044 -210.217358) (xy 22.030159 -210.266175)
			(xy 22.000411 -210.311139) (xy 21.964433 -210.351293) (xy 21.922991 -210.385781) (xy 21.87697 -210.413867)
			(xy 21.82735 -210.434954) (xy 21.775189 -210.44859) (xy 21.721598 -210.454487) (xy 21.667719 -210.452518)
			(xy 21.614701 -210.442725) (xy 21.563674 -210.425317) (xy 21.515726 -210.400665) (xy 21.471878 -210.369295)
			(xy 21.433065 -210.331874) (xy 21.400113 -210.289201) (xy 21.373727 -210.242184) (xy 21.354467 -210.191827)
			(xy 21.342744 -210.139203) (xy 21.338809 -210.085432) (xy 15.598394 -210.085432) (xy 15.598394 -210.935316)
			(xy 17.238741 -210.935316) (xy 17.242676 -210.881545) (xy 17.254399 -210.828921) (xy 17.273659 -210.778564)
			(xy 17.300045 -210.731547) (xy 17.332997 -210.688874) (xy 17.37181 -210.651453) (xy 17.415658 -210.620083)
			(xy 17.463606 -210.595431) (xy 17.514633 -210.578023) (xy 17.567651 -210.56823) (xy 17.62153 -210.566261)
			(xy 17.675121 -210.572158) (xy 17.727282 -210.585794) (xy 17.776902 -210.606881) (xy 17.822923 -210.634967)
			(xy 17.864365 -210.669455) (xy 17.900343 -210.709609) (xy 17.930091 -210.754573) (xy 17.952976 -210.80339)
			(xy 17.968508 -210.855019) (xy 17.976358 -210.908359) (xy 17.97685 -210.935316) (xy 21.338809 -210.935316)
			(xy 21.342744 -210.881545) (xy 21.354467 -210.828921) (xy 21.373727 -210.778564) (xy 21.400113 -210.731547)
			(xy 21.433065 -210.688874) (xy 21.471878 -210.651453) (xy 21.515726 -210.620083) (xy 21.563674 -210.595431)
			(xy 21.614701 -210.578023) (xy 21.667719 -210.56823) (xy 21.721598 -210.566261) (xy 21.775189 -210.572158)
			(xy 21.82735 -210.585794) (xy 21.87697 -210.606881) (xy 21.922991 -210.634967) (xy 21.964433 -210.669455)
			(xy 22.000411 -210.709609) (xy 22.030159 -210.754573) (xy 22.053044 -210.80339) (xy 22.068576 -210.855019)
			(xy 22.076426 -210.908359) (xy 22.076918 -210.935316) (xy 24.782795 -210.935316) (xy 24.78673 -210.881545)
			(xy 24.798453 -210.828921) (xy 24.817713 -210.778564) (xy 24.844099 -210.731547) (xy 24.877051 -210.688874)
			(xy 24.915864 -210.651453) (xy 24.959712 -210.620083) (xy 25.00766 -210.595431) (xy 25.058687 -210.578023)
			(xy 25.111705 -210.56823) (xy 25.165584 -210.566261) (xy 25.219175 -210.572158) (xy 25.271336 -210.585794)
			(xy 25.320956 -210.606881) (xy 25.366977 -210.634967) (xy 25.408419 -210.669455) (xy 25.444397 -210.709609)
			(xy 25.474145 -210.754573) (xy 25.49703 -210.80339) (xy 25.512562 -210.855019) (xy 25.520412 -210.908359)
			(xy 25.520904 -210.935316) (xy 28.882863 -210.935316) (xy 28.886798 -210.881545) (xy 28.898521 -210.828921)
			(xy 28.917781 -210.778564) (xy 28.944167 -210.731547) (xy 28.977119 -210.688874) (xy 29.015932 -210.651453)
			(xy 29.05978 -210.620083) (xy 29.107728 -210.595431) (xy 29.158755 -210.578023) (xy 29.211773 -210.56823)
			(xy 29.265652 -210.566261) (xy 29.319243 -210.572158) (xy 29.371404 -210.585794) (xy 29.421024 -210.606881)
			(xy 29.467045 -210.634967) (xy 29.508487 -210.669455) (xy 29.544465 -210.709609) (xy 29.574213 -210.754573)
			(xy 29.597098 -210.80339) (xy 29.61263 -210.855019) (xy 29.62048 -210.908359) (xy 29.620972 -210.935316)
			(xy 32.326595 -210.935316) (xy 32.33053 -210.881545) (xy 32.342253 -210.828921) (xy 32.361513 -210.778564)
			(xy 32.387899 -210.731547) (xy 32.420851 -210.688874) (xy 32.459664 -210.651453) (xy 32.503512 -210.620083)
			(xy 32.55146 -210.595431) (xy 32.602487 -210.578023) (xy 32.655505 -210.56823) (xy 32.709384 -210.566261)
			(xy 32.762975 -210.572158) (xy 32.815136 -210.585794) (xy 32.864756 -210.606881) (xy 32.910777 -210.634967)
			(xy 32.952219 -210.669455) (xy 32.988197 -210.709609) (xy 33.017945 -210.754573) (xy 33.04083 -210.80339)
			(xy 33.056362 -210.855019) (xy 33.064212 -210.908359) (xy 33.064704 -210.935316) (xy 36.426663 -210.935316)
			(xy 36.430598 -210.881545) (xy 36.442321 -210.828921) (xy 36.461581 -210.778564) (xy 36.487967 -210.731547)
			(xy 36.520919 -210.688874) (xy 36.559732 -210.651453) (xy 36.60358 -210.620083) (xy 36.651528 -210.595431)
			(xy 36.702555 -210.578023) (xy 36.755573 -210.56823) (xy 36.809452 -210.566261) (xy 36.863043 -210.572158)
			(xy 36.915204 -210.585794) (xy 36.964824 -210.606881) (xy 37.010845 -210.634967) (xy 37.052287 -210.669455)
			(xy 37.088265 -210.709609) (xy 37.118013 -210.754573) (xy 37.140898 -210.80339) (xy 37.15643 -210.855019)
			(xy 37.16428 -210.908359) (xy 37.164772 -210.935316) (xy 39.870649 -210.935316) (xy 39.874584 -210.881545)
			(xy 39.886307 -210.828921) (xy 39.905567 -210.778564) (xy 39.931953 -210.731547) (xy 39.964905 -210.688874)
			(xy 40.003718 -210.651453) (xy 40.047566 -210.620083) (xy 40.095514 -210.595431) (xy 40.146541 -210.578023)
			(xy 40.199559 -210.56823) (xy 40.253438 -210.566261) (xy 40.307029 -210.572158) (xy 40.35919 -210.585794)
			(xy 40.40881 -210.606881) (xy 40.454831 -210.634967) (xy 40.496273 -210.669455) (xy 40.532251 -210.709609)
			(xy 40.561999 -210.754573) (xy 40.584884 -210.80339) (xy 40.600416 -210.855019) (xy 40.608266 -210.908359)
			(xy 40.608758 -210.935316) (xy 43.970717 -210.935316) (xy 43.974652 -210.881545) (xy 43.986375 -210.828921)
			(xy 44.005635 -210.778564) (xy 44.032021 -210.731547) (xy 44.064973 -210.688874) (xy 44.103786 -210.651453)
			(xy 44.147634 -210.620083) (xy 44.195582 -210.595431) (xy 44.246609 -210.578023) (xy 44.299627 -210.56823)
			(xy 44.353506 -210.566261) (xy 44.407097 -210.572158) (xy 44.459258 -210.585794) (xy 44.508878 -210.606881)
			(xy 44.554899 -210.634967) (xy 44.596341 -210.669455) (xy 44.632319 -210.709609) (xy 44.662067 -210.754573)
			(xy 44.684952 -210.80339) (xy 44.700484 -210.855019) (xy 44.708334 -210.908359) (xy 44.708826 -210.935316)
			(xy 44.708334 -210.962273) (xy 44.700484 -211.015613) (xy 44.684952 -211.067242) (xy 44.662067 -211.116059)
			(xy 44.632319 -211.161023) (xy 44.596341 -211.201177) (xy 44.554899 -211.235665) (xy 44.508878 -211.263751)
			(xy 44.459258 -211.284838) (xy 44.407097 -211.298474) (xy 44.353506 -211.304371) (xy 44.299627 -211.302402)
			(xy 44.246609 -211.292609) (xy 44.195582 -211.275201) (xy 44.147634 -211.250549) (xy 44.103786 -211.219179)
			(xy 44.064973 -211.181758) (xy 44.032021 -211.139085) (xy 44.005635 -211.092068) (xy 43.986375 -211.041711)
			(xy 43.974652 -210.989087) (xy 43.970717 -210.935316) (xy 40.608758 -210.935316) (xy 40.608266 -210.962273)
			(xy 40.600416 -211.015613) (xy 40.584884 -211.067242) (xy 40.561999 -211.116059) (xy 40.532251 -211.161023)
			(xy 40.496273 -211.201177) (xy 40.454831 -211.235665) (xy 40.40881 -211.263751) (xy 40.35919 -211.284838)
			(xy 40.307029 -211.298474) (xy 40.253438 -211.304371) (xy 40.199559 -211.302402) (xy 40.146541 -211.292609)
			(xy 40.095514 -211.275201) (xy 40.047566 -211.250549) (xy 40.003718 -211.219179) (xy 39.964905 -211.181758)
			(xy 39.931953 -211.139085) (xy 39.905567 -211.092068) (xy 39.886307 -211.041711) (xy 39.874584 -210.989087)
			(xy 39.870649 -210.935316) (xy 37.164772 -210.935316) (xy 37.16428 -210.962273) (xy 37.15643 -211.015613)
			(xy 37.140898 -211.067242) (xy 37.118013 -211.116059) (xy 37.088265 -211.161023) (xy 37.052287 -211.201177)
			(xy 37.010845 -211.235665) (xy 36.964824 -211.263751) (xy 36.915204 -211.284838) (xy 36.863043 -211.298474)
			(xy 36.809452 -211.304371) (xy 36.755573 -211.302402) (xy 36.702555 -211.292609) (xy 36.651528 -211.275201)
			(xy 36.60358 -211.250549) (xy 36.559732 -211.219179) (xy 36.520919 -211.181758) (xy 36.487967 -211.139085)
			(xy 36.461581 -211.092068) (xy 36.442321 -211.041711) (xy 36.430598 -210.989087) (xy 36.426663 -210.935316)
			(xy 33.064704 -210.935316) (xy 33.064212 -210.962273) (xy 33.056362 -211.015613) (xy 33.04083 -211.067242)
			(xy 33.017945 -211.116059) (xy 32.988197 -211.161023) (xy 32.952219 -211.201177) (xy 32.910777 -211.235665)
			(xy 32.864756 -211.263751) (xy 32.815136 -211.284838) (xy 32.762975 -211.298474) (xy 32.709384 -211.304371)
			(xy 32.655505 -211.302402) (xy 32.602487 -211.292609) (xy 32.55146 -211.275201) (xy 32.503512 -211.250549)
			(xy 32.459664 -211.219179) (xy 32.420851 -211.181758) (xy 32.387899 -211.139085) (xy 32.361513 -211.092068)
			(xy 32.342253 -211.041711) (xy 32.33053 -210.989087) (xy 32.326595 -210.935316) (xy 29.620972 -210.935316)
			(xy 29.62048 -210.962273) (xy 29.61263 -211.015613) (xy 29.597098 -211.067242) (xy 29.574213 -211.116059)
			(xy 29.544465 -211.161023) (xy 29.508487 -211.201177) (xy 29.467045 -211.235665) (xy 29.421024 -211.263751)
			(xy 29.371404 -211.284838) (xy 29.319243 -211.298474) (xy 29.265652 -211.304371) (xy 29.211773 -211.302402)
			(xy 29.158755 -211.292609) (xy 29.107728 -211.275201) (xy 29.05978 -211.250549) (xy 29.015932 -211.219179)
			(xy 28.977119 -211.181758) (xy 28.944167 -211.139085) (xy 28.917781 -211.092068) (xy 28.898521 -211.041711)
			(xy 28.886798 -210.989087) (xy 28.882863 -210.935316) (xy 25.520904 -210.935316) (xy 25.520412 -210.962273)
			(xy 25.512562 -211.015613) (xy 25.49703 -211.067242) (xy 25.474145 -211.116059) (xy 25.444397 -211.161023)
			(xy 25.408419 -211.201177) (xy 25.366977 -211.235665) (xy 25.320956 -211.263751) (xy 25.271336 -211.284838)
			(xy 25.219175 -211.298474) (xy 25.165584 -211.304371) (xy 25.111705 -211.302402) (xy 25.058687 -211.292609)
			(xy 25.00766 -211.275201) (xy 24.959712 -211.250549) (xy 24.915864 -211.219179) (xy 24.877051 -211.181758)
			(xy 24.844099 -211.139085) (xy 24.817713 -211.092068) (xy 24.798453 -211.041711) (xy 24.78673 -210.989087)
			(xy 24.782795 -210.935316) (xy 22.076918 -210.935316) (xy 22.076426 -210.962273) (xy 22.068576 -211.015613)
			(xy 22.053044 -211.067242) (xy 22.030159 -211.116059) (xy 22.000411 -211.161023) (xy 21.964433 -211.201177)
			(xy 21.922991 -211.235665) (xy 21.87697 -211.263751) (xy 21.82735 -211.284838) (xy 21.775189 -211.298474)
			(xy 21.721598 -211.304371) (xy 21.667719 -211.302402) (xy 21.614701 -211.292609) (xy 21.563674 -211.275201)
			(xy 21.515726 -211.250549) (xy 21.471878 -211.219179) (xy 21.433065 -211.181758) (xy 21.400113 -211.139085)
			(xy 21.373727 -211.092068) (xy 21.354467 -211.041711) (xy 21.342744 -210.989087) (xy 21.338809 -210.935316)
			(xy 17.97685 -210.935316) (xy 17.976358 -210.962273) (xy 17.968508 -211.015613) (xy 17.952976 -211.067242)
			(xy 17.930091 -211.116059) (xy 17.900343 -211.161023) (xy 17.864365 -211.201177) (xy 17.822923 -211.235665)
			(xy 17.776902 -211.263751) (xy 17.727282 -211.284838) (xy 17.675121 -211.298474) (xy 17.62153 -211.304371)
			(xy 17.567651 -211.302402) (xy 17.514633 -211.292609) (xy 17.463606 -211.275201) (xy 17.415658 -211.250549)
			(xy 17.37181 -211.219179) (xy 17.332997 -211.181758) (xy 17.300045 -211.139085) (xy 17.273659 -211.092068)
			(xy 17.254399 -211.041711) (xy 17.242676 -210.989087) (xy 17.238741 -210.935316) (xy 15.598394 -210.935316)
			(xy 15.598394 -211.7852) (xy 17.238741 -211.7852) (xy 17.242676 -211.731429) (xy 17.254399 -211.678805)
			(xy 17.273659 -211.628448) (xy 17.300045 -211.581431) (xy 17.332997 -211.538758) (xy 17.37181 -211.501337)
			(xy 17.415658 -211.469967) (xy 17.463606 -211.445315) (xy 17.514633 -211.427907) (xy 17.567651 -211.418114)
			(xy 17.62153 -211.416145) (xy 17.675121 -211.422042) (xy 17.727282 -211.435678) (xy 17.776902 -211.456765)
			(xy 17.822923 -211.484851) (xy 17.864365 -211.519339) (xy 17.900343 -211.559493) (xy 17.930091 -211.604457)
			(xy 17.952976 -211.653274) (xy 17.968508 -211.704903) (xy 17.976358 -211.758243) (xy 17.97685 -211.7852)
			(xy 24.782795 -211.7852) (xy 24.78673 -211.731429) (xy 24.798453 -211.678805) (xy 24.817713 -211.628448)
			(xy 24.844099 -211.581431) (xy 24.877051 -211.538758) (xy 24.915864 -211.501337) (xy 24.959712 -211.469967)
			(xy 25.00766 -211.445315) (xy 25.058687 -211.427907) (xy 25.111705 -211.418114) (xy 25.165584 -211.416145)
			(xy 25.219175 -211.422042) (xy 25.271336 -211.435678) (xy 25.320956 -211.456765) (xy 25.366977 -211.484851)
			(xy 25.408419 -211.519339) (xy 25.444397 -211.559493) (xy 25.474145 -211.604457) (xy 25.49703 -211.653274)
			(xy 25.512562 -211.704903) (xy 25.520412 -211.758243) (xy 25.520904 -211.7852) (xy 32.326595 -211.7852)
			(xy 32.33053 -211.731429) (xy 32.342253 -211.678805) (xy 32.361513 -211.628448) (xy 32.387899 -211.581431)
			(xy 32.420851 -211.538758) (xy 32.459664 -211.501337) (xy 32.503512 -211.469967) (xy 32.55146 -211.445315)
			(xy 32.602487 -211.427907) (xy 32.655505 -211.418114) (xy 32.709384 -211.416145) (xy 32.762975 -211.422042)
			(xy 32.815136 -211.435678) (xy 32.864756 -211.456765) (xy 32.910777 -211.484851) (xy 32.952219 -211.519339)
			(xy 32.988197 -211.559493) (xy 33.017945 -211.604457) (xy 33.04083 -211.653274) (xy 33.056362 -211.704903)
			(xy 33.064212 -211.758243) (xy 33.064704 -211.7852) (xy 39.870649 -211.7852) (xy 39.874584 -211.731429)
			(xy 39.886307 -211.678805) (xy 39.905567 -211.628448) (xy 39.931953 -211.581431) (xy 39.964905 -211.538758)
			(xy 40.003718 -211.501337) (xy 40.047566 -211.469967) (xy 40.095514 -211.445315) (xy 40.146541 -211.427907)
			(xy 40.199559 -211.418114) (xy 40.253438 -211.416145) (xy 40.307029 -211.422042) (xy 40.35919 -211.435678)
			(xy 40.40881 -211.456765) (xy 40.454831 -211.484851) (xy 40.496273 -211.519339) (xy 40.532251 -211.559493)
			(xy 40.561999 -211.604457) (xy 40.584884 -211.653274) (xy 40.600416 -211.704903) (xy 40.608266 -211.758243)
			(xy 40.608758 -211.7852) (xy 40.608266 -211.812157) (xy 40.600416 -211.865497) (xy 40.584884 -211.917126)
			(xy 40.561999 -211.965943) (xy 40.532251 -212.010907) (xy 40.496273 -212.051061) (xy 40.454831 -212.085549)
			(xy 40.40881 -212.113635) (xy 40.35919 -212.134722) (xy 40.307029 -212.148358) (xy 40.253438 -212.154255)
			(xy 40.199559 -212.152286) (xy 40.146541 -212.142493) (xy 40.095514 -212.125085) (xy 40.047566 -212.100433)
			(xy 40.003718 -212.069063) (xy 39.964905 -212.031642) (xy 39.931953 -211.988969) (xy 39.905567 -211.941952)
			(xy 39.886307 -211.891595) (xy 39.874584 -211.838971) (xy 39.870649 -211.7852) (xy 33.064704 -211.7852)
			(xy 33.064212 -211.812157) (xy 33.056362 -211.865497) (xy 33.04083 -211.917126) (xy 33.017945 -211.965943)
			(xy 32.988197 -212.010907) (xy 32.952219 -212.051061) (xy 32.910777 -212.085549) (xy 32.864756 -212.113635)
			(xy 32.815136 -212.134722) (xy 32.762975 -212.148358) (xy 32.709384 -212.154255) (xy 32.655505 -212.152286)
			(xy 32.602487 -212.142493) (xy 32.55146 -212.125085) (xy 32.503512 -212.100433) (xy 32.459664 -212.069063)
			(xy 32.420851 -212.031642) (xy 32.387899 -211.988969) (xy 32.361513 -211.941952) (xy 32.342253 -211.891595)
			(xy 32.33053 -211.838971) (xy 32.326595 -211.7852) (xy 25.520904 -211.7852) (xy 25.520412 -211.812157)
			(xy 25.512562 -211.865497) (xy 25.49703 -211.917126) (xy 25.474145 -211.965943) (xy 25.444397 -212.010907)
			(xy 25.408419 -212.051061) (xy 25.366977 -212.085549) (xy 25.320956 -212.113635) (xy 25.271336 -212.134722)
			(xy 25.219175 -212.148358) (xy 25.165584 -212.154255) (xy 25.111705 -212.152286) (xy 25.058687 -212.142493)
			(xy 25.00766 -212.125085) (xy 24.959712 -212.100433) (xy 24.915864 -212.069063) (xy 24.877051 -212.031642)
			(xy 24.844099 -211.988969) (xy 24.817713 -211.941952) (xy 24.798453 -211.891595) (xy 24.78673 -211.838971)
			(xy 24.782795 -211.7852) (xy 17.97685 -211.7852) (xy 17.976358 -211.812157) (xy 17.968508 -211.865497)
			(xy 17.952976 -211.917126) (xy 17.930091 -211.965943) (xy 17.900343 -212.010907) (xy 17.864365 -212.051061)
			(xy 17.822923 -212.085549) (xy 17.776902 -212.113635) (xy 17.727282 -212.134722) (xy 17.675121 -212.148358)
			(xy 17.62153 -212.154255) (xy 17.567651 -212.152286) (xy 17.514633 -212.142493) (xy 17.463606 -212.125085)
			(xy 17.415658 -212.100433) (xy 17.37181 -212.069063) (xy 17.332997 -212.031642) (xy 17.300045 -211.988969)
			(xy 17.273659 -211.941952) (xy 17.254399 -211.891595) (xy 17.242676 -211.838971) (xy 17.238741 -211.7852)
			(xy 15.598394 -211.7852) (xy 15.598394 -212.635338) (xy 21.338809 -212.635338) (xy 21.342744 -212.581567)
			(xy 21.354467 -212.528943) (xy 21.373727 -212.478586) (xy 21.400113 -212.431569) (xy 21.433065 -212.388896)
			(xy 21.471878 -212.351475) (xy 21.515726 -212.320105) (xy 21.563674 -212.295453) (xy 21.614701 -212.278045)
			(xy 21.667719 -212.268252) (xy 21.721598 -212.266283) (xy 21.775189 -212.27218) (xy 21.82735 -212.285816)
			(xy 21.87697 -212.306903) (xy 21.922991 -212.334989) (xy 21.964433 -212.369477) (xy 22.000411 -212.409631)
			(xy 22.030159 -212.454595) (xy 22.053044 -212.503412) (xy 22.068576 -212.555041) (xy 22.076426 -212.608381)
			(xy 22.076918 -212.635338) (xy 28.882863 -212.635338) (xy 28.886798 -212.581567) (xy 28.898521 -212.528943)
			(xy 28.917781 -212.478586) (xy 28.944167 -212.431569) (xy 28.977119 -212.388896) (xy 29.015932 -212.351475)
			(xy 29.05978 -212.320105) (xy 29.107728 -212.295453) (xy 29.158755 -212.278045) (xy 29.211773 -212.268252)
			(xy 29.265652 -212.266283) (xy 29.319243 -212.27218) (xy 29.371404 -212.285816) (xy 29.421024 -212.306903)
			(xy 29.467045 -212.334989) (xy 29.508487 -212.369477) (xy 29.544465 -212.409631) (xy 29.574213 -212.454595)
			(xy 29.597098 -212.503412) (xy 29.61263 -212.555041) (xy 29.62048 -212.608381) (xy 29.620972 -212.635338)
			(xy 36.426663 -212.635338) (xy 36.430598 -212.581567) (xy 36.442321 -212.528943) (xy 36.461581 -212.478586)
			(xy 36.487967 -212.431569) (xy 36.520919 -212.388896) (xy 36.559732 -212.351475) (xy 36.60358 -212.320105)
			(xy 36.651528 -212.295453) (xy 36.702555 -212.278045) (xy 36.755573 -212.268252) (xy 36.809452 -212.266283)
			(xy 36.863043 -212.27218) (xy 36.915204 -212.285816) (xy 36.964824 -212.306903) (xy 37.010845 -212.334989)
			(xy 37.052287 -212.369477) (xy 37.088265 -212.409631) (xy 37.118013 -212.454595) (xy 37.140898 -212.503412)
			(xy 37.15643 -212.555041) (xy 37.16428 -212.608381) (xy 37.164772 -212.635338) (xy 43.970717 -212.635338)
			(xy 43.974652 -212.581567) (xy 43.986375 -212.528943) (xy 44.005635 -212.478586) (xy 44.032021 -212.431569)
			(xy 44.064973 -212.388896) (xy 44.103786 -212.351475) (xy 44.147634 -212.320105) (xy 44.195582 -212.295453)
			(xy 44.246609 -212.278045) (xy 44.299627 -212.268252) (xy 44.353506 -212.266283) (xy 44.407097 -212.27218)
			(xy 44.459258 -212.285816) (xy 44.508878 -212.306903) (xy 44.554899 -212.334989) (xy 44.596341 -212.369477)
			(xy 44.632319 -212.409631) (xy 44.662067 -212.454595) (xy 44.684952 -212.503412) (xy 44.700484 -212.555041)
			(xy 44.708334 -212.608381) (xy 44.708826 -212.635338) (xy 44.708334 -212.662295) (xy 44.700484 -212.715635)
			(xy 44.684952 -212.767264) (xy 44.662067 -212.816081) (xy 44.632319 -212.861045) (xy 44.596341 -212.901199)
			(xy 44.554899 -212.935687) (xy 44.508878 -212.963773) (xy 44.459258 -212.98486) (xy 44.407097 -212.998496)
			(xy 44.353506 -213.004393) (xy 44.299627 -213.002424) (xy 44.246609 -212.992631) (xy 44.195582 -212.975223)
			(xy 44.147634 -212.950571) (xy 44.103786 -212.919201) (xy 44.064973 -212.88178) (xy 44.032021 -212.839107)
			(xy 44.005635 -212.79209) (xy 43.986375 -212.741733) (xy 43.974652 -212.689109) (xy 43.970717 -212.635338)
			(xy 37.164772 -212.635338) (xy 37.16428 -212.662295) (xy 37.15643 -212.715635) (xy 37.140898 -212.767264)
			(xy 37.118013 -212.816081) (xy 37.088265 -212.861045) (xy 37.052287 -212.901199) (xy 37.010845 -212.935687)
			(xy 36.964824 -212.963773) (xy 36.915204 -212.98486) (xy 36.863043 -212.998496) (xy 36.809452 -213.004393)
			(xy 36.755573 -213.002424) (xy 36.702555 -212.992631) (xy 36.651528 -212.975223) (xy 36.60358 -212.950571)
			(xy 36.559732 -212.919201) (xy 36.520919 -212.88178) (xy 36.487967 -212.839107) (xy 36.461581 -212.79209)
			(xy 36.442321 -212.741733) (xy 36.430598 -212.689109) (xy 36.426663 -212.635338) (xy 29.620972 -212.635338)
			(xy 29.62048 -212.662295) (xy 29.61263 -212.715635) (xy 29.597098 -212.767264) (xy 29.574213 -212.816081)
			(xy 29.544465 -212.861045) (xy 29.508487 -212.901199) (xy 29.467045 -212.935687) (xy 29.421024 -212.963773)
			(xy 29.371404 -212.98486) (xy 29.319243 -212.998496) (xy 29.265652 -213.004393) (xy 29.211773 -213.002424)
			(xy 29.158755 -212.992631) (xy 29.107728 -212.975223) (xy 29.05978 -212.950571) (xy 29.015932 -212.919201)
			(xy 28.977119 -212.88178) (xy 28.944167 -212.839107) (xy 28.917781 -212.79209) (xy 28.898521 -212.741733)
			(xy 28.886798 -212.689109) (xy 28.882863 -212.635338) (xy 22.076918 -212.635338) (xy 22.076426 -212.662295)
			(xy 22.068576 -212.715635) (xy 22.053044 -212.767264) (xy 22.030159 -212.816081) (xy 22.000411 -212.861045)
			(xy 21.964433 -212.901199) (xy 21.922991 -212.935687) (xy 21.87697 -212.963773) (xy 21.82735 -212.98486)
			(xy 21.775189 -212.998496) (xy 21.721598 -213.004393) (xy 21.667719 -213.002424) (xy 21.614701 -212.992631)
			(xy 21.563674 -212.975223) (xy 21.515726 -212.950571) (xy 21.471878 -212.919201) (xy 21.433065 -212.88178)
			(xy 21.400113 -212.839107) (xy 21.373727 -212.79209) (xy 21.354467 -212.741733) (xy 21.342744 -212.689109)
			(xy 21.338809 -212.635338) (xy 15.598394 -212.635338) (xy 15.598394 -213.485222) (xy 17.238741 -213.485222)
			(xy 17.242676 -213.431451) (xy 17.254399 -213.378827) (xy 17.273659 -213.32847) (xy 17.300045 -213.281453)
			(xy 17.332997 -213.23878) (xy 17.37181 -213.201359) (xy 17.415658 -213.169989) (xy 17.463606 -213.145337)
			(xy 17.514633 -213.127929) (xy 17.567651 -213.118136) (xy 17.62153 -213.116167) (xy 17.675121 -213.122064)
			(xy 17.727282 -213.1357) (xy 17.776902 -213.156787) (xy 17.822923 -213.184873) (xy 17.864365 -213.219361)
			(xy 17.900343 -213.259515) (xy 17.930091 -213.304479) (xy 17.952976 -213.353296) (xy 17.968508 -213.404925)
			(xy 17.976358 -213.458265) (xy 17.97685 -213.485222) (xy 24.782795 -213.485222) (xy 24.78673 -213.431451)
			(xy 24.798453 -213.378827) (xy 24.817713 -213.32847) (xy 24.844099 -213.281453) (xy 24.877051 -213.23878)
			(xy 24.915864 -213.201359) (xy 24.959712 -213.169989) (xy 25.00766 -213.145337) (xy 25.058687 -213.127929)
			(xy 25.111705 -213.118136) (xy 25.165584 -213.116167) (xy 25.219175 -213.122064) (xy 25.271336 -213.1357)
			(xy 25.320956 -213.156787) (xy 25.366977 -213.184873) (xy 25.408419 -213.219361) (xy 25.444397 -213.259515)
			(xy 25.474145 -213.304479) (xy 25.49703 -213.353296) (xy 25.512562 -213.404925) (xy 25.520412 -213.458265)
			(xy 25.520904 -213.485222) (xy 32.326595 -213.485222) (xy 32.33053 -213.431451) (xy 32.342253 -213.378827)
			(xy 32.361513 -213.32847) (xy 32.387899 -213.281453) (xy 32.420851 -213.23878) (xy 32.459664 -213.201359)
			(xy 32.503512 -213.169989) (xy 32.55146 -213.145337) (xy 32.602487 -213.127929) (xy 32.655505 -213.118136)
			(xy 32.709384 -213.116167) (xy 32.762975 -213.122064) (xy 32.815136 -213.1357) (xy 32.864756 -213.156787)
			(xy 32.910777 -213.184873) (xy 32.952219 -213.219361) (xy 32.988197 -213.259515) (xy 33.017945 -213.304479)
			(xy 33.04083 -213.353296) (xy 33.056362 -213.404925) (xy 33.064212 -213.458265) (xy 33.064704 -213.485222)
			(xy 39.870649 -213.485222) (xy 39.874584 -213.431451) (xy 39.886307 -213.378827) (xy 39.905567 -213.32847)
			(xy 39.931953 -213.281453) (xy 39.964905 -213.23878) (xy 40.003718 -213.201359) (xy 40.047566 -213.169989)
			(xy 40.095514 -213.145337) (xy 40.146541 -213.127929) (xy 40.199559 -213.118136) (xy 40.253438 -213.116167)
			(xy 40.307029 -213.122064) (xy 40.35919 -213.1357) (xy 40.40881 -213.156787) (xy 40.454831 -213.184873)
			(xy 40.496273 -213.219361) (xy 40.532251 -213.259515) (xy 40.561999 -213.304479) (xy 40.584884 -213.353296)
			(xy 40.600416 -213.404925) (xy 40.608266 -213.458265) (xy 40.608758 -213.485222) (xy 40.608266 -213.512179)
			(xy 40.600416 -213.565519) (xy 40.584884 -213.617148) (xy 40.561999 -213.665965) (xy 40.532251 -213.710929)
			(xy 40.496273 -213.751083) (xy 40.454831 -213.785571) (xy 40.40881 -213.813657) (xy 40.35919 -213.834744)
			(xy 40.307029 -213.84838) (xy 40.253438 -213.854277) (xy 40.199559 -213.852308) (xy 40.146541 -213.842515)
			(xy 40.095514 -213.825107) (xy 40.047566 -213.800455) (xy 40.003718 -213.769085) (xy 39.964905 -213.731664)
			(xy 39.931953 -213.688991) (xy 39.905567 -213.641974) (xy 39.886307 -213.591617) (xy 39.874584 -213.538993)
			(xy 39.870649 -213.485222) (xy 33.064704 -213.485222) (xy 33.064212 -213.512179) (xy 33.056362 -213.565519)
			(xy 33.04083 -213.617148) (xy 33.017945 -213.665965) (xy 32.988197 -213.710929) (xy 32.952219 -213.751083)
			(xy 32.910777 -213.785571) (xy 32.864756 -213.813657) (xy 32.815136 -213.834744) (xy 32.762975 -213.84838)
			(xy 32.709384 -213.854277) (xy 32.655505 -213.852308) (xy 32.602487 -213.842515) (xy 32.55146 -213.825107)
			(xy 32.503512 -213.800455) (xy 32.459664 -213.769085) (xy 32.420851 -213.731664) (xy 32.387899 -213.688991)
			(xy 32.361513 -213.641974) (xy 32.342253 -213.591617) (xy 32.33053 -213.538993) (xy 32.326595 -213.485222)
			(xy 25.520904 -213.485222) (xy 25.520412 -213.512179) (xy 25.512562 -213.565519) (xy 25.49703 -213.617148)
			(xy 25.474145 -213.665965) (xy 25.444397 -213.710929) (xy 25.408419 -213.751083) (xy 25.366977 -213.785571)
			(xy 25.320956 -213.813657) (xy 25.271336 -213.834744) (xy 25.219175 -213.84838) (xy 25.165584 -213.854277)
			(xy 25.111705 -213.852308) (xy 25.058687 -213.842515) (xy 25.00766 -213.825107) (xy 24.959712 -213.800455)
			(xy 24.915864 -213.769085) (xy 24.877051 -213.731664) (xy 24.844099 -213.688991) (xy 24.817713 -213.641974)
			(xy 24.798453 -213.591617) (xy 24.78673 -213.538993) (xy 24.782795 -213.485222) (xy 17.97685 -213.485222)
			(xy 17.976358 -213.512179) (xy 17.968508 -213.565519) (xy 17.952976 -213.617148) (xy 17.930091 -213.665965)
			(xy 17.900343 -213.710929) (xy 17.864365 -213.751083) (xy 17.822923 -213.785571) (xy 17.776902 -213.813657)
			(xy 17.727282 -213.834744) (xy 17.675121 -213.84838) (xy 17.62153 -213.854277) (xy 17.567651 -213.852308)
			(xy 17.514633 -213.842515) (xy 17.463606 -213.825107) (xy 17.415658 -213.800455) (xy 17.37181 -213.769085)
			(xy 17.332997 -213.731664) (xy 17.300045 -213.688991) (xy 17.273659 -213.641974) (xy 17.254399 -213.591617)
			(xy 17.242676 -213.538993) (xy 17.238741 -213.485222) (xy 15.598394 -213.485222) (xy 15.598394 -214.33536)
			(xy 21.338809 -214.33536) (xy 21.342744 -214.281589) (xy 21.354467 -214.228965) (xy 21.373727 -214.178608)
			(xy 21.400113 -214.131591) (xy 21.433065 -214.088918) (xy 21.471878 -214.051497) (xy 21.515726 -214.020127)
			(xy 21.563674 -213.995475) (xy 21.614701 -213.978067) (xy 21.667719 -213.968274) (xy 21.721598 -213.966305)
			(xy 21.775189 -213.972202) (xy 21.82735 -213.985838) (xy 21.87697 -214.006925) (xy 21.922991 -214.035011)
			(xy 21.964433 -214.069499) (xy 22.000411 -214.109653) (xy 22.030159 -214.154617) (xy 22.053044 -214.203434)
			(xy 22.068576 -214.255063) (xy 22.076426 -214.308403) (xy 22.076918 -214.33536) (xy 28.882863 -214.33536)
			(xy 28.886798 -214.281589) (xy 28.898521 -214.228965) (xy 28.917781 -214.178608) (xy 28.944167 -214.131591)
			(xy 28.977119 -214.088918) (xy 29.015932 -214.051497) (xy 29.05978 -214.020127) (xy 29.107728 -213.995475)
			(xy 29.158755 -213.978067) (xy 29.211773 -213.968274) (xy 29.265652 -213.966305) (xy 29.319243 -213.972202)
			(xy 29.371404 -213.985838) (xy 29.421024 -214.006925) (xy 29.467045 -214.035011) (xy 29.508487 -214.069499)
			(xy 29.544465 -214.109653) (xy 29.574213 -214.154617) (xy 29.597098 -214.203434) (xy 29.61263 -214.255063)
			(xy 29.62048 -214.308403) (xy 29.620972 -214.33536) (xy 36.426663 -214.33536) (xy 36.430598 -214.281589)
			(xy 36.442321 -214.228965) (xy 36.461581 -214.178608) (xy 36.487967 -214.131591) (xy 36.520919 -214.088918)
			(xy 36.559732 -214.051497) (xy 36.60358 -214.020127) (xy 36.651528 -213.995475) (xy 36.702555 -213.978067)
			(xy 36.755573 -213.968274) (xy 36.809452 -213.966305) (xy 36.863043 -213.972202) (xy 36.915204 -213.985838)
			(xy 36.964824 -214.006925) (xy 37.010845 -214.035011) (xy 37.052287 -214.069499) (xy 37.088265 -214.109653)
			(xy 37.118013 -214.154617) (xy 37.140898 -214.203434) (xy 37.15643 -214.255063) (xy 37.16428 -214.308403)
			(xy 37.164772 -214.33536) (xy 43.970717 -214.33536) (xy 43.974652 -214.281589) (xy 43.986375 -214.228965)
			(xy 44.005635 -214.178608) (xy 44.032021 -214.131591) (xy 44.064973 -214.088918) (xy 44.103786 -214.051497)
			(xy 44.147634 -214.020127) (xy 44.195582 -213.995475) (xy 44.246609 -213.978067) (xy 44.299627 -213.968274)
			(xy 44.353506 -213.966305) (xy 44.407097 -213.972202) (xy 44.459258 -213.985838) (xy 44.508878 -214.006925)
			(xy 44.554899 -214.035011) (xy 44.596341 -214.069499) (xy 44.632319 -214.109653) (xy 44.662067 -214.154617)
			(xy 44.684952 -214.203434) (xy 44.700484 -214.255063) (xy 44.708334 -214.308403) (xy 44.708826 -214.33536)
			(xy 44.708334 -214.362317) (xy 44.700484 -214.415657) (xy 44.684952 -214.467286) (xy 44.662067 -214.516103)
			(xy 44.632319 -214.561067) (xy 44.596341 -214.601221) (xy 44.554899 -214.635709) (xy 44.508878 -214.663795)
			(xy 44.459258 -214.684882) (xy 44.407097 -214.698518) (xy 44.353506 -214.704415) (xy 44.299627 -214.702446)
			(xy 44.246609 -214.692653) (xy 44.195582 -214.675245) (xy 44.147634 -214.650593) (xy 44.103786 -214.619223)
			(xy 44.064973 -214.581802) (xy 44.032021 -214.539129) (xy 44.005635 -214.492112) (xy 43.986375 -214.441755)
			(xy 43.974652 -214.389131) (xy 43.970717 -214.33536) (xy 37.164772 -214.33536) (xy 37.16428 -214.362317)
			(xy 37.15643 -214.415657) (xy 37.140898 -214.467286) (xy 37.118013 -214.516103) (xy 37.088265 -214.561067)
			(xy 37.052287 -214.601221) (xy 37.010845 -214.635709) (xy 36.964824 -214.663795) (xy 36.915204 -214.684882)
			(xy 36.863043 -214.698518) (xy 36.809452 -214.704415) (xy 36.755573 -214.702446) (xy 36.702555 -214.692653)
			(xy 36.651528 -214.675245) (xy 36.60358 -214.650593) (xy 36.559732 -214.619223) (xy 36.520919 -214.581802)
			(xy 36.487967 -214.539129) (xy 36.461581 -214.492112) (xy 36.442321 -214.441755) (xy 36.430598 -214.389131)
			(xy 36.426663 -214.33536) (xy 29.620972 -214.33536) (xy 29.62048 -214.362317) (xy 29.61263 -214.415657)
			(xy 29.597098 -214.467286) (xy 29.574213 -214.516103) (xy 29.544465 -214.561067) (xy 29.508487 -214.601221)
			(xy 29.467045 -214.635709) (xy 29.421024 -214.663795) (xy 29.371404 -214.684882) (xy 29.319243 -214.698518)
			(xy 29.265652 -214.704415) (xy 29.211773 -214.702446) (xy 29.158755 -214.692653) (xy 29.107728 -214.675245)
			(xy 29.05978 -214.650593) (xy 29.015932 -214.619223) (xy 28.977119 -214.581802) (xy 28.944167 -214.539129)
			(xy 28.917781 -214.492112) (xy 28.898521 -214.441755) (xy 28.886798 -214.389131) (xy 28.882863 -214.33536)
			(xy 22.076918 -214.33536) (xy 22.076426 -214.362317) (xy 22.068576 -214.415657) (xy 22.053044 -214.467286)
			(xy 22.030159 -214.516103) (xy 22.000411 -214.561067) (xy 21.964433 -214.601221) (xy 21.922991 -214.635709)
			(xy 21.87697 -214.663795) (xy 21.82735 -214.684882) (xy 21.775189 -214.698518) (xy 21.721598 -214.704415)
			(xy 21.667719 -214.702446) (xy 21.614701 -214.692653) (xy 21.563674 -214.675245) (xy 21.515726 -214.650593)
			(xy 21.471878 -214.619223) (xy 21.433065 -214.581802) (xy 21.400113 -214.539129) (xy 21.373727 -214.492112)
			(xy 21.354467 -214.441755) (xy 21.342744 -214.389131) (xy 21.338809 -214.33536) (xy 15.598394 -214.33536)
			(xy 15.598394 -215.185244) (xy 17.238741 -215.185244) (xy 17.242676 -215.131473) (xy 17.254399 -215.078849)
			(xy 17.273659 -215.028492) (xy 17.300045 -214.981475) (xy 17.332997 -214.938802) (xy 17.37181 -214.901381)
			(xy 17.415658 -214.870011) (xy 17.463606 -214.845359) (xy 17.514633 -214.827951) (xy 17.567651 -214.818158)
			(xy 17.62153 -214.816189) (xy 17.675121 -214.822086) (xy 17.727282 -214.835722) (xy 17.776902 -214.856809)
			(xy 17.822923 -214.884895) (xy 17.864365 -214.919383) (xy 17.900343 -214.959537) (xy 17.930091 -215.004501)
			(xy 17.952976 -215.053318) (xy 17.968508 -215.104947) (xy 17.976358 -215.158287) (xy 17.97685 -215.185244)
			(xy 24.782795 -215.185244) (xy 24.78673 -215.131473) (xy 24.798453 -215.078849) (xy 24.817713 -215.028492)
			(xy 24.844099 -214.981475) (xy 24.877051 -214.938802) (xy 24.915864 -214.901381) (xy 24.959712 -214.870011)
			(xy 25.00766 -214.845359) (xy 25.058687 -214.827951) (xy 25.111705 -214.818158) (xy 25.165584 -214.816189)
			(xy 25.219175 -214.822086) (xy 25.271336 -214.835722) (xy 25.320956 -214.856809) (xy 25.366977 -214.884895)
			(xy 25.408419 -214.919383) (xy 25.444397 -214.959537) (xy 25.474145 -215.004501) (xy 25.49703 -215.053318)
			(xy 25.512562 -215.104947) (xy 25.520412 -215.158287) (xy 25.520904 -215.185244) (xy 32.326595 -215.185244)
			(xy 32.33053 -215.131473) (xy 32.342253 -215.078849) (xy 32.361513 -215.028492) (xy 32.387899 -214.981475)
			(xy 32.420851 -214.938802) (xy 32.459664 -214.901381) (xy 32.503512 -214.870011) (xy 32.55146 -214.845359)
			(xy 32.602487 -214.827951) (xy 32.655505 -214.818158) (xy 32.709384 -214.816189) (xy 32.762975 -214.822086)
			(xy 32.815136 -214.835722) (xy 32.864756 -214.856809) (xy 32.910777 -214.884895) (xy 32.952219 -214.919383)
			(xy 32.988197 -214.959537) (xy 33.017945 -215.004501) (xy 33.04083 -215.053318) (xy 33.056362 -215.104947)
			(xy 33.064212 -215.158287) (xy 33.064704 -215.185244) (xy 39.870649 -215.185244) (xy 39.874584 -215.131473)
			(xy 39.886307 -215.078849) (xy 39.905567 -215.028492) (xy 39.931953 -214.981475) (xy 39.964905 -214.938802)
			(xy 40.003718 -214.901381) (xy 40.047566 -214.870011) (xy 40.095514 -214.845359) (xy 40.146541 -214.827951)
			(xy 40.199559 -214.818158) (xy 40.253438 -214.816189) (xy 40.307029 -214.822086) (xy 40.35919 -214.835722)
			(xy 40.40881 -214.856809) (xy 40.454831 -214.884895) (xy 40.496273 -214.919383) (xy 40.532251 -214.959537)
			(xy 40.561999 -215.004501) (xy 40.584884 -215.053318) (xy 40.600416 -215.104947) (xy 40.608266 -215.158287)
			(xy 40.608758 -215.185244) (xy 40.608266 -215.212201) (xy 40.600416 -215.265541) (xy 40.584884 -215.31717)
			(xy 40.561999 -215.365987) (xy 40.532251 -215.410951) (xy 40.496273 -215.451105) (xy 40.454831 -215.485593)
			(xy 40.40881 -215.513679) (xy 40.35919 -215.534766) (xy 40.307029 -215.548402) (xy 40.253438 -215.554299)
			(xy 40.199559 -215.55233) (xy 40.146541 -215.542537) (xy 40.095514 -215.525129) (xy 40.047566 -215.500477)
			(xy 40.003718 -215.469107) (xy 39.964905 -215.431686) (xy 39.931953 -215.389013) (xy 39.905567 -215.341996)
			(xy 39.886307 -215.291639) (xy 39.874584 -215.239015) (xy 39.870649 -215.185244) (xy 33.064704 -215.185244)
			(xy 33.064212 -215.212201) (xy 33.056362 -215.265541) (xy 33.04083 -215.31717) (xy 33.017945 -215.365987)
			(xy 32.988197 -215.410951) (xy 32.952219 -215.451105) (xy 32.910777 -215.485593) (xy 32.864756 -215.513679)
			(xy 32.815136 -215.534766) (xy 32.762975 -215.548402) (xy 32.709384 -215.554299) (xy 32.655505 -215.55233)
			(xy 32.602487 -215.542537) (xy 32.55146 -215.525129) (xy 32.503512 -215.500477) (xy 32.459664 -215.469107)
			(xy 32.420851 -215.431686) (xy 32.387899 -215.389013) (xy 32.361513 -215.341996) (xy 32.342253 -215.291639)
			(xy 32.33053 -215.239015) (xy 32.326595 -215.185244) (xy 25.520904 -215.185244) (xy 25.520412 -215.212201)
			(xy 25.512562 -215.265541) (xy 25.49703 -215.31717) (xy 25.474145 -215.365987) (xy 25.444397 -215.410951)
			(xy 25.408419 -215.451105) (xy 25.366977 -215.485593) (xy 25.320956 -215.513679) (xy 25.271336 -215.534766)
			(xy 25.219175 -215.548402) (xy 25.165584 -215.554299) (xy 25.111705 -215.55233) (xy 25.058687 -215.542537)
			(xy 25.00766 -215.525129) (xy 24.959712 -215.500477) (xy 24.915864 -215.469107) (xy 24.877051 -215.431686)
			(xy 24.844099 -215.389013) (xy 24.817713 -215.341996) (xy 24.798453 -215.291639) (xy 24.78673 -215.239015)
			(xy 24.782795 -215.185244) (xy 17.97685 -215.185244) (xy 17.976358 -215.212201) (xy 17.968508 -215.265541)
			(xy 17.952976 -215.31717) (xy 17.930091 -215.365987) (xy 17.900343 -215.410951) (xy 17.864365 -215.451105)
			(xy 17.822923 -215.485593) (xy 17.776902 -215.513679) (xy 17.727282 -215.534766) (xy 17.675121 -215.548402)
			(xy 17.62153 -215.554299) (xy 17.567651 -215.55233) (xy 17.514633 -215.542537) (xy 17.463606 -215.525129)
			(xy 17.415658 -215.500477) (xy 17.37181 -215.469107) (xy 17.332997 -215.431686) (xy 17.300045 -215.389013)
			(xy 17.273659 -215.341996) (xy 17.254399 -215.291639) (xy 17.242676 -215.239015) (xy 17.238741 -215.185244)
			(xy 15.598394 -215.185244) (xy 15.598394 -216.035382) (xy 21.338809 -216.035382) (xy 21.342744 -215.981611)
			(xy 21.354467 -215.928987) (xy 21.373727 -215.87863) (xy 21.400113 -215.831613) (xy 21.433065 -215.78894)
			(xy 21.471878 -215.751519) (xy 21.515726 -215.720149) (xy 21.563674 -215.695497) (xy 21.614701 -215.678089)
			(xy 21.667719 -215.668296) (xy 21.721598 -215.666327) (xy 21.775189 -215.672224) (xy 21.82735 -215.68586)
			(xy 21.87697 -215.706947) (xy 21.922991 -215.735033) (xy 21.964433 -215.769521) (xy 22.000411 -215.809675)
			(xy 22.030159 -215.854639) (xy 22.053044 -215.903456) (xy 22.068576 -215.955085) (xy 22.076426 -216.008425)
			(xy 22.076918 -216.035382) (xy 28.882863 -216.035382) (xy 28.886798 -215.981611) (xy 28.898521 -215.928987)
			(xy 28.917781 -215.87863) (xy 28.944167 -215.831613) (xy 28.977119 -215.78894) (xy 29.015932 -215.751519)
			(xy 29.05978 -215.720149) (xy 29.107728 -215.695497) (xy 29.158755 -215.678089) (xy 29.211773 -215.668296)
			(xy 29.265652 -215.666327) (xy 29.319243 -215.672224) (xy 29.371404 -215.68586) (xy 29.421024 -215.706947)
			(xy 29.467045 -215.735033) (xy 29.508487 -215.769521) (xy 29.544465 -215.809675) (xy 29.574213 -215.854639)
			(xy 29.597098 -215.903456) (xy 29.61263 -215.955085) (xy 29.62048 -216.008425) (xy 29.620972 -216.035382)
			(xy 36.426663 -216.035382) (xy 36.430598 -215.981611) (xy 36.442321 -215.928987) (xy 36.461581 -215.87863)
			(xy 36.487967 -215.831613) (xy 36.520919 -215.78894) (xy 36.559732 -215.751519) (xy 36.60358 -215.720149)
			(xy 36.651528 -215.695497) (xy 36.702555 -215.678089) (xy 36.755573 -215.668296) (xy 36.809452 -215.666327)
			(xy 36.863043 -215.672224) (xy 36.915204 -215.68586) (xy 36.964824 -215.706947) (xy 37.010845 -215.735033)
			(xy 37.052287 -215.769521) (xy 37.088265 -215.809675) (xy 37.118013 -215.854639) (xy 37.140898 -215.903456)
			(xy 37.15643 -215.955085) (xy 37.16428 -216.008425) (xy 37.164772 -216.035382) (xy 43.970717 -216.035382)
			(xy 43.974652 -215.981611) (xy 43.986375 -215.928987) (xy 44.005635 -215.87863) (xy 44.032021 -215.831613)
			(xy 44.064973 -215.78894) (xy 44.103786 -215.751519) (xy 44.147634 -215.720149) (xy 44.195582 -215.695497)
			(xy 44.246609 -215.678089) (xy 44.299627 -215.668296) (xy 44.353506 -215.666327) (xy 44.407097 -215.672224)
			(xy 44.459258 -215.68586) (xy 44.508878 -215.706947) (xy 44.554899 -215.735033) (xy 44.596341 -215.769521)
			(xy 44.632319 -215.809675) (xy 44.662067 -215.854639) (xy 44.684952 -215.903456) (xy 44.700484 -215.955085)
			(xy 44.708334 -216.008425) (xy 44.708826 -216.035382) (xy 44.708334 -216.062339) (xy 44.700484 -216.115679)
			(xy 44.684952 -216.167308) (xy 44.662067 -216.216125) (xy 44.632319 -216.261089) (xy 44.596341 -216.301243)
			(xy 44.554899 -216.335731) (xy 44.508878 -216.363817) (xy 44.459258 -216.384904) (xy 44.407097 -216.39854)
			(xy 44.353506 -216.404437) (xy 44.299627 -216.402468) (xy 44.246609 -216.392675) (xy 44.195582 -216.375267)
			(xy 44.147634 -216.350615) (xy 44.103786 -216.319245) (xy 44.064973 -216.281824) (xy 44.032021 -216.239151)
			(xy 44.005635 -216.192134) (xy 43.986375 -216.141777) (xy 43.974652 -216.089153) (xy 43.970717 -216.035382)
			(xy 37.164772 -216.035382) (xy 37.16428 -216.062339) (xy 37.15643 -216.115679) (xy 37.140898 -216.167308)
			(xy 37.118013 -216.216125) (xy 37.088265 -216.261089) (xy 37.052287 -216.301243) (xy 37.010845 -216.335731)
			(xy 36.964824 -216.363817) (xy 36.915204 -216.384904) (xy 36.863043 -216.39854) (xy 36.809452 -216.404437)
			(xy 36.755573 -216.402468) (xy 36.702555 -216.392675) (xy 36.651528 -216.375267) (xy 36.60358 -216.350615)
			(xy 36.559732 -216.319245) (xy 36.520919 -216.281824) (xy 36.487967 -216.239151) (xy 36.461581 -216.192134)
			(xy 36.442321 -216.141777) (xy 36.430598 -216.089153) (xy 36.426663 -216.035382) (xy 29.620972 -216.035382)
			(xy 29.62048 -216.062339) (xy 29.61263 -216.115679) (xy 29.597098 -216.167308) (xy 29.574213 -216.216125)
			(xy 29.544465 -216.261089) (xy 29.508487 -216.301243) (xy 29.467045 -216.335731) (xy 29.421024 -216.363817)
			(xy 29.371404 -216.384904) (xy 29.319243 -216.39854) (xy 29.265652 -216.404437) (xy 29.211773 -216.402468)
			(xy 29.158755 -216.392675) (xy 29.107728 -216.375267) (xy 29.05978 -216.350615) (xy 29.015932 -216.319245)
			(xy 28.977119 -216.281824) (xy 28.944167 -216.239151) (xy 28.917781 -216.192134) (xy 28.898521 -216.141777)
			(xy 28.886798 -216.089153) (xy 28.882863 -216.035382) (xy 22.076918 -216.035382) (xy 22.076426 -216.062339)
			(xy 22.068576 -216.115679) (xy 22.053044 -216.167308) (xy 22.030159 -216.216125) (xy 22.000411 -216.261089)
			(xy 21.964433 -216.301243) (xy 21.922991 -216.335731) (xy 21.87697 -216.363817) (xy 21.82735 -216.384904)
			(xy 21.775189 -216.39854) (xy 21.721598 -216.404437) (xy 21.667719 -216.402468) (xy 21.614701 -216.392675)
			(xy 21.563674 -216.375267) (xy 21.515726 -216.350615) (xy 21.471878 -216.319245) (xy 21.433065 -216.281824)
			(xy 21.400113 -216.239151) (xy 21.373727 -216.192134) (xy 21.354467 -216.141777) (xy 21.342744 -216.089153)
			(xy 21.338809 -216.035382) (xy 15.598394 -216.035382) (xy 15.598394 -216.885266) (xy 17.238741 -216.885266)
			(xy 17.242676 -216.831495) (xy 17.254399 -216.778871) (xy 17.273659 -216.728514) (xy 17.300045 -216.681497)
			(xy 17.332997 -216.638824) (xy 17.37181 -216.601403) (xy 17.415658 -216.570033) (xy 17.463606 -216.545381)
			(xy 17.514633 -216.527973) (xy 17.567651 -216.51818) (xy 17.62153 -216.516211) (xy 17.675121 -216.522108)
			(xy 17.727282 -216.535744) (xy 17.776902 -216.556831) (xy 17.822923 -216.584917) (xy 17.864365 -216.619405)
			(xy 17.900343 -216.659559) (xy 17.930091 -216.704523) (xy 17.952976 -216.75334) (xy 17.968508 -216.804969)
			(xy 17.976358 -216.858309) (xy 17.97685 -216.885266) (xy 24.782795 -216.885266) (xy 24.78673 -216.831495)
			(xy 24.798453 -216.778871) (xy 24.817713 -216.728514) (xy 24.844099 -216.681497) (xy 24.877051 -216.638824)
			(xy 24.915864 -216.601403) (xy 24.959712 -216.570033) (xy 25.00766 -216.545381) (xy 25.058687 -216.527973)
			(xy 25.111705 -216.51818) (xy 25.165584 -216.516211) (xy 25.219175 -216.522108) (xy 25.271336 -216.535744)
			(xy 25.320956 -216.556831) (xy 25.366977 -216.584917) (xy 25.408419 -216.619405) (xy 25.444397 -216.659559)
			(xy 25.474145 -216.704523) (xy 25.49703 -216.75334) (xy 25.512562 -216.804969) (xy 25.520412 -216.858309)
			(xy 25.520904 -216.885266) (xy 32.326595 -216.885266) (xy 32.33053 -216.831495) (xy 32.342253 -216.778871)
			(xy 32.361513 -216.728514) (xy 32.387899 -216.681497) (xy 32.420851 -216.638824) (xy 32.459664 -216.601403)
			(xy 32.503512 -216.570033) (xy 32.55146 -216.545381) (xy 32.602487 -216.527973) (xy 32.655505 -216.51818)
			(xy 32.709384 -216.516211) (xy 32.762975 -216.522108) (xy 32.815136 -216.535744) (xy 32.864756 -216.556831)
			(xy 32.910777 -216.584917) (xy 32.952219 -216.619405) (xy 32.988197 -216.659559) (xy 33.017945 -216.704523)
			(xy 33.04083 -216.75334) (xy 33.056362 -216.804969) (xy 33.064212 -216.858309) (xy 33.064704 -216.885266)
			(xy 39.870649 -216.885266) (xy 39.874584 -216.831495) (xy 39.886307 -216.778871) (xy 39.905567 -216.728514)
			(xy 39.931953 -216.681497) (xy 39.964905 -216.638824) (xy 40.003718 -216.601403) (xy 40.047566 -216.570033)
			(xy 40.095514 -216.545381) (xy 40.146541 -216.527973) (xy 40.199559 -216.51818) (xy 40.253438 -216.516211)
			(xy 40.307029 -216.522108) (xy 40.35919 -216.535744) (xy 40.40881 -216.556831) (xy 40.454831 -216.584917)
			(xy 40.496273 -216.619405) (xy 40.532251 -216.659559) (xy 40.561999 -216.704523) (xy 40.584884 -216.75334)
			(xy 40.600416 -216.804969) (xy 40.608266 -216.858309) (xy 40.608758 -216.885266) (xy 40.608266 -216.912223)
			(xy 40.600416 -216.965563) (xy 40.584884 -217.017192) (xy 40.561999 -217.066009) (xy 40.532251 -217.110973)
			(xy 40.496273 -217.151127) (xy 40.454831 -217.185615) (xy 40.40881 -217.213701) (xy 40.35919 -217.234788)
			(xy 40.307029 -217.248424) (xy 40.253438 -217.254321) (xy 40.199559 -217.252352) (xy 40.146541 -217.242559)
			(xy 40.095514 -217.225151) (xy 40.047566 -217.200499) (xy 40.003718 -217.169129) (xy 39.964905 -217.131708)
			(xy 39.931953 -217.089035) (xy 39.905567 -217.042018) (xy 39.886307 -216.991661) (xy 39.874584 -216.939037)
			(xy 39.870649 -216.885266) (xy 33.064704 -216.885266) (xy 33.064212 -216.912223) (xy 33.056362 -216.965563)
			(xy 33.04083 -217.017192) (xy 33.017945 -217.066009) (xy 32.988197 -217.110973) (xy 32.952219 -217.151127)
			(xy 32.910777 -217.185615) (xy 32.864756 -217.213701) (xy 32.815136 -217.234788) (xy 32.762975 -217.248424)
			(xy 32.709384 -217.254321) (xy 32.655505 -217.252352) (xy 32.602487 -217.242559) (xy 32.55146 -217.225151)
			(xy 32.503512 -217.200499) (xy 32.459664 -217.169129) (xy 32.420851 -217.131708) (xy 32.387899 -217.089035)
			(xy 32.361513 -217.042018) (xy 32.342253 -216.991661) (xy 32.33053 -216.939037) (xy 32.326595 -216.885266)
			(xy 25.520904 -216.885266) (xy 25.520412 -216.912223) (xy 25.512562 -216.965563) (xy 25.49703 -217.017192)
			(xy 25.474145 -217.066009) (xy 25.444397 -217.110973) (xy 25.408419 -217.151127) (xy 25.366977 -217.185615)
			(xy 25.320956 -217.213701) (xy 25.271336 -217.234788) (xy 25.219175 -217.248424) (xy 25.165584 -217.254321)
			(xy 25.111705 -217.252352) (xy 25.058687 -217.242559) (xy 25.00766 -217.225151) (xy 24.959712 -217.200499)
			(xy 24.915864 -217.169129) (xy 24.877051 -217.131708) (xy 24.844099 -217.089035) (xy 24.817713 -217.042018)
			(xy 24.798453 -216.991661) (xy 24.78673 -216.939037) (xy 24.782795 -216.885266) (xy 17.97685 -216.885266)
			(xy 17.976358 -216.912223) (xy 17.968508 -216.965563) (xy 17.952976 -217.017192) (xy 17.930091 -217.066009)
			(xy 17.900343 -217.110973) (xy 17.864365 -217.151127) (xy 17.822923 -217.185615) (xy 17.776902 -217.213701)
			(xy 17.727282 -217.234788) (xy 17.675121 -217.248424) (xy 17.62153 -217.254321) (xy 17.567651 -217.252352)
			(xy 17.514633 -217.242559) (xy 17.463606 -217.225151) (xy 17.415658 -217.200499) (xy 17.37181 -217.169129)
			(xy 17.332997 -217.131708) (xy 17.300045 -217.089035) (xy 17.273659 -217.042018) (xy 17.254399 -216.991661)
			(xy 17.242676 -216.939037) (xy 17.238741 -216.885266) (xy 15.598394 -216.885266) (xy 15.598394 -217.735404)
			(xy 21.338809 -217.735404) (xy 21.342744 -217.681633) (xy 21.354467 -217.629009) (xy 21.373727 -217.578652)
			(xy 21.400113 -217.531635) (xy 21.433065 -217.488962) (xy 21.471878 -217.451541) (xy 21.515726 -217.420171)
			(xy 21.563674 -217.395519) (xy 21.614701 -217.378111) (xy 21.667719 -217.368318) (xy 21.721598 -217.366349)
			(xy 21.775189 -217.372246) (xy 21.82735 -217.385882) (xy 21.87697 -217.406969) (xy 21.922991 -217.435055)
			(xy 21.964433 -217.469543) (xy 22.000411 -217.509697) (xy 22.030159 -217.554661) (xy 22.053044 -217.603478)
			(xy 22.068576 -217.655107) (xy 22.076426 -217.708447) (xy 22.076918 -217.735404) (xy 28.882863 -217.735404)
			(xy 28.886798 -217.681633) (xy 28.898521 -217.629009) (xy 28.917781 -217.578652) (xy 28.944167 -217.531635)
			(xy 28.977119 -217.488962) (xy 29.015932 -217.451541) (xy 29.05978 -217.420171) (xy 29.107728 -217.395519)
			(xy 29.158755 -217.378111) (xy 29.211773 -217.368318) (xy 29.265652 -217.366349) (xy 29.319243 -217.372246)
			(xy 29.371404 -217.385882) (xy 29.421024 -217.406969) (xy 29.467045 -217.435055) (xy 29.508487 -217.469543)
			(xy 29.544465 -217.509697) (xy 29.574213 -217.554661) (xy 29.597098 -217.603478) (xy 29.61263 -217.655107)
			(xy 29.62048 -217.708447) (xy 29.620972 -217.735404) (xy 36.426663 -217.735404) (xy 36.430598 -217.681633)
			(xy 36.442321 -217.629009) (xy 36.461581 -217.578652) (xy 36.487967 -217.531635) (xy 36.520919 -217.488962)
			(xy 36.559732 -217.451541) (xy 36.60358 -217.420171) (xy 36.651528 -217.395519) (xy 36.702555 -217.378111)
			(xy 36.755573 -217.368318) (xy 36.809452 -217.366349) (xy 36.863043 -217.372246) (xy 36.915204 -217.385882)
			(xy 36.964824 -217.406969) (xy 37.010845 -217.435055) (xy 37.052287 -217.469543) (xy 37.088265 -217.509697)
			(xy 37.118013 -217.554661) (xy 37.140898 -217.603478) (xy 37.15643 -217.655107) (xy 37.16428 -217.708447)
			(xy 37.164772 -217.735404) (xy 43.970717 -217.735404) (xy 43.974652 -217.681633) (xy 43.986375 -217.629009)
			(xy 44.005635 -217.578652) (xy 44.032021 -217.531635) (xy 44.064973 -217.488962) (xy 44.103786 -217.451541)
			(xy 44.147634 -217.420171) (xy 44.195582 -217.395519) (xy 44.246609 -217.378111) (xy 44.299627 -217.368318)
			(xy 44.353506 -217.366349) (xy 44.407097 -217.372246) (xy 44.459258 -217.385882) (xy 44.508878 -217.406969)
			(xy 44.554899 -217.435055) (xy 44.596341 -217.469543) (xy 44.632319 -217.509697) (xy 44.662067 -217.554661)
			(xy 44.684952 -217.603478) (xy 44.700484 -217.655107) (xy 44.708334 -217.708447) (xy 44.708826 -217.735404)
			(xy 44.708334 -217.762361) (xy 44.700484 -217.815701) (xy 44.684952 -217.86733) (xy 44.662067 -217.916147)
			(xy 44.632319 -217.961111) (xy 44.596341 -218.001265) (xy 44.554899 -218.035753) (xy 44.508878 -218.063839)
			(xy 44.459258 -218.084926) (xy 44.407097 -218.098562) (xy 44.353506 -218.104459) (xy 44.299627 -218.10249)
			(xy 44.246609 -218.092697) (xy 44.195582 -218.075289) (xy 44.147634 -218.050637) (xy 44.103786 -218.019267)
			(xy 44.064973 -217.981846) (xy 44.032021 -217.939173) (xy 44.005635 -217.892156) (xy 43.986375 -217.841799)
			(xy 43.974652 -217.789175) (xy 43.970717 -217.735404) (xy 37.164772 -217.735404) (xy 37.16428 -217.762361)
			(xy 37.15643 -217.815701) (xy 37.140898 -217.86733) (xy 37.118013 -217.916147) (xy 37.088265 -217.961111)
			(xy 37.052287 -218.001265) (xy 37.010845 -218.035753) (xy 36.964824 -218.063839) (xy 36.915204 -218.084926)
			(xy 36.863043 -218.098562) (xy 36.809452 -218.104459) (xy 36.755573 -218.10249) (xy 36.702555 -218.092697)
			(xy 36.651528 -218.075289) (xy 36.60358 -218.050637) (xy 36.559732 -218.019267) (xy 36.520919 -217.981846)
			(xy 36.487967 -217.939173) (xy 36.461581 -217.892156) (xy 36.442321 -217.841799) (xy 36.430598 -217.789175)
			(xy 36.426663 -217.735404) (xy 29.620972 -217.735404) (xy 29.62048 -217.762361) (xy 29.61263 -217.815701)
			(xy 29.597098 -217.86733) (xy 29.574213 -217.916147) (xy 29.544465 -217.961111) (xy 29.508487 -218.001265)
			(xy 29.467045 -218.035753) (xy 29.421024 -218.063839) (xy 29.371404 -218.084926) (xy 29.319243 -218.098562)
			(xy 29.265652 -218.104459) (xy 29.211773 -218.10249) (xy 29.158755 -218.092697) (xy 29.107728 -218.075289)
			(xy 29.05978 -218.050637) (xy 29.015932 -218.019267) (xy 28.977119 -217.981846) (xy 28.944167 -217.939173)
			(xy 28.917781 -217.892156) (xy 28.898521 -217.841799) (xy 28.886798 -217.789175) (xy 28.882863 -217.735404)
			(xy 22.076918 -217.735404) (xy 22.076426 -217.762361) (xy 22.068576 -217.815701) (xy 22.053044 -217.86733)
			(xy 22.030159 -217.916147) (xy 22.000411 -217.961111) (xy 21.964433 -218.001265) (xy 21.922991 -218.035753)
			(xy 21.87697 -218.063839) (xy 21.82735 -218.084926) (xy 21.775189 -218.098562) (xy 21.721598 -218.104459)
			(xy 21.667719 -218.10249) (xy 21.614701 -218.092697) (xy 21.563674 -218.075289) (xy 21.515726 -218.050637)
			(xy 21.471878 -218.019267) (xy 21.433065 -217.981846) (xy 21.400113 -217.939173) (xy 21.373727 -217.892156)
			(xy 21.354467 -217.841799) (xy 21.342744 -217.789175) (xy 21.338809 -217.735404) (xy 15.598394 -217.735404)
			(xy 15.598394 -218.585288) (xy 17.238741 -218.585288) (xy 17.242676 -218.531517) (xy 17.254399 -218.478893)
			(xy 17.273659 -218.428536) (xy 17.300045 -218.381519) (xy 17.332997 -218.338846) (xy 17.37181 -218.301425)
			(xy 17.415658 -218.270055) (xy 17.463606 -218.245403) (xy 17.514633 -218.227995) (xy 17.567651 -218.218202)
			(xy 17.62153 -218.216233) (xy 17.675121 -218.22213) (xy 17.727282 -218.235766) (xy 17.776902 -218.256853)
			(xy 17.822923 -218.284939) (xy 17.864365 -218.319427) (xy 17.900343 -218.359581) (xy 17.930091 -218.404545)
			(xy 17.952976 -218.453362) (xy 17.968508 -218.504991) (xy 17.976358 -218.558331) (xy 17.97685 -218.585288)
			(xy 24.782795 -218.585288) (xy 24.78673 -218.531517) (xy 24.798453 -218.478893) (xy 24.817713 -218.428536)
			(xy 24.844099 -218.381519) (xy 24.877051 -218.338846) (xy 24.915864 -218.301425) (xy 24.959712 -218.270055)
			(xy 25.00766 -218.245403) (xy 25.058687 -218.227995) (xy 25.111705 -218.218202) (xy 25.165584 -218.216233)
			(xy 25.219175 -218.22213) (xy 25.271336 -218.235766) (xy 25.320956 -218.256853) (xy 25.366977 -218.284939)
			(xy 25.408419 -218.319427) (xy 25.444397 -218.359581) (xy 25.474145 -218.404545) (xy 25.49703 -218.453362)
			(xy 25.512562 -218.504991) (xy 25.520412 -218.558331) (xy 25.520904 -218.585288) (xy 32.326595 -218.585288)
			(xy 32.33053 -218.531517) (xy 32.342253 -218.478893) (xy 32.361513 -218.428536) (xy 32.387899 -218.381519)
			(xy 32.420851 -218.338846) (xy 32.459664 -218.301425) (xy 32.503512 -218.270055) (xy 32.55146 -218.245403)
			(xy 32.602487 -218.227995) (xy 32.655505 -218.218202) (xy 32.709384 -218.216233) (xy 32.762975 -218.22213)
			(xy 32.815136 -218.235766) (xy 32.864756 -218.256853) (xy 32.910777 -218.284939) (xy 32.952219 -218.319427)
			(xy 32.988197 -218.359581) (xy 33.017945 -218.404545) (xy 33.04083 -218.453362) (xy 33.056362 -218.504991)
			(xy 33.064212 -218.558331) (xy 33.064704 -218.585288) (xy 39.870649 -218.585288) (xy 39.874584 -218.531517)
			(xy 39.886307 -218.478893) (xy 39.905567 -218.428536) (xy 39.931953 -218.381519) (xy 39.964905 -218.338846)
			(xy 40.003718 -218.301425) (xy 40.047566 -218.270055) (xy 40.095514 -218.245403) (xy 40.146541 -218.227995)
			(xy 40.199559 -218.218202) (xy 40.253438 -218.216233) (xy 40.307029 -218.22213) (xy 40.35919 -218.235766)
			(xy 40.40881 -218.256853) (xy 40.454831 -218.284939) (xy 40.496273 -218.319427) (xy 40.532251 -218.359581)
			(xy 40.561999 -218.404545) (xy 40.584884 -218.453362) (xy 40.600416 -218.504991) (xy 40.608266 -218.558331)
			(xy 40.608758 -218.585288) (xy 40.608266 -218.612245) (xy 40.600416 -218.665585) (xy 40.584884 -218.717214)
			(xy 40.561999 -218.766031) (xy 40.532251 -218.810995) (xy 40.496273 -218.851149) (xy 40.454831 -218.885637)
			(xy 40.40881 -218.913723) (xy 40.35919 -218.93481) (xy 40.307029 -218.948446) (xy 40.253438 -218.954343)
			(xy 40.199559 -218.952374) (xy 40.146541 -218.942581) (xy 40.095514 -218.925173) (xy 40.047566 -218.900521)
			(xy 40.003718 -218.869151) (xy 39.964905 -218.83173) (xy 39.931953 -218.789057) (xy 39.905567 -218.74204)
			(xy 39.886307 -218.691683) (xy 39.874584 -218.639059) (xy 39.870649 -218.585288) (xy 33.064704 -218.585288)
			(xy 33.064212 -218.612245) (xy 33.056362 -218.665585) (xy 33.04083 -218.717214) (xy 33.017945 -218.766031)
			(xy 32.988197 -218.810995) (xy 32.952219 -218.851149) (xy 32.910777 -218.885637) (xy 32.864756 -218.913723)
			(xy 32.815136 -218.93481) (xy 32.762975 -218.948446) (xy 32.709384 -218.954343) (xy 32.655505 -218.952374)
			(xy 32.602487 -218.942581) (xy 32.55146 -218.925173) (xy 32.503512 -218.900521) (xy 32.459664 -218.869151)
			(xy 32.420851 -218.83173) (xy 32.387899 -218.789057) (xy 32.361513 -218.74204) (xy 32.342253 -218.691683)
			(xy 32.33053 -218.639059) (xy 32.326595 -218.585288) (xy 25.520904 -218.585288) (xy 25.520412 -218.612245)
			(xy 25.512562 -218.665585) (xy 25.49703 -218.717214) (xy 25.474145 -218.766031) (xy 25.444397 -218.810995)
			(xy 25.408419 -218.851149) (xy 25.366977 -218.885637) (xy 25.320956 -218.913723) (xy 25.271336 -218.93481)
			(xy 25.219175 -218.948446) (xy 25.165584 -218.954343) (xy 25.111705 -218.952374) (xy 25.058687 -218.942581)
			(xy 25.00766 -218.925173) (xy 24.959712 -218.900521) (xy 24.915864 -218.869151) (xy 24.877051 -218.83173)
			(xy 24.844099 -218.789057) (xy 24.817713 -218.74204) (xy 24.798453 -218.691683) (xy 24.78673 -218.639059)
			(xy 24.782795 -218.585288) (xy 17.97685 -218.585288) (xy 17.976358 -218.612245) (xy 17.968508 -218.665585)
			(xy 17.952976 -218.717214) (xy 17.930091 -218.766031) (xy 17.900343 -218.810995) (xy 17.864365 -218.851149)
			(xy 17.822923 -218.885637) (xy 17.776902 -218.913723) (xy 17.727282 -218.93481) (xy 17.675121 -218.948446)
			(xy 17.62153 -218.954343) (xy 17.567651 -218.952374) (xy 17.514633 -218.942581) (xy 17.463606 -218.925173)
			(xy 17.415658 -218.900521) (xy 17.37181 -218.869151) (xy 17.332997 -218.83173) (xy 17.300045 -218.789057)
			(xy 17.273659 -218.74204) (xy 17.254399 -218.691683) (xy 17.242676 -218.639059) (xy 17.238741 -218.585288)
			(xy 15.598394 -218.585288) (xy 15.598394 -219.435426) (xy 21.338809 -219.435426) (xy 21.342744 -219.381655)
			(xy 21.354467 -219.329031) (xy 21.373727 -219.278674) (xy 21.400113 -219.231657) (xy 21.433065 -219.188984)
			(xy 21.471878 -219.151563) (xy 21.515726 -219.120193) (xy 21.563674 -219.095541) (xy 21.614701 -219.078133)
			(xy 21.667719 -219.06834) (xy 21.721598 -219.066371) (xy 21.775189 -219.072268) (xy 21.82735 -219.085904)
			(xy 21.87697 -219.106991) (xy 21.922991 -219.135077) (xy 21.964433 -219.169565) (xy 22.000411 -219.209719)
			(xy 22.030159 -219.254683) (xy 22.053044 -219.3035) (xy 22.068576 -219.355129) (xy 22.076426 -219.408469)
			(xy 22.076918 -219.435426) (xy 28.882863 -219.435426) (xy 28.886798 -219.381655) (xy 28.898521 -219.329031)
			(xy 28.917781 -219.278674) (xy 28.944167 -219.231657) (xy 28.977119 -219.188984) (xy 29.015932 -219.151563)
			(xy 29.05978 -219.120193) (xy 29.107728 -219.095541) (xy 29.158755 -219.078133) (xy 29.211773 -219.06834)
			(xy 29.265652 -219.066371) (xy 29.319243 -219.072268) (xy 29.371404 -219.085904) (xy 29.421024 -219.106991)
			(xy 29.467045 -219.135077) (xy 29.508487 -219.169565) (xy 29.544465 -219.209719) (xy 29.574213 -219.254683)
			(xy 29.597098 -219.3035) (xy 29.61263 -219.355129) (xy 29.62048 -219.408469) (xy 29.620972 -219.435426)
			(xy 36.426663 -219.435426) (xy 36.430598 -219.381655) (xy 36.442321 -219.329031) (xy 36.461581 -219.278674)
			(xy 36.487967 -219.231657) (xy 36.520919 -219.188984) (xy 36.559732 -219.151563) (xy 36.60358 -219.120193)
			(xy 36.651528 -219.095541) (xy 36.702555 -219.078133) (xy 36.755573 -219.06834) (xy 36.809452 -219.066371)
			(xy 36.863043 -219.072268) (xy 36.915204 -219.085904) (xy 36.964824 -219.106991) (xy 37.010845 -219.135077)
			(xy 37.052287 -219.169565) (xy 37.088265 -219.209719) (xy 37.118013 -219.254683) (xy 37.140898 -219.3035)
			(xy 37.15643 -219.355129) (xy 37.16428 -219.408469) (xy 37.164772 -219.435426) (xy 43.970717 -219.435426)
			(xy 43.974652 -219.381655) (xy 43.986375 -219.329031) (xy 44.005635 -219.278674) (xy 44.032021 -219.231657)
			(xy 44.064973 -219.188984) (xy 44.103786 -219.151563) (xy 44.147634 -219.120193) (xy 44.195582 -219.095541)
			(xy 44.246609 -219.078133) (xy 44.299627 -219.06834) (xy 44.353506 -219.066371) (xy 44.407097 -219.072268)
			(xy 44.459258 -219.085904) (xy 44.508878 -219.106991) (xy 44.554899 -219.135077) (xy 44.596341 -219.169565)
			(xy 44.632319 -219.209719) (xy 44.662067 -219.254683) (xy 44.684952 -219.3035) (xy 44.700484 -219.355129)
			(xy 44.708334 -219.408469) (xy 44.708826 -219.435426) (xy 44.708334 -219.462383) (xy 44.700484 -219.515723)
			(xy 44.684952 -219.567352) (xy 44.662067 -219.616169) (xy 44.632319 -219.661133) (xy 44.596341 -219.701287)
			(xy 44.554899 -219.735775) (xy 44.508878 -219.763861) (xy 44.459258 -219.784948) (xy 44.407097 -219.798584)
			(xy 44.353506 -219.804481) (xy 44.299627 -219.802512) (xy 44.246609 -219.792719) (xy 44.195582 -219.775311)
			(xy 44.147634 -219.750659) (xy 44.103786 -219.719289) (xy 44.064973 -219.681868) (xy 44.032021 -219.639195)
			(xy 44.005635 -219.592178) (xy 43.986375 -219.541821) (xy 43.974652 -219.489197) (xy 43.970717 -219.435426)
			(xy 37.164772 -219.435426) (xy 37.16428 -219.462383) (xy 37.15643 -219.515723) (xy 37.140898 -219.567352)
			(xy 37.118013 -219.616169) (xy 37.088265 -219.661133) (xy 37.052287 -219.701287) (xy 37.010845 -219.735775)
			(xy 36.964824 -219.763861) (xy 36.915204 -219.784948) (xy 36.863043 -219.798584) (xy 36.809452 -219.804481)
			(xy 36.755573 -219.802512) (xy 36.702555 -219.792719) (xy 36.651528 -219.775311) (xy 36.60358 -219.750659)
			(xy 36.559732 -219.719289) (xy 36.520919 -219.681868) (xy 36.487967 -219.639195) (xy 36.461581 -219.592178)
			(xy 36.442321 -219.541821) (xy 36.430598 -219.489197) (xy 36.426663 -219.435426) (xy 29.620972 -219.435426)
			(xy 29.62048 -219.462383) (xy 29.61263 -219.515723) (xy 29.597098 -219.567352) (xy 29.574213 -219.616169)
			(xy 29.544465 -219.661133) (xy 29.508487 -219.701287) (xy 29.467045 -219.735775) (xy 29.421024 -219.763861)
			(xy 29.371404 -219.784948) (xy 29.319243 -219.798584) (xy 29.265652 -219.804481) (xy 29.211773 -219.802512)
			(xy 29.158755 -219.792719) (xy 29.107728 -219.775311) (xy 29.05978 -219.750659) (xy 29.015932 -219.719289)
			(xy 28.977119 -219.681868) (xy 28.944167 -219.639195) (xy 28.917781 -219.592178) (xy 28.898521 -219.541821)
			(xy 28.886798 -219.489197) (xy 28.882863 -219.435426) (xy 22.076918 -219.435426) (xy 22.076426 -219.462383)
			(xy 22.068576 -219.515723) (xy 22.053044 -219.567352) (xy 22.030159 -219.616169) (xy 22.000411 -219.661133)
			(xy 21.964433 -219.701287) (xy 21.922991 -219.735775) (xy 21.87697 -219.763861) (xy 21.82735 -219.784948)
			(xy 21.775189 -219.798584) (xy 21.721598 -219.804481) (xy 21.667719 -219.802512) (xy 21.614701 -219.792719)
			(xy 21.563674 -219.775311) (xy 21.515726 -219.750659) (xy 21.471878 -219.719289) (xy 21.433065 -219.681868)
			(xy 21.400113 -219.639195) (xy 21.373727 -219.592178) (xy 21.354467 -219.541821) (xy 21.342744 -219.489197)
			(xy 21.338809 -219.435426) (xy 15.598394 -219.435426) (xy 15.598394 -220.28531) (xy 17.238741 -220.28531)
			(xy 17.242676 -220.231539) (xy 17.254399 -220.178915) (xy 17.273659 -220.128558) (xy 17.300045 -220.081541)
			(xy 17.332997 -220.038868) (xy 17.37181 -220.001447) (xy 17.415658 -219.970077) (xy 17.463606 -219.945425)
			(xy 17.514633 -219.928017) (xy 17.567651 -219.918224) (xy 17.62153 -219.916255) (xy 17.675121 -219.922152)
			(xy 17.727282 -219.935788) (xy 17.776902 -219.956875) (xy 17.822923 -219.984961) (xy 17.864365 -220.019449)
			(xy 17.900343 -220.059603) (xy 17.930091 -220.104567) (xy 17.952976 -220.153384) (xy 17.968508 -220.205013)
			(xy 17.976358 -220.258353) (xy 17.97685 -220.28531) (xy 21.338809 -220.28531) (xy 21.342744 -220.231539)
			(xy 21.354467 -220.178915) (xy 21.373727 -220.128558) (xy 21.400113 -220.081541) (xy 21.433065 -220.038868)
			(xy 21.471878 -220.001447) (xy 21.515726 -219.970077) (xy 21.563674 -219.945425) (xy 21.614701 -219.928017)
			(xy 21.667719 -219.918224) (xy 21.721598 -219.916255) (xy 21.775189 -219.922152) (xy 21.82735 -219.935788)
			(xy 21.87697 -219.956875) (xy 21.922991 -219.984961) (xy 21.964433 -220.019449) (xy 22.000411 -220.059603)
			(xy 22.030159 -220.104567) (xy 22.053044 -220.153384) (xy 22.068576 -220.205013) (xy 22.076426 -220.258353)
			(xy 22.076918 -220.28531) (xy 24.782795 -220.28531) (xy 24.78673 -220.231539) (xy 24.798453 -220.178915)
			(xy 24.817713 -220.128558) (xy 24.844099 -220.081541) (xy 24.877051 -220.038868) (xy 24.915864 -220.001447)
			(xy 24.959712 -219.970077) (xy 25.00766 -219.945425) (xy 25.058687 -219.928017) (xy 25.111705 -219.918224)
			(xy 25.165584 -219.916255) (xy 25.219175 -219.922152) (xy 25.271336 -219.935788) (xy 25.320956 -219.956875)
			(xy 25.366977 -219.984961) (xy 25.408419 -220.019449) (xy 25.444397 -220.059603) (xy 25.474145 -220.104567)
			(xy 25.49703 -220.153384) (xy 25.512562 -220.205013) (xy 25.520412 -220.258353) (xy 25.520904 -220.28531)
			(xy 28.882863 -220.28531) (xy 28.886798 -220.231539) (xy 28.898521 -220.178915) (xy 28.917781 -220.128558)
			(xy 28.944167 -220.081541) (xy 28.977119 -220.038868) (xy 29.015932 -220.001447) (xy 29.05978 -219.970077)
			(xy 29.107728 -219.945425) (xy 29.158755 -219.928017) (xy 29.211773 -219.918224) (xy 29.265652 -219.916255)
			(xy 29.319243 -219.922152) (xy 29.371404 -219.935788) (xy 29.421024 -219.956875) (xy 29.467045 -219.984961)
			(xy 29.508487 -220.019449) (xy 29.544465 -220.059603) (xy 29.574213 -220.104567) (xy 29.597098 -220.153384)
			(xy 29.61263 -220.205013) (xy 29.62048 -220.258353) (xy 29.620972 -220.28531) (xy 32.326595 -220.28531)
			(xy 32.33053 -220.231539) (xy 32.342253 -220.178915) (xy 32.361513 -220.128558) (xy 32.387899 -220.081541)
			(xy 32.420851 -220.038868) (xy 32.459664 -220.001447) (xy 32.503512 -219.970077) (xy 32.55146 -219.945425)
			(xy 32.602487 -219.928017) (xy 32.655505 -219.918224) (xy 32.709384 -219.916255) (xy 32.762975 -219.922152)
			(xy 32.815136 -219.935788) (xy 32.864756 -219.956875) (xy 32.910777 -219.984961) (xy 32.952219 -220.019449)
			(xy 32.988197 -220.059603) (xy 33.017945 -220.104567) (xy 33.04083 -220.153384) (xy 33.056362 -220.205013)
			(xy 33.064212 -220.258353) (xy 33.064704 -220.28531) (xy 36.426663 -220.28531) (xy 36.430598 -220.231539)
			(xy 36.442321 -220.178915) (xy 36.461581 -220.128558) (xy 36.487967 -220.081541) (xy 36.520919 -220.038868)
			(xy 36.559732 -220.001447) (xy 36.60358 -219.970077) (xy 36.651528 -219.945425) (xy 36.702555 -219.928017)
			(xy 36.755573 -219.918224) (xy 36.809452 -219.916255) (xy 36.863043 -219.922152) (xy 36.915204 -219.935788)
			(xy 36.964824 -219.956875) (xy 37.010845 -219.984961) (xy 37.052287 -220.019449) (xy 37.088265 -220.059603)
			(xy 37.118013 -220.104567) (xy 37.140898 -220.153384) (xy 37.15643 -220.205013) (xy 37.16428 -220.258353)
			(xy 37.164772 -220.28531) (xy 39.870649 -220.28531) (xy 39.874584 -220.231539) (xy 39.886307 -220.178915)
			(xy 39.905567 -220.128558) (xy 39.931953 -220.081541) (xy 39.964905 -220.038868) (xy 40.003718 -220.001447)
			(xy 40.047566 -219.970077) (xy 40.095514 -219.945425) (xy 40.146541 -219.928017) (xy 40.199559 -219.918224)
			(xy 40.253438 -219.916255) (xy 40.307029 -219.922152) (xy 40.35919 -219.935788) (xy 40.40881 -219.956875)
			(xy 40.454831 -219.984961) (xy 40.496273 -220.019449) (xy 40.532251 -220.059603) (xy 40.561999 -220.104567)
			(xy 40.584884 -220.153384) (xy 40.600416 -220.205013) (xy 40.608266 -220.258353) (xy 40.608758 -220.28531)
			(xy 43.970717 -220.28531) (xy 43.974652 -220.231539) (xy 43.986375 -220.178915) (xy 44.005635 -220.128558)
			(xy 44.032021 -220.081541) (xy 44.064973 -220.038868) (xy 44.103786 -220.001447) (xy 44.147634 -219.970077)
			(xy 44.195582 -219.945425) (xy 44.246609 -219.928017) (xy 44.299627 -219.918224) (xy 44.353506 -219.916255)
			(xy 44.407097 -219.922152) (xy 44.459258 -219.935788) (xy 44.508878 -219.956875) (xy 44.554899 -219.984961)
			(xy 44.596341 -220.019449) (xy 44.632319 -220.059603) (xy 44.662067 -220.104567) (xy 44.684952 -220.153384)
			(xy 44.700484 -220.205013) (xy 44.708334 -220.258353) (xy 44.708826 -220.28531) (xy 44.708334 -220.312267)
			(xy 44.700484 -220.365607) (xy 44.684952 -220.417236) (xy 44.662067 -220.466053) (xy 44.632319 -220.511017)
			(xy 44.596341 -220.551171) (xy 44.554899 -220.585659) (xy 44.508878 -220.613745) (xy 44.459258 -220.634832)
			(xy 44.407097 -220.648468) (xy 44.353506 -220.654365) (xy 44.299627 -220.652396) (xy 44.246609 -220.642603)
			(xy 44.195582 -220.625195) (xy 44.147634 -220.600543) (xy 44.103786 -220.569173) (xy 44.064973 -220.531752)
			(xy 44.032021 -220.489079) (xy 44.005635 -220.442062) (xy 43.986375 -220.391705) (xy 43.974652 -220.339081)
			(xy 43.970717 -220.28531) (xy 40.608758 -220.28531) (xy 40.608266 -220.312267) (xy 40.600416 -220.365607)
			(xy 40.584884 -220.417236) (xy 40.561999 -220.466053) (xy 40.532251 -220.511017) (xy 40.496273 -220.551171)
			(xy 40.454831 -220.585659) (xy 40.40881 -220.613745) (xy 40.35919 -220.634832) (xy 40.307029 -220.648468)
			(xy 40.253438 -220.654365) (xy 40.199559 -220.652396) (xy 40.146541 -220.642603) (xy 40.095514 -220.625195)
			(xy 40.047566 -220.600543) (xy 40.003718 -220.569173) (xy 39.964905 -220.531752) (xy 39.931953 -220.489079)
			(xy 39.905567 -220.442062) (xy 39.886307 -220.391705) (xy 39.874584 -220.339081) (xy 39.870649 -220.28531)
			(xy 37.164772 -220.28531) (xy 37.16428 -220.312267) (xy 37.15643 -220.365607) (xy 37.140898 -220.417236)
			(xy 37.118013 -220.466053) (xy 37.088265 -220.511017) (xy 37.052287 -220.551171) (xy 37.010845 -220.585659)
			(xy 36.964824 -220.613745) (xy 36.915204 -220.634832) (xy 36.863043 -220.648468) (xy 36.809452 -220.654365)
			(xy 36.755573 -220.652396) (xy 36.702555 -220.642603) (xy 36.651528 -220.625195) (xy 36.60358 -220.600543)
			(xy 36.559732 -220.569173) (xy 36.520919 -220.531752) (xy 36.487967 -220.489079) (xy 36.461581 -220.442062)
			(xy 36.442321 -220.391705) (xy 36.430598 -220.339081) (xy 36.426663 -220.28531) (xy 33.064704 -220.28531)
			(xy 33.064212 -220.312267) (xy 33.056362 -220.365607) (xy 33.04083 -220.417236) (xy 33.017945 -220.466053)
			(xy 32.988197 -220.511017) (xy 32.952219 -220.551171) (xy 32.910777 -220.585659) (xy 32.864756 -220.613745)
			(xy 32.815136 -220.634832) (xy 32.762975 -220.648468) (xy 32.709384 -220.654365) (xy 32.655505 -220.652396)
			(xy 32.602487 -220.642603) (xy 32.55146 -220.625195) (xy 32.503512 -220.600543) (xy 32.459664 -220.569173)
			(xy 32.420851 -220.531752) (xy 32.387899 -220.489079) (xy 32.361513 -220.442062) (xy 32.342253 -220.391705)
			(xy 32.33053 -220.339081) (xy 32.326595 -220.28531) (xy 29.620972 -220.28531) (xy 29.62048 -220.312267)
			(xy 29.61263 -220.365607) (xy 29.597098 -220.417236) (xy 29.574213 -220.466053) (xy 29.544465 -220.511017)
			(xy 29.508487 -220.551171) (xy 29.467045 -220.585659) (xy 29.421024 -220.613745) (xy 29.371404 -220.634832)
			(xy 29.319243 -220.648468) (xy 29.265652 -220.654365) (xy 29.211773 -220.652396) (xy 29.158755 -220.642603)
			(xy 29.107728 -220.625195) (xy 29.05978 -220.600543) (xy 29.015932 -220.569173) (xy 28.977119 -220.531752)
			(xy 28.944167 -220.489079) (xy 28.917781 -220.442062) (xy 28.898521 -220.391705) (xy 28.886798 -220.339081)
			(xy 28.882863 -220.28531) (xy 25.520904 -220.28531) (xy 25.520412 -220.312267) (xy 25.512562 -220.365607)
			(xy 25.49703 -220.417236) (xy 25.474145 -220.466053) (xy 25.444397 -220.511017) (xy 25.408419 -220.551171)
			(xy 25.366977 -220.585659) (xy 25.320956 -220.613745) (xy 25.271336 -220.634832) (xy 25.219175 -220.648468)
			(xy 25.165584 -220.654365) (xy 25.111705 -220.652396) (xy 25.058687 -220.642603) (xy 25.00766 -220.625195)
			(xy 24.959712 -220.600543) (xy 24.915864 -220.569173) (xy 24.877051 -220.531752) (xy 24.844099 -220.489079)
			(xy 24.817713 -220.442062) (xy 24.798453 -220.391705) (xy 24.78673 -220.339081) (xy 24.782795 -220.28531)
			(xy 22.076918 -220.28531) (xy 22.076426 -220.312267) (xy 22.068576 -220.365607) (xy 22.053044 -220.417236)
			(xy 22.030159 -220.466053) (xy 22.000411 -220.511017) (xy 21.964433 -220.551171) (xy 21.922991 -220.585659)
			(xy 21.87697 -220.613745) (xy 21.82735 -220.634832) (xy 21.775189 -220.648468) (xy 21.721598 -220.654365)
			(xy 21.667719 -220.652396) (xy 21.614701 -220.642603) (xy 21.563674 -220.625195) (xy 21.515726 -220.600543)
			(xy 21.471878 -220.569173) (xy 21.433065 -220.531752) (xy 21.400113 -220.489079) (xy 21.373727 -220.442062)
			(xy 21.354467 -220.391705) (xy 21.342744 -220.339081) (xy 21.338809 -220.28531) (xy 17.97685 -220.28531)
			(xy 17.976358 -220.312267) (xy 17.968508 -220.365607) (xy 17.952976 -220.417236) (xy 17.930091 -220.466053)
			(xy 17.900343 -220.511017) (xy 17.864365 -220.551171) (xy 17.822923 -220.585659) (xy 17.776902 -220.613745)
			(xy 17.727282 -220.634832) (xy 17.675121 -220.648468) (xy 17.62153 -220.654365) (xy 17.567651 -220.652396)
			(xy 17.514633 -220.642603) (xy 17.463606 -220.625195) (xy 17.415658 -220.600543) (xy 17.37181 -220.569173)
			(xy 17.332997 -220.531752) (xy 17.300045 -220.489079) (xy 17.273659 -220.442062) (xy 17.254399 -220.391705)
			(xy 17.242676 -220.339081) (xy 17.238741 -220.28531) (xy 15.598394 -220.28531) (xy 15.598394 -221.135194)
			(xy 17.238741 -221.135194) (xy 17.242676 -221.081423) (xy 17.254399 -221.028799) (xy 17.273659 -220.978442)
			(xy 17.300045 -220.931425) (xy 17.332997 -220.888752) (xy 17.37181 -220.851331) (xy 17.415658 -220.819961)
			(xy 17.463606 -220.795309) (xy 17.514633 -220.777901) (xy 17.567651 -220.768108) (xy 17.62153 -220.766139)
			(xy 17.675121 -220.772036) (xy 17.727282 -220.785672) (xy 17.776902 -220.806759) (xy 17.822923 -220.834845)
			(xy 17.864365 -220.869333) (xy 17.900343 -220.909487) (xy 17.930091 -220.954451) (xy 17.952976 -221.003268)
			(xy 17.968508 -221.054897) (xy 17.976358 -221.108237) (xy 17.97685 -221.135194) (xy 24.782795 -221.135194)
			(xy 24.78673 -221.081423) (xy 24.798453 -221.028799) (xy 24.817713 -220.978442) (xy 24.844099 -220.931425)
			(xy 24.877051 -220.888752) (xy 24.915864 -220.851331) (xy 24.959712 -220.819961) (xy 25.00766 -220.795309)
			(xy 25.058687 -220.777901) (xy 25.111705 -220.768108) (xy 25.165584 -220.766139) (xy 25.219175 -220.772036)
			(xy 25.271336 -220.785672) (xy 25.320956 -220.806759) (xy 25.366977 -220.834845) (xy 25.408419 -220.869333)
			(xy 25.444397 -220.909487) (xy 25.474145 -220.954451) (xy 25.49703 -221.003268) (xy 25.512562 -221.054897)
			(xy 25.520412 -221.108237) (xy 25.520904 -221.135194) (xy 32.326595 -221.135194) (xy 32.33053 -221.081423)
			(xy 32.342253 -221.028799) (xy 32.361513 -220.978442) (xy 32.387899 -220.931425) (xy 32.420851 -220.888752)
			(xy 32.459664 -220.851331) (xy 32.503512 -220.819961) (xy 32.55146 -220.795309) (xy 32.602487 -220.777901)
			(xy 32.655505 -220.768108) (xy 32.709384 -220.766139) (xy 32.762975 -220.772036) (xy 32.815136 -220.785672)
			(xy 32.864756 -220.806759) (xy 32.910777 -220.834845) (xy 32.952219 -220.869333) (xy 32.988197 -220.909487)
			(xy 33.017945 -220.954451) (xy 33.04083 -221.003268) (xy 33.056362 -221.054897) (xy 33.064212 -221.108237)
			(xy 33.064704 -221.135194) (xy 39.870649 -221.135194) (xy 39.874584 -221.081423) (xy 39.886307 -221.028799)
			(xy 39.905567 -220.978442) (xy 39.931953 -220.931425) (xy 39.964905 -220.888752) (xy 40.003718 -220.851331)
			(xy 40.047566 -220.819961) (xy 40.095514 -220.795309) (xy 40.146541 -220.777901) (xy 40.199559 -220.768108)
			(xy 40.253438 -220.766139) (xy 40.307029 -220.772036) (xy 40.35919 -220.785672) (xy 40.40881 -220.806759)
			(xy 40.454831 -220.834845) (xy 40.496273 -220.869333) (xy 40.532251 -220.909487) (xy 40.561999 -220.954451)
			(xy 40.584884 -221.003268) (xy 40.600416 -221.054897) (xy 40.608266 -221.108237) (xy 40.608758 -221.135194)
			(xy 40.608266 -221.162151) (xy 40.600416 -221.215491) (xy 40.584884 -221.26712) (xy 40.561999 -221.315937)
			(xy 40.532251 -221.360901) (xy 40.496273 -221.401055) (xy 40.454831 -221.435543) (xy 40.40881 -221.463629)
			(xy 40.35919 -221.484716) (xy 40.307029 -221.498352) (xy 40.253438 -221.504249) (xy 40.199559 -221.50228)
			(xy 40.146541 -221.492487) (xy 40.095514 -221.475079) (xy 40.047566 -221.450427) (xy 40.003718 -221.419057)
			(xy 39.964905 -221.381636) (xy 39.931953 -221.338963) (xy 39.905567 -221.291946) (xy 39.886307 -221.241589)
			(xy 39.874584 -221.188965) (xy 39.870649 -221.135194) (xy 33.064704 -221.135194) (xy 33.064212 -221.162151)
			(xy 33.056362 -221.215491) (xy 33.04083 -221.26712) (xy 33.017945 -221.315937) (xy 32.988197 -221.360901)
			(xy 32.952219 -221.401055) (xy 32.910777 -221.435543) (xy 32.864756 -221.463629) (xy 32.815136 -221.484716)
			(xy 32.762975 -221.498352) (xy 32.709384 -221.504249) (xy 32.655505 -221.50228) (xy 32.602487 -221.492487)
			(xy 32.55146 -221.475079) (xy 32.503512 -221.450427) (xy 32.459664 -221.419057) (xy 32.420851 -221.381636)
			(xy 32.387899 -221.338963) (xy 32.361513 -221.291946) (xy 32.342253 -221.241589) (xy 32.33053 -221.188965)
			(xy 32.326595 -221.135194) (xy 25.520904 -221.135194) (xy 25.520412 -221.162151) (xy 25.512562 -221.215491)
			(xy 25.49703 -221.26712) (xy 25.474145 -221.315937) (xy 25.444397 -221.360901) (xy 25.408419 -221.401055)
			(xy 25.366977 -221.435543) (xy 25.320956 -221.463629) (xy 25.271336 -221.484716) (xy 25.219175 -221.498352)
			(xy 25.165584 -221.504249) (xy 25.111705 -221.50228) (xy 25.058687 -221.492487) (xy 25.00766 -221.475079)
			(xy 24.959712 -221.450427) (xy 24.915864 -221.419057) (xy 24.877051 -221.381636) (xy 24.844099 -221.338963)
			(xy 24.817713 -221.291946) (xy 24.798453 -221.241589) (xy 24.78673 -221.188965) (xy 24.782795 -221.135194)
			(xy 17.97685 -221.135194) (xy 17.976358 -221.162151) (xy 17.968508 -221.215491) (xy 17.952976 -221.26712)
			(xy 17.930091 -221.315937) (xy 17.900343 -221.360901) (xy 17.864365 -221.401055) (xy 17.822923 -221.435543)
			(xy 17.776902 -221.463629) (xy 17.727282 -221.484716) (xy 17.675121 -221.498352) (xy 17.62153 -221.504249)
			(xy 17.567651 -221.50228) (xy 17.514633 -221.492487) (xy 17.463606 -221.475079) (xy 17.415658 -221.450427)
			(xy 17.37181 -221.419057) (xy 17.332997 -221.381636) (xy 17.300045 -221.338963) (xy 17.273659 -221.291946)
			(xy 17.254399 -221.241589) (xy 17.242676 -221.188965) (xy 17.238741 -221.135194) (xy 15.598394 -221.135194)
			(xy 15.598394 -221.985332) (xy 21.338809 -221.985332) (xy 21.342744 -221.931561) (xy 21.354467 -221.878937)
			(xy 21.373727 -221.82858) (xy 21.400113 -221.781563) (xy 21.433065 -221.73889) (xy 21.471878 -221.701469)
			(xy 21.515726 -221.670099) (xy 21.563674 -221.645447) (xy 21.614701 -221.628039) (xy 21.667719 -221.618246)
			(xy 21.721598 -221.616277) (xy 21.775189 -221.622174) (xy 21.82735 -221.63581) (xy 21.87697 -221.656897)
			(xy 21.922991 -221.684983) (xy 21.964433 -221.719471) (xy 22.000411 -221.759625) (xy 22.030159 -221.804589)
			(xy 22.053044 -221.853406) (xy 22.068576 -221.905035) (xy 22.076426 -221.958375) (xy 22.076918 -221.985332)
			(xy 28.882863 -221.985332) (xy 28.886798 -221.931561) (xy 28.898521 -221.878937) (xy 28.917781 -221.82858)
			(xy 28.944167 -221.781563) (xy 28.977119 -221.73889) (xy 29.015932 -221.701469) (xy 29.05978 -221.670099)
			(xy 29.107728 -221.645447) (xy 29.158755 -221.628039) (xy 29.211773 -221.618246) (xy 29.265652 -221.616277)
			(xy 29.319243 -221.622174) (xy 29.371404 -221.63581) (xy 29.421024 -221.656897) (xy 29.467045 -221.684983)
			(xy 29.508487 -221.719471) (xy 29.544465 -221.759625) (xy 29.574213 -221.804589) (xy 29.597098 -221.853406)
			(xy 29.61263 -221.905035) (xy 29.62048 -221.958375) (xy 29.620972 -221.985332) (xy 36.426663 -221.985332)
			(xy 36.430598 -221.931561) (xy 36.442321 -221.878937) (xy 36.461581 -221.82858) (xy 36.487967 -221.781563)
			(xy 36.520919 -221.73889) (xy 36.559732 -221.701469) (xy 36.60358 -221.670099) (xy 36.651528 -221.645447)
			(xy 36.702555 -221.628039) (xy 36.755573 -221.618246) (xy 36.809452 -221.616277) (xy 36.863043 -221.622174)
			(xy 36.915204 -221.63581) (xy 36.964824 -221.656897) (xy 37.010845 -221.684983) (xy 37.052287 -221.719471)
			(xy 37.088265 -221.759625) (xy 37.118013 -221.804589) (xy 37.140898 -221.853406) (xy 37.15643 -221.905035)
			(xy 37.16428 -221.958375) (xy 37.164772 -221.985332) (xy 43.970717 -221.985332) (xy 43.974652 -221.931561)
			(xy 43.986375 -221.878937) (xy 44.005635 -221.82858) (xy 44.032021 -221.781563) (xy 44.064973 -221.73889)
			(xy 44.103786 -221.701469) (xy 44.147634 -221.670099) (xy 44.195582 -221.645447) (xy 44.246609 -221.628039)
			(xy 44.299627 -221.618246) (xy 44.353506 -221.616277) (xy 44.407097 -221.622174) (xy 44.459258 -221.63581)
			(xy 44.508878 -221.656897) (xy 44.554899 -221.684983) (xy 44.596341 -221.719471) (xy 44.632319 -221.759625)
			(xy 44.662067 -221.804589) (xy 44.684952 -221.853406) (xy 44.700484 -221.905035) (xy 44.708334 -221.958375)
			(xy 44.708826 -221.985332) (xy 44.708334 -222.012289) (xy 44.700484 -222.065629) (xy 44.684952 -222.117258)
			(xy 44.662067 -222.166075) (xy 44.632319 -222.211039) (xy 44.596341 -222.251193) (xy 44.554899 -222.285681)
			(xy 44.508878 -222.313767) (xy 44.459258 -222.334854) (xy 44.407097 -222.34849) (xy 44.353506 -222.354387)
			(xy 44.299627 -222.352418) (xy 44.246609 -222.342625) (xy 44.195582 -222.325217) (xy 44.147634 -222.300565)
			(xy 44.103786 -222.269195) (xy 44.064973 -222.231774) (xy 44.032021 -222.189101) (xy 44.005635 -222.142084)
			(xy 43.986375 -222.091727) (xy 43.974652 -222.039103) (xy 43.970717 -221.985332) (xy 37.164772 -221.985332)
			(xy 37.16428 -222.012289) (xy 37.15643 -222.065629) (xy 37.140898 -222.117258) (xy 37.118013 -222.166075)
			(xy 37.088265 -222.211039) (xy 37.052287 -222.251193) (xy 37.010845 -222.285681) (xy 36.964824 -222.313767)
			(xy 36.915204 -222.334854) (xy 36.863043 -222.34849) (xy 36.809452 -222.354387) (xy 36.755573 -222.352418)
			(xy 36.702555 -222.342625) (xy 36.651528 -222.325217) (xy 36.60358 -222.300565) (xy 36.559732 -222.269195)
			(xy 36.520919 -222.231774) (xy 36.487967 -222.189101) (xy 36.461581 -222.142084) (xy 36.442321 -222.091727)
			(xy 36.430598 -222.039103) (xy 36.426663 -221.985332) (xy 29.620972 -221.985332) (xy 29.62048 -222.012289)
			(xy 29.61263 -222.065629) (xy 29.597098 -222.117258) (xy 29.574213 -222.166075) (xy 29.544465 -222.211039)
			(xy 29.508487 -222.251193) (xy 29.467045 -222.285681) (xy 29.421024 -222.313767) (xy 29.371404 -222.334854)
			(xy 29.319243 -222.34849) (xy 29.265652 -222.354387) (xy 29.211773 -222.352418) (xy 29.158755 -222.342625)
			(xy 29.107728 -222.325217) (xy 29.05978 -222.300565) (xy 29.015932 -222.269195) (xy 28.977119 -222.231774)
			(xy 28.944167 -222.189101) (xy 28.917781 -222.142084) (xy 28.898521 -222.091727) (xy 28.886798 -222.039103)
			(xy 28.882863 -221.985332) (xy 22.076918 -221.985332) (xy 22.076426 -222.012289) (xy 22.068576 -222.065629)
			(xy 22.053044 -222.117258) (xy 22.030159 -222.166075) (xy 22.000411 -222.211039) (xy 21.964433 -222.251193)
			(xy 21.922991 -222.285681) (xy 21.87697 -222.313767) (xy 21.82735 -222.334854) (xy 21.775189 -222.34849)
			(xy 21.721598 -222.354387) (xy 21.667719 -222.352418) (xy 21.614701 -222.342625) (xy 21.563674 -222.325217)
			(xy 21.515726 -222.300565) (xy 21.471878 -222.269195) (xy 21.433065 -222.231774) (xy 21.400113 -222.189101)
			(xy 21.373727 -222.142084) (xy 21.354467 -222.091727) (xy 21.342744 -222.039103) (xy 21.338809 -221.985332)
			(xy 15.598394 -221.985332) (xy 15.598394 -222.835216) (xy 17.238741 -222.835216) (xy 17.242676 -222.781445)
			(xy 17.254399 -222.728821) (xy 17.273659 -222.678464) (xy 17.300045 -222.631447) (xy 17.332997 -222.588774)
			(xy 17.37181 -222.551353) (xy 17.415658 -222.519983) (xy 17.463606 -222.495331) (xy 17.514633 -222.477923)
			(xy 17.567651 -222.46813) (xy 17.62153 -222.466161) (xy 17.675121 -222.472058) (xy 17.727282 -222.485694)
			(xy 17.776902 -222.506781) (xy 17.822923 -222.534867) (xy 17.864365 -222.569355) (xy 17.900343 -222.609509)
			(xy 17.930091 -222.654473) (xy 17.952976 -222.70329) (xy 17.968508 -222.754919) (xy 17.976358 -222.808259)
			(xy 17.97685 -222.835216) (xy 24.782795 -222.835216) (xy 24.78673 -222.781445) (xy 24.798453 -222.728821)
			(xy 24.817713 -222.678464) (xy 24.844099 -222.631447) (xy 24.877051 -222.588774) (xy 24.915864 -222.551353)
			(xy 24.959712 -222.519983) (xy 25.00766 -222.495331) (xy 25.058687 -222.477923) (xy 25.111705 -222.46813)
			(xy 25.165584 -222.466161) (xy 25.219175 -222.472058) (xy 25.271336 -222.485694) (xy 25.320956 -222.506781)
			(xy 25.366977 -222.534867) (xy 25.408419 -222.569355) (xy 25.444397 -222.609509) (xy 25.474145 -222.654473)
			(xy 25.49703 -222.70329) (xy 25.512562 -222.754919) (xy 25.520412 -222.808259) (xy 25.520904 -222.835216)
			(xy 32.326595 -222.835216) (xy 32.33053 -222.781445) (xy 32.342253 -222.728821) (xy 32.361513 -222.678464)
			(xy 32.387899 -222.631447) (xy 32.420851 -222.588774) (xy 32.459664 -222.551353) (xy 32.503512 -222.519983)
			(xy 32.55146 -222.495331) (xy 32.602487 -222.477923) (xy 32.655505 -222.46813) (xy 32.709384 -222.466161)
			(xy 32.762975 -222.472058) (xy 32.815136 -222.485694) (xy 32.864756 -222.506781) (xy 32.910777 -222.534867)
			(xy 32.952219 -222.569355) (xy 32.988197 -222.609509) (xy 33.017945 -222.654473) (xy 33.04083 -222.70329)
			(xy 33.056362 -222.754919) (xy 33.064212 -222.808259) (xy 33.064704 -222.835216) (xy 39.870649 -222.835216)
			(xy 39.874584 -222.781445) (xy 39.886307 -222.728821) (xy 39.905567 -222.678464) (xy 39.931953 -222.631447)
			(xy 39.964905 -222.588774) (xy 40.003718 -222.551353) (xy 40.047566 -222.519983) (xy 40.095514 -222.495331)
			(xy 40.146541 -222.477923) (xy 40.199559 -222.46813) (xy 40.253438 -222.466161) (xy 40.307029 -222.472058)
			(xy 40.35919 -222.485694) (xy 40.40881 -222.506781) (xy 40.454831 -222.534867) (xy 40.496273 -222.569355)
			(xy 40.532251 -222.609509) (xy 40.561999 -222.654473) (xy 40.584884 -222.70329) (xy 40.600416 -222.754919)
			(xy 40.608266 -222.808259) (xy 40.608758 -222.835216) (xy 40.608266 -222.862173) (xy 40.600416 -222.915513)
			(xy 40.584884 -222.967142) (xy 40.561999 -223.015959) (xy 40.532251 -223.060923) (xy 40.496273 -223.101077)
			(xy 40.454831 -223.135565) (xy 40.40881 -223.163651) (xy 40.35919 -223.184738) (xy 40.307029 -223.198374)
			(xy 40.253438 -223.204271) (xy 40.199559 -223.202302) (xy 40.146541 -223.192509) (xy 40.095514 -223.175101)
			(xy 40.047566 -223.150449) (xy 40.003718 -223.119079) (xy 39.964905 -223.081658) (xy 39.931953 -223.038985)
			(xy 39.905567 -222.991968) (xy 39.886307 -222.941611) (xy 39.874584 -222.888987) (xy 39.870649 -222.835216)
			(xy 33.064704 -222.835216) (xy 33.064212 -222.862173) (xy 33.056362 -222.915513) (xy 33.04083 -222.967142)
			(xy 33.017945 -223.015959) (xy 32.988197 -223.060923) (xy 32.952219 -223.101077) (xy 32.910777 -223.135565)
			(xy 32.864756 -223.163651) (xy 32.815136 -223.184738) (xy 32.762975 -223.198374) (xy 32.709384 -223.204271)
			(xy 32.655505 -223.202302) (xy 32.602487 -223.192509) (xy 32.55146 -223.175101) (xy 32.503512 -223.150449)
			(xy 32.459664 -223.119079) (xy 32.420851 -223.081658) (xy 32.387899 -223.038985) (xy 32.361513 -222.991968)
			(xy 32.342253 -222.941611) (xy 32.33053 -222.888987) (xy 32.326595 -222.835216) (xy 25.520904 -222.835216)
			(xy 25.520412 -222.862173) (xy 25.512562 -222.915513) (xy 25.49703 -222.967142) (xy 25.474145 -223.015959)
			(xy 25.444397 -223.060923) (xy 25.408419 -223.101077) (xy 25.366977 -223.135565) (xy 25.320956 -223.163651)
			(xy 25.271336 -223.184738) (xy 25.219175 -223.198374) (xy 25.165584 -223.204271) (xy 25.111705 -223.202302)
			(xy 25.058687 -223.192509) (xy 25.00766 -223.175101) (xy 24.959712 -223.150449) (xy 24.915864 -223.119079)
			(xy 24.877051 -223.081658) (xy 24.844099 -223.038985) (xy 24.817713 -222.991968) (xy 24.798453 -222.941611)
			(xy 24.78673 -222.888987) (xy 24.782795 -222.835216) (xy 17.97685 -222.835216) (xy 17.976358 -222.862173)
			(xy 17.968508 -222.915513) (xy 17.952976 -222.967142) (xy 17.930091 -223.015959) (xy 17.900343 -223.060923)
			(xy 17.864365 -223.101077) (xy 17.822923 -223.135565) (xy 17.776902 -223.163651) (xy 17.727282 -223.184738)
			(xy 17.675121 -223.198374) (xy 17.62153 -223.204271) (xy 17.567651 -223.202302) (xy 17.514633 -223.192509)
			(xy 17.463606 -223.175101) (xy 17.415658 -223.150449) (xy 17.37181 -223.119079) (xy 17.332997 -223.081658)
			(xy 17.300045 -223.038985) (xy 17.273659 -222.991968) (xy 17.254399 -222.941611) (xy 17.242676 -222.888987)
			(xy 17.238741 -222.835216) (xy 15.598394 -222.835216) (xy 15.598394 -223.685354) (xy 21.338809 -223.685354)
			(xy 21.342744 -223.631583) (xy 21.354467 -223.578959) (xy 21.373727 -223.528602) (xy 21.400113 -223.481585)
			(xy 21.433065 -223.438912) (xy 21.471878 -223.401491) (xy 21.515726 -223.370121) (xy 21.563674 -223.345469)
			(xy 21.614701 -223.328061) (xy 21.667719 -223.318268) (xy 21.721598 -223.316299) (xy 21.775189 -223.322196)
			(xy 21.82735 -223.335832) (xy 21.87697 -223.356919) (xy 21.922991 -223.385005) (xy 21.964433 -223.419493)
			(xy 22.000411 -223.459647) (xy 22.030159 -223.504611) (xy 22.053044 -223.553428) (xy 22.068576 -223.605057)
			(xy 22.076426 -223.658397) (xy 22.076918 -223.685354) (xy 28.882863 -223.685354) (xy 28.886798 -223.631583)
			(xy 28.898521 -223.578959) (xy 28.917781 -223.528602) (xy 28.944167 -223.481585) (xy 28.977119 -223.438912)
			(xy 29.015932 -223.401491) (xy 29.05978 -223.370121) (xy 29.107728 -223.345469) (xy 29.158755 -223.328061)
			(xy 29.211773 -223.318268) (xy 29.265652 -223.316299) (xy 29.319243 -223.322196) (xy 29.371404 -223.335832)
			(xy 29.421024 -223.356919) (xy 29.467045 -223.385005) (xy 29.508487 -223.419493) (xy 29.544465 -223.459647)
			(xy 29.574213 -223.504611) (xy 29.597098 -223.553428) (xy 29.61263 -223.605057) (xy 29.62048 -223.658397)
			(xy 29.620972 -223.685354) (xy 36.426663 -223.685354) (xy 36.430598 -223.631583) (xy 36.442321 -223.578959)
			(xy 36.461581 -223.528602) (xy 36.487967 -223.481585) (xy 36.520919 -223.438912) (xy 36.559732 -223.401491)
			(xy 36.60358 -223.370121) (xy 36.651528 -223.345469) (xy 36.702555 -223.328061) (xy 36.755573 -223.318268)
			(xy 36.809452 -223.316299) (xy 36.863043 -223.322196) (xy 36.915204 -223.335832) (xy 36.964824 -223.356919)
			(xy 37.010845 -223.385005) (xy 37.052287 -223.419493) (xy 37.088265 -223.459647) (xy 37.118013 -223.504611)
			(xy 37.140898 -223.553428) (xy 37.15643 -223.605057) (xy 37.16428 -223.658397) (xy 37.164772 -223.685354)
			(xy 43.970717 -223.685354) (xy 43.974652 -223.631583) (xy 43.986375 -223.578959) (xy 44.005635 -223.528602)
			(xy 44.032021 -223.481585) (xy 44.064973 -223.438912) (xy 44.103786 -223.401491) (xy 44.147634 -223.370121)
			(xy 44.195582 -223.345469) (xy 44.246609 -223.328061) (xy 44.299627 -223.318268) (xy 44.353506 -223.316299)
			(xy 44.407097 -223.322196) (xy 44.459258 -223.335832) (xy 44.508878 -223.356919) (xy 44.554899 -223.385005)
			(xy 44.596341 -223.419493) (xy 44.632319 -223.459647) (xy 44.662067 -223.504611) (xy 44.684952 -223.553428)
			(xy 44.700484 -223.605057) (xy 44.708334 -223.658397) (xy 44.708826 -223.685354) (xy 44.708334 -223.712311)
			(xy 44.700484 -223.765651) (xy 44.684952 -223.81728) (xy 44.662067 -223.866097) (xy 44.632319 -223.911061)
			(xy 44.596341 -223.951215) (xy 44.554899 -223.985703) (xy 44.508878 -224.013789) (xy 44.459258 -224.034876)
			(xy 44.407097 -224.048512) (xy 44.353506 -224.054409) (xy 44.299627 -224.05244) (xy 44.246609 -224.042647)
			(xy 44.195582 -224.025239) (xy 44.147634 -224.000587) (xy 44.103786 -223.969217) (xy 44.064973 -223.931796)
			(xy 44.032021 -223.889123) (xy 44.005635 -223.842106) (xy 43.986375 -223.791749) (xy 43.974652 -223.739125)
			(xy 43.970717 -223.685354) (xy 37.164772 -223.685354) (xy 37.16428 -223.712311) (xy 37.15643 -223.765651)
			(xy 37.140898 -223.81728) (xy 37.118013 -223.866097) (xy 37.088265 -223.911061) (xy 37.052287 -223.951215)
			(xy 37.010845 -223.985703) (xy 36.964824 -224.013789) (xy 36.915204 -224.034876) (xy 36.863043 -224.048512)
			(xy 36.809452 -224.054409) (xy 36.755573 -224.05244) (xy 36.702555 -224.042647) (xy 36.651528 -224.025239)
			(xy 36.60358 -224.000587) (xy 36.559732 -223.969217) (xy 36.520919 -223.931796) (xy 36.487967 -223.889123)
			(xy 36.461581 -223.842106) (xy 36.442321 -223.791749) (xy 36.430598 -223.739125) (xy 36.426663 -223.685354)
			(xy 29.620972 -223.685354) (xy 29.62048 -223.712311) (xy 29.61263 -223.765651) (xy 29.597098 -223.81728)
			(xy 29.574213 -223.866097) (xy 29.544465 -223.911061) (xy 29.508487 -223.951215) (xy 29.467045 -223.985703)
			(xy 29.421024 -224.013789) (xy 29.371404 -224.034876) (xy 29.319243 -224.048512) (xy 29.265652 -224.054409)
			(xy 29.211773 -224.05244) (xy 29.158755 -224.042647) (xy 29.107728 -224.025239) (xy 29.05978 -224.000587)
			(xy 29.015932 -223.969217) (xy 28.977119 -223.931796) (xy 28.944167 -223.889123) (xy 28.917781 -223.842106)
			(xy 28.898521 -223.791749) (xy 28.886798 -223.739125) (xy 28.882863 -223.685354) (xy 22.076918 -223.685354)
			(xy 22.076426 -223.712311) (xy 22.068576 -223.765651) (xy 22.053044 -223.81728) (xy 22.030159 -223.866097)
			(xy 22.000411 -223.911061) (xy 21.964433 -223.951215) (xy 21.922991 -223.985703) (xy 21.87697 -224.013789)
			(xy 21.82735 -224.034876) (xy 21.775189 -224.048512) (xy 21.721598 -224.054409) (xy 21.667719 -224.05244)
			(xy 21.614701 -224.042647) (xy 21.563674 -224.025239) (xy 21.515726 -224.000587) (xy 21.471878 -223.969217)
			(xy 21.433065 -223.931796) (xy 21.400113 -223.889123) (xy 21.373727 -223.842106) (xy 21.354467 -223.791749)
			(xy 21.342744 -223.739125) (xy 21.338809 -223.685354) (xy 15.598394 -223.685354) (xy 15.598394 -224.535238)
			(xy 17.238741 -224.535238) (xy 17.242676 -224.481467) (xy 17.254399 -224.428843) (xy 17.273659 -224.378486)
			(xy 17.300045 -224.331469) (xy 17.332997 -224.288796) (xy 17.37181 -224.251375) (xy 17.415658 -224.220005)
			(xy 17.463606 -224.195353) (xy 17.514633 -224.177945) (xy 17.567651 -224.168152) (xy 17.62153 -224.166183)
			(xy 17.675121 -224.17208) (xy 17.727282 -224.185716) (xy 17.776902 -224.206803) (xy 17.822923 -224.234889)
			(xy 17.864365 -224.269377) (xy 17.900343 -224.309531) (xy 17.930091 -224.354495) (xy 17.952976 -224.403312)
			(xy 17.968508 -224.454941) (xy 17.976358 -224.508281) (xy 17.97685 -224.535238) (xy 24.782795 -224.535238)
			(xy 24.78673 -224.481467) (xy 24.798453 -224.428843) (xy 24.817713 -224.378486) (xy 24.844099 -224.331469)
			(xy 24.877051 -224.288796) (xy 24.915864 -224.251375) (xy 24.959712 -224.220005) (xy 25.00766 -224.195353)
			(xy 25.058687 -224.177945) (xy 25.111705 -224.168152) (xy 25.165584 -224.166183) (xy 25.219175 -224.17208)
			(xy 25.271336 -224.185716) (xy 25.320956 -224.206803) (xy 25.366977 -224.234889) (xy 25.408419 -224.269377)
			(xy 25.444397 -224.309531) (xy 25.474145 -224.354495) (xy 25.49703 -224.403312) (xy 25.512562 -224.454941)
			(xy 25.520412 -224.508281) (xy 25.520904 -224.535238) (xy 32.326595 -224.535238) (xy 32.33053 -224.481467)
			(xy 32.342253 -224.428843) (xy 32.361513 -224.378486) (xy 32.387899 -224.331469) (xy 32.420851 -224.288796)
			(xy 32.459664 -224.251375) (xy 32.503512 -224.220005) (xy 32.55146 -224.195353) (xy 32.602487 -224.177945)
			(xy 32.655505 -224.168152) (xy 32.709384 -224.166183) (xy 32.762975 -224.17208) (xy 32.815136 -224.185716)
			(xy 32.864756 -224.206803) (xy 32.910777 -224.234889) (xy 32.952219 -224.269377) (xy 32.988197 -224.309531)
			(xy 33.017945 -224.354495) (xy 33.04083 -224.403312) (xy 33.056362 -224.454941) (xy 33.064212 -224.508281)
			(xy 33.064704 -224.535238) (xy 39.870649 -224.535238) (xy 39.874584 -224.481467) (xy 39.886307 -224.428843)
			(xy 39.905567 -224.378486) (xy 39.931953 -224.331469) (xy 39.964905 -224.288796) (xy 40.003718 -224.251375)
			(xy 40.047566 -224.220005) (xy 40.095514 -224.195353) (xy 40.146541 -224.177945) (xy 40.199559 -224.168152)
			(xy 40.253438 -224.166183) (xy 40.307029 -224.17208) (xy 40.35919 -224.185716) (xy 40.40881 -224.206803)
			(xy 40.454831 -224.234889) (xy 40.496273 -224.269377) (xy 40.532251 -224.309531) (xy 40.561999 -224.354495)
			(xy 40.584884 -224.403312) (xy 40.600416 -224.454941) (xy 40.608266 -224.508281) (xy 40.608758 -224.535238)
			(xy 40.608266 -224.562195) (xy 40.600416 -224.615535) (xy 40.584884 -224.667164) (xy 40.561999 -224.715981)
			(xy 40.532251 -224.760945) (xy 40.496273 -224.801099) (xy 40.454831 -224.835587) (xy 40.40881 -224.863673)
			(xy 40.35919 -224.88476) (xy 40.307029 -224.898396) (xy 40.253438 -224.904293) (xy 40.199559 -224.902324)
			(xy 40.146541 -224.892531) (xy 40.095514 -224.875123) (xy 40.047566 -224.850471) (xy 40.003718 -224.819101)
			(xy 39.964905 -224.78168) (xy 39.931953 -224.739007) (xy 39.905567 -224.69199) (xy 39.886307 -224.641633)
			(xy 39.874584 -224.589009) (xy 39.870649 -224.535238) (xy 33.064704 -224.535238) (xy 33.064212 -224.562195)
			(xy 33.056362 -224.615535) (xy 33.04083 -224.667164) (xy 33.017945 -224.715981) (xy 32.988197 -224.760945)
			(xy 32.952219 -224.801099) (xy 32.910777 -224.835587) (xy 32.864756 -224.863673) (xy 32.815136 -224.88476)
			(xy 32.762975 -224.898396) (xy 32.709384 -224.904293) (xy 32.655505 -224.902324) (xy 32.602487 -224.892531)
			(xy 32.55146 -224.875123) (xy 32.503512 -224.850471) (xy 32.459664 -224.819101) (xy 32.420851 -224.78168)
			(xy 32.387899 -224.739007) (xy 32.361513 -224.69199) (xy 32.342253 -224.641633) (xy 32.33053 -224.589009)
			(xy 32.326595 -224.535238) (xy 25.520904 -224.535238) (xy 25.520412 -224.562195) (xy 25.512562 -224.615535)
			(xy 25.49703 -224.667164) (xy 25.474145 -224.715981) (xy 25.444397 -224.760945) (xy 25.408419 -224.801099)
			(xy 25.366977 -224.835587) (xy 25.320956 -224.863673) (xy 25.271336 -224.88476) (xy 25.219175 -224.898396)
			(xy 25.165584 -224.904293) (xy 25.111705 -224.902324) (xy 25.058687 -224.892531) (xy 25.00766 -224.875123)
			(xy 24.959712 -224.850471) (xy 24.915864 -224.819101) (xy 24.877051 -224.78168) (xy 24.844099 -224.739007)
			(xy 24.817713 -224.69199) (xy 24.798453 -224.641633) (xy 24.78673 -224.589009) (xy 24.782795 -224.535238)
			(xy 17.97685 -224.535238) (xy 17.976358 -224.562195) (xy 17.968508 -224.615535) (xy 17.952976 -224.667164)
			(xy 17.930091 -224.715981) (xy 17.900343 -224.760945) (xy 17.864365 -224.801099) (xy 17.822923 -224.835587)
			(xy 17.776902 -224.863673) (xy 17.727282 -224.88476) (xy 17.675121 -224.898396) (xy 17.62153 -224.904293)
			(xy 17.567651 -224.902324) (xy 17.514633 -224.892531) (xy 17.463606 -224.875123) (xy 17.415658 -224.850471)
			(xy 17.37181 -224.819101) (xy 17.332997 -224.78168) (xy 17.300045 -224.739007) (xy 17.273659 -224.69199)
			(xy 17.254399 -224.641633) (xy 17.242676 -224.589009) (xy 17.238741 -224.535238) (xy 15.598394 -224.535238)
			(xy 15.598394 -225.385376) (xy 21.338809 -225.385376) (xy 21.342744 -225.331605) (xy 21.354467 -225.278981)
			(xy 21.373727 -225.228624) (xy 21.400113 -225.181607) (xy 21.433065 -225.138934) (xy 21.471878 -225.101513)
			(xy 21.515726 -225.070143) (xy 21.563674 -225.045491) (xy 21.614701 -225.028083) (xy 21.667719 -225.01829)
			(xy 21.721598 -225.016321) (xy 21.775189 -225.022218) (xy 21.82735 -225.035854) (xy 21.87697 -225.056941)
			(xy 21.922991 -225.085027) (xy 21.964433 -225.119515) (xy 22.000411 -225.159669) (xy 22.030159 -225.204633)
			(xy 22.053044 -225.25345) (xy 22.068576 -225.305079) (xy 22.076426 -225.358419) (xy 22.076918 -225.385376)
			(xy 28.882863 -225.385376) (xy 28.886798 -225.331605) (xy 28.898521 -225.278981) (xy 28.917781 -225.228624)
			(xy 28.944167 -225.181607) (xy 28.977119 -225.138934) (xy 29.015932 -225.101513) (xy 29.05978 -225.070143)
			(xy 29.107728 -225.045491) (xy 29.158755 -225.028083) (xy 29.211773 -225.01829) (xy 29.265652 -225.016321)
			(xy 29.319243 -225.022218) (xy 29.371404 -225.035854) (xy 29.421024 -225.056941) (xy 29.467045 -225.085027)
			(xy 29.508487 -225.119515) (xy 29.544465 -225.159669) (xy 29.574213 -225.204633) (xy 29.597098 -225.25345)
			(xy 29.61263 -225.305079) (xy 29.62048 -225.358419) (xy 29.620972 -225.385376) (xy 36.426663 -225.385376)
			(xy 36.430598 -225.331605) (xy 36.442321 -225.278981) (xy 36.461581 -225.228624) (xy 36.487967 -225.181607)
			(xy 36.520919 -225.138934) (xy 36.559732 -225.101513) (xy 36.60358 -225.070143) (xy 36.651528 -225.045491)
			(xy 36.702555 -225.028083) (xy 36.755573 -225.01829) (xy 36.809452 -225.016321) (xy 36.863043 -225.022218)
			(xy 36.915204 -225.035854) (xy 36.964824 -225.056941) (xy 37.010845 -225.085027) (xy 37.052287 -225.119515)
			(xy 37.088265 -225.159669) (xy 37.118013 -225.204633) (xy 37.140898 -225.25345) (xy 37.15643 -225.305079)
			(xy 37.16428 -225.358419) (xy 37.164772 -225.385376) (xy 43.970717 -225.385376) (xy 43.974652 -225.331605)
			(xy 43.986375 -225.278981) (xy 44.005635 -225.228624) (xy 44.032021 -225.181607) (xy 44.064973 -225.138934)
			(xy 44.103786 -225.101513) (xy 44.147634 -225.070143) (xy 44.195582 -225.045491) (xy 44.246609 -225.028083)
			(xy 44.299627 -225.01829) (xy 44.353506 -225.016321) (xy 44.407097 -225.022218) (xy 44.459258 -225.035854)
			(xy 44.508878 -225.056941) (xy 44.554899 -225.085027) (xy 44.596341 -225.119515) (xy 44.632319 -225.159669)
			(xy 44.662067 -225.204633) (xy 44.684952 -225.25345) (xy 44.700484 -225.305079) (xy 44.708334 -225.358419)
			(xy 44.708826 -225.385376) (xy 44.708334 -225.412333) (xy 44.700484 -225.465673) (xy 44.684952 -225.517302)
			(xy 44.662067 -225.566119) (xy 44.632319 -225.611083) (xy 44.596341 -225.651237) (xy 44.554899 -225.685725)
			(xy 44.508878 -225.713811) (xy 44.459258 -225.734898) (xy 44.407097 -225.748534) (xy 44.353506 -225.754431)
			(xy 44.299627 -225.752462) (xy 44.246609 -225.742669) (xy 44.195582 -225.725261) (xy 44.147634 -225.700609)
			(xy 44.103786 -225.669239) (xy 44.064973 -225.631818) (xy 44.032021 -225.589145) (xy 44.005635 -225.542128)
			(xy 43.986375 -225.491771) (xy 43.974652 -225.439147) (xy 43.970717 -225.385376) (xy 37.164772 -225.385376)
			(xy 37.16428 -225.412333) (xy 37.15643 -225.465673) (xy 37.140898 -225.517302) (xy 37.118013 -225.566119)
			(xy 37.088265 -225.611083) (xy 37.052287 -225.651237) (xy 37.010845 -225.685725) (xy 36.964824 -225.713811)
			(xy 36.915204 -225.734898) (xy 36.863043 -225.748534) (xy 36.809452 -225.754431) (xy 36.755573 -225.752462)
			(xy 36.702555 -225.742669) (xy 36.651528 -225.725261) (xy 36.60358 -225.700609) (xy 36.559732 -225.669239)
			(xy 36.520919 -225.631818) (xy 36.487967 -225.589145) (xy 36.461581 -225.542128) (xy 36.442321 -225.491771)
			(xy 36.430598 -225.439147) (xy 36.426663 -225.385376) (xy 29.620972 -225.385376) (xy 29.62048 -225.412333)
			(xy 29.61263 -225.465673) (xy 29.597098 -225.517302) (xy 29.574213 -225.566119) (xy 29.544465 -225.611083)
			(xy 29.508487 -225.651237) (xy 29.467045 -225.685725) (xy 29.421024 -225.713811) (xy 29.371404 -225.734898)
			(xy 29.319243 -225.748534) (xy 29.265652 -225.754431) (xy 29.211773 -225.752462) (xy 29.158755 -225.742669)
			(xy 29.107728 -225.725261) (xy 29.05978 -225.700609) (xy 29.015932 -225.669239) (xy 28.977119 -225.631818)
			(xy 28.944167 -225.589145) (xy 28.917781 -225.542128) (xy 28.898521 -225.491771) (xy 28.886798 -225.439147)
			(xy 28.882863 -225.385376) (xy 22.076918 -225.385376) (xy 22.076426 -225.412333) (xy 22.068576 -225.465673)
			(xy 22.053044 -225.517302) (xy 22.030159 -225.566119) (xy 22.000411 -225.611083) (xy 21.964433 -225.651237)
			(xy 21.922991 -225.685725) (xy 21.87697 -225.713811) (xy 21.82735 -225.734898) (xy 21.775189 -225.748534)
			(xy 21.721598 -225.754431) (xy 21.667719 -225.752462) (xy 21.614701 -225.742669) (xy 21.563674 -225.725261)
			(xy 21.515726 -225.700609) (xy 21.471878 -225.669239) (xy 21.433065 -225.631818) (xy 21.400113 -225.589145)
			(xy 21.373727 -225.542128) (xy 21.354467 -225.491771) (xy 21.342744 -225.439147) (xy 21.338809 -225.385376)
			(xy 15.598394 -225.385376) (xy 15.598394 -226.23526) (xy 17.238741 -226.23526) (xy 17.242676 -226.181489)
			(xy 17.254399 -226.128865) (xy 17.273659 -226.078508) (xy 17.300045 -226.031491) (xy 17.332997 -225.988818)
			(xy 17.37181 -225.951397) (xy 17.415658 -225.920027) (xy 17.463606 -225.895375) (xy 17.514633 -225.877967)
			(xy 17.567651 -225.868174) (xy 17.62153 -225.866205) (xy 17.675121 -225.872102) (xy 17.727282 -225.885738)
			(xy 17.776902 -225.906825) (xy 17.822923 -225.934911) (xy 17.864365 -225.969399) (xy 17.900343 -226.009553)
			(xy 17.930091 -226.054517) (xy 17.952976 -226.103334) (xy 17.968508 -226.154963) (xy 17.976358 -226.208303)
			(xy 17.97685 -226.23526) (xy 24.782795 -226.23526) (xy 24.78673 -226.181489) (xy 24.798453 -226.128865)
			(xy 24.817713 -226.078508) (xy 24.844099 -226.031491) (xy 24.877051 -225.988818) (xy 24.915864 -225.951397)
			(xy 24.959712 -225.920027) (xy 25.00766 -225.895375) (xy 25.058687 -225.877967) (xy 25.111705 -225.868174)
			(xy 25.165584 -225.866205) (xy 25.219175 -225.872102) (xy 25.271336 -225.885738) (xy 25.320956 -225.906825)
			(xy 25.366977 -225.934911) (xy 25.408419 -225.969399) (xy 25.444397 -226.009553) (xy 25.474145 -226.054517)
			(xy 25.49703 -226.103334) (xy 25.512562 -226.154963) (xy 25.520412 -226.208303) (xy 25.520904 -226.23526)
			(xy 32.326595 -226.23526) (xy 32.33053 -226.181489) (xy 32.342253 -226.128865) (xy 32.361513 -226.078508)
			(xy 32.387899 -226.031491) (xy 32.420851 -225.988818) (xy 32.459664 -225.951397) (xy 32.503512 -225.920027)
			(xy 32.55146 -225.895375) (xy 32.602487 -225.877967) (xy 32.655505 -225.868174) (xy 32.709384 -225.866205)
			(xy 32.762975 -225.872102) (xy 32.815136 -225.885738) (xy 32.864756 -225.906825) (xy 32.910777 -225.934911)
			(xy 32.952219 -225.969399) (xy 32.988197 -226.009553) (xy 33.017945 -226.054517) (xy 33.04083 -226.103334)
			(xy 33.056362 -226.154963) (xy 33.064212 -226.208303) (xy 33.064704 -226.23526) (xy 39.870649 -226.23526)
			(xy 39.874584 -226.181489) (xy 39.886307 -226.128865) (xy 39.905567 -226.078508) (xy 39.931953 -226.031491)
			(xy 39.964905 -225.988818) (xy 40.003718 -225.951397) (xy 40.047566 -225.920027) (xy 40.095514 -225.895375)
			(xy 40.146541 -225.877967) (xy 40.199559 -225.868174) (xy 40.253438 -225.866205) (xy 40.307029 -225.872102)
			(xy 40.35919 -225.885738) (xy 40.40881 -225.906825) (xy 40.454831 -225.934911) (xy 40.496273 -225.969399)
			(xy 40.532251 -226.009553) (xy 40.561999 -226.054517) (xy 40.584884 -226.103334) (xy 40.600416 -226.154963)
			(xy 40.608266 -226.208303) (xy 40.608758 -226.23526) (xy 40.608266 -226.262217) (xy 40.600416 -226.315557)
			(xy 40.584884 -226.367186) (xy 40.561999 -226.416003) (xy 40.532251 -226.460967) (xy 40.496273 -226.501121)
			(xy 40.454831 -226.535609) (xy 40.40881 -226.563695) (xy 40.35919 -226.584782) (xy 40.307029 -226.598418)
			(xy 40.253438 -226.604315) (xy 40.199559 -226.602346) (xy 40.146541 -226.592553) (xy 40.095514 -226.575145)
			(xy 40.047566 -226.550493) (xy 40.003718 -226.519123) (xy 39.964905 -226.481702) (xy 39.931953 -226.439029)
			(xy 39.905567 -226.392012) (xy 39.886307 -226.341655) (xy 39.874584 -226.289031) (xy 39.870649 -226.23526)
			(xy 33.064704 -226.23526) (xy 33.064212 -226.262217) (xy 33.056362 -226.315557) (xy 33.04083 -226.367186)
			(xy 33.017945 -226.416003) (xy 32.988197 -226.460967) (xy 32.952219 -226.501121) (xy 32.910777 -226.535609)
			(xy 32.864756 -226.563695) (xy 32.815136 -226.584782) (xy 32.762975 -226.598418) (xy 32.709384 -226.604315)
			(xy 32.655505 -226.602346) (xy 32.602487 -226.592553) (xy 32.55146 -226.575145) (xy 32.503512 -226.550493)
			(xy 32.459664 -226.519123) (xy 32.420851 -226.481702) (xy 32.387899 -226.439029) (xy 32.361513 -226.392012)
			(xy 32.342253 -226.341655) (xy 32.33053 -226.289031) (xy 32.326595 -226.23526) (xy 25.520904 -226.23526)
			(xy 25.520412 -226.262217) (xy 25.512562 -226.315557) (xy 25.49703 -226.367186) (xy 25.474145 -226.416003)
			(xy 25.444397 -226.460967) (xy 25.408419 -226.501121) (xy 25.366977 -226.535609) (xy 25.320956 -226.563695)
			(xy 25.271336 -226.584782) (xy 25.219175 -226.598418) (xy 25.165584 -226.604315) (xy 25.111705 -226.602346)
			(xy 25.058687 -226.592553) (xy 25.00766 -226.575145) (xy 24.959712 -226.550493) (xy 24.915864 -226.519123)
			(xy 24.877051 -226.481702) (xy 24.844099 -226.439029) (xy 24.817713 -226.392012) (xy 24.798453 -226.341655)
			(xy 24.78673 -226.289031) (xy 24.782795 -226.23526) (xy 17.97685 -226.23526) (xy 17.976358 -226.262217)
			(xy 17.968508 -226.315557) (xy 17.952976 -226.367186) (xy 17.930091 -226.416003) (xy 17.900343 -226.460967)
			(xy 17.864365 -226.501121) (xy 17.822923 -226.535609) (xy 17.776902 -226.563695) (xy 17.727282 -226.584782)
			(xy 17.675121 -226.598418) (xy 17.62153 -226.604315) (xy 17.567651 -226.602346) (xy 17.514633 -226.592553)
			(xy 17.463606 -226.575145) (xy 17.415658 -226.550493) (xy 17.37181 -226.519123) (xy 17.332997 -226.481702)
			(xy 17.300045 -226.439029) (xy 17.273659 -226.392012) (xy 17.254399 -226.341655) (xy 17.242676 -226.289031)
			(xy 17.238741 -226.23526) (xy 15.598394 -226.23526) (xy 15.598394 -227.085398) (xy 21.338809 -227.085398)
			(xy 21.342744 -227.031627) (xy 21.354467 -226.979003) (xy 21.373727 -226.928646) (xy 21.400113 -226.881629)
			(xy 21.433065 -226.838956) (xy 21.471878 -226.801535) (xy 21.515726 -226.770165) (xy 21.563674 -226.745513)
			(xy 21.614701 -226.728105) (xy 21.667719 -226.718312) (xy 21.721598 -226.716343) (xy 21.775189 -226.72224)
			(xy 21.82735 -226.735876) (xy 21.87697 -226.756963) (xy 21.922991 -226.785049) (xy 21.964433 -226.819537)
			(xy 22.000411 -226.859691) (xy 22.030159 -226.904655) (xy 22.053044 -226.953472) (xy 22.068576 -227.005101)
			(xy 22.076426 -227.058441) (xy 22.076918 -227.085398) (xy 28.882863 -227.085398) (xy 28.886798 -227.031627)
			(xy 28.898521 -226.979003) (xy 28.917781 -226.928646) (xy 28.944167 -226.881629) (xy 28.977119 -226.838956)
			(xy 29.015932 -226.801535) (xy 29.05978 -226.770165) (xy 29.107728 -226.745513) (xy 29.158755 -226.728105)
			(xy 29.211773 -226.718312) (xy 29.265652 -226.716343) (xy 29.319243 -226.72224) (xy 29.371404 -226.735876)
			(xy 29.421024 -226.756963) (xy 29.467045 -226.785049) (xy 29.508487 -226.819537) (xy 29.544465 -226.859691)
			(xy 29.574213 -226.904655) (xy 29.597098 -226.953472) (xy 29.61263 -227.005101) (xy 29.62048 -227.058441)
			(xy 29.620972 -227.085398) (xy 36.426663 -227.085398) (xy 36.430598 -227.031627) (xy 36.442321 -226.979003)
			(xy 36.461581 -226.928646) (xy 36.487967 -226.881629) (xy 36.520919 -226.838956) (xy 36.559732 -226.801535)
			(xy 36.60358 -226.770165) (xy 36.651528 -226.745513) (xy 36.702555 -226.728105) (xy 36.755573 -226.718312)
			(xy 36.809452 -226.716343) (xy 36.863043 -226.72224) (xy 36.915204 -226.735876) (xy 36.964824 -226.756963)
			(xy 37.010845 -226.785049) (xy 37.052287 -226.819537) (xy 37.088265 -226.859691) (xy 37.118013 -226.904655)
			(xy 37.140898 -226.953472) (xy 37.15643 -227.005101) (xy 37.16428 -227.058441) (xy 37.164772 -227.085398)
			(xy 43.970717 -227.085398) (xy 43.974652 -227.031627) (xy 43.986375 -226.979003) (xy 44.005635 -226.928646)
			(xy 44.032021 -226.881629) (xy 44.064973 -226.838956) (xy 44.103786 -226.801535) (xy 44.147634 -226.770165)
			(xy 44.195582 -226.745513) (xy 44.246609 -226.728105) (xy 44.299627 -226.718312) (xy 44.353506 -226.716343)
			(xy 44.407097 -226.72224) (xy 44.459258 -226.735876) (xy 44.508878 -226.756963) (xy 44.554899 -226.785049)
			(xy 44.596341 -226.819537) (xy 44.632319 -226.859691) (xy 44.662067 -226.904655) (xy 44.684952 -226.953472)
			(xy 44.700484 -227.005101) (xy 44.708334 -227.058441) (xy 44.708826 -227.085398) (xy 44.708334 -227.112355)
			(xy 44.700484 -227.165695) (xy 44.684952 -227.217324) (xy 44.662067 -227.266141) (xy 44.632319 -227.311105)
			(xy 44.596341 -227.351259) (xy 44.554899 -227.385747) (xy 44.508878 -227.413833) (xy 44.459258 -227.43492)
			(xy 44.407097 -227.448556) (xy 44.353506 -227.454453) (xy 44.299627 -227.452484) (xy 44.246609 -227.442691)
			(xy 44.195582 -227.425283) (xy 44.147634 -227.400631) (xy 44.103786 -227.369261) (xy 44.064973 -227.33184)
			(xy 44.032021 -227.289167) (xy 44.005635 -227.24215) (xy 43.986375 -227.191793) (xy 43.974652 -227.139169)
			(xy 43.970717 -227.085398) (xy 37.164772 -227.085398) (xy 37.16428 -227.112355) (xy 37.15643 -227.165695)
			(xy 37.140898 -227.217324) (xy 37.118013 -227.266141) (xy 37.088265 -227.311105) (xy 37.052287 -227.351259)
			(xy 37.010845 -227.385747) (xy 36.964824 -227.413833) (xy 36.915204 -227.43492) (xy 36.863043 -227.448556)
			(xy 36.809452 -227.454453) (xy 36.755573 -227.452484) (xy 36.702555 -227.442691) (xy 36.651528 -227.425283)
			(xy 36.60358 -227.400631) (xy 36.559732 -227.369261) (xy 36.520919 -227.33184) (xy 36.487967 -227.289167)
			(xy 36.461581 -227.24215) (xy 36.442321 -227.191793) (xy 36.430598 -227.139169) (xy 36.426663 -227.085398)
			(xy 29.620972 -227.085398) (xy 29.62048 -227.112355) (xy 29.61263 -227.165695) (xy 29.597098 -227.217324)
			(xy 29.574213 -227.266141) (xy 29.544465 -227.311105) (xy 29.508487 -227.351259) (xy 29.467045 -227.385747)
			(xy 29.421024 -227.413833) (xy 29.371404 -227.43492) (xy 29.319243 -227.448556) (xy 29.265652 -227.454453)
			(xy 29.211773 -227.452484) (xy 29.158755 -227.442691) (xy 29.107728 -227.425283) (xy 29.05978 -227.400631)
			(xy 29.015932 -227.369261) (xy 28.977119 -227.33184) (xy 28.944167 -227.289167) (xy 28.917781 -227.24215)
			(xy 28.898521 -227.191793) (xy 28.886798 -227.139169) (xy 28.882863 -227.085398) (xy 22.076918 -227.085398)
			(xy 22.076426 -227.112355) (xy 22.068576 -227.165695) (xy 22.053044 -227.217324) (xy 22.030159 -227.266141)
			(xy 22.000411 -227.311105) (xy 21.964433 -227.351259) (xy 21.922991 -227.385747) (xy 21.87697 -227.413833)
			(xy 21.82735 -227.43492) (xy 21.775189 -227.448556) (xy 21.721598 -227.454453) (xy 21.667719 -227.452484)
			(xy 21.614701 -227.442691) (xy 21.563674 -227.425283) (xy 21.515726 -227.400631) (xy 21.471878 -227.369261)
			(xy 21.433065 -227.33184) (xy 21.400113 -227.289167) (xy 21.373727 -227.24215) (xy 21.354467 -227.191793)
			(xy 21.342744 -227.139169) (xy 21.338809 -227.085398) (xy 15.598394 -227.085398) (xy 15.598394 -227.935282)
			(xy 17.238741 -227.935282) (xy 17.242676 -227.881511) (xy 17.254399 -227.828887) (xy 17.273659 -227.77853)
			(xy 17.300045 -227.731513) (xy 17.332997 -227.68884) (xy 17.37181 -227.651419) (xy 17.415658 -227.620049)
			(xy 17.463606 -227.595397) (xy 17.514633 -227.577989) (xy 17.567651 -227.568196) (xy 17.62153 -227.566227)
			(xy 17.675121 -227.572124) (xy 17.727282 -227.58576) (xy 17.776902 -227.606847) (xy 17.822923 -227.634933)
			(xy 17.864365 -227.669421) (xy 17.900343 -227.709575) (xy 17.930091 -227.754539) (xy 17.952976 -227.803356)
			(xy 17.968508 -227.854985) (xy 17.976358 -227.908325) (xy 17.97685 -227.935282) (xy 24.782795 -227.935282)
			(xy 24.78673 -227.881511) (xy 24.798453 -227.828887) (xy 24.817713 -227.77853) (xy 24.844099 -227.731513)
			(xy 24.877051 -227.68884) (xy 24.915864 -227.651419) (xy 24.959712 -227.620049) (xy 25.00766 -227.595397)
			(xy 25.058687 -227.577989) (xy 25.111705 -227.568196) (xy 25.165584 -227.566227) (xy 25.219175 -227.572124)
			(xy 25.271336 -227.58576) (xy 25.320956 -227.606847) (xy 25.366977 -227.634933) (xy 25.408419 -227.669421)
			(xy 25.444397 -227.709575) (xy 25.474145 -227.754539) (xy 25.49703 -227.803356) (xy 25.512562 -227.854985)
			(xy 25.520412 -227.908325) (xy 25.520904 -227.935282) (xy 32.326595 -227.935282) (xy 32.33053 -227.881511)
			(xy 32.342253 -227.828887) (xy 32.361513 -227.77853) (xy 32.387899 -227.731513) (xy 32.420851 -227.68884)
			(xy 32.459664 -227.651419) (xy 32.503512 -227.620049) (xy 32.55146 -227.595397) (xy 32.602487 -227.577989)
			(xy 32.655505 -227.568196) (xy 32.709384 -227.566227) (xy 32.762975 -227.572124) (xy 32.815136 -227.58576)
			(xy 32.864756 -227.606847) (xy 32.910777 -227.634933) (xy 32.952219 -227.669421) (xy 32.988197 -227.709575)
			(xy 33.017945 -227.754539) (xy 33.04083 -227.803356) (xy 33.056362 -227.854985) (xy 33.064212 -227.908325)
			(xy 33.064704 -227.935282) (xy 39.870649 -227.935282) (xy 39.874584 -227.881511) (xy 39.886307 -227.828887)
			(xy 39.905567 -227.77853) (xy 39.931953 -227.731513) (xy 39.964905 -227.68884) (xy 40.003718 -227.651419)
			(xy 40.047566 -227.620049) (xy 40.095514 -227.595397) (xy 40.146541 -227.577989) (xy 40.199559 -227.568196)
			(xy 40.253438 -227.566227) (xy 40.307029 -227.572124) (xy 40.35919 -227.58576) (xy 40.40881 -227.606847)
			(xy 40.454831 -227.634933) (xy 40.496273 -227.669421) (xy 40.532251 -227.709575) (xy 40.561999 -227.754539)
			(xy 40.584884 -227.803356) (xy 40.600416 -227.854985) (xy 40.608266 -227.908325) (xy 40.608758 -227.935282)
			(xy 40.608266 -227.962239) (xy 40.600416 -228.015579) (xy 40.584884 -228.067208) (xy 40.561999 -228.116025)
			(xy 40.532251 -228.160989) (xy 40.496273 -228.201143) (xy 40.454831 -228.235631) (xy 40.40881 -228.263717)
			(xy 40.35919 -228.284804) (xy 40.307029 -228.29844) (xy 40.253438 -228.304337) (xy 40.199559 -228.302368)
			(xy 40.146541 -228.292575) (xy 40.095514 -228.275167) (xy 40.047566 -228.250515) (xy 40.003718 -228.219145)
			(xy 39.964905 -228.181724) (xy 39.931953 -228.139051) (xy 39.905567 -228.092034) (xy 39.886307 -228.041677)
			(xy 39.874584 -227.989053) (xy 39.870649 -227.935282) (xy 33.064704 -227.935282) (xy 33.064212 -227.962239)
			(xy 33.056362 -228.015579) (xy 33.04083 -228.067208) (xy 33.017945 -228.116025) (xy 32.988197 -228.160989)
			(xy 32.952219 -228.201143) (xy 32.910777 -228.235631) (xy 32.864756 -228.263717) (xy 32.815136 -228.284804)
			(xy 32.762975 -228.29844) (xy 32.709384 -228.304337) (xy 32.655505 -228.302368) (xy 32.602487 -228.292575)
			(xy 32.55146 -228.275167) (xy 32.503512 -228.250515) (xy 32.459664 -228.219145) (xy 32.420851 -228.181724)
			(xy 32.387899 -228.139051) (xy 32.361513 -228.092034) (xy 32.342253 -228.041677) (xy 32.33053 -227.989053)
			(xy 32.326595 -227.935282) (xy 25.520904 -227.935282) (xy 25.520412 -227.962239) (xy 25.512562 -228.015579)
			(xy 25.49703 -228.067208) (xy 25.474145 -228.116025) (xy 25.444397 -228.160989) (xy 25.408419 -228.201143)
			(xy 25.366977 -228.235631) (xy 25.320956 -228.263717) (xy 25.271336 -228.284804) (xy 25.219175 -228.29844)
			(xy 25.165584 -228.304337) (xy 25.111705 -228.302368) (xy 25.058687 -228.292575) (xy 25.00766 -228.275167)
			(xy 24.959712 -228.250515) (xy 24.915864 -228.219145) (xy 24.877051 -228.181724) (xy 24.844099 -228.139051)
			(xy 24.817713 -228.092034) (xy 24.798453 -228.041677) (xy 24.78673 -227.989053) (xy 24.782795 -227.935282)
			(xy 17.97685 -227.935282) (xy 17.976358 -227.962239) (xy 17.968508 -228.015579) (xy 17.952976 -228.067208)
			(xy 17.930091 -228.116025) (xy 17.900343 -228.160989) (xy 17.864365 -228.201143) (xy 17.822923 -228.235631)
			(xy 17.776902 -228.263717) (xy 17.727282 -228.284804) (xy 17.675121 -228.29844) (xy 17.62153 -228.304337)
			(xy 17.567651 -228.302368) (xy 17.514633 -228.292575) (xy 17.463606 -228.275167) (xy 17.415658 -228.250515)
			(xy 17.37181 -228.219145) (xy 17.332997 -228.181724) (xy 17.300045 -228.139051) (xy 17.273659 -228.092034)
			(xy 17.254399 -228.041677) (xy 17.242676 -227.989053) (xy 17.238741 -227.935282) (xy 15.598394 -227.935282)
			(xy 15.598394 -228.78542) (xy 21.338809 -228.78542) (xy 21.342744 -228.731649) (xy 21.354467 -228.679025)
			(xy 21.373727 -228.628668) (xy 21.400113 -228.581651) (xy 21.433065 -228.538978) (xy 21.471878 -228.501557)
			(xy 21.515726 -228.470187) (xy 21.563674 -228.445535) (xy 21.614701 -228.428127) (xy 21.667719 -228.418334)
			(xy 21.721598 -228.416365) (xy 21.775189 -228.422262) (xy 21.82735 -228.435898) (xy 21.87697 -228.456985)
			(xy 21.922991 -228.485071) (xy 21.964433 -228.519559) (xy 22.000411 -228.559713) (xy 22.030159 -228.604677)
			(xy 22.053044 -228.653494) (xy 22.068576 -228.705123) (xy 22.076426 -228.758463) (xy 22.076918 -228.78542)
			(xy 28.882863 -228.78542) (xy 28.886798 -228.731649) (xy 28.898521 -228.679025) (xy 28.917781 -228.628668)
			(xy 28.944167 -228.581651) (xy 28.977119 -228.538978) (xy 29.015932 -228.501557) (xy 29.05978 -228.470187)
			(xy 29.107728 -228.445535) (xy 29.158755 -228.428127) (xy 29.211773 -228.418334) (xy 29.265652 -228.416365)
			(xy 29.319243 -228.422262) (xy 29.371404 -228.435898) (xy 29.421024 -228.456985) (xy 29.467045 -228.485071)
			(xy 29.508487 -228.519559) (xy 29.544465 -228.559713) (xy 29.574213 -228.604677) (xy 29.597098 -228.653494)
			(xy 29.61263 -228.705123) (xy 29.62048 -228.758463) (xy 29.620972 -228.78542) (xy 36.426663 -228.78542)
			(xy 36.430598 -228.731649) (xy 36.442321 -228.679025) (xy 36.461581 -228.628668) (xy 36.487967 -228.581651)
			(xy 36.520919 -228.538978) (xy 36.559732 -228.501557) (xy 36.60358 -228.470187) (xy 36.651528 -228.445535)
			(xy 36.702555 -228.428127) (xy 36.755573 -228.418334) (xy 36.809452 -228.416365) (xy 36.863043 -228.422262)
			(xy 36.915204 -228.435898) (xy 36.964824 -228.456985) (xy 37.010845 -228.485071) (xy 37.052287 -228.519559)
			(xy 37.088265 -228.559713) (xy 37.118013 -228.604677) (xy 37.140898 -228.653494) (xy 37.15643 -228.705123)
			(xy 37.16428 -228.758463) (xy 37.164772 -228.78542) (xy 43.970717 -228.78542) (xy 43.974652 -228.731649)
			(xy 43.986375 -228.679025) (xy 44.005635 -228.628668) (xy 44.032021 -228.581651) (xy 44.064973 -228.538978)
			(xy 44.103786 -228.501557) (xy 44.147634 -228.470187) (xy 44.195582 -228.445535) (xy 44.246609 -228.428127)
			(xy 44.299627 -228.418334) (xy 44.353506 -228.416365) (xy 44.407097 -228.422262) (xy 44.459258 -228.435898)
			(xy 44.508878 -228.456985) (xy 44.554899 -228.485071) (xy 44.596341 -228.519559) (xy 44.632319 -228.559713)
			(xy 44.662067 -228.604677) (xy 44.684952 -228.653494) (xy 44.700484 -228.705123) (xy 44.708334 -228.758463)
			(xy 44.708826 -228.78542) (xy 44.708334 -228.812377) (xy 44.700484 -228.865717) (xy 44.684952 -228.917346)
			(xy 44.662067 -228.966163) (xy 44.632319 -229.011127) (xy 44.596341 -229.051281) (xy 44.554899 -229.085769)
			(xy 44.508878 -229.113855) (xy 44.459258 -229.134942) (xy 44.407097 -229.148578) (xy 44.353506 -229.154475)
			(xy 44.299627 -229.152506) (xy 44.246609 -229.142713) (xy 44.195582 -229.125305) (xy 44.147634 -229.100653)
			(xy 44.103786 -229.069283) (xy 44.064973 -229.031862) (xy 44.032021 -228.989189) (xy 44.005635 -228.942172)
			(xy 43.986375 -228.891815) (xy 43.974652 -228.839191) (xy 43.970717 -228.78542) (xy 37.164772 -228.78542)
			(xy 37.16428 -228.812377) (xy 37.15643 -228.865717) (xy 37.140898 -228.917346) (xy 37.118013 -228.966163)
			(xy 37.088265 -229.011127) (xy 37.052287 -229.051281) (xy 37.010845 -229.085769) (xy 36.964824 -229.113855)
			(xy 36.915204 -229.134942) (xy 36.863043 -229.148578) (xy 36.809452 -229.154475) (xy 36.755573 -229.152506)
			(xy 36.702555 -229.142713) (xy 36.651528 -229.125305) (xy 36.60358 -229.100653) (xy 36.559732 -229.069283)
			(xy 36.520919 -229.031862) (xy 36.487967 -228.989189) (xy 36.461581 -228.942172) (xy 36.442321 -228.891815)
			(xy 36.430598 -228.839191) (xy 36.426663 -228.78542) (xy 29.620972 -228.78542) (xy 29.62048 -228.812377)
			(xy 29.61263 -228.865717) (xy 29.597098 -228.917346) (xy 29.574213 -228.966163) (xy 29.544465 -229.011127)
			(xy 29.508487 -229.051281) (xy 29.467045 -229.085769) (xy 29.421024 -229.113855) (xy 29.371404 -229.134942)
			(xy 29.319243 -229.148578) (xy 29.265652 -229.154475) (xy 29.211773 -229.152506) (xy 29.158755 -229.142713)
			(xy 29.107728 -229.125305) (xy 29.05978 -229.100653) (xy 29.015932 -229.069283) (xy 28.977119 -229.031862)
			(xy 28.944167 -228.989189) (xy 28.917781 -228.942172) (xy 28.898521 -228.891815) (xy 28.886798 -228.839191)
			(xy 28.882863 -228.78542) (xy 22.076918 -228.78542) (xy 22.076426 -228.812377) (xy 22.068576 -228.865717)
			(xy 22.053044 -228.917346) (xy 22.030159 -228.966163) (xy 22.000411 -229.011127) (xy 21.964433 -229.051281)
			(xy 21.922991 -229.085769) (xy 21.87697 -229.113855) (xy 21.82735 -229.134942) (xy 21.775189 -229.148578)
			(xy 21.721598 -229.154475) (xy 21.667719 -229.152506) (xy 21.614701 -229.142713) (xy 21.563674 -229.125305)
			(xy 21.515726 -229.100653) (xy 21.471878 -229.069283) (xy 21.433065 -229.031862) (xy 21.400113 -228.989189)
			(xy 21.373727 -228.942172) (xy 21.354467 -228.891815) (xy 21.342744 -228.839191) (xy 21.338809 -228.78542)
			(xy 15.598394 -228.78542) (xy 15.598394 -229.635304) (xy 17.238741 -229.635304) (xy 17.242676 -229.581533)
			(xy 17.254399 -229.528909) (xy 17.273659 -229.478552) (xy 17.300045 -229.431535) (xy 17.332997 -229.388862)
			(xy 17.37181 -229.351441) (xy 17.415658 -229.320071) (xy 17.463606 -229.295419) (xy 17.514633 -229.278011)
			(xy 17.567651 -229.268218) (xy 17.62153 -229.266249) (xy 17.675121 -229.272146) (xy 17.727282 -229.285782)
			(xy 17.776902 -229.306869) (xy 17.822923 -229.334955) (xy 17.864365 -229.369443) (xy 17.900343 -229.409597)
			(xy 17.930091 -229.454561) (xy 17.952976 -229.503378) (xy 17.968508 -229.555007) (xy 17.976358 -229.608347)
			(xy 17.97685 -229.635304) (xy 21.338809 -229.635304) (xy 21.342744 -229.581533) (xy 21.354467 -229.528909)
			(xy 21.373727 -229.478552) (xy 21.400113 -229.431535) (xy 21.433065 -229.388862) (xy 21.471878 -229.351441)
			(xy 21.515726 -229.320071) (xy 21.563674 -229.295419) (xy 21.614701 -229.278011) (xy 21.667719 -229.268218)
			(xy 21.721598 -229.266249) (xy 21.775189 -229.272146) (xy 21.82735 -229.285782) (xy 21.87697 -229.306869)
			(xy 21.922991 -229.334955) (xy 21.964433 -229.369443) (xy 22.000411 -229.409597) (xy 22.030159 -229.454561)
			(xy 22.053044 -229.503378) (xy 22.068576 -229.555007) (xy 22.076426 -229.608347) (xy 22.076918 -229.635304)
			(xy 24.782795 -229.635304) (xy 24.78673 -229.581533) (xy 24.798453 -229.528909) (xy 24.817713 -229.478552)
			(xy 24.844099 -229.431535) (xy 24.877051 -229.388862) (xy 24.915864 -229.351441) (xy 24.959712 -229.320071)
			(xy 25.00766 -229.295419) (xy 25.058687 -229.278011) (xy 25.111705 -229.268218) (xy 25.165584 -229.266249)
			(xy 25.219175 -229.272146) (xy 25.271336 -229.285782) (xy 25.320956 -229.306869) (xy 25.366977 -229.334955)
			(xy 25.408419 -229.369443) (xy 25.444397 -229.409597) (xy 25.474145 -229.454561) (xy 25.49703 -229.503378)
			(xy 25.512562 -229.555007) (xy 25.520412 -229.608347) (xy 25.520904 -229.635304) (xy 28.882863 -229.635304)
			(xy 28.886798 -229.581533) (xy 28.898521 -229.528909) (xy 28.917781 -229.478552) (xy 28.944167 -229.431535)
			(xy 28.977119 -229.388862) (xy 29.015932 -229.351441) (xy 29.05978 -229.320071) (xy 29.107728 -229.295419)
			(xy 29.158755 -229.278011) (xy 29.211773 -229.268218) (xy 29.265652 -229.266249) (xy 29.319243 -229.272146)
			(xy 29.371404 -229.285782) (xy 29.421024 -229.306869) (xy 29.467045 -229.334955) (xy 29.508487 -229.369443)
			(xy 29.544465 -229.409597) (xy 29.574213 -229.454561) (xy 29.597098 -229.503378) (xy 29.61263 -229.555007)
			(xy 29.62048 -229.608347) (xy 29.620972 -229.635304) (xy 32.326595 -229.635304) (xy 32.33053 -229.581533)
			(xy 32.342253 -229.528909) (xy 32.361513 -229.478552) (xy 32.387899 -229.431535) (xy 32.420851 -229.388862)
			(xy 32.459664 -229.351441) (xy 32.503512 -229.320071) (xy 32.55146 -229.295419) (xy 32.602487 -229.278011)
			(xy 32.655505 -229.268218) (xy 32.709384 -229.266249) (xy 32.762975 -229.272146) (xy 32.815136 -229.285782)
			(xy 32.864756 -229.306869) (xy 32.910777 -229.334955) (xy 32.952219 -229.369443) (xy 32.988197 -229.409597)
			(xy 33.017945 -229.454561) (xy 33.04083 -229.503378) (xy 33.056362 -229.555007) (xy 33.064212 -229.608347)
			(xy 33.064704 -229.635304) (xy 36.426663 -229.635304) (xy 36.430598 -229.581533) (xy 36.442321 -229.528909)
			(xy 36.461581 -229.478552) (xy 36.487967 -229.431535) (xy 36.520919 -229.388862) (xy 36.559732 -229.351441)
			(xy 36.60358 -229.320071) (xy 36.651528 -229.295419) (xy 36.702555 -229.278011) (xy 36.755573 -229.268218)
			(xy 36.809452 -229.266249) (xy 36.863043 -229.272146) (xy 36.915204 -229.285782) (xy 36.964824 -229.306869)
			(xy 37.010845 -229.334955) (xy 37.052287 -229.369443) (xy 37.088265 -229.409597) (xy 37.118013 -229.454561)
			(xy 37.140898 -229.503378) (xy 37.15643 -229.555007) (xy 37.16428 -229.608347) (xy 37.164772 -229.635304)
			(xy 39.870649 -229.635304) (xy 39.874584 -229.581533) (xy 39.886307 -229.528909) (xy 39.905567 -229.478552)
			(xy 39.931953 -229.431535) (xy 39.964905 -229.388862) (xy 40.003718 -229.351441) (xy 40.047566 -229.320071)
			(xy 40.095514 -229.295419) (xy 40.146541 -229.278011) (xy 40.199559 -229.268218) (xy 40.253438 -229.266249)
			(xy 40.307029 -229.272146) (xy 40.35919 -229.285782) (xy 40.40881 -229.306869) (xy 40.454831 -229.334955)
			(xy 40.496273 -229.369443) (xy 40.532251 -229.409597) (xy 40.561999 -229.454561) (xy 40.584884 -229.503378)
			(xy 40.600416 -229.555007) (xy 40.608266 -229.608347) (xy 40.608758 -229.635304) (xy 43.970717 -229.635304)
			(xy 43.974652 -229.581533) (xy 43.986375 -229.528909) (xy 44.005635 -229.478552) (xy 44.032021 -229.431535)
			(xy 44.064973 -229.388862) (xy 44.103786 -229.351441) (xy 44.147634 -229.320071) (xy 44.195582 -229.295419)
			(xy 44.246609 -229.278011) (xy 44.299627 -229.268218) (xy 44.353506 -229.266249) (xy 44.407097 -229.272146)
			(xy 44.459258 -229.285782) (xy 44.508878 -229.306869) (xy 44.554899 -229.334955) (xy 44.596341 -229.369443)
			(xy 44.632319 -229.409597) (xy 44.662067 -229.454561) (xy 44.684952 -229.503378) (xy 44.700484 -229.555007)
			(xy 44.708334 -229.608347) (xy 44.708826 -229.635304) (xy 44.708334 -229.662261) (xy 44.700484 -229.715601)
			(xy 44.684952 -229.76723) (xy 44.662067 -229.816047) (xy 44.632319 -229.861011) (xy 44.596341 -229.901165)
			(xy 44.554899 -229.935653) (xy 44.508878 -229.963739) (xy 44.459258 -229.984826) (xy 44.407097 -229.998462)
			(xy 44.353506 -230.004359) (xy 44.299627 -230.00239) (xy 44.246609 -229.992597) (xy 44.195582 -229.975189)
			(xy 44.147634 -229.950537) (xy 44.103786 -229.919167) (xy 44.064973 -229.881746) (xy 44.032021 -229.839073)
			(xy 44.005635 -229.792056) (xy 43.986375 -229.741699) (xy 43.974652 -229.689075) (xy 43.970717 -229.635304)
			(xy 40.608758 -229.635304) (xy 40.608266 -229.662261) (xy 40.600416 -229.715601) (xy 40.584884 -229.76723)
			(xy 40.561999 -229.816047) (xy 40.532251 -229.861011) (xy 40.496273 -229.901165) (xy 40.454831 -229.935653)
			(xy 40.40881 -229.963739) (xy 40.35919 -229.984826) (xy 40.307029 -229.998462) (xy 40.253438 -230.004359)
			(xy 40.199559 -230.00239) (xy 40.146541 -229.992597) (xy 40.095514 -229.975189) (xy 40.047566 -229.950537)
			(xy 40.003718 -229.919167) (xy 39.964905 -229.881746) (xy 39.931953 -229.839073) (xy 39.905567 -229.792056)
			(xy 39.886307 -229.741699) (xy 39.874584 -229.689075) (xy 39.870649 -229.635304) (xy 37.164772 -229.635304)
			(xy 37.16428 -229.662261) (xy 37.15643 -229.715601) (xy 37.140898 -229.76723) (xy 37.118013 -229.816047)
			(xy 37.088265 -229.861011) (xy 37.052287 -229.901165) (xy 37.010845 -229.935653) (xy 36.964824 -229.963739)
			(xy 36.915204 -229.984826) (xy 36.863043 -229.998462) (xy 36.809452 -230.004359) (xy 36.755573 -230.00239)
			(xy 36.702555 -229.992597) (xy 36.651528 -229.975189) (xy 36.60358 -229.950537) (xy 36.559732 -229.919167)
			(xy 36.520919 -229.881746) (xy 36.487967 -229.839073) (xy 36.461581 -229.792056) (xy 36.442321 -229.741699)
			(xy 36.430598 -229.689075) (xy 36.426663 -229.635304) (xy 33.064704 -229.635304) (xy 33.064212 -229.662261)
			(xy 33.056362 -229.715601) (xy 33.04083 -229.76723) (xy 33.017945 -229.816047) (xy 32.988197 -229.861011)
			(xy 32.952219 -229.901165) (xy 32.910777 -229.935653) (xy 32.864756 -229.963739) (xy 32.815136 -229.984826)
			(xy 32.762975 -229.998462) (xy 32.709384 -230.004359) (xy 32.655505 -230.00239) (xy 32.602487 -229.992597)
			(xy 32.55146 -229.975189) (xy 32.503512 -229.950537) (xy 32.459664 -229.919167) (xy 32.420851 -229.881746)
			(xy 32.387899 -229.839073) (xy 32.361513 -229.792056) (xy 32.342253 -229.741699) (xy 32.33053 -229.689075)
			(xy 32.326595 -229.635304) (xy 29.620972 -229.635304) (xy 29.62048 -229.662261) (xy 29.61263 -229.715601)
			(xy 29.597098 -229.76723) (xy 29.574213 -229.816047) (xy 29.544465 -229.861011) (xy 29.508487 -229.901165)
			(xy 29.467045 -229.935653) (xy 29.421024 -229.963739) (xy 29.371404 -229.984826) (xy 29.319243 -229.998462)
			(xy 29.265652 -230.004359) (xy 29.211773 -230.00239) (xy 29.158755 -229.992597) (xy 29.107728 -229.975189)
			(xy 29.05978 -229.950537) (xy 29.015932 -229.919167) (xy 28.977119 -229.881746) (xy 28.944167 -229.839073)
			(xy 28.917781 -229.792056) (xy 28.898521 -229.741699) (xy 28.886798 -229.689075) (xy 28.882863 -229.635304)
			(xy 25.520904 -229.635304) (xy 25.520412 -229.662261) (xy 25.512562 -229.715601) (xy 25.49703 -229.76723)
			(xy 25.474145 -229.816047) (xy 25.444397 -229.861011) (xy 25.408419 -229.901165) (xy 25.366977 -229.935653)
			(xy 25.320956 -229.963739) (xy 25.271336 -229.984826) (xy 25.219175 -229.998462) (xy 25.165584 -230.004359)
			(xy 25.111705 -230.00239) (xy 25.058687 -229.992597) (xy 25.00766 -229.975189) (xy 24.959712 -229.950537)
			(xy 24.915864 -229.919167) (xy 24.877051 -229.881746) (xy 24.844099 -229.839073) (xy 24.817713 -229.792056)
			(xy 24.798453 -229.741699) (xy 24.78673 -229.689075) (xy 24.782795 -229.635304) (xy 22.076918 -229.635304)
			(xy 22.076426 -229.662261) (xy 22.068576 -229.715601) (xy 22.053044 -229.76723) (xy 22.030159 -229.816047)
			(xy 22.000411 -229.861011) (xy 21.964433 -229.901165) (xy 21.922991 -229.935653) (xy 21.87697 -229.963739)
			(xy 21.82735 -229.984826) (xy 21.775189 -229.998462) (xy 21.721598 -230.004359) (xy 21.667719 -230.00239)
			(xy 21.614701 -229.992597) (xy 21.563674 -229.975189) (xy 21.515726 -229.950537) (xy 21.471878 -229.919167)
			(xy 21.433065 -229.881746) (xy 21.400113 -229.839073) (xy 21.373727 -229.792056) (xy 21.354467 -229.741699)
			(xy 21.342744 -229.689075) (xy 21.338809 -229.635304) (xy 17.97685 -229.635304) (xy 17.976358 -229.662261)
			(xy 17.968508 -229.715601) (xy 17.952976 -229.76723) (xy 17.930091 -229.816047) (xy 17.900343 -229.861011)
			(xy 17.864365 -229.901165) (xy 17.822923 -229.935653) (xy 17.776902 -229.963739) (xy 17.727282 -229.984826)
			(xy 17.675121 -229.998462) (xy 17.62153 -230.004359) (xy 17.567651 -230.00239) (xy 17.514633 -229.992597)
			(xy 17.463606 -229.975189) (xy 17.415658 -229.950537) (xy 17.37181 -229.919167) (xy 17.332997 -229.881746)
			(xy 17.300045 -229.839073) (xy 17.273659 -229.792056) (xy 17.254399 -229.741699) (xy 17.242676 -229.689075)
			(xy 17.238741 -229.635304) (xy 15.598394 -229.635304) (xy 15.598394 -230.485442) (xy 17.238741 -230.485442)
			(xy 17.242676 -230.431671) (xy 17.254399 -230.379047) (xy 17.273659 -230.32869) (xy 17.300045 -230.281673)
			(xy 17.332997 -230.239) (xy 17.37181 -230.201579) (xy 17.415658 -230.170209) (xy 17.463606 -230.145557)
			(xy 17.514633 -230.128149) (xy 17.567651 -230.118356) (xy 17.62153 -230.116387) (xy 17.675121 -230.122284)
			(xy 17.727282 -230.13592) (xy 17.776902 -230.157007) (xy 17.822923 -230.185093) (xy 17.864365 -230.219581)
			(xy 17.900343 -230.259735) (xy 17.930091 -230.304699) (xy 17.952976 -230.353516) (xy 17.968508 -230.405145)
			(xy 17.976358 -230.458485) (xy 17.97685 -230.485442) (xy 24.782795 -230.485442) (xy 24.78673 -230.431671)
			(xy 24.798453 -230.379047) (xy 24.817713 -230.32869) (xy 24.844099 -230.281673) (xy 24.877051 -230.239)
			(xy 24.915864 -230.201579) (xy 24.959712 -230.170209) (xy 25.00766 -230.145557) (xy 25.058687 -230.128149)
			(xy 25.111705 -230.118356) (xy 25.165584 -230.116387) (xy 25.219175 -230.122284) (xy 25.271336 -230.13592)
			(xy 25.320956 -230.157007) (xy 25.366977 -230.185093) (xy 25.408419 -230.219581) (xy 25.444397 -230.259735)
			(xy 25.474145 -230.304699) (xy 25.49703 -230.353516) (xy 25.512562 -230.405145) (xy 25.520412 -230.458485)
			(xy 25.520904 -230.485442) (xy 32.326595 -230.485442) (xy 32.33053 -230.431671) (xy 32.342253 -230.379047)
			(xy 32.361513 -230.32869) (xy 32.387899 -230.281673) (xy 32.420851 -230.239) (xy 32.459664 -230.201579)
			(xy 32.503512 -230.170209) (xy 32.55146 -230.145557) (xy 32.602487 -230.128149) (xy 32.655505 -230.118356)
			(xy 32.709384 -230.116387) (xy 32.762975 -230.122284) (xy 32.815136 -230.13592) (xy 32.864756 -230.157007)
			(xy 32.910777 -230.185093) (xy 32.952219 -230.219581) (xy 32.988197 -230.259735) (xy 33.017945 -230.304699)
			(xy 33.04083 -230.353516) (xy 33.056362 -230.405145) (xy 33.064212 -230.458485) (xy 33.064704 -230.485442)
			(xy 39.870649 -230.485442) (xy 39.874584 -230.431671) (xy 39.886307 -230.379047) (xy 39.905567 -230.32869)
			(xy 39.931953 -230.281673) (xy 39.964905 -230.239) (xy 40.003718 -230.201579) (xy 40.047566 -230.170209)
			(xy 40.095514 -230.145557) (xy 40.146541 -230.128149) (xy 40.199559 -230.118356) (xy 40.253438 -230.116387)
			(xy 40.307029 -230.122284) (xy 40.35919 -230.13592) (xy 40.40881 -230.157007) (xy 40.454831 -230.185093)
			(xy 40.496273 -230.219581) (xy 40.532251 -230.259735) (xy 40.561999 -230.304699) (xy 40.584884 -230.353516)
			(xy 40.600416 -230.405145) (xy 40.608266 -230.458485) (xy 40.608758 -230.485442) (xy 40.608266 -230.512399)
			(xy 40.600416 -230.565739) (xy 40.584884 -230.617368) (xy 40.561999 -230.666185) (xy 40.532251 -230.711149)
			(xy 40.496273 -230.751303) (xy 40.454831 -230.785791) (xy 40.40881 -230.813877) (xy 40.35919 -230.834964)
			(xy 40.307029 -230.8486) (xy 40.253438 -230.854497) (xy 40.199559 -230.852528) (xy 40.146541 -230.842735)
			(xy 40.095514 -230.825327) (xy 40.047566 -230.800675) (xy 40.003718 -230.769305) (xy 39.964905 -230.731884)
			(xy 39.931953 -230.689211) (xy 39.905567 -230.642194) (xy 39.886307 -230.591837) (xy 39.874584 -230.539213)
			(xy 39.870649 -230.485442) (xy 33.064704 -230.485442) (xy 33.064212 -230.512399) (xy 33.056362 -230.565739)
			(xy 33.04083 -230.617368) (xy 33.017945 -230.666185) (xy 32.988197 -230.711149) (xy 32.952219 -230.751303)
			(xy 32.910777 -230.785791) (xy 32.864756 -230.813877) (xy 32.815136 -230.834964) (xy 32.762975 -230.8486)
			(xy 32.709384 -230.854497) (xy 32.655505 -230.852528) (xy 32.602487 -230.842735) (xy 32.55146 -230.825327)
			(xy 32.503512 -230.800675) (xy 32.459664 -230.769305) (xy 32.420851 -230.731884) (xy 32.387899 -230.689211)
			(xy 32.361513 -230.642194) (xy 32.342253 -230.591837) (xy 32.33053 -230.539213) (xy 32.326595 -230.485442)
			(xy 25.520904 -230.485442) (xy 25.520412 -230.512399) (xy 25.512562 -230.565739) (xy 25.49703 -230.617368)
			(xy 25.474145 -230.666185) (xy 25.444397 -230.711149) (xy 25.408419 -230.751303) (xy 25.366977 -230.785791)
			(xy 25.320956 -230.813877) (xy 25.271336 -230.834964) (xy 25.219175 -230.8486) (xy 25.165584 -230.854497)
			(xy 25.111705 -230.852528) (xy 25.058687 -230.842735) (xy 25.00766 -230.825327) (xy 24.959712 -230.800675)
			(xy 24.915864 -230.769305) (xy 24.877051 -230.731884) (xy 24.844099 -230.689211) (xy 24.817713 -230.642194)
			(xy 24.798453 -230.591837) (xy 24.78673 -230.539213) (xy 24.782795 -230.485442) (xy 17.97685 -230.485442)
			(xy 17.976358 -230.512399) (xy 17.968508 -230.565739) (xy 17.952976 -230.617368) (xy 17.930091 -230.666185)
			(xy 17.900343 -230.711149) (xy 17.864365 -230.751303) (xy 17.822923 -230.785791) (xy 17.776902 -230.813877)
			(xy 17.727282 -230.834964) (xy 17.675121 -230.8486) (xy 17.62153 -230.854497) (xy 17.567651 -230.852528)
			(xy 17.514633 -230.842735) (xy 17.463606 -230.825327) (xy 17.415658 -230.800675) (xy 17.37181 -230.769305)
			(xy 17.332997 -230.731884) (xy 17.300045 -230.689211) (xy 17.273659 -230.642194) (xy 17.254399 -230.591837)
			(xy 17.242676 -230.539213) (xy 17.238741 -230.485442) (xy 15.598394 -230.485442) (xy 15.598394 -231.335326)
			(xy 21.338809 -231.335326) (xy 21.342744 -231.281555) (xy 21.354467 -231.228931) (xy 21.373727 -231.178574)
			(xy 21.400113 -231.131557) (xy 21.433065 -231.088884) (xy 21.471878 -231.051463) (xy 21.515726 -231.020093)
			(xy 21.563674 -230.995441) (xy 21.614701 -230.978033) (xy 21.667719 -230.96824) (xy 21.721598 -230.966271)
			(xy 21.775189 -230.972168) (xy 21.82735 -230.985804) (xy 21.87697 -231.006891) (xy 21.922991 -231.034977)
			(xy 21.964433 -231.069465) (xy 22.000411 -231.109619) (xy 22.030159 -231.154583) (xy 22.053044 -231.2034)
			(xy 22.068576 -231.255029) (xy 22.076426 -231.308369) (xy 22.076918 -231.335326) (xy 28.882863 -231.335326)
			(xy 28.886798 -231.281555) (xy 28.898521 -231.228931) (xy 28.917781 -231.178574) (xy 28.944167 -231.131557)
			(xy 28.977119 -231.088884) (xy 29.015932 -231.051463) (xy 29.05978 -231.020093) (xy 29.107728 -230.995441)
			(xy 29.158755 -230.978033) (xy 29.211773 -230.96824) (xy 29.265652 -230.966271) (xy 29.319243 -230.972168)
			(xy 29.371404 -230.985804) (xy 29.421024 -231.006891) (xy 29.467045 -231.034977) (xy 29.508487 -231.069465)
			(xy 29.544465 -231.109619) (xy 29.574213 -231.154583) (xy 29.597098 -231.2034) (xy 29.61263 -231.255029)
			(xy 29.62048 -231.308369) (xy 29.620972 -231.335326) (xy 36.426663 -231.335326) (xy 36.430598 -231.281555)
			(xy 36.442321 -231.228931) (xy 36.461581 -231.178574) (xy 36.487967 -231.131557) (xy 36.520919 -231.088884)
			(xy 36.559732 -231.051463) (xy 36.60358 -231.020093) (xy 36.651528 -230.995441) (xy 36.702555 -230.978033)
			(xy 36.755573 -230.96824) (xy 36.809452 -230.966271) (xy 36.863043 -230.972168) (xy 36.915204 -230.985804)
			(xy 36.964824 -231.006891) (xy 37.010845 -231.034977) (xy 37.052287 -231.069465) (xy 37.088265 -231.109619)
			(xy 37.118013 -231.154583) (xy 37.140898 -231.2034) (xy 37.15643 -231.255029) (xy 37.16428 -231.308369)
			(xy 37.164772 -231.335326) (xy 43.970717 -231.335326) (xy 43.974652 -231.281555) (xy 43.986375 -231.228931)
			(xy 44.005635 -231.178574) (xy 44.032021 -231.131557) (xy 44.064973 -231.088884) (xy 44.103786 -231.051463)
			(xy 44.147634 -231.020093) (xy 44.195582 -230.995441) (xy 44.246609 -230.978033) (xy 44.299627 -230.96824)
			(xy 44.353506 -230.966271) (xy 44.407097 -230.972168) (xy 44.459258 -230.985804) (xy 44.508878 -231.006891)
			(xy 44.554899 -231.034977) (xy 44.596341 -231.069465) (xy 44.632319 -231.109619) (xy 44.662067 -231.154583)
			(xy 44.684952 -231.2034) (xy 44.700484 -231.255029) (xy 44.708334 -231.308369) (xy 44.708826 -231.335326)
			(xy 44.708334 -231.362283) (xy 44.700484 -231.415623) (xy 44.684952 -231.467252) (xy 44.662067 -231.516069)
			(xy 44.632319 -231.561033) (xy 44.596341 -231.601187) (xy 44.554899 -231.635675) (xy 44.508878 -231.663761)
			(xy 44.459258 -231.684848) (xy 44.407097 -231.698484) (xy 44.353506 -231.704381) (xy 44.299627 -231.702412)
			(xy 44.246609 -231.692619) (xy 44.195582 -231.675211) (xy 44.147634 -231.650559) (xy 44.103786 -231.619189)
			(xy 44.064973 -231.581768) (xy 44.032021 -231.539095) (xy 44.005635 -231.492078) (xy 43.986375 -231.441721)
			(xy 43.974652 -231.389097) (xy 43.970717 -231.335326) (xy 37.164772 -231.335326) (xy 37.16428 -231.362283)
			(xy 37.15643 -231.415623) (xy 37.140898 -231.467252) (xy 37.118013 -231.516069) (xy 37.088265 -231.561033)
			(xy 37.052287 -231.601187) (xy 37.010845 -231.635675) (xy 36.964824 -231.663761) (xy 36.915204 -231.684848)
			(xy 36.863043 -231.698484) (xy 36.809452 -231.704381) (xy 36.755573 -231.702412) (xy 36.702555 -231.692619)
			(xy 36.651528 -231.675211) (xy 36.60358 -231.650559) (xy 36.559732 -231.619189) (xy 36.520919 -231.581768)
			(xy 36.487967 -231.539095) (xy 36.461581 -231.492078) (xy 36.442321 -231.441721) (xy 36.430598 -231.389097)
			(xy 36.426663 -231.335326) (xy 29.620972 -231.335326) (xy 29.62048 -231.362283) (xy 29.61263 -231.415623)
			(xy 29.597098 -231.467252) (xy 29.574213 -231.516069) (xy 29.544465 -231.561033) (xy 29.508487 -231.601187)
			(xy 29.467045 -231.635675) (xy 29.421024 -231.663761) (xy 29.371404 -231.684848) (xy 29.319243 -231.698484)
			(xy 29.265652 -231.704381) (xy 29.211773 -231.702412) (xy 29.158755 -231.692619) (xy 29.107728 -231.675211)
			(xy 29.05978 -231.650559) (xy 29.015932 -231.619189) (xy 28.977119 -231.581768) (xy 28.944167 -231.539095)
			(xy 28.917781 -231.492078) (xy 28.898521 -231.441721) (xy 28.886798 -231.389097) (xy 28.882863 -231.335326)
			(xy 22.076918 -231.335326) (xy 22.076426 -231.362283) (xy 22.068576 -231.415623) (xy 22.053044 -231.467252)
			(xy 22.030159 -231.516069) (xy 22.000411 -231.561033) (xy 21.964433 -231.601187) (xy 21.922991 -231.635675)
			(xy 21.87697 -231.663761) (xy 21.82735 -231.684848) (xy 21.775189 -231.698484) (xy 21.721598 -231.704381)
			(xy 21.667719 -231.702412) (xy 21.614701 -231.692619) (xy 21.563674 -231.675211) (xy 21.515726 -231.650559)
			(xy 21.471878 -231.619189) (xy 21.433065 -231.581768) (xy 21.400113 -231.539095) (xy 21.373727 -231.492078)
			(xy 21.354467 -231.441721) (xy 21.342744 -231.389097) (xy 21.338809 -231.335326) (xy 15.598394 -231.335326)
			(xy 15.598394 -232.18521) (xy 17.238741 -232.18521) (xy 17.242676 -232.131439) (xy 17.254399 -232.078815)
			(xy 17.273659 -232.028458) (xy 17.300045 -231.981441) (xy 17.332997 -231.938768) (xy 17.37181 -231.901347)
			(xy 17.415658 -231.869977) (xy 17.463606 -231.845325) (xy 17.514633 -231.827917) (xy 17.567651 -231.818124)
			(xy 17.62153 -231.816155) (xy 17.675121 -231.822052) (xy 17.727282 -231.835688) (xy 17.776902 -231.856775)
			(xy 17.822923 -231.884861) (xy 17.864365 -231.919349) (xy 17.900343 -231.959503) (xy 17.930091 -232.004467)
			(xy 17.952976 -232.053284) (xy 17.968508 -232.104913) (xy 17.976358 -232.158253) (xy 17.97685 -232.18521)
			(xy 24.782795 -232.18521) (xy 24.78673 -232.131439) (xy 24.798453 -232.078815) (xy 24.817713 -232.028458)
			(xy 24.844099 -231.981441) (xy 24.877051 -231.938768) (xy 24.915864 -231.901347) (xy 24.959712 -231.869977)
			(xy 25.00766 -231.845325) (xy 25.058687 -231.827917) (xy 25.111705 -231.818124) (xy 25.165584 -231.816155)
			(xy 25.219175 -231.822052) (xy 25.271336 -231.835688) (xy 25.320956 -231.856775) (xy 25.366977 -231.884861)
			(xy 25.408419 -231.919349) (xy 25.444397 -231.959503) (xy 25.474145 -232.004467) (xy 25.49703 -232.053284)
			(xy 25.512562 -232.104913) (xy 25.520412 -232.158253) (xy 25.520904 -232.18521) (xy 32.326595 -232.18521)
			(xy 32.33053 -232.131439) (xy 32.342253 -232.078815) (xy 32.361513 -232.028458) (xy 32.387899 -231.981441)
			(xy 32.420851 -231.938768) (xy 32.459664 -231.901347) (xy 32.503512 -231.869977) (xy 32.55146 -231.845325)
			(xy 32.602487 -231.827917) (xy 32.655505 -231.818124) (xy 32.709384 -231.816155) (xy 32.762975 -231.822052)
			(xy 32.815136 -231.835688) (xy 32.864756 -231.856775) (xy 32.910777 -231.884861) (xy 32.952219 -231.919349)
			(xy 32.988197 -231.959503) (xy 33.017945 -232.004467) (xy 33.04083 -232.053284) (xy 33.056362 -232.104913)
			(xy 33.064212 -232.158253) (xy 33.064704 -232.18521) (xy 39.870649 -232.18521) (xy 39.874584 -232.131439)
			(xy 39.886307 -232.078815) (xy 39.905567 -232.028458) (xy 39.931953 -231.981441) (xy 39.964905 -231.938768)
			(xy 40.003718 -231.901347) (xy 40.047566 -231.869977) (xy 40.095514 -231.845325) (xy 40.146541 -231.827917)
			(xy 40.199559 -231.818124) (xy 40.253438 -231.816155) (xy 40.307029 -231.822052) (xy 40.35919 -231.835688)
			(xy 40.40881 -231.856775) (xy 40.454831 -231.884861) (xy 40.496273 -231.919349) (xy 40.532251 -231.959503)
			(xy 40.561999 -232.004467) (xy 40.584884 -232.053284) (xy 40.600416 -232.104913) (xy 40.608266 -232.158253)
			(xy 40.608758 -232.18521) (xy 40.608266 -232.212167) (xy 40.600416 -232.265507) (xy 40.584884 -232.317136)
			(xy 40.561999 -232.365953) (xy 40.532251 -232.410917) (xy 40.496273 -232.451071) (xy 40.454831 -232.485559)
			(xy 40.40881 -232.513645) (xy 40.35919 -232.534732) (xy 40.307029 -232.548368) (xy 40.253438 -232.554265)
			(xy 40.199559 -232.552296) (xy 40.146541 -232.542503) (xy 40.095514 -232.525095) (xy 40.047566 -232.500443)
			(xy 40.003718 -232.469073) (xy 39.964905 -232.431652) (xy 39.931953 -232.388979) (xy 39.905567 -232.341962)
			(xy 39.886307 -232.291605) (xy 39.874584 -232.238981) (xy 39.870649 -232.18521) (xy 33.064704 -232.18521)
			(xy 33.064212 -232.212167) (xy 33.056362 -232.265507) (xy 33.04083 -232.317136) (xy 33.017945 -232.365953)
			(xy 32.988197 -232.410917) (xy 32.952219 -232.451071) (xy 32.910777 -232.485559) (xy 32.864756 -232.513645)
			(xy 32.815136 -232.534732) (xy 32.762975 -232.548368) (xy 32.709384 -232.554265) (xy 32.655505 -232.552296)
			(xy 32.602487 -232.542503) (xy 32.55146 -232.525095) (xy 32.503512 -232.500443) (xy 32.459664 -232.469073)
			(xy 32.420851 -232.431652) (xy 32.387899 -232.388979) (xy 32.361513 -232.341962) (xy 32.342253 -232.291605)
			(xy 32.33053 -232.238981) (xy 32.326595 -232.18521) (xy 25.520904 -232.18521) (xy 25.520412 -232.212167)
			(xy 25.512562 -232.265507) (xy 25.49703 -232.317136) (xy 25.474145 -232.365953) (xy 25.444397 -232.410917)
			(xy 25.408419 -232.451071) (xy 25.366977 -232.485559) (xy 25.320956 -232.513645) (xy 25.271336 -232.534732)
			(xy 25.219175 -232.548368) (xy 25.165584 -232.554265) (xy 25.111705 -232.552296) (xy 25.058687 -232.542503)
			(xy 25.00766 -232.525095) (xy 24.959712 -232.500443) (xy 24.915864 -232.469073) (xy 24.877051 -232.431652)
			(xy 24.844099 -232.388979) (xy 24.817713 -232.341962) (xy 24.798453 -232.291605) (xy 24.78673 -232.238981)
			(xy 24.782795 -232.18521) (xy 17.97685 -232.18521) (xy 17.976358 -232.212167) (xy 17.968508 -232.265507)
			(xy 17.952976 -232.317136) (xy 17.930091 -232.365953) (xy 17.900343 -232.410917) (xy 17.864365 -232.451071)
			(xy 17.822923 -232.485559) (xy 17.776902 -232.513645) (xy 17.727282 -232.534732) (xy 17.675121 -232.548368)
			(xy 17.62153 -232.554265) (xy 17.567651 -232.552296) (xy 17.514633 -232.542503) (xy 17.463606 -232.525095)
			(xy 17.415658 -232.500443) (xy 17.37181 -232.469073) (xy 17.332997 -232.431652) (xy 17.300045 -232.388979)
			(xy 17.273659 -232.341962) (xy 17.254399 -232.291605) (xy 17.242676 -232.238981) (xy 17.238741 -232.18521)
			(xy 15.598394 -232.18521) (xy 15.598394 -233.035348) (xy 21.338809 -233.035348) (xy 21.342744 -232.981577)
			(xy 21.354467 -232.928953) (xy 21.373727 -232.878596) (xy 21.400113 -232.831579) (xy 21.433065 -232.788906)
			(xy 21.471878 -232.751485) (xy 21.515726 -232.720115) (xy 21.563674 -232.695463) (xy 21.614701 -232.678055)
			(xy 21.667719 -232.668262) (xy 21.721598 -232.666293) (xy 21.775189 -232.67219) (xy 21.82735 -232.685826)
			(xy 21.87697 -232.706913) (xy 21.922991 -232.734999) (xy 21.964433 -232.769487) (xy 22.000411 -232.809641)
			(xy 22.030159 -232.854605) (xy 22.053044 -232.903422) (xy 22.068576 -232.955051) (xy 22.076426 -233.008391)
			(xy 22.076918 -233.035348) (xy 28.882863 -233.035348) (xy 28.886798 -232.981577) (xy 28.898521 -232.928953)
			(xy 28.917781 -232.878596) (xy 28.944167 -232.831579) (xy 28.977119 -232.788906) (xy 29.015932 -232.751485)
			(xy 29.05978 -232.720115) (xy 29.107728 -232.695463) (xy 29.158755 -232.678055) (xy 29.211773 -232.668262)
			(xy 29.265652 -232.666293) (xy 29.319243 -232.67219) (xy 29.371404 -232.685826) (xy 29.421024 -232.706913)
			(xy 29.467045 -232.734999) (xy 29.508487 -232.769487) (xy 29.544465 -232.809641) (xy 29.574213 -232.854605)
			(xy 29.597098 -232.903422) (xy 29.61263 -232.955051) (xy 29.62048 -233.008391) (xy 29.620972 -233.035348)
			(xy 36.426663 -233.035348) (xy 36.430598 -232.981577) (xy 36.442321 -232.928953) (xy 36.461581 -232.878596)
			(xy 36.487967 -232.831579) (xy 36.520919 -232.788906) (xy 36.559732 -232.751485) (xy 36.60358 -232.720115)
			(xy 36.651528 -232.695463) (xy 36.702555 -232.678055) (xy 36.755573 -232.668262) (xy 36.809452 -232.666293)
			(xy 36.863043 -232.67219) (xy 36.915204 -232.685826) (xy 36.964824 -232.706913) (xy 37.010845 -232.734999)
			(xy 37.052287 -232.769487) (xy 37.088265 -232.809641) (xy 37.118013 -232.854605) (xy 37.140898 -232.903422)
			(xy 37.15643 -232.955051) (xy 37.16428 -233.008391) (xy 37.164772 -233.035348) (xy 43.970717 -233.035348)
			(xy 43.974652 -232.981577) (xy 43.986375 -232.928953) (xy 44.005635 -232.878596) (xy 44.032021 -232.831579)
			(xy 44.064973 -232.788906) (xy 44.103786 -232.751485) (xy 44.147634 -232.720115) (xy 44.195582 -232.695463)
			(xy 44.246609 -232.678055) (xy 44.299627 -232.668262) (xy 44.353506 -232.666293) (xy 44.407097 -232.67219)
			(xy 44.459258 -232.685826) (xy 44.508878 -232.706913) (xy 44.554899 -232.734999) (xy 44.596341 -232.769487)
			(xy 44.632319 -232.809641) (xy 44.662067 -232.854605) (xy 44.684952 -232.903422) (xy 44.700484 -232.955051)
			(xy 44.708334 -233.008391) (xy 44.708826 -233.035348) (xy 44.708334 -233.062305) (xy 44.700484 -233.115645)
			(xy 44.684952 -233.167274) (xy 44.662067 -233.216091) (xy 44.632319 -233.261055) (xy 44.596341 -233.301209)
			(xy 44.554899 -233.335697) (xy 44.508878 -233.363783) (xy 44.459258 -233.38487) (xy 44.407097 -233.398506)
			(xy 44.353506 -233.404403) (xy 44.299627 -233.402434) (xy 44.246609 -233.392641) (xy 44.195582 -233.375233)
			(xy 44.147634 -233.350581) (xy 44.103786 -233.319211) (xy 44.064973 -233.28179) (xy 44.032021 -233.239117)
			(xy 44.005635 -233.1921) (xy 43.986375 -233.141743) (xy 43.974652 -233.089119) (xy 43.970717 -233.035348)
			(xy 37.164772 -233.035348) (xy 37.16428 -233.062305) (xy 37.15643 -233.115645) (xy 37.140898 -233.167274)
			(xy 37.118013 -233.216091) (xy 37.088265 -233.261055) (xy 37.052287 -233.301209) (xy 37.010845 -233.335697)
			(xy 36.964824 -233.363783) (xy 36.915204 -233.38487) (xy 36.863043 -233.398506) (xy 36.809452 -233.404403)
			(xy 36.755573 -233.402434) (xy 36.702555 -233.392641) (xy 36.651528 -233.375233) (xy 36.60358 -233.350581)
			(xy 36.559732 -233.319211) (xy 36.520919 -233.28179) (xy 36.487967 -233.239117) (xy 36.461581 -233.1921)
			(xy 36.442321 -233.141743) (xy 36.430598 -233.089119) (xy 36.426663 -233.035348) (xy 29.620972 -233.035348)
			(xy 29.62048 -233.062305) (xy 29.61263 -233.115645) (xy 29.597098 -233.167274) (xy 29.574213 -233.216091)
			(xy 29.544465 -233.261055) (xy 29.508487 -233.301209) (xy 29.467045 -233.335697) (xy 29.421024 -233.363783)
			(xy 29.371404 -233.38487) (xy 29.319243 -233.398506) (xy 29.265652 -233.404403) (xy 29.211773 -233.402434)
			(xy 29.158755 -233.392641) (xy 29.107728 -233.375233) (xy 29.05978 -233.350581) (xy 29.015932 -233.319211)
			(xy 28.977119 -233.28179) (xy 28.944167 -233.239117) (xy 28.917781 -233.1921) (xy 28.898521 -233.141743)
			(xy 28.886798 -233.089119) (xy 28.882863 -233.035348) (xy 22.076918 -233.035348) (xy 22.076426 -233.062305)
			(xy 22.068576 -233.115645) (xy 22.053044 -233.167274) (xy 22.030159 -233.216091) (xy 22.000411 -233.261055)
			(xy 21.964433 -233.301209) (xy 21.922991 -233.335697) (xy 21.87697 -233.363783) (xy 21.82735 -233.38487)
			(xy 21.775189 -233.398506) (xy 21.721598 -233.404403) (xy 21.667719 -233.402434) (xy 21.614701 -233.392641)
			(xy 21.563674 -233.375233) (xy 21.515726 -233.350581) (xy 21.471878 -233.319211) (xy 21.433065 -233.28179)
			(xy 21.400113 -233.239117) (xy 21.373727 -233.1921) (xy 21.354467 -233.141743) (xy 21.342744 -233.089119)
			(xy 21.338809 -233.035348) (xy 15.598394 -233.035348) (xy 15.598394 -233.885232) (xy 17.238741 -233.885232)
			(xy 17.242676 -233.831461) (xy 17.254399 -233.778837) (xy 17.273659 -233.72848) (xy 17.300045 -233.681463)
			(xy 17.332997 -233.63879) (xy 17.37181 -233.601369) (xy 17.415658 -233.569999) (xy 17.463606 -233.545347)
			(xy 17.514633 -233.527939) (xy 17.567651 -233.518146) (xy 17.62153 -233.516177) (xy 17.675121 -233.522074)
			(xy 17.727282 -233.53571) (xy 17.776902 -233.556797) (xy 17.822923 -233.584883) (xy 17.864365 -233.619371)
			(xy 17.900343 -233.659525) (xy 17.930091 -233.704489) (xy 17.952976 -233.753306) (xy 17.968508 -233.804935)
			(xy 17.976358 -233.858275) (xy 17.97685 -233.885232) (xy 24.782795 -233.885232) (xy 24.78673 -233.831461)
			(xy 24.798453 -233.778837) (xy 24.817713 -233.72848) (xy 24.844099 -233.681463) (xy 24.877051 -233.63879)
			(xy 24.915864 -233.601369) (xy 24.959712 -233.569999) (xy 25.00766 -233.545347) (xy 25.058687 -233.527939)
			(xy 25.111705 -233.518146) (xy 25.165584 -233.516177) (xy 25.219175 -233.522074) (xy 25.271336 -233.53571)
			(xy 25.320956 -233.556797) (xy 25.366977 -233.584883) (xy 25.408419 -233.619371) (xy 25.444397 -233.659525)
			(xy 25.474145 -233.704489) (xy 25.49703 -233.753306) (xy 25.512562 -233.804935) (xy 25.520412 -233.858275)
			(xy 25.520904 -233.885232) (xy 32.326595 -233.885232) (xy 32.33053 -233.831461) (xy 32.342253 -233.778837)
			(xy 32.361513 -233.72848) (xy 32.387899 -233.681463) (xy 32.420851 -233.63879) (xy 32.459664 -233.601369)
			(xy 32.503512 -233.569999) (xy 32.55146 -233.545347) (xy 32.602487 -233.527939) (xy 32.655505 -233.518146)
			(xy 32.709384 -233.516177) (xy 32.762975 -233.522074) (xy 32.815136 -233.53571) (xy 32.864756 -233.556797)
			(xy 32.910777 -233.584883) (xy 32.952219 -233.619371) (xy 32.988197 -233.659525) (xy 33.017945 -233.704489)
			(xy 33.04083 -233.753306) (xy 33.056362 -233.804935) (xy 33.064212 -233.858275) (xy 33.064704 -233.885232)
			(xy 39.870649 -233.885232) (xy 39.874584 -233.831461) (xy 39.886307 -233.778837) (xy 39.905567 -233.72848)
			(xy 39.931953 -233.681463) (xy 39.964905 -233.63879) (xy 40.003718 -233.601369) (xy 40.047566 -233.569999)
			(xy 40.095514 -233.545347) (xy 40.146541 -233.527939) (xy 40.199559 -233.518146) (xy 40.253438 -233.516177)
			(xy 40.307029 -233.522074) (xy 40.35919 -233.53571) (xy 40.40881 -233.556797) (xy 40.454831 -233.584883)
			(xy 40.496273 -233.619371) (xy 40.532251 -233.659525) (xy 40.561999 -233.704489) (xy 40.584884 -233.753306)
			(xy 40.600416 -233.804935) (xy 40.608266 -233.858275) (xy 40.608758 -233.885232) (xy 40.608266 -233.912189)
			(xy 40.600416 -233.965529) (xy 40.584884 -234.017158) (xy 40.561999 -234.065975) (xy 40.532251 -234.110939)
			(xy 40.496273 -234.151093) (xy 40.454831 -234.185581) (xy 40.40881 -234.213667) (xy 40.35919 -234.234754)
			(xy 40.307029 -234.24839) (xy 40.253438 -234.254287) (xy 40.199559 -234.252318) (xy 40.146541 -234.242525)
			(xy 40.095514 -234.225117) (xy 40.047566 -234.200465) (xy 40.003718 -234.169095) (xy 39.964905 -234.131674)
			(xy 39.931953 -234.089001) (xy 39.905567 -234.041984) (xy 39.886307 -233.991627) (xy 39.874584 -233.939003)
			(xy 39.870649 -233.885232) (xy 33.064704 -233.885232) (xy 33.064212 -233.912189) (xy 33.056362 -233.965529)
			(xy 33.04083 -234.017158) (xy 33.017945 -234.065975) (xy 32.988197 -234.110939) (xy 32.952219 -234.151093)
			(xy 32.910777 -234.185581) (xy 32.864756 -234.213667) (xy 32.815136 -234.234754) (xy 32.762975 -234.24839)
			(xy 32.709384 -234.254287) (xy 32.655505 -234.252318) (xy 32.602487 -234.242525) (xy 32.55146 -234.225117)
			(xy 32.503512 -234.200465) (xy 32.459664 -234.169095) (xy 32.420851 -234.131674) (xy 32.387899 -234.089001)
			(xy 32.361513 -234.041984) (xy 32.342253 -233.991627) (xy 32.33053 -233.939003) (xy 32.326595 -233.885232)
			(xy 25.520904 -233.885232) (xy 25.520412 -233.912189) (xy 25.512562 -233.965529) (xy 25.49703 -234.017158)
			(xy 25.474145 -234.065975) (xy 25.444397 -234.110939) (xy 25.408419 -234.151093) (xy 25.366977 -234.185581)
			(xy 25.320956 -234.213667) (xy 25.271336 -234.234754) (xy 25.219175 -234.24839) (xy 25.165584 -234.254287)
			(xy 25.111705 -234.252318) (xy 25.058687 -234.242525) (xy 25.00766 -234.225117) (xy 24.959712 -234.200465)
			(xy 24.915864 -234.169095) (xy 24.877051 -234.131674) (xy 24.844099 -234.089001) (xy 24.817713 -234.041984)
			(xy 24.798453 -233.991627) (xy 24.78673 -233.939003) (xy 24.782795 -233.885232) (xy 17.97685 -233.885232)
			(xy 17.976358 -233.912189) (xy 17.968508 -233.965529) (xy 17.952976 -234.017158) (xy 17.930091 -234.065975)
			(xy 17.900343 -234.110939) (xy 17.864365 -234.151093) (xy 17.822923 -234.185581) (xy 17.776902 -234.213667)
			(xy 17.727282 -234.234754) (xy 17.675121 -234.24839) (xy 17.62153 -234.254287) (xy 17.567651 -234.252318)
			(xy 17.514633 -234.242525) (xy 17.463606 -234.225117) (xy 17.415658 -234.200465) (xy 17.37181 -234.169095)
			(xy 17.332997 -234.131674) (xy 17.300045 -234.089001) (xy 17.273659 -234.041984) (xy 17.254399 -233.991627)
			(xy 17.242676 -233.939003) (xy 17.238741 -233.885232) (xy 15.598394 -233.885232) (xy 15.598394 -234.73537)
			(xy 21.338809 -234.73537) (xy 21.342744 -234.681599) (xy 21.354467 -234.628975) (xy 21.373727 -234.578618)
			(xy 21.400113 -234.531601) (xy 21.433065 -234.488928) (xy 21.471878 -234.451507) (xy 21.515726 -234.420137)
			(xy 21.563674 -234.395485) (xy 21.614701 -234.378077) (xy 21.667719 -234.368284) (xy 21.721598 -234.366315)
			(xy 21.775189 -234.372212) (xy 21.82735 -234.385848) (xy 21.87697 -234.406935) (xy 21.922991 -234.435021)
			(xy 21.964433 -234.469509) (xy 22.000411 -234.509663) (xy 22.030159 -234.554627) (xy 22.053044 -234.603444)
			(xy 22.068576 -234.655073) (xy 22.076426 -234.708413) (xy 22.076918 -234.73537) (xy 28.882863 -234.73537)
			(xy 28.886798 -234.681599) (xy 28.898521 -234.628975) (xy 28.917781 -234.578618) (xy 28.944167 -234.531601)
			(xy 28.977119 -234.488928) (xy 29.015932 -234.451507) (xy 29.05978 -234.420137) (xy 29.107728 -234.395485)
			(xy 29.158755 -234.378077) (xy 29.211773 -234.368284) (xy 29.265652 -234.366315) (xy 29.319243 -234.372212)
			(xy 29.371404 -234.385848) (xy 29.421024 -234.406935) (xy 29.467045 -234.435021) (xy 29.508487 -234.469509)
			(xy 29.544465 -234.509663) (xy 29.574213 -234.554627) (xy 29.597098 -234.603444) (xy 29.61263 -234.655073)
			(xy 29.62048 -234.708413) (xy 29.620972 -234.73537) (xy 36.426663 -234.73537) (xy 36.430598 -234.681599)
			(xy 36.442321 -234.628975) (xy 36.461581 -234.578618) (xy 36.487967 -234.531601) (xy 36.520919 -234.488928)
			(xy 36.559732 -234.451507) (xy 36.60358 -234.420137) (xy 36.651528 -234.395485) (xy 36.702555 -234.378077)
			(xy 36.755573 -234.368284) (xy 36.809452 -234.366315) (xy 36.863043 -234.372212) (xy 36.915204 -234.385848)
			(xy 36.964824 -234.406935) (xy 37.010845 -234.435021) (xy 37.052287 -234.469509) (xy 37.088265 -234.509663)
			(xy 37.118013 -234.554627) (xy 37.140898 -234.603444) (xy 37.15643 -234.655073) (xy 37.16428 -234.708413)
			(xy 37.164772 -234.73537) (xy 43.970717 -234.73537) (xy 43.974652 -234.681599) (xy 43.986375 -234.628975)
			(xy 44.005635 -234.578618) (xy 44.032021 -234.531601) (xy 44.064973 -234.488928) (xy 44.103786 -234.451507)
			(xy 44.147634 -234.420137) (xy 44.195582 -234.395485) (xy 44.246609 -234.378077) (xy 44.299627 -234.368284)
			(xy 44.353506 -234.366315) (xy 44.407097 -234.372212) (xy 44.459258 -234.385848) (xy 44.508878 -234.406935)
			(xy 44.554899 -234.435021) (xy 44.596341 -234.469509) (xy 44.632319 -234.509663) (xy 44.662067 -234.554627)
			(xy 44.684952 -234.603444) (xy 44.700484 -234.655073) (xy 44.708334 -234.708413) (xy 44.708826 -234.73537)
			(xy 44.708334 -234.762327) (xy 44.700484 -234.815667) (xy 44.684952 -234.867296) (xy 44.662067 -234.916113)
			(xy 44.632319 -234.961077) (xy 44.596341 -235.001231) (xy 44.554899 -235.035719) (xy 44.508878 -235.063805)
			(xy 44.459258 -235.084892) (xy 44.407097 -235.098528) (xy 44.353506 -235.104425) (xy 44.299627 -235.102456)
			(xy 44.246609 -235.092663) (xy 44.195582 -235.075255) (xy 44.147634 -235.050603) (xy 44.103786 -235.019233)
			(xy 44.064973 -234.981812) (xy 44.032021 -234.939139) (xy 44.005635 -234.892122) (xy 43.986375 -234.841765)
			(xy 43.974652 -234.789141) (xy 43.970717 -234.73537) (xy 37.164772 -234.73537) (xy 37.16428 -234.762327)
			(xy 37.15643 -234.815667) (xy 37.140898 -234.867296) (xy 37.118013 -234.916113) (xy 37.088265 -234.961077)
			(xy 37.052287 -235.001231) (xy 37.010845 -235.035719) (xy 36.964824 -235.063805) (xy 36.915204 -235.084892)
			(xy 36.863043 -235.098528) (xy 36.809452 -235.104425) (xy 36.755573 -235.102456) (xy 36.702555 -235.092663)
			(xy 36.651528 -235.075255) (xy 36.60358 -235.050603) (xy 36.559732 -235.019233) (xy 36.520919 -234.981812)
			(xy 36.487967 -234.939139) (xy 36.461581 -234.892122) (xy 36.442321 -234.841765) (xy 36.430598 -234.789141)
			(xy 36.426663 -234.73537) (xy 29.620972 -234.73537) (xy 29.62048 -234.762327) (xy 29.61263 -234.815667)
			(xy 29.597098 -234.867296) (xy 29.574213 -234.916113) (xy 29.544465 -234.961077) (xy 29.508487 -235.001231)
			(xy 29.467045 -235.035719) (xy 29.421024 -235.063805) (xy 29.371404 -235.084892) (xy 29.319243 -235.098528)
			(xy 29.265652 -235.104425) (xy 29.211773 -235.102456) (xy 29.158755 -235.092663) (xy 29.107728 -235.075255)
			(xy 29.05978 -235.050603) (xy 29.015932 -235.019233) (xy 28.977119 -234.981812) (xy 28.944167 -234.939139)
			(xy 28.917781 -234.892122) (xy 28.898521 -234.841765) (xy 28.886798 -234.789141) (xy 28.882863 -234.73537)
			(xy 22.076918 -234.73537) (xy 22.076426 -234.762327) (xy 22.068576 -234.815667) (xy 22.053044 -234.867296)
			(xy 22.030159 -234.916113) (xy 22.000411 -234.961077) (xy 21.964433 -235.001231) (xy 21.922991 -235.035719)
			(xy 21.87697 -235.063805) (xy 21.82735 -235.084892) (xy 21.775189 -235.098528) (xy 21.721598 -235.104425)
			(xy 21.667719 -235.102456) (xy 21.614701 -235.092663) (xy 21.563674 -235.075255) (xy 21.515726 -235.050603)
			(xy 21.471878 -235.019233) (xy 21.433065 -234.981812) (xy 21.400113 -234.939139) (xy 21.373727 -234.892122)
			(xy 21.354467 -234.841765) (xy 21.342744 -234.789141) (xy 21.338809 -234.73537) (xy 15.598394 -234.73537)
			(xy 15.598394 -235.585254) (xy 17.238741 -235.585254) (xy 17.242676 -235.531483) (xy 17.254399 -235.478859)
			(xy 17.273659 -235.428502) (xy 17.300045 -235.381485) (xy 17.332997 -235.338812) (xy 17.37181 -235.301391)
			(xy 17.415658 -235.270021) (xy 17.463606 -235.245369) (xy 17.514633 -235.227961) (xy 17.567651 -235.218168)
			(xy 17.62153 -235.216199) (xy 17.675121 -235.222096) (xy 17.727282 -235.235732) (xy 17.776902 -235.256819)
			(xy 17.822923 -235.284905) (xy 17.864365 -235.319393) (xy 17.900343 -235.359547) (xy 17.930091 -235.404511)
			(xy 17.952976 -235.453328) (xy 17.968508 -235.504957) (xy 17.976358 -235.558297) (xy 17.97685 -235.585254)
			(xy 24.782795 -235.585254) (xy 24.78673 -235.531483) (xy 24.798453 -235.478859) (xy 24.817713 -235.428502)
			(xy 24.844099 -235.381485) (xy 24.877051 -235.338812) (xy 24.915864 -235.301391) (xy 24.959712 -235.270021)
			(xy 25.00766 -235.245369) (xy 25.058687 -235.227961) (xy 25.111705 -235.218168) (xy 25.165584 -235.216199)
			(xy 25.219175 -235.222096) (xy 25.271336 -235.235732) (xy 25.320956 -235.256819) (xy 25.366977 -235.284905)
			(xy 25.408419 -235.319393) (xy 25.444397 -235.359547) (xy 25.474145 -235.404511) (xy 25.49703 -235.453328)
			(xy 25.512562 -235.504957) (xy 25.520412 -235.558297) (xy 25.520904 -235.585254) (xy 32.326595 -235.585254)
			(xy 32.33053 -235.531483) (xy 32.342253 -235.478859) (xy 32.361513 -235.428502) (xy 32.387899 -235.381485)
			(xy 32.420851 -235.338812) (xy 32.459664 -235.301391) (xy 32.503512 -235.270021) (xy 32.55146 -235.245369)
			(xy 32.602487 -235.227961) (xy 32.655505 -235.218168) (xy 32.709384 -235.216199) (xy 32.762975 -235.222096)
			(xy 32.815136 -235.235732) (xy 32.864756 -235.256819) (xy 32.910777 -235.284905) (xy 32.952219 -235.319393)
			(xy 32.988197 -235.359547) (xy 33.017945 -235.404511) (xy 33.04083 -235.453328) (xy 33.056362 -235.504957)
			(xy 33.064212 -235.558297) (xy 33.064704 -235.585254) (xy 39.870649 -235.585254) (xy 39.874584 -235.531483)
			(xy 39.886307 -235.478859) (xy 39.905567 -235.428502) (xy 39.931953 -235.381485) (xy 39.964905 -235.338812)
			(xy 40.003718 -235.301391) (xy 40.047566 -235.270021) (xy 40.095514 -235.245369) (xy 40.146541 -235.227961)
			(xy 40.199559 -235.218168) (xy 40.253438 -235.216199) (xy 40.307029 -235.222096) (xy 40.35919 -235.235732)
			(xy 40.40881 -235.256819) (xy 40.454831 -235.284905) (xy 40.496273 -235.319393) (xy 40.532251 -235.359547)
			(xy 40.561999 -235.404511) (xy 40.584884 -235.453328) (xy 40.600416 -235.504957) (xy 40.608266 -235.558297)
			(xy 40.608758 -235.585254) (xy 40.608266 -235.612211) (xy 40.600416 -235.665551) (xy 40.584884 -235.71718)
			(xy 40.561999 -235.765997) (xy 40.532251 -235.810961) (xy 40.496273 -235.851115) (xy 40.454831 -235.885603)
			(xy 40.40881 -235.913689) (xy 40.35919 -235.934776) (xy 40.307029 -235.948412) (xy 40.253438 -235.954309)
			(xy 40.199559 -235.95234) (xy 40.146541 -235.942547) (xy 40.095514 -235.925139) (xy 40.047566 -235.900487)
			(xy 40.003718 -235.869117) (xy 39.964905 -235.831696) (xy 39.931953 -235.789023) (xy 39.905567 -235.742006)
			(xy 39.886307 -235.691649) (xy 39.874584 -235.639025) (xy 39.870649 -235.585254) (xy 33.064704 -235.585254)
			(xy 33.064212 -235.612211) (xy 33.056362 -235.665551) (xy 33.04083 -235.71718) (xy 33.017945 -235.765997)
			(xy 32.988197 -235.810961) (xy 32.952219 -235.851115) (xy 32.910777 -235.885603) (xy 32.864756 -235.913689)
			(xy 32.815136 -235.934776) (xy 32.762975 -235.948412) (xy 32.709384 -235.954309) (xy 32.655505 -235.95234)
			(xy 32.602487 -235.942547) (xy 32.55146 -235.925139) (xy 32.503512 -235.900487) (xy 32.459664 -235.869117)
			(xy 32.420851 -235.831696) (xy 32.387899 -235.789023) (xy 32.361513 -235.742006) (xy 32.342253 -235.691649)
			(xy 32.33053 -235.639025) (xy 32.326595 -235.585254) (xy 25.520904 -235.585254) (xy 25.520412 -235.612211)
			(xy 25.512562 -235.665551) (xy 25.49703 -235.71718) (xy 25.474145 -235.765997) (xy 25.444397 -235.810961)
			(xy 25.408419 -235.851115) (xy 25.366977 -235.885603) (xy 25.320956 -235.913689) (xy 25.271336 -235.934776)
			(xy 25.219175 -235.948412) (xy 25.165584 -235.954309) (xy 25.111705 -235.95234) (xy 25.058687 -235.942547)
			(xy 25.00766 -235.925139) (xy 24.959712 -235.900487) (xy 24.915864 -235.869117) (xy 24.877051 -235.831696)
			(xy 24.844099 -235.789023) (xy 24.817713 -235.742006) (xy 24.798453 -235.691649) (xy 24.78673 -235.639025)
			(xy 24.782795 -235.585254) (xy 17.97685 -235.585254) (xy 17.976358 -235.612211) (xy 17.968508 -235.665551)
			(xy 17.952976 -235.71718) (xy 17.930091 -235.765997) (xy 17.900343 -235.810961) (xy 17.864365 -235.851115)
			(xy 17.822923 -235.885603) (xy 17.776902 -235.913689) (xy 17.727282 -235.934776) (xy 17.675121 -235.948412)
			(xy 17.62153 -235.954309) (xy 17.567651 -235.95234) (xy 17.514633 -235.942547) (xy 17.463606 -235.925139)
			(xy 17.415658 -235.900487) (xy 17.37181 -235.869117) (xy 17.332997 -235.831696) (xy 17.300045 -235.789023)
			(xy 17.273659 -235.742006) (xy 17.254399 -235.691649) (xy 17.242676 -235.639025) (xy 17.238741 -235.585254)
			(xy 15.598394 -235.585254) (xy 15.598394 -236.435392) (xy 21.338809 -236.435392) (xy 21.342744 -236.381621)
			(xy 21.354467 -236.328997) (xy 21.373727 -236.27864) (xy 21.400113 -236.231623) (xy 21.433065 -236.18895)
			(xy 21.471878 -236.151529) (xy 21.515726 -236.120159) (xy 21.563674 -236.095507) (xy 21.614701 -236.078099)
			(xy 21.667719 -236.068306) (xy 21.721598 -236.066337) (xy 21.775189 -236.072234) (xy 21.82735 -236.08587)
			(xy 21.87697 -236.106957) (xy 21.922991 -236.135043) (xy 21.964433 -236.169531) (xy 22.000411 -236.209685)
			(xy 22.030159 -236.254649) (xy 22.053044 -236.303466) (xy 22.068576 -236.355095) (xy 22.076426 -236.408435)
			(xy 22.076918 -236.435392) (xy 28.882863 -236.435392) (xy 28.886798 -236.381621) (xy 28.898521 -236.328997)
			(xy 28.917781 -236.27864) (xy 28.944167 -236.231623) (xy 28.977119 -236.18895) (xy 29.015932 -236.151529)
			(xy 29.05978 -236.120159) (xy 29.107728 -236.095507) (xy 29.158755 -236.078099) (xy 29.211773 -236.068306)
			(xy 29.265652 -236.066337) (xy 29.319243 -236.072234) (xy 29.371404 -236.08587) (xy 29.421024 -236.106957)
			(xy 29.467045 -236.135043) (xy 29.508487 -236.169531) (xy 29.544465 -236.209685) (xy 29.574213 -236.254649)
			(xy 29.597098 -236.303466) (xy 29.61263 -236.355095) (xy 29.62048 -236.408435) (xy 29.620972 -236.435392)
			(xy 36.426663 -236.435392) (xy 36.430598 -236.381621) (xy 36.442321 -236.328997) (xy 36.461581 -236.27864)
			(xy 36.487967 -236.231623) (xy 36.520919 -236.18895) (xy 36.559732 -236.151529) (xy 36.60358 -236.120159)
			(xy 36.651528 -236.095507) (xy 36.702555 -236.078099) (xy 36.755573 -236.068306) (xy 36.809452 -236.066337)
			(xy 36.863043 -236.072234) (xy 36.915204 -236.08587) (xy 36.964824 -236.106957) (xy 37.010845 -236.135043)
			(xy 37.052287 -236.169531) (xy 37.088265 -236.209685) (xy 37.118013 -236.254649) (xy 37.140898 -236.303466)
			(xy 37.15643 -236.355095) (xy 37.16428 -236.408435) (xy 37.164772 -236.435392) (xy 43.970717 -236.435392)
			(xy 43.974652 -236.381621) (xy 43.986375 -236.328997) (xy 44.005635 -236.27864) (xy 44.032021 -236.231623)
			(xy 44.064973 -236.18895) (xy 44.103786 -236.151529) (xy 44.147634 -236.120159) (xy 44.195582 -236.095507)
			(xy 44.246609 -236.078099) (xy 44.299627 -236.068306) (xy 44.353506 -236.066337) (xy 44.407097 -236.072234)
			(xy 44.459258 -236.08587) (xy 44.508878 -236.106957) (xy 44.554899 -236.135043) (xy 44.596341 -236.169531)
			(xy 44.632319 -236.209685) (xy 44.662067 -236.254649) (xy 44.684952 -236.303466) (xy 44.700484 -236.355095)
			(xy 44.708334 -236.408435) (xy 44.708826 -236.435392) (xy 44.708334 -236.462349) (xy 44.700484 -236.515689)
			(xy 44.684952 -236.567318) (xy 44.662067 -236.616135) (xy 44.632319 -236.661099) (xy 44.596341 -236.701253)
			(xy 44.554899 -236.735741) (xy 44.508878 -236.763827) (xy 44.459258 -236.784914) (xy 44.407097 -236.79855)
			(xy 44.353506 -236.804447) (xy 44.299627 -236.802478) (xy 44.246609 -236.792685) (xy 44.195582 -236.775277)
			(xy 44.147634 -236.750625) (xy 44.103786 -236.719255) (xy 44.064973 -236.681834) (xy 44.032021 -236.639161)
			(xy 44.005635 -236.592144) (xy 43.986375 -236.541787) (xy 43.974652 -236.489163) (xy 43.970717 -236.435392)
			(xy 37.164772 -236.435392) (xy 37.16428 -236.462349) (xy 37.15643 -236.515689) (xy 37.140898 -236.567318)
			(xy 37.118013 -236.616135) (xy 37.088265 -236.661099) (xy 37.052287 -236.701253) (xy 37.010845 -236.735741)
			(xy 36.964824 -236.763827) (xy 36.915204 -236.784914) (xy 36.863043 -236.79855) (xy 36.809452 -236.804447)
			(xy 36.755573 -236.802478) (xy 36.702555 -236.792685) (xy 36.651528 -236.775277) (xy 36.60358 -236.750625)
			(xy 36.559732 -236.719255) (xy 36.520919 -236.681834) (xy 36.487967 -236.639161) (xy 36.461581 -236.592144)
			(xy 36.442321 -236.541787) (xy 36.430598 -236.489163) (xy 36.426663 -236.435392) (xy 29.620972 -236.435392)
			(xy 29.62048 -236.462349) (xy 29.61263 -236.515689) (xy 29.597098 -236.567318) (xy 29.574213 -236.616135)
			(xy 29.544465 -236.661099) (xy 29.508487 -236.701253) (xy 29.467045 -236.735741) (xy 29.421024 -236.763827)
			(xy 29.371404 -236.784914) (xy 29.319243 -236.79855) (xy 29.265652 -236.804447) (xy 29.211773 -236.802478)
			(xy 29.158755 -236.792685) (xy 29.107728 -236.775277) (xy 29.05978 -236.750625) (xy 29.015932 -236.719255)
			(xy 28.977119 -236.681834) (xy 28.944167 -236.639161) (xy 28.917781 -236.592144) (xy 28.898521 -236.541787)
			(xy 28.886798 -236.489163) (xy 28.882863 -236.435392) (xy 22.076918 -236.435392) (xy 22.076426 -236.462349)
			(xy 22.068576 -236.515689) (xy 22.053044 -236.567318) (xy 22.030159 -236.616135) (xy 22.000411 -236.661099)
			(xy 21.964433 -236.701253) (xy 21.922991 -236.735741) (xy 21.87697 -236.763827) (xy 21.82735 -236.784914)
			(xy 21.775189 -236.79855) (xy 21.721598 -236.804447) (xy 21.667719 -236.802478) (xy 21.614701 -236.792685)
			(xy 21.563674 -236.775277) (xy 21.515726 -236.750625) (xy 21.471878 -236.719255) (xy 21.433065 -236.681834)
			(xy 21.400113 -236.639161) (xy 21.373727 -236.592144) (xy 21.354467 -236.541787) (xy 21.342744 -236.489163)
			(xy 21.338809 -236.435392) (xy 15.598394 -236.435392) (xy 15.598394 -237.285276) (xy 17.238741 -237.285276)
			(xy 17.242676 -237.231505) (xy 17.254399 -237.178881) (xy 17.273659 -237.128524) (xy 17.300045 -237.081507)
			(xy 17.332997 -237.038834) (xy 17.37181 -237.001413) (xy 17.415658 -236.970043) (xy 17.463606 -236.945391)
			(xy 17.514633 -236.927983) (xy 17.567651 -236.91819) (xy 17.62153 -236.916221) (xy 17.675121 -236.922118)
			(xy 17.727282 -236.935754) (xy 17.776902 -236.956841) (xy 17.822923 -236.984927) (xy 17.864365 -237.019415)
			(xy 17.900343 -237.059569) (xy 17.930091 -237.104533) (xy 17.952976 -237.15335) (xy 17.968508 -237.204979)
			(xy 17.976358 -237.258319) (xy 17.97685 -237.285276) (xy 24.782795 -237.285276) (xy 24.78673 -237.231505)
			(xy 24.798453 -237.178881) (xy 24.817713 -237.128524) (xy 24.844099 -237.081507) (xy 24.877051 -237.038834)
			(xy 24.915864 -237.001413) (xy 24.959712 -236.970043) (xy 25.00766 -236.945391) (xy 25.058687 -236.927983)
			(xy 25.111705 -236.91819) (xy 25.165584 -236.916221) (xy 25.219175 -236.922118) (xy 25.271336 -236.935754)
			(xy 25.320956 -236.956841) (xy 25.366977 -236.984927) (xy 25.408419 -237.019415) (xy 25.444397 -237.059569)
			(xy 25.474145 -237.104533) (xy 25.49703 -237.15335) (xy 25.512562 -237.204979) (xy 25.520412 -237.258319)
			(xy 25.520904 -237.285276) (xy 32.326595 -237.285276) (xy 32.33053 -237.231505) (xy 32.342253 -237.178881)
			(xy 32.361513 -237.128524) (xy 32.387899 -237.081507) (xy 32.420851 -237.038834) (xy 32.459664 -237.001413)
			(xy 32.503512 -236.970043) (xy 32.55146 -236.945391) (xy 32.602487 -236.927983) (xy 32.655505 -236.91819)
			(xy 32.709384 -236.916221) (xy 32.762975 -236.922118) (xy 32.815136 -236.935754) (xy 32.864756 -236.956841)
			(xy 32.910777 -236.984927) (xy 32.952219 -237.019415) (xy 32.988197 -237.059569) (xy 33.017945 -237.104533)
			(xy 33.04083 -237.15335) (xy 33.056362 -237.204979) (xy 33.064212 -237.258319) (xy 33.064704 -237.285276)
			(xy 39.870649 -237.285276) (xy 39.874584 -237.231505) (xy 39.886307 -237.178881) (xy 39.905567 -237.128524)
			(xy 39.931953 -237.081507) (xy 39.964905 -237.038834) (xy 40.003718 -237.001413) (xy 40.047566 -236.970043)
			(xy 40.095514 -236.945391) (xy 40.146541 -236.927983) (xy 40.199559 -236.91819) (xy 40.253438 -236.916221)
			(xy 40.307029 -236.922118) (xy 40.35919 -236.935754) (xy 40.40881 -236.956841) (xy 40.454831 -236.984927)
			(xy 40.496273 -237.019415) (xy 40.532251 -237.059569) (xy 40.561999 -237.104533) (xy 40.584884 -237.15335)
			(xy 40.600416 -237.204979) (xy 40.608266 -237.258319) (xy 40.608758 -237.285276) (xy 40.608266 -237.312233)
			(xy 40.600416 -237.365573) (xy 40.584884 -237.417202) (xy 40.561999 -237.466019) (xy 40.532251 -237.510983)
			(xy 40.496273 -237.551137) (xy 40.454831 -237.585625) (xy 40.40881 -237.613711) (xy 40.35919 -237.634798)
			(xy 40.307029 -237.648434) (xy 40.253438 -237.654331) (xy 40.199559 -237.652362) (xy 40.146541 -237.642569)
			(xy 40.095514 -237.625161) (xy 40.047566 -237.600509) (xy 40.003718 -237.569139) (xy 39.964905 -237.531718)
			(xy 39.931953 -237.489045) (xy 39.905567 -237.442028) (xy 39.886307 -237.391671) (xy 39.874584 -237.339047)
			(xy 39.870649 -237.285276) (xy 33.064704 -237.285276) (xy 33.064212 -237.312233) (xy 33.056362 -237.365573)
			(xy 33.04083 -237.417202) (xy 33.017945 -237.466019) (xy 32.988197 -237.510983) (xy 32.952219 -237.551137)
			(xy 32.910777 -237.585625) (xy 32.864756 -237.613711) (xy 32.815136 -237.634798) (xy 32.762975 -237.648434)
			(xy 32.709384 -237.654331) (xy 32.655505 -237.652362) (xy 32.602487 -237.642569) (xy 32.55146 -237.625161)
			(xy 32.503512 -237.600509) (xy 32.459664 -237.569139) (xy 32.420851 -237.531718) (xy 32.387899 -237.489045)
			(xy 32.361513 -237.442028) (xy 32.342253 -237.391671) (xy 32.33053 -237.339047) (xy 32.326595 -237.285276)
			(xy 25.520904 -237.285276) (xy 25.520412 -237.312233) (xy 25.512562 -237.365573) (xy 25.49703 -237.417202)
			(xy 25.474145 -237.466019) (xy 25.444397 -237.510983) (xy 25.408419 -237.551137) (xy 25.366977 -237.585625)
			(xy 25.320956 -237.613711) (xy 25.271336 -237.634798) (xy 25.219175 -237.648434) (xy 25.165584 -237.654331)
			(xy 25.111705 -237.652362) (xy 25.058687 -237.642569) (xy 25.00766 -237.625161) (xy 24.959712 -237.600509)
			(xy 24.915864 -237.569139) (xy 24.877051 -237.531718) (xy 24.844099 -237.489045) (xy 24.817713 -237.442028)
			(xy 24.798453 -237.391671) (xy 24.78673 -237.339047) (xy 24.782795 -237.285276) (xy 17.97685 -237.285276)
			(xy 17.976358 -237.312233) (xy 17.968508 -237.365573) (xy 17.952976 -237.417202) (xy 17.930091 -237.466019)
			(xy 17.900343 -237.510983) (xy 17.864365 -237.551137) (xy 17.822923 -237.585625) (xy 17.776902 -237.613711)
			(xy 17.727282 -237.634798) (xy 17.675121 -237.648434) (xy 17.62153 -237.654331) (xy 17.567651 -237.652362)
			(xy 17.514633 -237.642569) (xy 17.463606 -237.625161) (xy 17.415658 -237.600509) (xy 17.37181 -237.569139)
			(xy 17.332997 -237.531718) (xy 17.300045 -237.489045) (xy 17.273659 -237.442028) (xy 17.254399 -237.391671)
			(xy 17.242676 -237.339047) (xy 17.238741 -237.285276) (xy 15.598394 -237.285276) (xy 15.598394 -238.135414)
			(xy 21.338809 -238.135414) (xy 21.342744 -238.081643) (xy 21.354467 -238.029019) (xy 21.373727 -237.978662)
			(xy 21.400113 -237.931645) (xy 21.433065 -237.888972) (xy 21.471878 -237.851551) (xy 21.515726 -237.820181)
			(xy 21.563674 -237.795529) (xy 21.614701 -237.778121) (xy 21.667719 -237.768328) (xy 21.721598 -237.766359)
			(xy 21.775189 -237.772256) (xy 21.82735 -237.785892) (xy 21.87697 -237.806979) (xy 21.922991 -237.835065)
			(xy 21.964433 -237.869553) (xy 22.000411 -237.909707) (xy 22.030159 -237.954671) (xy 22.053044 -238.003488)
			(xy 22.068576 -238.055117) (xy 22.076426 -238.108457) (xy 22.076918 -238.135414) (xy 28.882863 -238.135414)
			(xy 28.886798 -238.081643) (xy 28.898521 -238.029019) (xy 28.917781 -237.978662) (xy 28.944167 -237.931645)
			(xy 28.977119 -237.888972) (xy 29.015932 -237.851551) (xy 29.05978 -237.820181) (xy 29.107728 -237.795529)
			(xy 29.158755 -237.778121) (xy 29.211773 -237.768328) (xy 29.265652 -237.766359) (xy 29.319243 -237.772256)
			(xy 29.371404 -237.785892) (xy 29.421024 -237.806979) (xy 29.467045 -237.835065) (xy 29.508487 -237.869553)
			(xy 29.544465 -237.909707) (xy 29.574213 -237.954671) (xy 29.597098 -238.003488) (xy 29.61263 -238.055117)
			(xy 29.62048 -238.108457) (xy 29.620972 -238.135414) (xy 36.426663 -238.135414) (xy 36.430598 -238.081643)
			(xy 36.442321 -238.029019) (xy 36.461581 -237.978662) (xy 36.487967 -237.931645) (xy 36.520919 -237.888972)
			(xy 36.559732 -237.851551) (xy 36.60358 -237.820181) (xy 36.651528 -237.795529) (xy 36.702555 -237.778121)
			(xy 36.755573 -237.768328) (xy 36.809452 -237.766359) (xy 36.863043 -237.772256) (xy 36.915204 -237.785892)
			(xy 36.964824 -237.806979) (xy 37.010845 -237.835065) (xy 37.052287 -237.869553) (xy 37.088265 -237.909707)
			(xy 37.118013 -237.954671) (xy 37.140898 -238.003488) (xy 37.15643 -238.055117) (xy 37.16428 -238.108457)
			(xy 37.164772 -238.135414) (xy 43.970717 -238.135414) (xy 43.974652 -238.081643) (xy 43.986375 -238.029019)
			(xy 44.005635 -237.978662) (xy 44.032021 -237.931645) (xy 44.064973 -237.888972) (xy 44.103786 -237.851551)
			(xy 44.147634 -237.820181) (xy 44.195582 -237.795529) (xy 44.246609 -237.778121) (xy 44.299627 -237.768328)
			(xy 44.353506 -237.766359) (xy 44.407097 -237.772256) (xy 44.459258 -237.785892) (xy 44.508878 -237.806979)
			(xy 44.554899 -237.835065) (xy 44.596341 -237.869553) (xy 44.632319 -237.909707) (xy 44.662067 -237.954671)
			(xy 44.684952 -238.003488) (xy 44.700484 -238.055117) (xy 44.708334 -238.108457) (xy 44.708826 -238.135414)
			(xy 44.708334 -238.162371) (xy 44.700484 -238.215711) (xy 44.684952 -238.26734) (xy 44.662067 -238.316157)
			(xy 44.632319 -238.361121) (xy 44.596341 -238.401275) (xy 44.554899 -238.435763) (xy 44.508878 -238.463849)
			(xy 44.459258 -238.484936) (xy 44.407097 -238.498572) (xy 44.353506 -238.504469) (xy 44.299627 -238.5025)
			(xy 44.246609 -238.492707) (xy 44.195582 -238.475299) (xy 44.147634 -238.450647) (xy 44.103786 -238.419277)
			(xy 44.064973 -238.381856) (xy 44.032021 -238.339183) (xy 44.005635 -238.292166) (xy 43.986375 -238.241809)
			(xy 43.974652 -238.189185) (xy 43.970717 -238.135414) (xy 37.164772 -238.135414) (xy 37.16428 -238.162371)
			(xy 37.15643 -238.215711) (xy 37.140898 -238.26734) (xy 37.118013 -238.316157) (xy 37.088265 -238.361121)
			(xy 37.052287 -238.401275) (xy 37.010845 -238.435763) (xy 36.964824 -238.463849) (xy 36.915204 -238.484936)
			(xy 36.863043 -238.498572) (xy 36.809452 -238.504469) (xy 36.755573 -238.5025) (xy 36.702555 -238.492707)
			(xy 36.651528 -238.475299) (xy 36.60358 -238.450647) (xy 36.559732 -238.419277) (xy 36.520919 -238.381856)
			(xy 36.487967 -238.339183) (xy 36.461581 -238.292166) (xy 36.442321 -238.241809) (xy 36.430598 -238.189185)
			(xy 36.426663 -238.135414) (xy 29.620972 -238.135414) (xy 29.62048 -238.162371) (xy 29.61263 -238.215711)
			(xy 29.597098 -238.26734) (xy 29.574213 -238.316157) (xy 29.544465 -238.361121) (xy 29.508487 -238.401275)
			(xy 29.467045 -238.435763) (xy 29.421024 -238.463849) (xy 29.371404 -238.484936) (xy 29.319243 -238.498572)
			(xy 29.265652 -238.504469) (xy 29.211773 -238.5025) (xy 29.158755 -238.492707) (xy 29.107728 -238.475299)
			(xy 29.05978 -238.450647) (xy 29.015932 -238.419277) (xy 28.977119 -238.381856) (xy 28.944167 -238.339183)
			(xy 28.917781 -238.292166) (xy 28.898521 -238.241809) (xy 28.886798 -238.189185) (xy 28.882863 -238.135414)
			(xy 22.076918 -238.135414) (xy 22.076426 -238.162371) (xy 22.068576 -238.215711) (xy 22.053044 -238.26734)
			(xy 22.030159 -238.316157) (xy 22.000411 -238.361121) (xy 21.964433 -238.401275) (xy 21.922991 -238.435763)
			(xy 21.87697 -238.463849) (xy 21.82735 -238.484936) (xy 21.775189 -238.498572) (xy 21.721598 -238.504469)
			(xy 21.667719 -238.5025) (xy 21.614701 -238.492707) (xy 21.563674 -238.475299) (xy 21.515726 -238.450647)
			(xy 21.471878 -238.419277) (xy 21.433065 -238.381856) (xy 21.400113 -238.339183) (xy 21.373727 -238.292166)
			(xy 21.354467 -238.241809) (xy 21.342744 -238.189185) (xy 21.338809 -238.135414) (xy 15.598394 -238.135414)
			(xy 15.598394 -238.985298) (xy 17.238741 -238.985298) (xy 17.242676 -238.931527) (xy 17.254399 -238.878903)
			(xy 17.273659 -238.828546) (xy 17.300045 -238.781529) (xy 17.332997 -238.738856) (xy 17.37181 -238.701435)
			(xy 17.415658 -238.670065) (xy 17.463606 -238.645413) (xy 17.514633 -238.628005) (xy 17.567651 -238.618212)
			(xy 17.62153 -238.616243) (xy 17.675121 -238.62214) (xy 17.727282 -238.635776) (xy 17.776902 -238.656863)
			(xy 17.822923 -238.684949) (xy 17.864365 -238.719437) (xy 17.900343 -238.759591) (xy 17.930091 -238.804555)
			(xy 17.952976 -238.853372) (xy 17.968508 -238.905001) (xy 17.976358 -238.958341) (xy 17.97685 -238.985298)
			(xy 21.338809 -238.985298) (xy 21.342744 -238.931527) (xy 21.354467 -238.878903) (xy 21.373727 -238.828546)
			(xy 21.400113 -238.781529) (xy 21.433065 -238.738856) (xy 21.471878 -238.701435) (xy 21.515726 -238.670065)
			(xy 21.563674 -238.645413) (xy 21.614701 -238.628005) (xy 21.667719 -238.618212) (xy 21.721598 -238.616243)
			(xy 21.775189 -238.62214) (xy 21.82735 -238.635776) (xy 21.87697 -238.656863) (xy 21.922991 -238.684949)
			(xy 21.964433 -238.719437) (xy 22.000411 -238.759591) (xy 22.030159 -238.804555) (xy 22.053044 -238.853372)
			(xy 22.068576 -238.905001) (xy 22.076426 -238.958341) (xy 22.076918 -238.985298) (xy 24.782795 -238.985298)
			(xy 24.78673 -238.931527) (xy 24.798453 -238.878903) (xy 24.817713 -238.828546) (xy 24.844099 -238.781529)
			(xy 24.877051 -238.738856) (xy 24.915864 -238.701435) (xy 24.959712 -238.670065) (xy 25.00766 -238.645413)
			(xy 25.058687 -238.628005) (xy 25.111705 -238.618212) (xy 25.165584 -238.616243) (xy 25.219175 -238.62214)
			(xy 25.271336 -238.635776) (xy 25.320956 -238.656863) (xy 25.366977 -238.684949) (xy 25.408419 -238.719437)
			(xy 25.444397 -238.759591) (xy 25.474145 -238.804555) (xy 25.49703 -238.853372) (xy 25.512562 -238.905001)
			(xy 25.520412 -238.958341) (xy 25.520904 -238.985298) (xy 28.882863 -238.985298) (xy 28.886798 -238.931527)
			(xy 28.898521 -238.878903) (xy 28.917781 -238.828546) (xy 28.944167 -238.781529) (xy 28.977119 -238.738856)
			(xy 29.015932 -238.701435) (xy 29.05978 -238.670065) (xy 29.107728 -238.645413) (xy 29.158755 -238.628005)
			(xy 29.211773 -238.618212) (xy 29.265652 -238.616243) (xy 29.319243 -238.62214) (xy 29.371404 -238.635776)
			(xy 29.421024 -238.656863) (xy 29.467045 -238.684949) (xy 29.508487 -238.719437) (xy 29.544465 -238.759591)
			(xy 29.574213 -238.804555) (xy 29.597098 -238.853372) (xy 29.61263 -238.905001) (xy 29.62048 -238.958341)
			(xy 29.620972 -238.985298) (xy 32.326595 -238.985298) (xy 32.33053 -238.931527) (xy 32.342253 -238.878903)
			(xy 32.361513 -238.828546) (xy 32.387899 -238.781529) (xy 32.420851 -238.738856) (xy 32.459664 -238.701435)
			(xy 32.503512 -238.670065) (xy 32.55146 -238.645413) (xy 32.602487 -238.628005) (xy 32.655505 -238.618212)
			(xy 32.709384 -238.616243) (xy 32.762975 -238.62214) (xy 32.815136 -238.635776) (xy 32.864756 -238.656863)
			(xy 32.910777 -238.684949) (xy 32.952219 -238.719437) (xy 32.988197 -238.759591) (xy 33.017945 -238.804555)
			(xy 33.04083 -238.853372) (xy 33.056362 -238.905001) (xy 33.064212 -238.958341) (xy 33.064704 -238.985298)
			(xy 36.426663 -238.985298) (xy 36.430598 -238.931527) (xy 36.442321 -238.878903) (xy 36.461581 -238.828546)
			(xy 36.487967 -238.781529) (xy 36.520919 -238.738856) (xy 36.559732 -238.701435) (xy 36.60358 -238.670065)
			(xy 36.651528 -238.645413) (xy 36.702555 -238.628005) (xy 36.755573 -238.618212) (xy 36.809452 -238.616243)
			(xy 36.863043 -238.62214) (xy 36.915204 -238.635776) (xy 36.964824 -238.656863) (xy 37.010845 -238.684949)
			(xy 37.052287 -238.719437) (xy 37.088265 -238.759591) (xy 37.118013 -238.804555) (xy 37.140898 -238.853372)
			(xy 37.15643 -238.905001) (xy 37.16428 -238.958341) (xy 37.164772 -238.985298) (xy 39.870649 -238.985298)
			(xy 39.874584 -238.931527) (xy 39.886307 -238.878903) (xy 39.905567 -238.828546) (xy 39.931953 -238.781529)
			(xy 39.964905 -238.738856) (xy 40.003718 -238.701435) (xy 40.047566 -238.670065) (xy 40.095514 -238.645413)
			(xy 40.146541 -238.628005) (xy 40.199559 -238.618212) (xy 40.253438 -238.616243) (xy 40.307029 -238.62214)
			(xy 40.35919 -238.635776) (xy 40.40881 -238.656863) (xy 40.454831 -238.684949) (xy 40.496273 -238.719437)
			(xy 40.532251 -238.759591) (xy 40.561999 -238.804555) (xy 40.584884 -238.853372) (xy 40.600416 -238.905001)
			(xy 40.608266 -238.958341) (xy 40.608758 -238.985298) (xy 43.970717 -238.985298) (xy 43.974652 -238.931527)
			(xy 43.986375 -238.878903) (xy 44.005635 -238.828546) (xy 44.032021 -238.781529) (xy 44.064973 -238.738856)
			(xy 44.103786 -238.701435) (xy 44.147634 -238.670065) (xy 44.195582 -238.645413) (xy 44.246609 -238.628005)
			(xy 44.299627 -238.618212) (xy 44.353506 -238.616243) (xy 44.407097 -238.62214) (xy 44.459258 -238.635776)
			(xy 44.508878 -238.656863) (xy 44.554899 -238.684949) (xy 44.596341 -238.719437) (xy 44.632319 -238.759591)
			(xy 44.662067 -238.804555) (xy 44.684952 -238.853372) (xy 44.700484 -238.905001) (xy 44.708334 -238.958341)
			(xy 44.708826 -238.985298) (xy 44.708334 -239.012255) (xy 44.700484 -239.065595) (xy 44.684952 -239.117224)
			(xy 44.662067 -239.166041) (xy 44.632319 -239.211005) (xy 44.596341 -239.251159) (xy 44.554899 -239.285647)
			(xy 44.508878 -239.313733) (xy 44.459258 -239.33482) (xy 44.407097 -239.348456) (xy 44.353506 -239.354353)
			(xy 44.299627 -239.352384) (xy 44.246609 -239.342591) (xy 44.195582 -239.325183) (xy 44.147634 -239.300531)
			(xy 44.103786 -239.269161) (xy 44.064973 -239.23174) (xy 44.032021 -239.189067) (xy 44.005635 -239.14205)
			(xy 43.986375 -239.091693) (xy 43.974652 -239.039069) (xy 43.970717 -238.985298) (xy 40.608758 -238.985298)
			(xy 40.608266 -239.012255) (xy 40.600416 -239.065595) (xy 40.584884 -239.117224) (xy 40.561999 -239.166041)
			(xy 40.532251 -239.211005) (xy 40.496273 -239.251159) (xy 40.454831 -239.285647) (xy 40.40881 -239.313733)
			(xy 40.35919 -239.33482) (xy 40.307029 -239.348456) (xy 40.253438 -239.354353) (xy 40.199559 -239.352384)
			(xy 40.146541 -239.342591) (xy 40.095514 -239.325183) (xy 40.047566 -239.300531) (xy 40.003718 -239.269161)
			(xy 39.964905 -239.23174) (xy 39.931953 -239.189067) (xy 39.905567 -239.14205) (xy 39.886307 -239.091693)
			(xy 39.874584 -239.039069) (xy 39.870649 -238.985298) (xy 37.164772 -238.985298) (xy 37.16428 -239.012255)
			(xy 37.15643 -239.065595) (xy 37.140898 -239.117224) (xy 37.118013 -239.166041) (xy 37.088265 -239.211005)
			(xy 37.052287 -239.251159) (xy 37.010845 -239.285647) (xy 36.964824 -239.313733) (xy 36.915204 -239.33482)
			(xy 36.863043 -239.348456) (xy 36.809452 -239.354353) (xy 36.755573 -239.352384) (xy 36.702555 -239.342591)
			(xy 36.651528 -239.325183) (xy 36.60358 -239.300531) (xy 36.559732 -239.269161) (xy 36.520919 -239.23174)
			(xy 36.487967 -239.189067) (xy 36.461581 -239.14205) (xy 36.442321 -239.091693) (xy 36.430598 -239.039069)
			(xy 36.426663 -238.985298) (xy 33.064704 -238.985298) (xy 33.064212 -239.012255) (xy 33.056362 -239.065595)
			(xy 33.04083 -239.117224) (xy 33.017945 -239.166041) (xy 32.988197 -239.211005) (xy 32.952219 -239.251159)
			(xy 32.910777 -239.285647) (xy 32.864756 -239.313733) (xy 32.815136 -239.33482) (xy 32.762975 -239.348456)
			(xy 32.709384 -239.354353) (xy 32.655505 -239.352384) (xy 32.602487 -239.342591) (xy 32.55146 -239.325183)
			(xy 32.503512 -239.300531) (xy 32.459664 -239.269161) (xy 32.420851 -239.23174) (xy 32.387899 -239.189067)
			(xy 32.361513 -239.14205) (xy 32.342253 -239.091693) (xy 32.33053 -239.039069) (xy 32.326595 -238.985298)
			(xy 29.620972 -238.985298) (xy 29.62048 -239.012255) (xy 29.61263 -239.065595) (xy 29.597098 -239.117224)
			(xy 29.574213 -239.166041) (xy 29.544465 -239.211005) (xy 29.508487 -239.251159) (xy 29.467045 -239.285647)
			(xy 29.421024 -239.313733) (xy 29.371404 -239.33482) (xy 29.319243 -239.348456) (xy 29.265652 -239.354353)
			(xy 29.211773 -239.352384) (xy 29.158755 -239.342591) (xy 29.107728 -239.325183) (xy 29.05978 -239.300531)
			(xy 29.015932 -239.269161) (xy 28.977119 -239.23174) (xy 28.944167 -239.189067) (xy 28.917781 -239.14205)
			(xy 28.898521 -239.091693) (xy 28.886798 -239.039069) (xy 28.882863 -238.985298) (xy 25.520904 -238.985298)
			(xy 25.520412 -239.012255) (xy 25.512562 -239.065595) (xy 25.49703 -239.117224) (xy 25.474145 -239.166041)
			(xy 25.444397 -239.211005) (xy 25.408419 -239.251159) (xy 25.366977 -239.285647) (xy 25.320956 -239.313733)
			(xy 25.271336 -239.33482) (xy 25.219175 -239.348456) (xy 25.165584 -239.354353) (xy 25.111705 -239.352384)
			(xy 25.058687 -239.342591) (xy 25.00766 -239.325183) (xy 24.959712 -239.300531) (xy 24.915864 -239.269161)
			(xy 24.877051 -239.23174) (xy 24.844099 -239.189067) (xy 24.817713 -239.14205) (xy 24.798453 -239.091693)
			(xy 24.78673 -239.039069) (xy 24.782795 -238.985298) (xy 22.076918 -238.985298) (xy 22.076426 -239.012255)
			(xy 22.068576 -239.065595) (xy 22.053044 -239.117224) (xy 22.030159 -239.166041) (xy 22.000411 -239.211005)
			(xy 21.964433 -239.251159) (xy 21.922991 -239.285647) (xy 21.87697 -239.313733) (xy 21.82735 -239.33482)
			(xy 21.775189 -239.348456) (xy 21.721598 -239.354353) (xy 21.667719 -239.352384) (xy 21.614701 -239.342591)
			(xy 21.563674 -239.325183) (xy 21.515726 -239.300531) (xy 21.471878 -239.269161) (xy 21.433065 -239.23174)
			(xy 21.400113 -239.189067) (xy 21.373727 -239.14205) (xy 21.354467 -239.091693) (xy 21.342744 -239.039069)
			(xy 21.338809 -238.985298) (xy 17.97685 -238.985298) (xy 17.976358 -239.012255) (xy 17.968508 -239.065595)
			(xy 17.952976 -239.117224) (xy 17.930091 -239.166041) (xy 17.900343 -239.211005) (xy 17.864365 -239.251159)
			(xy 17.822923 -239.285647) (xy 17.776902 -239.313733) (xy 17.727282 -239.33482) (xy 17.675121 -239.348456)
			(xy 17.62153 -239.354353) (xy 17.567651 -239.352384) (xy 17.514633 -239.342591) (xy 17.463606 -239.325183)
			(xy 17.415658 -239.300531) (xy 17.37181 -239.269161) (xy 17.332997 -239.23174) (xy 17.300045 -239.189067)
			(xy 17.273659 -239.14205) (xy 17.254399 -239.091693) (xy 17.242676 -239.039069) (xy 17.238741 -238.985298)
			(xy 15.598394 -238.985298) (xy 15.598394 -239.835436) (xy 17.238741 -239.835436) (xy 17.242676 -239.781665)
			(xy 17.254399 -239.729041) (xy 17.273659 -239.678684) (xy 17.300045 -239.631667) (xy 17.332997 -239.588994)
			(xy 17.37181 -239.551573) (xy 17.415658 -239.520203) (xy 17.463606 -239.495551) (xy 17.514633 -239.478143)
			(xy 17.567651 -239.46835) (xy 17.62153 -239.466381) (xy 17.675121 -239.472278) (xy 17.727282 -239.485914)
			(xy 17.776902 -239.507001) (xy 17.822923 -239.535087) (xy 17.864365 -239.569575) (xy 17.900343 -239.609729)
			(xy 17.930091 -239.654693) (xy 17.952976 -239.70351) (xy 17.968508 -239.755139) (xy 17.976358 -239.808479)
			(xy 17.97685 -239.835436) (xy 24.782795 -239.835436) (xy 24.78673 -239.781665) (xy 24.798453 -239.729041)
			(xy 24.817713 -239.678684) (xy 24.844099 -239.631667) (xy 24.877051 -239.588994) (xy 24.915864 -239.551573)
			(xy 24.959712 -239.520203) (xy 25.00766 -239.495551) (xy 25.058687 -239.478143) (xy 25.111705 -239.46835)
			(xy 25.165584 -239.466381) (xy 25.219175 -239.472278) (xy 25.271336 -239.485914) (xy 25.320956 -239.507001)
			(xy 25.366977 -239.535087) (xy 25.408419 -239.569575) (xy 25.444397 -239.609729) (xy 25.474145 -239.654693)
			(xy 25.49703 -239.70351) (xy 25.512562 -239.755139) (xy 25.520412 -239.808479) (xy 25.520904 -239.835436)
			(xy 32.326595 -239.835436) (xy 32.33053 -239.781665) (xy 32.342253 -239.729041) (xy 32.361513 -239.678684)
			(xy 32.387899 -239.631667) (xy 32.420851 -239.588994) (xy 32.459664 -239.551573) (xy 32.503512 -239.520203)
			(xy 32.55146 -239.495551) (xy 32.602487 -239.478143) (xy 32.655505 -239.46835) (xy 32.709384 -239.466381)
			(xy 32.762975 -239.472278) (xy 32.815136 -239.485914) (xy 32.864756 -239.507001) (xy 32.910777 -239.535087)
			(xy 32.952219 -239.569575) (xy 32.988197 -239.609729) (xy 33.017945 -239.654693) (xy 33.04083 -239.70351)
			(xy 33.056362 -239.755139) (xy 33.064212 -239.808479) (xy 33.064704 -239.835436) (xy 39.870649 -239.835436)
			(xy 39.874584 -239.781665) (xy 39.886307 -239.729041) (xy 39.905567 -239.678684) (xy 39.931953 -239.631667)
			(xy 39.964905 -239.588994) (xy 40.003718 -239.551573) (xy 40.047566 -239.520203) (xy 40.095514 -239.495551)
			(xy 40.146541 -239.478143) (xy 40.199559 -239.46835) (xy 40.253438 -239.466381) (xy 40.307029 -239.472278)
			(xy 40.35919 -239.485914) (xy 40.40881 -239.507001) (xy 40.454831 -239.535087) (xy 40.496273 -239.569575)
			(xy 40.532251 -239.609729) (xy 40.561999 -239.654693) (xy 40.584884 -239.70351) (xy 40.600416 -239.755139)
			(xy 40.608266 -239.808479) (xy 40.608758 -239.835436) (xy 40.608266 -239.862393) (xy 40.600416 -239.915733)
			(xy 40.584884 -239.967362) (xy 40.561999 -240.016179) (xy 40.532251 -240.061143) (xy 40.496273 -240.101297)
			(xy 40.454831 -240.135785) (xy 40.40881 -240.163871) (xy 40.35919 -240.184958) (xy 40.307029 -240.198594)
			(xy 40.253438 -240.204491) (xy 40.199559 -240.202522) (xy 40.146541 -240.192729) (xy 40.095514 -240.175321)
			(xy 40.047566 -240.150669) (xy 40.003718 -240.119299) (xy 39.964905 -240.081878) (xy 39.931953 -240.039205)
			(xy 39.905567 -239.992188) (xy 39.886307 -239.941831) (xy 39.874584 -239.889207) (xy 39.870649 -239.835436)
			(xy 33.064704 -239.835436) (xy 33.064212 -239.862393) (xy 33.056362 -239.915733) (xy 33.04083 -239.967362)
			(xy 33.017945 -240.016179) (xy 32.988197 -240.061143) (xy 32.952219 -240.101297) (xy 32.910777 -240.135785)
			(xy 32.864756 -240.163871) (xy 32.815136 -240.184958) (xy 32.762975 -240.198594) (xy 32.709384 -240.204491)
			(xy 32.655505 -240.202522) (xy 32.602487 -240.192729) (xy 32.55146 -240.175321) (xy 32.503512 -240.150669)
			(xy 32.459664 -240.119299) (xy 32.420851 -240.081878) (xy 32.387899 -240.039205) (xy 32.361513 -239.992188)
			(xy 32.342253 -239.941831) (xy 32.33053 -239.889207) (xy 32.326595 -239.835436) (xy 25.520904 -239.835436)
			(xy 25.520412 -239.862393) (xy 25.512562 -239.915733) (xy 25.49703 -239.967362) (xy 25.474145 -240.016179)
			(xy 25.444397 -240.061143) (xy 25.408419 -240.101297) (xy 25.366977 -240.135785) (xy 25.320956 -240.163871)
			(xy 25.271336 -240.184958) (xy 25.219175 -240.198594) (xy 25.165584 -240.204491) (xy 25.111705 -240.202522)
			(xy 25.058687 -240.192729) (xy 25.00766 -240.175321) (xy 24.959712 -240.150669) (xy 24.915864 -240.119299)
			(xy 24.877051 -240.081878) (xy 24.844099 -240.039205) (xy 24.817713 -239.992188) (xy 24.798453 -239.941831)
			(xy 24.78673 -239.889207) (xy 24.782795 -239.835436) (xy 17.97685 -239.835436) (xy 17.976358 -239.862393)
			(xy 17.968508 -239.915733) (xy 17.952976 -239.967362) (xy 17.930091 -240.016179) (xy 17.900343 -240.061143)
			(xy 17.864365 -240.101297) (xy 17.822923 -240.135785) (xy 17.776902 -240.163871) (xy 17.727282 -240.184958)
			(xy 17.675121 -240.198594) (xy 17.62153 -240.204491) (xy 17.567651 -240.202522) (xy 17.514633 -240.192729)
			(xy 17.463606 -240.175321) (xy 17.415658 -240.150669) (xy 17.37181 -240.119299) (xy 17.332997 -240.081878)
			(xy 17.300045 -240.039205) (xy 17.273659 -239.992188) (xy 17.254399 -239.941831) (xy 17.242676 -239.889207)
			(xy 17.238741 -239.835436) (xy 15.598394 -239.835436) (xy 15.598394 -240.68532) (xy 21.338809 -240.68532)
			(xy 21.342744 -240.631549) (xy 21.354467 -240.578925) (xy 21.373727 -240.528568) (xy 21.400113 -240.481551)
			(xy 21.433065 -240.438878) (xy 21.471878 -240.401457) (xy 21.515726 -240.370087) (xy 21.563674 -240.345435)
			(xy 21.614701 -240.328027) (xy 21.667719 -240.318234) (xy 21.721598 -240.316265) (xy 21.775189 -240.322162)
			(xy 21.82735 -240.335798) (xy 21.87697 -240.356885) (xy 21.922991 -240.384971) (xy 21.964433 -240.419459)
			(xy 22.000411 -240.459613) (xy 22.030159 -240.504577) (xy 22.053044 -240.553394) (xy 22.068576 -240.605023)
			(xy 22.076426 -240.658363) (xy 22.076918 -240.68532) (xy 28.882863 -240.68532) (xy 28.886798 -240.631549)
			(xy 28.898521 -240.578925) (xy 28.917781 -240.528568) (xy 28.944167 -240.481551) (xy 28.977119 -240.438878)
			(xy 29.015932 -240.401457) (xy 29.05978 -240.370087) (xy 29.107728 -240.345435) (xy 29.158755 -240.328027)
			(xy 29.211773 -240.318234) (xy 29.265652 -240.316265) (xy 29.319243 -240.322162) (xy 29.371404 -240.335798)
			(xy 29.421024 -240.356885) (xy 29.467045 -240.384971) (xy 29.508487 -240.419459) (xy 29.544465 -240.459613)
			(xy 29.574213 -240.504577) (xy 29.597098 -240.553394) (xy 29.61263 -240.605023) (xy 29.62048 -240.658363)
			(xy 29.620972 -240.68532) (xy 36.426663 -240.68532) (xy 36.430598 -240.631549) (xy 36.442321 -240.578925)
			(xy 36.461581 -240.528568) (xy 36.487967 -240.481551) (xy 36.520919 -240.438878) (xy 36.559732 -240.401457)
			(xy 36.60358 -240.370087) (xy 36.651528 -240.345435) (xy 36.702555 -240.328027) (xy 36.755573 -240.318234)
			(xy 36.809452 -240.316265) (xy 36.863043 -240.322162) (xy 36.915204 -240.335798) (xy 36.964824 -240.356885)
			(xy 37.010845 -240.384971) (xy 37.052287 -240.419459) (xy 37.088265 -240.459613) (xy 37.118013 -240.504577)
			(xy 37.140898 -240.553394) (xy 37.15643 -240.605023) (xy 37.16428 -240.658363) (xy 37.164772 -240.68532)
			(xy 43.970717 -240.68532) (xy 43.974652 -240.631549) (xy 43.986375 -240.578925) (xy 44.005635 -240.528568)
			(xy 44.032021 -240.481551) (xy 44.064973 -240.438878) (xy 44.103786 -240.401457) (xy 44.147634 -240.370087)
			(xy 44.195582 -240.345435) (xy 44.246609 -240.328027) (xy 44.299627 -240.318234) (xy 44.353506 -240.316265)
			(xy 44.407097 -240.322162) (xy 44.459258 -240.335798) (xy 44.508878 -240.356885) (xy 44.554899 -240.384971)
			(xy 44.596341 -240.419459) (xy 44.632319 -240.459613) (xy 44.662067 -240.504577) (xy 44.684952 -240.553394)
			(xy 44.700484 -240.605023) (xy 44.708334 -240.658363) (xy 44.708826 -240.68532) (xy 44.708334 -240.712277)
			(xy 44.700484 -240.765617) (xy 44.684952 -240.817246) (xy 44.662067 -240.866063) (xy 44.632319 -240.911027)
			(xy 44.596341 -240.951181) (xy 44.554899 -240.985669) (xy 44.508878 -241.013755) (xy 44.459258 -241.034842)
			(xy 44.407097 -241.048478) (xy 44.353506 -241.054375) (xy 44.299627 -241.052406) (xy 44.246609 -241.042613)
			(xy 44.195582 -241.025205) (xy 44.147634 -241.000553) (xy 44.103786 -240.969183) (xy 44.064973 -240.931762)
			(xy 44.032021 -240.889089) (xy 44.005635 -240.842072) (xy 43.986375 -240.791715) (xy 43.974652 -240.739091)
			(xy 43.970717 -240.68532) (xy 37.164772 -240.68532) (xy 37.16428 -240.712277) (xy 37.15643 -240.765617)
			(xy 37.140898 -240.817246) (xy 37.118013 -240.866063) (xy 37.088265 -240.911027) (xy 37.052287 -240.951181)
			(xy 37.010845 -240.985669) (xy 36.964824 -241.013755) (xy 36.915204 -241.034842) (xy 36.863043 -241.048478)
			(xy 36.809452 -241.054375) (xy 36.755573 -241.052406) (xy 36.702555 -241.042613) (xy 36.651528 -241.025205)
			(xy 36.60358 -241.000553) (xy 36.559732 -240.969183) (xy 36.520919 -240.931762) (xy 36.487967 -240.889089)
			(xy 36.461581 -240.842072) (xy 36.442321 -240.791715) (xy 36.430598 -240.739091) (xy 36.426663 -240.68532)
			(xy 29.620972 -240.68532) (xy 29.62048 -240.712277) (xy 29.61263 -240.765617) (xy 29.597098 -240.817246)
			(xy 29.574213 -240.866063) (xy 29.544465 -240.911027) (xy 29.508487 -240.951181) (xy 29.467045 -240.985669)
			(xy 29.421024 -241.013755) (xy 29.371404 -241.034842) (xy 29.319243 -241.048478) (xy 29.265652 -241.054375)
			(xy 29.211773 -241.052406) (xy 29.158755 -241.042613) (xy 29.107728 -241.025205) (xy 29.05978 -241.000553)
			(xy 29.015932 -240.969183) (xy 28.977119 -240.931762) (xy 28.944167 -240.889089) (xy 28.917781 -240.842072)
			(xy 28.898521 -240.791715) (xy 28.886798 -240.739091) (xy 28.882863 -240.68532) (xy 22.076918 -240.68532)
			(xy 22.076426 -240.712277) (xy 22.068576 -240.765617) (xy 22.053044 -240.817246) (xy 22.030159 -240.866063)
			(xy 22.000411 -240.911027) (xy 21.964433 -240.951181) (xy 21.922991 -240.985669) (xy 21.87697 -241.013755)
			(xy 21.82735 -241.034842) (xy 21.775189 -241.048478) (xy 21.721598 -241.054375) (xy 21.667719 -241.052406)
			(xy 21.614701 -241.042613) (xy 21.563674 -241.025205) (xy 21.515726 -241.000553) (xy 21.471878 -240.969183)
			(xy 21.433065 -240.931762) (xy 21.400113 -240.889089) (xy 21.373727 -240.842072) (xy 21.354467 -240.791715)
			(xy 21.342744 -240.739091) (xy 21.338809 -240.68532) (xy 15.598394 -240.68532) (xy 15.598394 -241.535204)
			(xy 17.238741 -241.535204) (xy 17.242676 -241.481433) (xy 17.254399 -241.428809) (xy 17.273659 -241.378452)
			(xy 17.300045 -241.331435) (xy 17.332997 -241.288762) (xy 17.37181 -241.251341) (xy 17.415658 -241.219971)
			(xy 17.463606 -241.195319) (xy 17.514633 -241.177911) (xy 17.567651 -241.168118) (xy 17.62153 -241.166149)
			(xy 17.675121 -241.172046) (xy 17.727282 -241.185682) (xy 17.776902 -241.206769) (xy 17.822923 -241.234855)
			(xy 17.864365 -241.269343) (xy 17.900343 -241.309497) (xy 17.930091 -241.354461) (xy 17.952976 -241.403278)
			(xy 17.968508 -241.454907) (xy 17.976358 -241.508247) (xy 17.97685 -241.535204) (xy 24.782795 -241.535204)
			(xy 24.78673 -241.481433) (xy 24.798453 -241.428809) (xy 24.817713 -241.378452) (xy 24.844099 -241.331435)
			(xy 24.877051 -241.288762) (xy 24.915864 -241.251341) (xy 24.959712 -241.219971) (xy 25.00766 -241.195319)
			(xy 25.058687 -241.177911) (xy 25.111705 -241.168118) (xy 25.165584 -241.166149) (xy 25.219175 -241.172046)
			(xy 25.271336 -241.185682) (xy 25.320956 -241.206769) (xy 25.366977 -241.234855) (xy 25.408419 -241.269343)
			(xy 25.444397 -241.309497) (xy 25.474145 -241.354461) (xy 25.49703 -241.403278) (xy 25.512562 -241.454907)
			(xy 25.520412 -241.508247) (xy 25.520904 -241.535204) (xy 32.326595 -241.535204) (xy 32.33053 -241.481433)
			(xy 32.342253 -241.428809) (xy 32.361513 -241.378452) (xy 32.387899 -241.331435) (xy 32.420851 -241.288762)
			(xy 32.459664 -241.251341) (xy 32.503512 -241.219971) (xy 32.55146 -241.195319) (xy 32.602487 -241.177911)
			(xy 32.655505 -241.168118) (xy 32.709384 -241.166149) (xy 32.762975 -241.172046) (xy 32.815136 -241.185682)
			(xy 32.864756 -241.206769) (xy 32.910777 -241.234855) (xy 32.952219 -241.269343) (xy 32.988197 -241.309497)
			(xy 33.017945 -241.354461) (xy 33.04083 -241.403278) (xy 33.056362 -241.454907) (xy 33.064212 -241.508247)
			(xy 33.064704 -241.535204) (xy 39.870649 -241.535204) (xy 39.874584 -241.481433) (xy 39.886307 -241.428809)
			(xy 39.905567 -241.378452) (xy 39.931953 -241.331435) (xy 39.964905 -241.288762) (xy 40.003718 -241.251341)
			(xy 40.047566 -241.219971) (xy 40.095514 -241.195319) (xy 40.146541 -241.177911) (xy 40.199559 -241.168118)
			(xy 40.253438 -241.166149) (xy 40.307029 -241.172046) (xy 40.35919 -241.185682) (xy 40.40881 -241.206769)
			(xy 40.454831 -241.234855) (xy 40.496273 -241.269343) (xy 40.532251 -241.309497) (xy 40.561999 -241.354461)
			(xy 40.584884 -241.403278) (xy 40.600416 -241.454907) (xy 40.608266 -241.508247) (xy 40.608758 -241.535204)
			(xy 40.608266 -241.562161) (xy 40.600416 -241.615501) (xy 40.584884 -241.66713) (xy 40.561999 -241.715947)
			(xy 40.532251 -241.760911) (xy 40.496273 -241.801065) (xy 40.454831 -241.835553) (xy 40.40881 -241.863639)
			(xy 40.35919 -241.884726) (xy 40.307029 -241.898362) (xy 40.253438 -241.904259) (xy 40.199559 -241.90229)
			(xy 40.146541 -241.892497) (xy 40.095514 -241.875089) (xy 40.047566 -241.850437) (xy 40.003718 -241.819067)
			(xy 39.964905 -241.781646) (xy 39.931953 -241.738973) (xy 39.905567 -241.691956) (xy 39.886307 -241.641599)
			(xy 39.874584 -241.588975) (xy 39.870649 -241.535204) (xy 33.064704 -241.535204) (xy 33.064212 -241.562161)
			(xy 33.056362 -241.615501) (xy 33.04083 -241.66713) (xy 33.017945 -241.715947) (xy 32.988197 -241.760911)
			(xy 32.952219 -241.801065) (xy 32.910777 -241.835553) (xy 32.864756 -241.863639) (xy 32.815136 -241.884726)
			(xy 32.762975 -241.898362) (xy 32.709384 -241.904259) (xy 32.655505 -241.90229) (xy 32.602487 -241.892497)
			(xy 32.55146 -241.875089) (xy 32.503512 -241.850437) (xy 32.459664 -241.819067) (xy 32.420851 -241.781646)
			(xy 32.387899 -241.738973) (xy 32.361513 -241.691956) (xy 32.342253 -241.641599) (xy 32.33053 -241.588975)
			(xy 32.326595 -241.535204) (xy 25.520904 -241.535204) (xy 25.520412 -241.562161) (xy 25.512562 -241.615501)
			(xy 25.49703 -241.66713) (xy 25.474145 -241.715947) (xy 25.444397 -241.760911) (xy 25.408419 -241.801065)
			(xy 25.366977 -241.835553) (xy 25.320956 -241.863639) (xy 25.271336 -241.884726) (xy 25.219175 -241.898362)
			(xy 25.165584 -241.904259) (xy 25.111705 -241.90229) (xy 25.058687 -241.892497) (xy 25.00766 -241.875089)
			(xy 24.959712 -241.850437) (xy 24.915864 -241.819067) (xy 24.877051 -241.781646) (xy 24.844099 -241.738973)
			(xy 24.817713 -241.691956) (xy 24.798453 -241.641599) (xy 24.78673 -241.588975) (xy 24.782795 -241.535204)
			(xy 17.97685 -241.535204) (xy 17.976358 -241.562161) (xy 17.968508 -241.615501) (xy 17.952976 -241.66713)
			(xy 17.930091 -241.715947) (xy 17.900343 -241.760911) (xy 17.864365 -241.801065) (xy 17.822923 -241.835553)
			(xy 17.776902 -241.863639) (xy 17.727282 -241.884726) (xy 17.675121 -241.898362) (xy 17.62153 -241.904259)
			(xy 17.567651 -241.90229) (xy 17.514633 -241.892497) (xy 17.463606 -241.875089) (xy 17.415658 -241.850437)
			(xy 17.37181 -241.819067) (xy 17.332997 -241.781646) (xy 17.300045 -241.738973) (xy 17.273659 -241.691956)
			(xy 17.254399 -241.641599) (xy 17.242676 -241.588975) (xy 17.238741 -241.535204) (xy 15.598394 -241.535204)
			(xy 15.598394 -242.385342) (xy 21.338809 -242.385342) (xy 21.342744 -242.331571) (xy 21.354467 -242.278947)
			(xy 21.373727 -242.22859) (xy 21.400113 -242.181573) (xy 21.433065 -242.1389) (xy 21.471878 -242.101479)
			(xy 21.515726 -242.070109) (xy 21.563674 -242.045457) (xy 21.614701 -242.028049) (xy 21.667719 -242.018256)
			(xy 21.721598 -242.016287) (xy 21.775189 -242.022184) (xy 21.82735 -242.03582) (xy 21.87697 -242.056907)
			(xy 21.922991 -242.084993) (xy 21.964433 -242.119481) (xy 22.000411 -242.159635) (xy 22.030159 -242.204599)
			(xy 22.053044 -242.253416) (xy 22.068576 -242.305045) (xy 22.076426 -242.358385) (xy 22.076918 -242.385342)
			(xy 28.882863 -242.385342) (xy 28.886798 -242.331571) (xy 28.898521 -242.278947) (xy 28.917781 -242.22859)
			(xy 28.944167 -242.181573) (xy 28.977119 -242.1389) (xy 29.015932 -242.101479) (xy 29.05978 -242.070109)
			(xy 29.107728 -242.045457) (xy 29.158755 -242.028049) (xy 29.211773 -242.018256) (xy 29.265652 -242.016287)
			(xy 29.319243 -242.022184) (xy 29.371404 -242.03582) (xy 29.421024 -242.056907) (xy 29.467045 -242.084993)
			(xy 29.508487 -242.119481) (xy 29.544465 -242.159635) (xy 29.574213 -242.204599) (xy 29.597098 -242.253416)
			(xy 29.61263 -242.305045) (xy 29.62048 -242.358385) (xy 29.620972 -242.385342) (xy 36.426663 -242.385342)
			(xy 36.430598 -242.331571) (xy 36.442321 -242.278947) (xy 36.461581 -242.22859) (xy 36.487967 -242.181573)
			(xy 36.520919 -242.1389) (xy 36.559732 -242.101479) (xy 36.60358 -242.070109) (xy 36.651528 -242.045457)
			(xy 36.702555 -242.028049) (xy 36.755573 -242.018256) (xy 36.809452 -242.016287) (xy 36.863043 -242.022184)
			(xy 36.915204 -242.03582) (xy 36.964824 -242.056907) (xy 37.010845 -242.084993) (xy 37.052287 -242.119481)
			(xy 37.088265 -242.159635) (xy 37.118013 -242.204599) (xy 37.140898 -242.253416) (xy 37.15643 -242.305045)
			(xy 37.16428 -242.358385) (xy 37.164772 -242.385342) (xy 43.970717 -242.385342) (xy 43.974652 -242.331571)
			(xy 43.986375 -242.278947) (xy 44.005635 -242.22859) (xy 44.032021 -242.181573) (xy 44.064973 -242.1389)
			(xy 44.103786 -242.101479) (xy 44.147634 -242.070109) (xy 44.195582 -242.045457) (xy 44.246609 -242.028049)
			(xy 44.299627 -242.018256) (xy 44.353506 -242.016287) (xy 44.407097 -242.022184) (xy 44.459258 -242.03582)
			(xy 44.508878 -242.056907) (xy 44.554899 -242.084993) (xy 44.596341 -242.119481) (xy 44.632319 -242.159635)
			(xy 44.662067 -242.204599) (xy 44.684952 -242.253416) (xy 44.700484 -242.305045) (xy 44.708334 -242.358385)
			(xy 44.708826 -242.385342) (xy 44.708334 -242.412299) (xy 44.700484 -242.465639) (xy 44.684952 -242.517268)
			(xy 44.662067 -242.566085) (xy 44.632319 -242.611049) (xy 44.596341 -242.651203) (xy 44.554899 -242.685691)
			(xy 44.508878 -242.713777) (xy 44.459258 -242.734864) (xy 44.407097 -242.7485) (xy 44.353506 -242.754397)
			(xy 44.299627 -242.752428) (xy 44.246609 -242.742635) (xy 44.195582 -242.725227) (xy 44.147634 -242.700575)
			(xy 44.103786 -242.669205) (xy 44.064973 -242.631784) (xy 44.032021 -242.589111) (xy 44.005635 -242.542094)
			(xy 43.986375 -242.491737) (xy 43.974652 -242.439113) (xy 43.970717 -242.385342) (xy 37.164772 -242.385342)
			(xy 37.16428 -242.412299) (xy 37.15643 -242.465639) (xy 37.140898 -242.517268) (xy 37.118013 -242.566085)
			(xy 37.088265 -242.611049) (xy 37.052287 -242.651203) (xy 37.010845 -242.685691) (xy 36.964824 -242.713777)
			(xy 36.915204 -242.734864) (xy 36.863043 -242.7485) (xy 36.809452 -242.754397) (xy 36.755573 -242.752428)
			(xy 36.702555 -242.742635) (xy 36.651528 -242.725227) (xy 36.60358 -242.700575) (xy 36.559732 -242.669205)
			(xy 36.520919 -242.631784) (xy 36.487967 -242.589111) (xy 36.461581 -242.542094) (xy 36.442321 -242.491737)
			(xy 36.430598 -242.439113) (xy 36.426663 -242.385342) (xy 29.620972 -242.385342) (xy 29.62048 -242.412299)
			(xy 29.61263 -242.465639) (xy 29.597098 -242.517268) (xy 29.574213 -242.566085) (xy 29.544465 -242.611049)
			(xy 29.508487 -242.651203) (xy 29.467045 -242.685691) (xy 29.421024 -242.713777) (xy 29.371404 -242.734864)
			(xy 29.319243 -242.7485) (xy 29.265652 -242.754397) (xy 29.211773 -242.752428) (xy 29.158755 -242.742635)
			(xy 29.107728 -242.725227) (xy 29.05978 -242.700575) (xy 29.015932 -242.669205) (xy 28.977119 -242.631784)
			(xy 28.944167 -242.589111) (xy 28.917781 -242.542094) (xy 28.898521 -242.491737) (xy 28.886798 -242.439113)
			(xy 28.882863 -242.385342) (xy 22.076918 -242.385342) (xy 22.076426 -242.412299) (xy 22.068576 -242.465639)
			(xy 22.053044 -242.517268) (xy 22.030159 -242.566085) (xy 22.000411 -242.611049) (xy 21.964433 -242.651203)
			(xy 21.922991 -242.685691) (xy 21.87697 -242.713777) (xy 21.82735 -242.734864) (xy 21.775189 -242.7485)
			(xy 21.721598 -242.754397) (xy 21.667719 -242.752428) (xy 21.614701 -242.742635) (xy 21.563674 -242.725227)
			(xy 21.515726 -242.700575) (xy 21.471878 -242.669205) (xy 21.433065 -242.631784) (xy 21.400113 -242.589111)
			(xy 21.373727 -242.542094) (xy 21.354467 -242.491737) (xy 21.342744 -242.439113) (xy 21.338809 -242.385342)
			(xy 15.598394 -242.385342) (xy 15.598394 -243.235226) (xy 17.238741 -243.235226) (xy 17.242676 -243.181455)
			(xy 17.254399 -243.128831) (xy 17.273659 -243.078474) (xy 17.300045 -243.031457) (xy 17.332997 -242.988784)
			(xy 17.37181 -242.951363) (xy 17.415658 -242.919993) (xy 17.463606 -242.895341) (xy 17.514633 -242.877933)
			(xy 17.567651 -242.86814) (xy 17.62153 -242.866171) (xy 17.675121 -242.872068) (xy 17.727282 -242.885704)
			(xy 17.776902 -242.906791) (xy 17.822923 -242.934877) (xy 17.864365 -242.969365) (xy 17.900343 -243.009519)
			(xy 17.930091 -243.054483) (xy 17.952976 -243.1033) (xy 17.968508 -243.154929) (xy 17.976358 -243.208269)
			(xy 17.97685 -243.235226) (xy 24.782795 -243.235226) (xy 24.78673 -243.181455) (xy 24.798453 -243.128831)
			(xy 24.817713 -243.078474) (xy 24.844099 -243.031457) (xy 24.877051 -242.988784) (xy 24.915864 -242.951363)
			(xy 24.959712 -242.919993) (xy 25.00766 -242.895341) (xy 25.058687 -242.877933) (xy 25.111705 -242.86814)
			(xy 25.165584 -242.866171) (xy 25.219175 -242.872068) (xy 25.271336 -242.885704) (xy 25.320956 -242.906791)
			(xy 25.366977 -242.934877) (xy 25.408419 -242.969365) (xy 25.444397 -243.009519) (xy 25.474145 -243.054483)
			(xy 25.49703 -243.1033) (xy 25.512562 -243.154929) (xy 25.520412 -243.208269) (xy 25.520904 -243.235226)
			(xy 32.326595 -243.235226) (xy 32.33053 -243.181455) (xy 32.342253 -243.128831) (xy 32.361513 -243.078474)
			(xy 32.387899 -243.031457) (xy 32.420851 -242.988784) (xy 32.459664 -242.951363) (xy 32.503512 -242.919993)
			(xy 32.55146 -242.895341) (xy 32.602487 -242.877933) (xy 32.655505 -242.86814) (xy 32.709384 -242.866171)
			(xy 32.762975 -242.872068) (xy 32.815136 -242.885704) (xy 32.864756 -242.906791) (xy 32.910777 -242.934877)
			(xy 32.952219 -242.969365) (xy 32.988197 -243.009519) (xy 33.017945 -243.054483) (xy 33.04083 -243.1033)
			(xy 33.056362 -243.154929) (xy 33.064212 -243.208269) (xy 33.064704 -243.235226) (xy 39.870649 -243.235226)
			(xy 39.874584 -243.181455) (xy 39.886307 -243.128831) (xy 39.905567 -243.078474) (xy 39.931953 -243.031457)
			(xy 39.964905 -242.988784) (xy 40.003718 -242.951363) (xy 40.047566 -242.919993) (xy 40.095514 -242.895341)
			(xy 40.146541 -242.877933) (xy 40.199559 -242.86814) (xy 40.253438 -242.866171) (xy 40.307029 -242.872068)
			(xy 40.35919 -242.885704) (xy 40.40881 -242.906791) (xy 40.454831 -242.934877) (xy 40.496273 -242.969365)
			(xy 40.532251 -243.009519) (xy 40.561999 -243.054483) (xy 40.584884 -243.1033) (xy 40.600416 -243.154929)
			(xy 40.608266 -243.208269) (xy 40.608758 -243.235226) (xy 40.608266 -243.262183) (xy 40.600416 -243.315523)
			(xy 40.584884 -243.367152) (xy 40.561999 -243.415969) (xy 40.532251 -243.460933) (xy 40.496273 -243.501087)
			(xy 40.454831 -243.535575) (xy 40.40881 -243.563661) (xy 40.35919 -243.584748) (xy 40.307029 -243.598384)
			(xy 40.253438 -243.604281) (xy 40.199559 -243.602312) (xy 40.146541 -243.592519) (xy 40.095514 -243.575111)
			(xy 40.047566 -243.550459) (xy 40.003718 -243.519089) (xy 39.964905 -243.481668) (xy 39.931953 -243.438995)
			(xy 39.905567 -243.391978) (xy 39.886307 -243.341621) (xy 39.874584 -243.288997) (xy 39.870649 -243.235226)
			(xy 33.064704 -243.235226) (xy 33.064212 -243.262183) (xy 33.056362 -243.315523) (xy 33.04083 -243.367152)
			(xy 33.017945 -243.415969) (xy 32.988197 -243.460933) (xy 32.952219 -243.501087) (xy 32.910777 -243.535575)
			(xy 32.864756 -243.563661) (xy 32.815136 -243.584748) (xy 32.762975 -243.598384) (xy 32.709384 -243.604281)
			(xy 32.655505 -243.602312) (xy 32.602487 -243.592519) (xy 32.55146 -243.575111) (xy 32.503512 -243.550459)
			(xy 32.459664 -243.519089) (xy 32.420851 -243.481668) (xy 32.387899 -243.438995) (xy 32.361513 -243.391978)
			(xy 32.342253 -243.341621) (xy 32.33053 -243.288997) (xy 32.326595 -243.235226) (xy 25.520904 -243.235226)
			(xy 25.520412 -243.262183) (xy 25.512562 -243.315523) (xy 25.49703 -243.367152) (xy 25.474145 -243.415969)
			(xy 25.444397 -243.460933) (xy 25.408419 -243.501087) (xy 25.366977 -243.535575) (xy 25.320956 -243.563661)
			(xy 25.271336 -243.584748) (xy 25.219175 -243.598384) (xy 25.165584 -243.604281) (xy 25.111705 -243.602312)
			(xy 25.058687 -243.592519) (xy 25.00766 -243.575111) (xy 24.959712 -243.550459) (xy 24.915864 -243.519089)
			(xy 24.877051 -243.481668) (xy 24.844099 -243.438995) (xy 24.817713 -243.391978) (xy 24.798453 -243.341621)
			(xy 24.78673 -243.288997) (xy 24.782795 -243.235226) (xy 17.97685 -243.235226) (xy 17.976358 -243.262183)
			(xy 17.968508 -243.315523) (xy 17.952976 -243.367152) (xy 17.930091 -243.415969) (xy 17.900343 -243.460933)
			(xy 17.864365 -243.501087) (xy 17.822923 -243.535575) (xy 17.776902 -243.563661) (xy 17.727282 -243.584748)
			(xy 17.675121 -243.598384) (xy 17.62153 -243.604281) (xy 17.567651 -243.602312) (xy 17.514633 -243.592519)
			(xy 17.463606 -243.575111) (xy 17.415658 -243.550459) (xy 17.37181 -243.519089) (xy 17.332997 -243.481668)
			(xy 17.300045 -243.438995) (xy 17.273659 -243.391978) (xy 17.254399 -243.341621) (xy 17.242676 -243.288997)
			(xy 17.238741 -243.235226) (xy 15.598394 -243.235226) (xy 15.598394 -244.0854) (xy 21.338713 -244.0854)
			(xy 21.342839 -244.030345) (xy 21.355125 -243.97652) (xy 21.375296 -243.925127) (xy 21.402901 -243.877314)
			(xy 21.437324 -243.83415) (xy 21.477796 -243.796598) (xy 21.523413 -243.765499) (xy 21.573155 -243.741545)
			(xy 21.625912 -243.725273) (xy 21.680505 -243.717046) (xy 21.70811 -243.716556) (xy 21.733259 -243.716988)
			(xy 21.783089 -243.723845) (xy 21.831522 -243.737418) (xy 21.877659 -243.757453) (xy 21.899372 -243.77015)
			(xy 21.905468 -243.773706) (xy 21.918676 -243.777516) (xy 21.991828 -243.777516) (xy 22.001016 -243.777116)
			(xy 22.0182 -243.770595) (xy 22.025356 -243.764816) (xy 22.040947 -243.751545) (xy 22.075963 -243.730334)
			(xy 22.11423 -243.715786) (xy 22.154493 -243.708378) (xy 22.174962 -243.70792) (xy 22.442678 -243.70792)
			(xy 22.442678 -243.71808) (xy 22.44319 -243.727864) (xy 22.450772 -243.745914) (xy 22.464622 -243.759751)
			(xy 22.482678 -243.767318) (xy 22.492462 -243.767864) (xy 22.910292 -243.767864) (xy 22.92223 -243.764816)
			(xy 22.927818 -243.761768) (xy 22.939756 -243.755926) (xy 22.94001 -243.755672) (xy 22.95144 -243.74983)
			(xy 22.954989 -243.74794) (xy 22.961494 -243.743217) (xy 22.964394 -243.740432) (xy 22.98192 -243.722906)
			(xy 22.98932 -243.716065) (xy 23.007919 -243.708346) (xy 23.017988 -243.70792) (xy 23.235158 -243.70792)
			(xy 23.257466 -243.708491) (xy 23.301218 -243.717224) (xy 23.342411 -243.73436) (xy 23.379448 -243.759235)
			(xy 23.410894 -243.790885) (xy 23.435529 -243.828082) (xy 23.452399 -243.869386) (xy 23.460849 -243.913193)
			(xy 23.461218 -243.935504) (xy 23.461218 -243.98859) (xy 23.462742 -243.994686) (xy 23.468 -244.016985)
			(xy 23.473603 -244.062456) (xy 23.473918 -244.085364) (xy 23.473918 -244.0854) (xy 28.882839 -244.0854)
			(xy 28.886964 -244.030353) (xy 28.899247 -243.976535) (xy 28.919413 -243.92515) (xy 28.947012 -243.877343)
			(xy 28.981428 -243.834183) (xy 29.021891 -243.796635) (xy 29.067499 -243.765536) (xy 29.117232 -243.741582)
			(xy 29.169979 -243.725307) (xy 29.224563 -243.717074) (xy 29.252164 -243.716556) (xy 29.277313 -243.717008)
			(xy 29.327141 -243.72386) (xy 29.375575 -243.737426) (xy 29.421712 -243.757456) (xy 29.443426 -243.77015)
			(xy 29.449522 -243.773706) (xy 29.46273 -243.777516) (xy 29.535882 -243.777516) (xy 29.545068 -243.777093)
			(xy 29.562252 -243.770588) (xy 29.56941 -243.764816) (xy 29.585018 -243.751567) (xy 29.620028 -243.730351)
			(xy 29.658289 -243.715797) (xy 29.698548 -243.708382) (xy 29.719016 -243.70792) (xy 29.986478 -243.70792)
			(xy 29.986478 -243.717064) (xy 29.986949 -243.72708) (xy 29.994603 -243.745592) (xy 30.008759 -243.759765)
			(xy 30.027262 -243.76744) (xy 30.037278 -243.767864) (xy 30.454346 -243.767864) (xy 30.466284 -243.764816)
			(xy 30.471872 -243.761768) (xy 30.48381 -243.755926) (xy 30.484064 -243.755672) (xy 30.495748 -243.74983)
			(xy 30.499454 -243.747852) (xy 30.50622 -243.742874) (xy 30.50921 -243.739924) (xy 30.52572 -243.72316)
			(xy 30.533164 -243.716238) (xy 30.551888 -243.708372) (xy 30.562042 -243.70792) (xy 30.779212 -243.70792)
			(xy 30.799511 -243.708277) (xy 30.839459 -243.715511) (xy 30.877473 -243.729762) (xy 30.912331 -243.750573)
			(xy 30.942912 -243.777274) (xy 30.968234 -243.809007) (xy 30.987482 -243.844752) (xy 31.000037 -243.883359)
			(xy 31.005497 -243.923588) (xy 31.005018 -243.943886) (xy 31.005018 -243.987574) (xy 31.006542 -243.993924)
			(xy 31.011894 -244.016404) (xy 31.017627 -244.062258) (xy 31.017972 -244.085364) (xy 31.017971 -244.0854)
			(xy 36.426639 -244.0854) (xy 36.430764 -244.030353) (xy 36.443047 -243.976535) (xy 36.463213 -243.92515)
			(xy 36.490812 -243.877343) (xy 36.525228 -243.834183) (xy 36.565691 -243.796635) (xy 36.611299 -243.765536)
			(xy 36.661032 -243.741582) (xy 36.713779 -243.725307) (xy 36.768363 -243.717074) (xy 36.795964 -243.716556)
			(xy 36.821113 -243.717008) (xy 36.870941 -243.72386) (xy 36.919375 -243.737426) (xy 36.965512 -243.757456)
			(xy 36.987226 -243.77015) (xy 36.993322 -243.773706) (xy 37.00653 -243.777516) (xy 37.079682 -243.777516)
			(xy 37.088868 -243.777093) (xy 37.106052 -243.770588) (xy 37.11321 -243.764816) (xy 37.128818 -243.751567)
			(xy 37.163828 -243.730351) (xy 37.202089 -243.715797) (xy 37.242348 -243.708382) (xy 37.262816 -243.70792)
			(xy 37.530278 -243.70792) (xy 37.530278 -243.717064) (xy 37.530749 -243.72708) (xy 37.538403 -243.745592)
			(xy 37.552559 -243.759765) (xy 37.571062 -243.76744) (xy 37.581078 -243.767864) (xy 37.998146 -243.767864)
			(xy 38.010084 -243.764816) (xy 38.015672 -243.761768) (xy 38.02761 -243.755926) (xy 38.027864 -243.755672)
			(xy 38.039548 -243.74983) (xy 38.043254 -243.747852) (xy 38.05002 -243.742874) (xy 38.05301 -243.739924)
			(xy 38.06952 -243.72316) (xy 38.076964 -243.716238) (xy 38.095688 -243.708372) (xy 38.105842 -243.70792)
			(xy 38.323012 -243.70792) (xy 38.343311 -243.708277) (xy 38.383259 -243.715511) (xy 38.421273 -243.729762)
			(xy 38.456131 -243.750573) (xy 38.486712 -243.777274) (xy 38.512034 -243.809007) (xy 38.531282 -243.844752)
			(xy 38.543837 -243.883359) (xy 38.549297 -243.923588) (xy 38.548818 -243.943886) (xy 38.548818 -243.987574)
			(xy 38.550342 -243.993924) (xy 38.555694 -244.016404) (xy 38.561427 -244.062258) (xy 38.561772 -244.085364)
			(xy 38.561407 -244.110509) (xy 38.554654 -244.160343) (xy 38.54831 -244.184678) (xy 38.546974 -244.189772)
			(xy 38.546198 -244.200273) (xy 38.546786 -244.205506) (xy 38.549213 -244.226847) (xy 38.546988 -244.269734)
			(xy 38.536717 -244.311433) (xy 38.518767 -244.350446) (xy 38.493782 -244.385375) (xy 38.46266 -244.414966)
			(xy 38.426516 -244.438158) (xy 38.386647 -244.454118) (xy 38.344484 -244.462274) (xy 38.323012 -244.462808)
			(xy 38.05555 -244.462808) (xy 38.05555 -244.445536) (xy 38.04031 -244.421152) (xy 38.027102 -244.414802)
			(xy 38.015672 -244.40896) (xy 38.010084 -244.405912) (xy 37.998146 -244.402864) (xy 37.557202 -244.402864)
			(xy 37.532056 -244.41912) (xy 37.52596 -244.43309) (xy 37.521631 -244.441672) (xy 37.50786 -244.45505)
			(xy 37.490091 -244.462321) (xy 37.480494 -244.462808) (xy 37.262816 -244.462808) (xy 37.242353 -244.462301)
			(xy 37.202106 -244.454865) (xy 37.16385 -244.440321) (xy 37.128826 -244.419144) (xy 37.11321 -244.405912)
			(xy 37.106078 -244.400096) (xy 37.088878 -244.393593) (xy 37.079682 -244.393212) (xy 37.00653 -244.393212)
			(xy 36.993322 -244.397022) (xy 36.987226 -244.400578) (xy 36.965518 -244.413282) (xy 36.919374 -244.433298)
			(xy 36.87094 -244.446864) (xy 36.821113 -244.453729) (xy 36.795964 -244.454172) (xy 36.768363 -244.453726)
			(xy 36.713779 -244.445493) (xy 36.661032 -244.429218) (xy 36.611299 -244.405264) (xy 36.565691 -244.374165)
			(xy 36.525228 -244.336617) (xy 36.490812 -244.293457) (xy 36.463213 -244.24565) (xy 36.443047 -244.194265)
			(xy 36.430764 -244.140447) (xy 36.426639 -244.0854) (xy 31.017971 -244.0854) (xy 31.017607 -244.110509)
			(xy 31.010854 -244.160343) (xy 31.00451 -244.184678) (xy 31.003174 -244.189772) (xy 31.002398 -244.200273)
			(xy 31.002986 -244.205506) (xy 31.005413 -244.226847) (xy 31.003188 -244.269734) (xy 30.992917 -244.311433)
			(xy 30.974967 -244.350446) (xy 30.949982 -244.385375) (xy 30.91886 -244.414966) (xy 30.882716 -244.438158)
			(xy 30.842847 -244.454118) (xy 30.800684 -244.462274) (xy 30.779212 -244.462808) (xy 30.51175 -244.462808)
			(xy 30.51175 -244.445536) (xy 30.49651 -244.421152) (xy 30.483302 -244.414802) (xy 30.471872 -244.40896)
			(xy 30.466284 -244.405912) (xy 30.454346 -244.402864) (xy 30.013402 -244.402864) (xy 29.988256 -244.41912)
			(xy 29.98216 -244.43309) (xy 29.977831 -244.441672) (xy 29.96406 -244.45505) (xy 29.946291 -244.462321)
			(xy 29.936694 -244.462808) (xy 29.719016 -244.462808) (xy 29.698553 -244.462301) (xy 29.658306 -244.454865)
			(xy 29.62005 -244.440321) (xy 29.585026 -244.419144) (xy 29.56941 -244.405912) (xy 29.562278 -244.400096)
			(xy 29.545078 -244.393593) (xy 29.535882 -244.393212) (xy 29.46273 -244.393212) (xy 29.449522 -244.397022)
			(xy 29.443426 -244.400578) (xy 29.421718 -244.413282) (xy 29.375574 -244.433298) (xy 29.32714 -244.446864)
			(xy 29.277313 -244.453729) (xy 29.252164 -244.454172) (xy 29.224563 -244.453726) (xy 29.169979 -244.445493)
			(xy 29.117232 -244.429218) (xy 29.067499 -244.405264) (xy 29.021891 -244.374165) (xy 28.981428 -244.336617)
			(xy 28.947012 -244.293457) (xy 28.919413 -244.24565) (xy 28.899247 -244.194265) (xy 28.886964 -244.140447)
			(xy 28.882839 -244.0854) (xy 23.473918 -244.0854) (xy 23.473607 -244.108272) (xy 23.468006 -244.153744)
			(xy 23.462742 -244.176042) (xy 23.461218 -244.182138) (xy 23.461218 -244.235224) (xy 23.460931 -244.257541)
			(xy 23.452474 -244.301361) (xy 23.435595 -244.342674) (xy 23.41095 -244.379881) (xy 23.379493 -244.411538)
			(xy 23.342444 -244.436419) (xy 23.301238 -244.453559) (xy 23.257472 -244.462294) (xy 23.235158 -244.462808)
			(xy 22.967442 -244.462808) (xy 22.967442 -244.445536) (xy 22.952202 -244.421152) (xy 22.938994 -244.414548)
			(xy 22.927818 -244.40896) (xy 22.92223 -244.405912) (xy 22.910292 -244.402864) (xy 22.469602 -244.402864)
			(xy 22.444456 -244.41912) (xy 22.43836 -244.43309) (xy 22.434071 -244.441748) (xy 22.420201 -244.455177)
			(xy 22.402294 -244.462392) (xy 22.39264 -244.462808) (xy 22.174962 -244.462808) (xy 22.154498 -244.462332)
			(xy 22.11425 -244.454886) (xy 22.075993 -244.440334) (xy 22.040971 -244.419148) (xy 22.025356 -244.405912)
			(xy 22.018211 -244.400116) (xy 22.00102 -244.3936) (xy 21.991828 -244.393212) (xy 21.918676 -244.393212)
			(xy 21.905468 -244.397022) (xy 21.899372 -244.400578) (xy 21.877653 -244.413263) (xy 21.831514 -244.433284)
			(xy 21.783083 -244.446855) (xy 21.733258 -244.453726) (xy 21.70811 -244.454172) (xy 21.680505 -244.453754)
			(xy 21.625912 -244.445527) (xy 21.573155 -244.429255) (xy 21.523413 -244.405301) (xy 21.477796 -244.374202)
			(xy 21.437324 -244.33665) (xy 21.402901 -244.293486) (xy 21.375296 -244.245673) (xy 21.355125 -244.19428)
			(xy 21.342839 -244.140455) (xy 21.338713 -244.0854) (xy 15.598394 -244.0854) (xy 15.598394 -244.935248)
			(xy 17.238741 -244.935248) (xy 17.242676 -244.881477) (xy 17.254399 -244.828853) (xy 17.273659 -244.778496)
			(xy 17.300045 -244.731479) (xy 17.332997 -244.688806) (xy 17.37181 -244.651385) (xy 17.415658 -244.620015)
			(xy 17.463606 -244.595363) (xy 17.514633 -244.577955) (xy 17.567651 -244.568162) (xy 17.62153 -244.566193)
			(xy 17.675121 -244.57209) (xy 17.727282 -244.585726) (xy 17.776902 -244.606813) (xy 17.822923 -244.634899)
			(xy 17.864365 -244.669387) (xy 17.900343 -244.709541) (xy 17.930091 -244.754505) (xy 17.952976 -244.803322)
			(xy 17.968508 -244.854951) (xy 17.976358 -244.908291) (xy 17.97685 -244.935248) (xy 24.782795 -244.935248)
			(xy 24.78673 -244.881477) (xy 24.798453 -244.828853) (xy 24.817713 -244.778496) (xy 24.844099 -244.731479)
			(xy 24.877051 -244.688806) (xy 24.915864 -244.651385) (xy 24.959712 -244.620015) (xy 25.00766 -244.595363)
			(xy 25.058687 -244.577955) (xy 25.111705 -244.568162) (xy 25.165584 -244.566193) (xy 25.219175 -244.57209)
			(xy 25.271336 -244.585726) (xy 25.320956 -244.606813) (xy 25.366977 -244.634899) (xy 25.408419 -244.669387)
			(xy 25.444397 -244.709541) (xy 25.474145 -244.754505) (xy 25.49703 -244.803322) (xy 25.512562 -244.854951)
			(xy 25.520412 -244.908291) (xy 25.520904 -244.935248) (xy 32.326595 -244.935248) (xy 32.33053 -244.881477)
			(xy 32.342253 -244.828853) (xy 32.361513 -244.778496) (xy 32.387899 -244.731479) (xy 32.420851 -244.688806)
			(xy 32.459664 -244.651385) (xy 32.503512 -244.620015) (xy 32.55146 -244.595363) (xy 32.602487 -244.577955)
			(xy 32.655505 -244.568162) (xy 32.709384 -244.566193) (xy 32.762975 -244.57209) (xy 32.815136 -244.585726)
			(xy 32.864756 -244.606813) (xy 32.910777 -244.634899) (xy 32.952219 -244.669387) (xy 32.988197 -244.709541)
			(xy 33.017945 -244.754505) (xy 33.04083 -244.803322) (xy 33.056362 -244.854951) (xy 33.064212 -244.908291)
			(xy 33.064704 -244.935248) (xy 39.870649 -244.935248) (xy 39.874584 -244.881477) (xy 39.886307 -244.828853)
			(xy 39.905567 -244.778496) (xy 39.931953 -244.731479) (xy 39.964905 -244.688806) (xy 40.003718 -244.651385)
			(xy 40.047566 -244.620015) (xy 40.095514 -244.595363) (xy 40.146541 -244.577955) (xy 40.199559 -244.568162)
			(xy 40.253438 -244.566193) (xy 40.307029 -244.57209) (xy 40.35919 -244.585726) (xy 40.40881 -244.606813)
			(xy 40.454831 -244.634899) (xy 40.496273 -244.669387) (xy 40.532251 -244.709541) (xy 40.561999 -244.754505)
			(xy 40.584884 -244.803322) (xy 40.600416 -244.854951) (xy 40.608266 -244.908291) (xy 40.608758 -244.935248)
			(xy 40.608266 -244.962205) (xy 40.600416 -245.015545) (xy 40.584884 -245.067174) (xy 40.561999 -245.115991)
			(xy 40.532251 -245.160955) (xy 40.496273 -245.201109) (xy 40.454831 -245.235597) (xy 40.40881 -245.263683)
			(xy 40.35919 -245.28477) (xy 40.307029 -245.298406) (xy 40.253438 -245.304303) (xy 40.199559 -245.302334)
			(xy 40.146541 -245.292541) (xy 40.095514 -245.275133) (xy 40.047566 -245.250481) (xy 40.003718 -245.219111)
			(xy 39.964905 -245.18169) (xy 39.931953 -245.139017) (xy 39.905567 -245.092) (xy 39.886307 -245.041643)
			(xy 39.874584 -244.989019) (xy 39.870649 -244.935248) (xy 33.064704 -244.935248) (xy 33.064212 -244.962205)
			(xy 33.056362 -245.015545) (xy 33.04083 -245.067174) (xy 33.017945 -245.115991) (xy 32.988197 -245.160955)
			(xy 32.952219 -245.201109) (xy 32.910777 -245.235597) (xy 32.864756 -245.263683) (xy 32.815136 -245.28477)
			(xy 32.762975 -245.298406) (xy 32.709384 -245.304303) (xy 32.655505 -245.302334) (xy 32.602487 -245.292541)
			(xy 32.55146 -245.275133) (xy 32.503512 -245.250481) (xy 32.459664 -245.219111) (xy 32.420851 -245.18169)
			(xy 32.387899 -245.139017) (xy 32.361513 -245.092) (xy 32.342253 -245.041643) (xy 32.33053 -244.989019)
			(xy 32.326595 -244.935248) (xy 25.520904 -244.935248) (xy 25.520412 -244.962205) (xy 25.512562 -245.015545)
			(xy 25.49703 -245.067174) (xy 25.474145 -245.115991) (xy 25.444397 -245.160955) (xy 25.408419 -245.201109)
			(xy 25.366977 -245.235597) (xy 25.320956 -245.263683) (xy 25.271336 -245.28477) (xy 25.219175 -245.298406)
			(xy 25.165584 -245.304303) (xy 25.111705 -245.302334) (xy 25.058687 -245.292541) (xy 25.00766 -245.275133)
			(xy 24.959712 -245.250481) (xy 24.915864 -245.219111) (xy 24.877051 -245.18169) (xy 24.844099 -245.139017)
			(xy 24.817713 -245.092) (xy 24.798453 -245.041643) (xy 24.78673 -244.989019) (xy 24.782795 -244.935248)
			(xy 17.97685 -244.935248) (xy 17.976358 -244.962205) (xy 17.968508 -245.015545) (xy 17.952976 -245.067174)
			(xy 17.930091 -245.115991) (xy 17.900343 -245.160955) (xy 17.864365 -245.201109) (xy 17.822923 -245.235597)
			(xy 17.776902 -245.263683) (xy 17.727282 -245.28477) (xy 17.675121 -245.298406) (xy 17.62153 -245.304303)
			(xy 17.567651 -245.302334) (xy 17.514633 -245.292541) (xy 17.463606 -245.275133) (xy 17.415658 -245.250481)
			(xy 17.37181 -245.219111) (xy 17.332997 -245.18169) (xy 17.300045 -245.139017) (xy 17.273659 -245.092)
			(xy 17.254399 -245.041643) (xy 17.242676 -244.989019) (xy 17.238741 -244.935248) (xy 15.598394 -244.935248)
			(xy 15.598394 -245.785386) (xy 21.338809 -245.785386) (xy 21.342744 -245.731615) (xy 21.354467 -245.678991)
			(xy 21.373727 -245.628634) (xy 21.400113 -245.581617) (xy 21.433065 -245.538944) (xy 21.471878 -245.501523)
			(xy 21.515726 -245.470153) (xy 21.563674 -245.445501) (xy 21.614701 -245.428093) (xy 21.667719 -245.4183)
			(xy 21.721598 -245.416331) (xy 21.775189 -245.422228) (xy 21.82735 -245.435864) (xy 21.87697 -245.456951)
			(xy 21.922991 -245.485037) (xy 21.964433 -245.519525) (xy 22.000411 -245.559679) (xy 22.030159 -245.604643)
			(xy 22.053044 -245.65346) (xy 22.068576 -245.705089) (xy 22.076426 -245.758429) (xy 22.076918 -245.785386)
			(xy 28.882863 -245.785386) (xy 28.886798 -245.731615) (xy 28.898521 -245.678991) (xy 28.917781 -245.628634)
			(xy 28.944167 -245.581617) (xy 28.977119 -245.538944) (xy 29.015932 -245.501523) (xy 29.05978 -245.470153)
			(xy 29.107728 -245.445501) (xy 29.158755 -245.428093) (xy 29.211773 -245.4183) (xy 29.265652 -245.416331)
			(xy 29.319243 -245.422228) (xy 29.371404 -245.435864) (xy 29.421024 -245.456951) (xy 29.467045 -245.485037)
			(xy 29.508487 -245.519525) (xy 29.544465 -245.559679) (xy 29.574213 -245.604643) (xy 29.597098 -245.65346)
			(xy 29.61263 -245.705089) (xy 29.62048 -245.758429) (xy 29.620972 -245.785386) (xy 36.426663 -245.785386)
			(xy 36.430598 -245.731615) (xy 36.442321 -245.678991) (xy 36.461581 -245.628634) (xy 36.487967 -245.581617)
			(xy 36.520919 -245.538944) (xy 36.559732 -245.501523) (xy 36.60358 -245.470153) (xy 36.651528 -245.445501)
			(xy 36.702555 -245.428093) (xy 36.755573 -245.4183) (xy 36.809452 -245.416331) (xy 36.863043 -245.422228)
			(xy 36.915204 -245.435864) (xy 36.964824 -245.456951) (xy 37.010845 -245.485037) (xy 37.052287 -245.519525)
			(xy 37.088265 -245.559679) (xy 37.118013 -245.604643) (xy 37.140898 -245.65346) (xy 37.15643 -245.705089)
			(xy 37.16428 -245.758429) (xy 37.164772 -245.785386) (xy 43.970717 -245.785386) (xy 43.974652 -245.731615)
			(xy 43.986375 -245.678991) (xy 44.005635 -245.628634) (xy 44.032021 -245.581617) (xy 44.064973 -245.538944)
			(xy 44.103786 -245.501523) (xy 44.147634 -245.470153) (xy 44.195582 -245.445501) (xy 44.246609 -245.428093)
			(xy 44.299627 -245.4183) (xy 44.353506 -245.416331) (xy 44.407097 -245.422228) (xy 44.459258 -245.435864)
			(xy 44.508878 -245.456951) (xy 44.554899 -245.485037) (xy 44.596341 -245.519525) (xy 44.632319 -245.559679)
			(xy 44.662067 -245.604643) (xy 44.684952 -245.65346) (xy 44.700484 -245.705089) (xy 44.708334 -245.758429)
			(xy 44.708826 -245.785386) (xy 44.708334 -245.812343) (xy 44.700484 -245.865683) (xy 44.684952 -245.917312)
			(xy 44.662067 -245.966129) (xy 44.632319 -246.011093) (xy 44.596341 -246.051247) (xy 44.554899 -246.085735)
			(xy 44.508878 -246.113821) (xy 44.459258 -246.134908) (xy 44.407097 -246.148544) (xy 44.353506 -246.154441)
			(xy 44.299627 -246.152472) (xy 44.246609 -246.142679) (xy 44.195582 -246.125271) (xy 44.147634 -246.100619)
			(xy 44.103786 -246.069249) (xy 44.064973 -246.031828) (xy 44.032021 -245.989155) (xy 44.005635 -245.942138)
			(xy 43.986375 -245.891781) (xy 43.974652 -245.839157) (xy 43.970717 -245.785386) (xy 37.164772 -245.785386)
			(xy 37.16428 -245.812343) (xy 37.15643 -245.865683) (xy 37.140898 -245.917312) (xy 37.118013 -245.966129)
			(xy 37.088265 -246.011093) (xy 37.052287 -246.051247) (xy 37.010845 -246.085735) (xy 36.964824 -246.113821)
			(xy 36.915204 -246.134908) (xy 36.863043 -246.148544) (xy 36.809452 -246.154441) (xy 36.755573 -246.152472)
			(xy 36.702555 -246.142679) (xy 36.651528 -246.125271) (xy 36.60358 -246.100619) (xy 36.559732 -246.069249)
			(xy 36.520919 -246.031828) (xy 36.487967 -245.989155) (xy 36.461581 -245.942138) (xy 36.442321 -245.891781)
			(xy 36.430598 -245.839157) (xy 36.426663 -245.785386) (xy 29.620972 -245.785386) (xy 29.62048 -245.812343)
			(xy 29.61263 -245.865683) (xy 29.597098 -245.917312) (xy 29.574213 -245.966129) (xy 29.544465 -246.011093)
			(xy 29.508487 -246.051247) (xy 29.467045 -246.085735) (xy 29.421024 -246.113821) (xy 29.371404 -246.134908)
			(xy 29.319243 -246.148544) (xy 29.265652 -246.154441) (xy 29.211773 -246.152472) (xy 29.158755 -246.142679)
			(xy 29.107728 -246.125271) (xy 29.05978 -246.100619) (xy 29.015932 -246.069249) (xy 28.977119 -246.031828)
			(xy 28.944167 -245.989155) (xy 28.917781 -245.942138) (xy 28.898521 -245.891781) (xy 28.886798 -245.839157)
			(xy 28.882863 -245.785386) (xy 22.076918 -245.785386) (xy 22.076426 -245.812343) (xy 22.068576 -245.865683)
			(xy 22.053044 -245.917312) (xy 22.030159 -245.966129) (xy 22.000411 -246.011093) (xy 21.964433 -246.051247)
			(xy 21.922991 -246.085735) (xy 21.87697 -246.113821) (xy 21.82735 -246.134908) (xy 21.775189 -246.148544)
			(xy 21.721598 -246.154441) (xy 21.667719 -246.152472) (xy 21.614701 -246.142679) (xy 21.563674 -246.125271)
			(xy 21.515726 -246.100619) (xy 21.471878 -246.069249) (xy 21.433065 -246.031828) (xy 21.400113 -245.989155)
			(xy 21.373727 -245.942138) (xy 21.354467 -245.891781) (xy 21.342744 -245.839157) (xy 21.338809 -245.785386)
			(xy 15.598394 -245.785386) (xy 15.598394 -246.63527) (xy 17.238741 -246.63527) (xy 17.242676 -246.581499)
			(xy 17.254399 -246.528875) (xy 17.273659 -246.478518) (xy 17.300045 -246.431501) (xy 17.332997 -246.388828)
			(xy 17.37181 -246.351407) (xy 17.415658 -246.320037) (xy 17.463606 -246.295385) (xy 17.514633 -246.277977)
			(xy 17.567651 -246.268184) (xy 17.62153 -246.266215) (xy 17.675121 -246.272112) (xy 17.727282 -246.285748)
			(xy 17.776902 -246.306835) (xy 17.822923 -246.334921) (xy 17.864365 -246.369409) (xy 17.900343 -246.409563)
			(xy 17.930091 -246.454527) (xy 17.952976 -246.503344) (xy 17.968508 -246.554973) (xy 17.976358 -246.608313)
			(xy 17.97685 -246.63527) (xy 24.782795 -246.63527) (xy 24.78673 -246.581499) (xy 24.798453 -246.528875)
			(xy 24.817713 -246.478518) (xy 24.844099 -246.431501) (xy 24.877051 -246.388828) (xy 24.915864 -246.351407)
			(xy 24.959712 -246.320037) (xy 25.00766 -246.295385) (xy 25.058687 -246.277977) (xy 25.111705 -246.268184)
			(xy 25.165584 -246.266215) (xy 25.219175 -246.272112) (xy 25.271336 -246.285748) (xy 25.320956 -246.306835)
			(xy 25.366977 -246.334921) (xy 25.408419 -246.369409) (xy 25.444397 -246.409563) (xy 25.474145 -246.454527)
			(xy 25.49703 -246.503344) (xy 25.512562 -246.554973) (xy 25.520412 -246.608313) (xy 25.520904 -246.63527)
			(xy 32.326595 -246.63527) (xy 32.33053 -246.581499) (xy 32.342253 -246.528875) (xy 32.361513 -246.478518)
			(xy 32.387899 -246.431501) (xy 32.420851 -246.388828) (xy 32.459664 -246.351407) (xy 32.503512 -246.320037)
			(xy 32.55146 -246.295385) (xy 32.602487 -246.277977) (xy 32.655505 -246.268184) (xy 32.709384 -246.266215)
			(xy 32.762975 -246.272112) (xy 32.815136 -246.285748) (xy 32.864756 -246.306835) (xy 32.910777 -246.334921)
			(xy 32.952219 -246.369409) (xy 32.988197 -246.409563) (xy 33.017945 -246.454527) (xy 33.04083 -246.503344)
			(xy 33.056362 -246.554973) (xy 33.064212 -246.608313) (xy 33.064704 -246.63527) (xy 39.870649 -246.63527)
			(xy 39.874584 -246.581499) (xy 39.886307 -246.528875) (xy 39.905567 -246.478518) (xy 39.931953 -246.431501)
			(xy 39.964905 -246.388828) (xy 40.003718 -246.351407) (xy 40.047566 -246.320037) (xy 40.095514 -246.295385)
			(xy 40.146541 -246.277977) (xy 40.199559 -246.268184) (xy 40.253438 -246.266215) (xy 40.307029 -246.272112)
			(xy 40.35919 -246.285748) (xy 40.40881 -246.306835) (xy 40.454831 -246.334921) (xy 40.496273 -246.369409)
			(xy 40.532251 -246.409563) (xy 40.561999 -246.454527) (xy 40.584884 -246.503344) (xy 40.600416 -246.554973)
			(xy 40.608266 -246.608313) (xy 40.608758 -246.63527) (xy 40.608266 -246.662227) (xy 40.600416 -246.715567)
			(xy 40.584884 -246.767196) (xy 40.561999 -246.816013) (xy 40.532251 -246.860977) (xy 40.496273 -246.901131)
			(xy 40.454831 -246.935619) (xy 40.40881 -246.963705) (xy 40.35919 -246.984792) (xy 40.307029 -246.998428)
			(xy 40.253438 -247.004325) (xy 40.199559 -247.002356) (xy 40.146541 -246.992563) (xy 40.095514 -246.975155)
			(xy 40.047566 -246.950503) (xy 40.003718 -246.919133) (xy 39.964905 -246.881712) (xy 39.931953 -246.839039)
			(xy 39.905567 -246.792022) (xy 39.886307 -246.741665) (xy 39.874584 -246.689041) (xy 39.870649 -246.63527)
			(xy 33.064704 -246.63527) (xy 33.064212 -246.662227) (xy 33.056362 -246.715567) (xy 33.04083 -246.767196)
			(xy 33.017945 -246.816013) (xy 32.988197 -246.860977) (xy 32.952219 -246.901131) (xy 32.910777 -246.935619)
			(xy 32.864756 -246.963705) (xy 32.815136 -246.984792) (xy 32.762975 -246.998428) (xy 32.709384 -247.004325)
			(xy 32.655505 -247.002356) (xy 32.602487 -246.992563) (xy 32.55146 -246.975155) (xy 32.503512 -246.950503)
			(xy 32.459664 -246.919133) (xy 32.420851 -246.881712) (xy 32.387899 -246.839039) (xy 32.361513 -246.792022)
			(xy 32.342253 -246.741665) (xy 32.33053 -246.689041) (xy 32.326595 -246.63527) (xy 25.520904 -246.63527)
			(xy 25.520412 -246.662227) (xy 25.512562 -246.715567) (xy 25.49703 -246.767196) (xy 25.474145 -246.816013)
			(xy 25.444397 -246.860977) (xy 25.408419 -246.901131) (xy 25.366977 -246.935619) (xy 25.320956 -246.963705)
			(xy 25.271336 -246.984792) (xy 25.219175 -246.998428) (xy 25.165584 -247.004325) (xy 25.111705 -247.002356)
			(xy 25.058687 -246.992563) (xy 25.00766 -246.975155) (xy 24.959712 -246.950503) (xy 24.915864 -246.919133)
			(xy 24.877051 -246.881712) (xy 24.844099 -246.839039) (xy 24.817713 -246.792022) (xy 24.798453 -246.741665)
			(xy 24.78673 -246.689041) (xy 24.782795 -246.63527) (xy 17.97685 -246.63527) (xy 17.976358 -246.662227)
			(xy 17.968508 -246.715567) (xy 17.952976 -246.767196) (xy 17.930091 -246.816013) (xy 17.900343 -246.860977)
			(xy 17.864365 -246.901131) (xy 17.822923 -246.935619) (xy 17.776902 -246.963705) (xy 17.727282 -246.984792)
			(xy 17.675121 -246.998428) (xy 17.62153 -247.004325) (xy 17.567651 -247.002356) (xy 17.514633 -246.992563)
			(xy 17.463606 -246.975155) (xy 17.415658 -246.950503) (xy 17.37181 -246.919133) (xy 17.332997 -246.881712)
			(xy 17.300045 -246.839039) (xy 17.273659 -246.792022) (xy 17.254399 -246.741665) (xy 17.242676 -246.689041)
			(xy 17.238741 -246.63527) (xy 15.598394 -246.63527) (xy 15.598394 -247.485408) (xy 21.338809 -247.485408)
			(xy 21.342744 -247.431637) (xy 21.354467 -247.379013) (xy 21.373727 -247.328656) (xy 21.400113 -247.281639)
			(xy 21.433065 -247.238966) (xy 21.471878 -247.201545) (xy 21.515726 -247.170175) (xy 21.563674 -247.145523)
			(xy 21.614701 -247.128115) (xy 21.667719 -247.118322) (xy 21.721598 -247.116353) (xy 21.775189 -247.12225)
			(xy 21.82735 -247.135886) (xy 21.87697 -247.156973) (xy 21.922991 -247.185059) (xy 21.964433 -247.219547)
			(xy 22.000411 -247.259701) (xy 22.030159 -247.304665) (xy 22.053044 -247.353482) (xy 22.068576 -247.405111)
			(xy 22.076426 -247.458451) (xy 22.076918 -247.485408) (xy 28.882863 -247.485408) (xy 28.886798 -247.431637)
			(xy 28.898521 -247.379013) (xy 28.917781 -247.328656) (xy 28.944167 -247.281639) (xy 28.977119 -247.238966)
			(xy 29.015932 -247.201545) (xy 29.05978 -247.170175) (xy 29.107728 -247.145523) (xy 29.158755 -247.128115)
			(xy 29.211773 -247.118322) (xy 29.265652 -247.116353) (xy 29.319243 -247.12225) (xy 29.371404 -247.135886)
			(xy 29.421024 -247.156973) (xy 29.467045 -247.185059) (xy 29.508487 -247.219547) (xy 29.544465 -247.259701)
			(xy 29.574213 -247.304665) (xy 29.597098 -247.353482) (xy 29.61263 -247.405111) (xy 29.62048 -247.458451)
			(xy 29.620972 -247.485408) (xy 36.426663 -247.485408) (xy 36.430598 -247.431637) (xy 36.442321 -247.379013)
			(xy 36.461581 -247.328656) (xy 36.487967 -247.281639) (xy 36.520919 -247.238966) (xy 36.559732 -247.201545)
			(xy 36.60358 -247.170175) (xy 36.651528 -247.145523) (xy 36.702555 -247.128115) (xy 36.755573 -247.118322)
			(xy 36.809452 -247.116353) (xy 36.863043 -247.12225) (xy 36.915204 -247.135886) (xy 36.964824 -247.156973)
			(xy 37.010845 -247.185059) (xy 37.052287 -247.219547) (xy 37.088265 -247.259701) (xy 37.118013 -247.304665)
			(xy 37.140898 -247.353482) (xy 37.15643 -247.405111) (xy 37.16428 -247.458451) (xy 37.164772 -247.485408)
			(xy 43.970717 -247.485408) (xy 43.974652 -247.431637) (xy 43.986375 -247.379013) (xy 44.005635 -247.328656)
			(xy 44.032021 -247.281639) (xy 44.064973 -247.238966) (xy 44.103786 -247.201545) (xy 44.147634 -247.170175)
			(xy 44.195582 -247.145523) (xy 44.246609 -247.128115) (xy 44.299627 -247.118322) (xy 44.353506 -247.116353)
			(xy 44.407097 -247.12225) (xy 44.459258 -247.135886) (xy 44.508878 -247.156973) (xy 44.554899 -247.185059)
			(xy 44.596341 -247.219547) (xy 44.632319 -247.259701) (xy 44.662067 -247.304665) (xy 44.684952 -247.353482)
			(xy 44.700484 -247.405111) (xy 44.708334 -247.458451) (xy 44.708826 -247.485408) (xy 44.708334 -247.512365)
			(xy 44.700484 -247.565705) (xy 44.684952 -247.617334) (xy 44.662067 -247.666151) (xy 44.632319 -247.711115)
			(xy 44.596341 -247.751269) (xy 44.554899 -247.785757) (xy 44.508878 -247.813843) (xy 44.459258 -247.83493)
			(xy 44.407097 -247.848566) (xy 44.353506 -247.854463) (xy 44.299627 -247.852494) (xy 44.246609 -247.842701)
			(xy 44.195582 -247.825293) (xy 44.147634 -247.800641) (xy 44.103786 -247.769271) (xy 44.064973 -247.73185)
			(xy 44.032021 -247.689177) (xy 44.005635 -247.64216) (xy 43.986375 -247.591803) (xy 43.974652 -247.539179)
			(xy 43.970717 -247.485408) (xy 37.164772 -247.485408) (xy 37.16428 -247.512365) (xy 37.15643 -247.565705)
			(xy 37.140898 -247.617334) (xy 37.118013 -247.666151) (xy 37.088265 -247.711115) (xy 37.052287 -247.751269)
			(xy 37.010845 -247.785757) (xy 36.964824 -247.813843) (xy 36.915204 -247.83493) (xy 36.863043 -247.848566)
			(xy 36.809452 -247.854463) (xy 36.755573 -247.852494) (xy 36.702555 -247.842701) (xy 36.651528 -247.825293)
			(xy 36.60358 -247.800641) (xy 36.559732 -247.769271) (xy 36.520919 -247.73185) (xy 36.487967 -247.689177)
			(xy 36.461581 -247.64216) (xy 36.442321 -247.591803) (xy 36.430598 -247.539179) (xy 36.426663 -247.485408)
			(xy 29.620972 -247.485408) (xy 29.62048 -247.512365) (xy 29.61263 -247.565705) (xy 29.597098 -247.617334)
			(xy 29.574213 -247.666151) (xy 29.544465 -247.711115) (xy 29.508487 -247.751269) (xy 29.467045 -247.785757)
			(xy 29.421024 -247.813843) (xy 29.371404 -247.83493) (xy 29.319243 -247.848566) (xy 29.265652 -247.854463)
			(xy 29.211773 -247.852494) (xy 29.158755 -247.842701) (xy 29.107728 -247.825293) (xy 29.05978 -247.800641)
			(xy 29.015932 -247.769271) (xy 28.977119 -247.73185) (xy 28.944167 -247.689177) (xy 28.917781 -247.64216)
			(xy 28.898521 -247.591803) (xy 28.886798 -247.539179) (xy 28.882863 -247.485408) (xy 22.076918 -247.485408)
			(xy 22.076426 -247.512365) (xy 22.068576 -247.565705) (xy 22.053044 -247.617334) (xy 22.030159 -247.666151)
			(xy 22.000411 -247.711115) (xy 21.964433 -247.751269) (xy 21.922991 -247.785757) (xy 21.87697 -247.813843)
			(xy 21.82735 -247.83493) (xy 21.775189 -247.848566) (xy 21.721598 -247.854463) (xy 21.667719 -247.852494)
			(xy 21.614701 -247.842701) (xy 21.563674 -247.825293) (xy 21.515726 -247.800641) (xy 21.471878 -247.769271)
			(xy 21.433065 -247.73185) (xy 21.400113 -247.689177) (xy 21.373727 -247.64216) (xy 21.354467 -247.591803)
			(xy 21.342744 -247.539179) (xy 21.338809 -247.485408) (xy 15.598394 -247.485408) (xy 15.598394 -248.335292)
			(xy 17.238741 -248.335292) (xy 17.242676 -248.281521) (xy 17.254399 -248.228897) (xy 17.273659 -248.17854)
			(xy 17.300045 -248.131523) (xy 17.332997 -248.08885) (xy 17.37181 -248.051429) (xy 17.415658 -248.020059)
			(xy 17.463606 -247.995407) (xy 17.514633 -247.977999) (xy 17.567651 -247.968206) (xy 17.62153 -247.966237)
			(xy 17.675121 -247.972134) (xy 17.727282 -247.98577) (xy 17.776902 -248.006857) (xy 17.822923 -248.034943)
			(xy 17.864365 -248.069431) (xy 17.900343 -248.109585) (xy 17.930091 -248.154549) (xy 17.952976 -248.203366)
			(xy 17.968508 -248.254995) (xy 17.976358 -248.308335) (xy 17.97685 -248.335292) (xy 24.782795 -248.335292)
			(xy 24.78673 -248.281521) (xy 24.798453 -248.228897) (xy 24.817713 -248.17854) (xy 24.844099 -248.131523)
			(xy 24.877051 -248.08885) (xy 24.915864 -248.051429) (xy 24.959712 -248.020059) (xy 25.00766 -247.995407)
			(xy 25.058687 -247.977999) (xy 25.111705 -247.968206) (xy 25.165584 -247.966237) (xy 25.219175 -247.972134)
			(xy 25.271336 -247.98577) (xy 25.320956 -248.006857) (xy 25.366977 -248.034943) (xy 25.408419 -248.069431)
			(xy 25.444397 -248.109585) (xy 25.474145 -248.154549) (xy 25.49703 -248.203366) (xy 25.512562 -248.254995)
			(xy 25.520412 -248.308335) (xy 25.520904 -248.335292) (xy 32.326595 -248.335292) (xy 32.33053 -248.281521)
			(xy 32.342253 -248.228897) (xy 32.361513 -248.17854) (xy 32.387899 -248.131523) (xy 32.420851 -248.08885)
			(xy 32.459664 -248.051429) (xy 32.503512 -248.020059) (xy 32.55146 -247.995407) (xy 32.602487 -247.977999)
			(xy 32.655505 -247.968206) (xy 32.709384 -247.966237) (xy 32.762975 -247.972134) (xy 32.815136 -247.98577)
			(xy 32.864756 -248.006857) (xy 32.910777 -248.034943) (xy 32.952219 -248.069431) (xy 32.988197 -248.109585)
			(xy 33.017945 -248.154549) (xy 33.04083 -248.203366) (xy 33.056362 -248.254995) (xy 33.064212 -248.308335)
			(xy 33.064704 -248.335292) (xy 39.870649 -248.335292) (xy 39.874584 -248.281521) (xy 39.886307 -248.228897)
			(xy 39.905567 -248.17854) (xy 39.931953 -248.131523) (xy 39.964905 -248.08885) (xy 40.003718 -248.051429)
			(xy 40.047566 -248.020059) (xy 40.095514 -247.995407) (xy 40.146541 -247.977999) (xy 40.199559 -247.968206)
			(xy 40.253438 -247.966237) (xy 40.307029 -247.972134) (xy 40.35919 -247.98577) (xy 40.40881 -248.006857)
			(xy 40.454831 -248.034943) (xy 40.496273 -248.069431) (xy 40.532251 -248.109585) (xy 40.561999 -248.154549)
			(xy 40.584884 -248.203366) (xy 40.600416 -248.254995) (xy 40.608266 -248.308335) (xy 40.608758 -248.335292)
			(xy 40.608266 -248.362249) (xy 40.600416 -248.415589) (xy 40.584884 -248.467218) (xy 40.561999 -248.516035)
			(xy 40.532251 -248.560999) (xy 40.496273 -248.601153) (xy 40.454831 -248.635641) (xy 40.40881 -248.663727)
			(xy 40.35919 -248.684814) (xy 40.307029 -248.69845) (xy 40.253438 -248.704347) (xy 40.199559 -248.702378)
			(xy 40.146541 -248.692585) (xy 40.095514 -248.675177) (xy 40.047566 -248.650525) (xy 40.003718 -248.619155)
			(xy 39.964905 -248.581734) (xy 39.931953 -248.539061) (xy 39.905567 -248.492044) (xy 39.886307 -248.441687)
			(xy 39.874584 -248.389063) (xy 39.870649 -248.335292) (xy 33.064704 -248.335292) (xy 33.064212 -248.362249)
			(xy 33.056362 -248.415589) (xy 33.04083 -248.467218) (xy 33.017945 -248.516035) (xy 32.988197 -248.560999)
			(xy 32.952219 -248.601153) (xy 32.910777 -248.635641) (xy 32.864756 -248.663727) (xy 32.815136 -248.684814)
			(xy 32.762975 -248.69845) (xy 32.709384 -248.704347) (xy 32.655505 -248.702378) (xy 32.602487 -248.692585)
			(xy 32.55146 -248.675177) (xy 32.503512 -248.650525) (xy 32.459664 -248.619155) (xy 32.420851 -248.581734)
			(xy 32.387899 -248.539061) (xy 32.361513 -248.492044) (xy 32.342253 -248.441687) (xy 32.33053 -248.389063)
			(xy 32.326595 -248.335292) (xy 25.520904 -248.335292) (xy 25.520412 -248.362249) (xy 25.512562 -248.415589)
			(xy 25.49703 -248.467218) (xy 25.474145 -248.516035) (xy 25.444397 -248.560999) (xy 25.408419 -248.601153)
			(xy 25.366977 -248.635641) (xy 25.320956 -248.663727) (xy 25.271336 -248.684814) (xy 25.219175 -248.69845)
			(xy 25.165584 -248.704347) (xy 25.111705 -248.702378) (xy 25.058687 -248.692585) (xy 25.00766 -248.675177)
			(xy 24.959712 -248.650525) (xy 24.915864 -248.619155) (xy 24.877051 -248.581734) (xy 24.844099 -248.539061)
			(xy 24.817713 -248.492044) (xy 24.798453 -248.441687) (xy 24.78673 -248.389063) (xy 24.782795 -248.335292)
			(xy 17.97685 -248.335292) (xy 17.976358 -248.362249) (xy 17.968508 -248.415589) (xy 17.952976 -248.467218)
			(xy 17.930091 -248.516035) (xy 17.900343 -248.560999) (xy 17.864365 -248.601153) (xy 17.822923 -248.635641)
			(xy 17.776902 -248.663727) (xy 17.727282 -248.684814) (xy 17.675121 -248.69845) (xy 17.62153 -248.704347)
			(xy 17.567651 -248.702378) (xy 17.514633 -248.692585) (xy 17.463606 -248.675177) (xy 17.415658 -248.650525)
			(xy 17.37181 -248.619155) (xy 17.332997 -248.581734) (xy 17.300045 -248.539061) (xy 17.273659 -248.492044)
			(xy 17.254399 -248.441687) (xy 17.242676 -248.389063) (xy 17.238741 -248.335292) (xy 15.598394 -248.335292)
			(xy 15.598394 -249.18543) (xy 21.338809 -249.18543) (xy 21.342744 -249.131659) (xy 21.354467 -249.079035)
			(xy 21.373727 -249.028678) (xy 21.400113 -248.981661) (xy 21.433065 -248.938988) (xy 21.471878 -248.901567)
			(xy 21.515726 -248.870197) (xy 21.563674 -248.845545) (xy 21.614701 -248.828137) (xy 21.667719 -248.818344)
			(xy 21.721598 -248.816375) (xy 21.775189 -248.822272) (xy 21.82735 -248.835908) (xy 21.87697 -248.856995)
			(xy 21.922991 -248.885081) (xy 21.964433 -248.919569) (xy 22.000411 -248.959723) (xy 22.030159 -249.004687)
			(xy 22.053044 -249.053504) (xy 22.068576 -249.105133) (xy 22.076426 -249.158473) (xy 22.076918 -249.18543)
			(xy 28.882863 -249.18543) (xy 28.886798 -249.131659) (xy 28.898521 -249.079035) (xy 28.917781 -249.028678)
			(xy 28.944167 -248.981661) (xy 28.977119 -248.938988) (xy 29.015932 -248.901567) (xy 29.05978 -248.870197)
			(xy 29.107728 -248.845545) (xy 29.158755 -248.828137) (xy 29.211773 -248.818344) (xy 29.265652 -248.816375)
			(xy 29.319243 -248.822272) (xy 29.371404 -248.835908) (xy 29.421024 -248.856995) (xy 29.467045 -248.885081)
			(xy 29.508487 -248.919569) (xy 29.544465 -248.959723) (xy 29.574213 -249.004687) (xy 29.597098 -249.053504)
			(xy 29.61263 -249.105133) (xy 29.62048 -249.158473) (xy 29.620972 -249.18543) (xy 36.426663 -249.18543)
			(xy 36.430598 -249.131659) (xy 36.442321 -249.079035) (xy 36.461581 -249.028678) (xy 36.487967 -248.981661)
			(xy 36.520919 -248.938988) (xy 36.559732 -248.901567) (xy 36.60358 -248.870197) (xy 36.651528 -248.845545)
			(xy 36.702555 -248.828137) (xy 36.755573 -248.818344) (xy 36.809452 -248.816375) (xy 36.863043 -248.822272)
			(xy 36.915204 -248.835908) (xy 36.964824 -248.856995) (xy 37.010845 -248.885081) (xy 37.052287 -248.919569)
			(xy 37.088265 -248.959723) (xy 37.118013 -249.004687) (xy 37.140898 -249.053504) (xy 37.15643 -249.105133)
			(xy 37.16428 -249.158473) (xy 37.164772 -249.18543) (xy 43.970717 -249.18543) (xy 43.974652 -249.131659)
			(xy 43.986375 -249.079035) (xy 44.005635 -249.028678) (xy 44.032021 -248.981661) (xy 44.064973 -248.938988)
			(xy 44.103786 -248.901567) (xy 44.147634 -248.870197) (xy 44.195582 -248.845545) (xy 44.246609 -248.828137)
			(xy 44.299627 -248.818344) (xy 44.353506 -248.816375) (xy 44.407097 -248.822272) (xy 44.459258 -248.835908)
			(xy 44.508878 -248.856995) (xy 44.554899 -248.885081) (xy 44.596341 -248.919569) (xy 44.632319 -248.959723)
			(xy 44.662067 -249.004687) (xy 44.684952 -249.053504) (xy 44.700484 -249.105133) (xy 44.708334 -249.158473)
			(xy 44.708826 -249.18543) (xy 44.708334 -249.212387) (xy 44.700484 -249.265727) (xy 44.684952 -249.317356)
			(xy 44.662067 -249.366173) (xy 44.632319 -249.411137) (xy 44.596341 -249.451291) (xy 44.554899 -249.485779)
			(xy 44.508878 -249.513865) (xy 44.459258 -249.534952) (xy 44.407097 -249.548588) (xy 44.353506 -249.554485)
			(xy 44.299627 -249.552516) (xy 44.246609 -249.542723) (xy 44.195582 -249.525315) (xy 44.147634 -249.500663)
			(xy 44.103786 -249.469293) (xy 44.064973 -249.431872) (xy 44.032021 -249.389199) (xy 44.005635 -249.342182)
			(xy 43.986375 -249.291825) (xy 43.974652 -249.239201) (xy 43.970717 -249.18543) (xy 37.164772 -249.18543)
			(xy 37.16428 -249.212387) (xy 37.15643 -249.265727) (xy 37.140898 -249.317356) (xy 37.118013 -249.366173)
			(xy 37.088265 -249.411137) (xy 37.052287 -249.451291) (xy 37.010845 -249.485779) (xy 36.964824 -249.513865)
			(xy 36.915204 -249.534952) (xy 36.863043 -249.548588) (xy 36.809452 -249.554485) (xy 36.755573 -249.552516)
			(xy 36.702555 -249.542723) (xy 36.651528 -249.525315) (xy 36.60358 -249.500663) (xy 36.559732 -249.469293)
			(xy 36.520919 -249.431872) (xy 36.487967 -249.389199) (xy 36.461581 -249.342182) (xy 36.442321 -249.291825)
			(xy 36.430598 -249.239201) (xy 36.426663 -249.18543) (xy 29.620972 -249.18543) (xy 29.62048 -249.212387)
			(xy 29.61263 -249.265727) (xy 29.597098 -249.317356) (xy 29.574213 -249.366173) (xy 29.544465 -249.411137)
			(xy 29.508487 -249.451291) (xy 29.467045 -249.485779) (xy 29.421024 -249.513865) (xy 29.371404 -249.534952)
			(xy 29.319243 -249.548588) (xy 29.265652 -249.554485) (xy 29.211773 -249.552516) (xy 29.158755 -249.542723)
			(xy 29.107728 -249.525315) (xy 29.05978 -249.500663) (xy 29.015932 -249.469293) (xy 28.977119 -249.431872)
			(xy 28.944167 -249.389199) (xy 28.917781 -249.342182) (xy 28.898521 -249.291825) (xy 28.886798 -249.239201)
			(xy 28.882863 -249.18543) (xy 22.076918 -249.18543) (xy 22.076426 -249.212387) (xy 22.068576 -249.265727)
			(xy 22.053044 -249.317356) (xy 22.030159 -249.366173) (xy 22.000411 -249.411137) (xy 21.964433 -249.451291)
			(xy 21.922991 -249.485779) (xy 21.87697 -249.513865) (xy 21.82735 -249.534952) (xy 21.775189 -249.548588)
			(xy 21.721598 -249.554485) (xy 21.667719 -249.552516) (xy 21.614701 -249.542723) (xy 21.563674 -249.525315)
			(xy 21.515726 -249.500663) (xy 21.471878 -249.469293) (xy 21.433065 -249.431872) (xy 21.400113 -249.389199)
			(xy 21.373727 -249.342182) (xy 21.354467 -249.291825) (xy 21.342744 -249.239201) (xy 21.338809 -249.18543)
			(xy 15.598394 -249.18543) (xy 15.598394 -250.035314) (xy 17.238741 -250.035314) (xy 17.242676 -249.981543)
			(xy 17.254399 -249.928919) (xy 17.273659 -249.878562) (xy 17.300045 -249.831545) (xy 17.332997 -249.788872)
			(xy 17.37181 -249.751451) (xy 17.415658 -249.720081) (xy 17.463606 -249.695429) (xy 17.514633 -249.678021)
			(xy 17.567651 -249.668228) (xy 17.62153 -249.666259) (xy 17.675121 -249.672156) (xy 17.727282 -249.685792)
			(xy 17.776902 -249.706879) (xy 17.822923 -249.734965) (xy 17.864365 -249.769453) (xy 17.900343 -249.809607)
			(xy 17.930091 -249.854571) (xy 17.952976 -249.903388) (xy 17.968508 -249.955017) (xy 17.976358 -250.008357)
			(xy 17.97685 -250.035314) (xy 24.782795 -250.035314) (xy 24.78673 -249.981543) (xy 24.798453 -249.928919)
			(xy 24.817713 -249.878562) (xy 24.844099 -249.831545) (xy 24.877051 -249.788872) (xy 24.915864 -249.751451)
			(xy 24.959712 -249.720081) (xy 25.00766 -249.695429) (xy 25.058687 -249.678021) (xy 25.111705 -249.668228)
			(xy 25.165584 -249.666259) (xy 25.219175 -249.672156) (xy 25.271336 -249.685792) (xy 25.320956 -249.706879)
			(xy 25.366977 -249.734965) (xy 25.408419 -249.769453) (xy 25.444397 -249.809607) (xy 25.474145 -249.854571)
			(xy 25.49703 -249.903388) (xy 25.512562 -249.955017) (xy 25.520412 -250.008357) (xy 25.520904 -250.035314)
			(xy 32.326595 -250.035314) (xy 32.33053 -249.981543) (xy 32.342253 -249.928919) (xy 32.361513 -249.878562)
			(xy 32.387899 -249.831545) (xy 32.420851 -249.788872) (xy 32.459664 -249.751451) (xy 32.503512 -249.720081)
			(xy 32.55146 -249.695429) (xy 32.602487 -249.678021) (xy 32.655505 -249.668228) (xy 32.709384 -249.666259)
			(xy 32.762975 -249.672156) (xy 32.815136 -249.685792) (xy 32.864756 -249.706879) (xy 32.910777 -249.734965)
			(xy 32.952219 -249.769453) (xy 32.988197 -249.809607) (xy 33.017945 -249.854571) (xy 33.04083 -249.903388)
			(xy 33.056362 -249.955017) (xy 33.064212 -250.008357) (xy 33.064704 -250.035314) (xy 39.870649 -250.035314)
			(xy 39.874584 -249.981543) (xy 39.886307 -249.928919) (xy 39.905567 -249.878562) (xy 39.931953 -249.831545)
			(xy 39.964905 -249.788872) (xy 40.003718 -249.751451) (xy 40.047566 -249.720081) (xy 40.095514 -249.695429)
			(xy 40.146541 -249.678021) (xy 40.199559 -249.668228) (xy 40.253438 -249.666259) (xy 40.307029 -249.672156)
			(xy 40.35919 -249.685792) (xy 40.40881 -249.706879) (xy 40.454831 -249.734965) (xy 40.496273 -249.769453)
			(xy 40.532251 -249.809607) (xy 40.561999 -249.854571) (xy 40.584884 -249.903388) (xy 40.600416 -249.955017)
			(xy 40.608266 -250.008357) (xy 40.608758 -250.035314) (xy 40.608266 -250.062271) (xy 40.600416 -250.115611)
			(xy 40.584884 -250.16724) (xy 40.561999 -250.216057) (xy 40.532251 -250.261021) (xy 40.496273 -250.301175)
			(xy 40.454831 -250.335663) (xy 40.40881 -250.363749) (xy 40.35919 -250.384836) (xy 40.307029 -250.398472)
			(xy 40.253438 -250.404369) (xy 40.199559 -250.4024) (xy 40.146541 -250.392607) (xy 40.095514 -250.375199)
			(xy 40.047566 -250.350547) (xy 40.003718 -250.319177) (xy 39.964905 -250.281756) (xy 39.931953 -250.239083)
			(xy 39.905567 -250.192066) (xy 39.886307 -250.141709) (xy 39.874584 -250.089085) (xy 39.870649 -250.035314)
			(xy 33.064704 -250.035314) (xy 33.064212 -250.062271) (xy 33.056362 -250.115611) (xy 33.04083 -250.16724)
			(xy 33.017945 -250.216057) (xy 32.988197 -250.261021) (xy 32.952219 -250.301175) (xy 32.910777 -250.335663)
			(xy 32.864756 -250.363749) (xy 32.815136 -250.384836) (xy 32.762975 -250.398472) (xy 32.709384 -250.404369)
			(xy 32.655505 -250.4024) (xy 32.602487 -250.392607) (xy 32.55146 -250.375199) (xy 32.503512 -250.350547)
			(xy 32.459664 -250.319177) (xy 32.420851 -250.281756) (xy 32.387899 -250.239083) (xy 32.361513 -250.192066)
			(xy 32.342253 -250.141709) (xy 32.33053 -250.089085) (xy 32.326595 -250.035314) (xy 25.520904 -250.035314)
			(xy 25.520412 -250.062271) (xy 25.512562 -250.115611) (xy 25.49703 -250.16724) (xy 25.474145 -250.216057)
			(xy 25.444397 -250.261021) (xy 25.408419 -250.301175) (xy 25.366977 -250.335663) (xy 25.320956 -250.363749)
			(xy 25.271336 -250.384836) (xy 25.219175 -250.398472) (xy 25.165584 -250.404369) (xy 25.111705 -250.4024)
			(xy 25.058687 -250.392607) (xy 25.00766 -250.375199) (xy 24.959712 -250.350547) (xy 24.915864 -250.319177)
			(xy 24.877051 -250.281756) (xy 24.844099 -250.239083) (xy 24.817713 -250.192066) (xy 24.798453 -250.141709)
			(xy 24.78673 -250.089085) (xy 24.782795 -250.035314) (xy 17.97685 -250.035314) (xy 17.976358 -250.062271)
			(xy 17.968508 -250.115611) (xy 17.952976 -250.16724) (xy 17.930091 -250.216057) (xy 17.900343 -250.261021)
			(xy 17.864365 -250.301175) (xy 17.822923 -250.335663) (xy 17.776902 -250.363749) (xy 17.727282 -250.384836)
			(xy 17.675121 -250.398472) (xy 17.62153 -250.404369) (xy 17.567651 -250.4024) (xy 17.514633 -250.392607)
			(xy 17.463606 -250.375199) (xy 17.415658 -250.350547) (xy 17.37181 -250.319177) (xy 17.332997 -250.281756)
			(xy 17.300045 -250.239083) (xy 17.273659 -250.192066) (xy 17.254399 -250.141709) (xy 17.242676 -250.089085)
			(xy 17.238741 -250.035314) (xy 15.598394 -250.035314) (xy 15.598394 -250.885198) (xy 21.338809 -250.885198)
			(xy 21.342744 -250.831427) (xy 21.354467 -250.778803) (xy 21.373727 -250.728446) (xy 21.400113 -250.681429)
			(xy 21.433065 -250.638756) (xy 21.471878 -250.601335) (xy 21.515726 -250.569965) (xy 21.563674 -250.545313)
			(xy 21.614701 -250.527905) (xy 21.667719 -250.518112) (xy 21.721598 -250.516143) (xy 21.775189 -250.52204)
			(xy 21.82735 -250.535676) (xy 21.87697 -250.556763) (xy 21.922991 -250.584849) (xy 21.964433 -250.619337)
			(xy 22.000411 -250.659491) (xy 22.030159 -250.704455) (xy 22.053044 -250.753272) (xy 22.068576 -250.804901)
			(xy 22.076426 -250.858241) (xy 22.076918 -250.885198) (xy 28.882863 -250.885198) (xy 28.886798 -250.831427)
			(xy 28.898521 -250.778803) (xy 28.917781 -250.728446) (xy 28.944167 -250.681429) (xy 28.977119 -250.638756)
			(xy 29.015932 -250.601335) (xy 29.05978 -250.569965) (xy 29.107728 -250.545313) (xy 29.158755 -250.527905)
			(xy 29.211773 -250.518112) (xy 29.265652 -250.516143) (xy 29.319243 -250.52204) (xy 29.371404 -250.535676)
			(xy 29.421024 -250.556763) (xy 29.467045 -250.584849) (xy 29.508487 -250.619337) (xy 29.544465 -250.659491)
			(xy 29.574213 -250.704455) (xy 29.597098 -250.753272) (xy 29.61263 -250.804901) (xy 29.62048 -250.858241)
			(xy 29.620972 -250.885198) (xy 36.426663 -250.885198) (xy 36.430598 -250.831427) (xy 36.442321 -250.778803)
			(xy 36.461581 -250.728446) (xy 36.487967 -250.681429) (xy 36.520919 -250.638756) (xy 36.559732 -250.601335)
			(xy 36.60358 -250.569965) (xy 36.651528 -250.545313) (xy 36.702555 -250.527905) (xy 36.755573 -250.518112)
			(xy 36.809452 -250.516143) (xy 36.863043 -250.52204) (xy 36.915204 -250.535676) (xy 36.964824 -250.556763)
			(xy 37.010845 -250.584849) (xy 37.052287 -250.619337) (xy 37.088265 -250.659491) (xy 37.118013 -250.704455)
			(xy 37.140898 -250.753272) (xy 37.15643 -250.804901) (xy 37.16428 -250.858241) (xy 37.164772 -250.885198)
			(xy 43.970717 -250.885198) (xy 43.974652 -250.831427) (xy 43.986375 -250.778803) (xy 44.005635 -250.728446)
			(xy 44.032021 -250.681429) (xy 44.064973 -250.638756) (xy 44.103786 -250.601335) (xy 44.147634 -250.569965)
			(xy 44.195582 -250.545313) (xy 44.246609 -250.527905) (xy 44.299627 -250.518112) (xy 44.353506 -250.516143)
			(xy 44.407097 -250.52204) (xy 44.459258 -250.535676) (xy 44.508878 -250.556763) (xy 44.554899 -250.584849)
			(xy 44.596341 -250.619337) (xy 44.632319 -250.659491) (xy 44.662067 -250.704455) (xy 44.684952 -250.753272)
			(xy 44.700484 -250.804901) (xy 44.708334 -250.858241) (xy 44.708826 -250.885198) (xy 44.708334 -250.912155)
			(xy 44.700484 -250.965495) (xy 44.684952 -251.017124) (xy 44.662067 -251.065941) (xy 44.632319 -251.110905)
			(xy 44.596341 -251.151059) (xy 44.554899 -251.185547) (xy 44.508878 -251.213633) (xy 44.459258 -251.23472)
			(xy 44.407097 -251.248356) (xy 44.353506 -251.254253) (xy 44.299627 -251.252284) (xy 44.246609 -251.242491)
			(xy 44.195582 -251.225083) (xy 44.147634 -251.200431) (xy 44.103786 -251.169061) (xy 44.064973 -251.13164)
			(xy 44.032021 -251.088967) (xy 44.005635 -251.04195) (xy 43.986375 -250.991593) (xy 43.974652 -250.938969)
			(xy 43.970717 -250.885198) (xy 37.164772 -250.885198) (xy 37.16428 -250.912155) (xy 37.15643 -250.965495)
			(xy 37.140898 -251.017124) (xy 37.118013 -251.065941) (xy 37.088265 -251.110905) (xy 37.052287 -251.151059)
			(xy 37.010845 -251.185547) (xy 36.964824 -251.213633) (xy 36.915204 -251.23472) (xy 36.863043 -251.248356)
			(xy 36.809452 -251.254253) (xy 36.755573 -251.252284) (xy 36.702555 -251.242491) (xy 36.651528 -251.225083)
			(xy 36.60358 -251.200431) (xy 36.559732 -251.169061) (xy 36.520919 -251.13164) (xy 36.487967 -251.088967)
			(xy 36.461581 -251.04195) (xy 36.442321 -250.991593) (xy 36.430598 -250.938969) (xy 36.426663 -250.885198)
			(xy 29.620972 -250.885198) (xy 29.62048 -250.912155) (xy 29.61263 -250.965495) (xy 29.597098 -251.017124)
			(xy 29.574213 -251.065941) (xy 29.544465 -251.110905) (xy 29.508487 -251.151059) (xy 29.467045 -251.185547)
			(xy 29.421024 -251.213633) (xy 29.371404 -251.23472) (xy 29.319243 -251.248356) (xy 29.265652 -251.254253)
			(xy 29.211773 -251.252284) (xy 29.158755 -251.242491) (xy 29.107728 -251.225083) (xy 29.05978 -251.200431)
			(xy 29.015932 -251.169061) (xy 28.977119 -251.13164) (xy 28.944167 -251.088967) (xy 28.917781 -251.04195)
			(xy 28.898521 -250.991593) (xy 28.886798 -250.938969) (xy 28.882863 -250.885198) (xy 22.076918 -250.885198)
			(xy 22.076426 -250.912155) (xy 22.068576 -250.965495) (xy 22.053044 -251.017124) (xy 22.030159 -251.065941)
			(xy 22.000411 -251.110905) (xy 21.964433 -251.151059) (xy 21.922991 -251.185547) (xy 21.87697 -251.213633)
			(xy 21.82735 -251.23472) (xy 21.775189 -251.248356) (xy 21.721598 -251.254253) (xy 21.667719 -251.252284)
			(xy 21.614701 -251.242491) (xy 21.563674 -251.225083) (xy 21.515726 -251.200431) (xy 21.471878 -251.169061)
			(xy 21.433065 -251.13164) (xy 21.400113 -251.088967) (xy 21.373727 -251.04195) (xy 21.354467 -250.991593)
			(xy 21.342744 -250.938969) (xy 21.338809 -250.885198) (xy 15.598394 -250.885198) (xy 15.598394 -251.735336)
			(xy 17.238741 -251.735336) (xy 17.242676 -251.681565) (xy 17.254399 -251.628941) (xy 17.273659 -251.578584)
			(xy 17.300045 -251.531567) (xy 17.332997 -251.488894) (xy 17.37181 -251.451473) (xy 17.415658 -251.420103)
			(xy 17.463606 -251.395451) (xy 17.514633 -251.378043) (xy 17.567651 -251.36825) (xy 17.62153 -251.366281)
			(xy 17.675121 -251.372178) (xy 17.727282 -251.385814) (xy 17.776902 -251.406901) (xy 17.822923 -251.434987)
			(xy 17.864365 -251.469475) (xy 17.900343 -251.509629) (xy 17.930091 -251.554593) (xy 17.952976 -251.60341)
			(xy 17.968508 -251.655039) (xy 17.976358 -251.708379) (xy 17.97685 -251.735336) (xy 24.782795 -251.735336)
			(xy 24.78673 -251.681565) (xy 24.798453 -251.628941) (xy 24.817713 -251.578584) (xy 24.844099 -251.531567)
			(xy 24.877051 -251.488894) (xy 24.915864 -251.451473) (xy 24.959712 -251.420103) (xy 25.00766 -251.395451)
			(xy 25.058687 -251.378043) (xy 25.111705 -251.36825) (xy 25.165584 -251.366281) (xy 25.219175 -251.372178)
			(xy 25.271336 -251.385814) (xy 25.320956 -251.406901) (xy 25.366977 -251.434987) (xy 25.408419 -251.469475)
			(xy 25.444397 -251.509629) (xy 25.474145 -251.554593) (xy 25.49703 -251.60341) (xy 25.512562 -251.655039)
			(xy 25.520412 -251.708379) (xy 25.520904 -251.735336) (xy 32.326595 -251.735336) (xy 32.33053 -251.681565)
			(xy 32.342253 -251.628941) (xy 32.361513 -251.578584) (xy 32.387899 -251.531567) (xy 32.420851 -251.488894)
			(xy 32.459664 -251.451473) (xy 32.503512 -251.420103) (xy 32.55146 -251.395451) (xy 32.602487 -251.378043)
			(xy 32.655505 -251.36825) (xy 32.709384 -251.366281) (xy 32.762975 -251.372178) (xy 32.815136 -251.385814)
			(xy 32.864756 -251.406901) (xy 32.910777 -251.434987) (xy 32.952219 -251.469475) (xy 32.988197 -251.509629)
			(xy 33.017945 -251.554593) (xy 33.04083 -251.60341) (xy 33.056362 -251.655039) (xy 33.064212 -251.708379)
			(xy 33.064704 -251.735336) (xy 39.870649 -251.735336) (xy 39.874584 -251.681565) (xy 39.886307 -251.628941)
			(xy 39.905567 -251.578584) (xy 39.931953 -251.531567) (xy 39.964905 -251.488894) (xy 40.003718 -251.451473)
			(xy 40.047566 -251.420103) (xy 40.095514 -251.395451) (xy 40.146541 -251.378043) (xy 40.199559 -251.36825)
			(xy 40.253438 -251.366281) (xy 40.307029 -251.372178) (xy 40.35919 -251.385814) (xy 40.40881 -251.406901)
			(xy 40.454831 -251.434987) (xy 40.496273 -251.469475) (xy 40.532251 -251.509629) (xy 40.561999 -251.554593)
			(xy 40.584884 -251.60341) (xy 40.600416 -251.655039) (xy 40.608266 -251.708379) (xy 40.608758 -251.735336)
			(xy 40.608266 -251.762293) (xy 40.600416 -251.815633) (xy 40.584884 -251.867262) (xy 40.561999 -251.916079)
			(xy 40.532251 -251.961043) (xy 40.496273 -252.001197) (xy 40.454831 -252.035685) (xy 40.40881 -252.063771)
			(xy 40.35919 -252.084858) (xy 40.307029 -252.098494) (xy 40.253438 -252.104391) (xy 40.199559 -252.102422)
			(xy 40.146541 -252.092629) (xy 40.095514 -252.075221) (xy 40.047566 -252.050569) (xy 40.003718 -252.019199)
			(xy 39.964905 -251.981778) (xy 39.931953 -251.939105) (xy 39.905567 -251.892088) (xy 39.886307 -251.841731)
			(xy 39.874584 -251.789107) (xy 39.870649 -251.735336) (xy 33.064704 -251.735336) (xy 33.064212 -251.762293)
			(xy 33.056362 -251.815633) (xy 33.04083 -251.867262) (xy 33.017945 -251.916079) (xy 32.988197 -251.961043)
			(xy 32.952219 -252.001197) (xy 32.910777 -252.035685) (xy 32.864756 -252.063771) (xy 32.815136 -252.084858)
			(xy 32.762975 -252.098494) (xy 32.709384 -252.104391) (xy 32.655505 -252.102422) (xy 32.602487 -252.092629)
			(xy 32.55146 -252.075221) (xy 32.503512 -252.050569) (xy 32.459664 -252.019199) (xy 32.420851 -251.981778)
			(xy 32.387899 -251.939105) (xy 32.361513 -251.892088) (xy 32.342253 -251.841731) (xy 32.33053 -251.789107)
			(xy 32.326595 -251.735336) (xy 25.520904 -251.735336) (xy 25.520412 -251.762293) (xy 25.512562 -251.815633)
			(xy 25.49703 -251.867262) (xy 25.474145 -251.916079) (xy 25.444397 -251.961043) (xy 25.408419 -252.001197)
			(xy 25.366977 -252.035685) (xy 25.320956 -252.063771) (xy 25.271336 -252.084858) (xy 25.219175 -252.098494)
			(xy 25.165584 -252.104391) (xy 25.111705 -252.102422) (xy 25.058687 -252.092629) (xy 25.00766 -252.075221)
			(xy 24.959712 -252.050569) (xy 24.915864 -252.019199) (xy 24.877051 -251.981778) (xy 24.844099 -251.939105)
			(xy 24.817713 -251.892088) (xy 24.798453 -251.841731) (xy 24.78673 -251.789107) (xy 24.782795 -251.735336)
			(xy 17.97685 -251.735336) (xy 17.976358 -251.762293) (xy 17.968508 -251.815633) (xy 17.952976 -251.867262)
			(xy 17.930091 -251.916079) (xy 17.900343 -251.961043) (xy 17.864365 -252.001197) (xy 17.822923 -252.035685)
			(xy 17.776902 -252.063771) (xy 17.727282 -252.084858) (xy 17.675121 -252.098494) (xy 17.62153 -252.104391)
			(xy 17.567651 -252.102422) (xy 17.514633 -252.092629) (xy 17.463606 -252.075221) (xy 17.415658 -252.050569)
			(xy 17.37181 -252.019199) (xy 17.332997 -251.981778) (xy 17.300045 -251.939105) (xy 17.273659 -251.892088)
			(xy 17.254399 -251.841731) (xy 17.242676 -251.789107) (xy 17.238741 -251.735336) (xy 15.598394 -251.735336)
			(xy 15.598394 -252.58522) (xy 21.338809 -252.58522) (xy 21.342744 -252.531449) (xy 21.354467 -252.478825)
			(xy 21.373727 -252.428468) (xy 21.400113 -252.381451) (xy 21.433065 -252.338778) (xy 21.471878 -252.301357)
			(xy 21.515726 -252.269987) (xy 21.563674 -252.245335) (xy 21.614701 -252.227927) (xy 21.667719 -252.218134)
			(xy 21.721598 -252.216165) (xy 21.775189 -252.222062) (xy 21.82735 -252.235698) (xy 21.87697 -252.256785)
			(xy 21.922991 -252.284871) (xy 21.964433 -252.319359) (xy 22.000411 -252.359513) (xy 22.030159 -252.404477)
			(xy 22.053044 -252.453294) (xy 22.068576 -252.504923) (xy 22.076426 -252.558263) (xy 22.076918 -252.58522)
			(xy 28.882863 -252.58522) (xy 28.886798 -252.531449) (xy 28.898521 -252.478825) (xy 28.917781 -252.428468)
			(xy 28.944167 -252.381451) (xy 28.977119 -252.338778) (xy 29.015932 -252.301357) (xy 29.05978 -252.269987)
			(xy 29.107728 -252.245335) (xy 29.158755 -252.227927) (xy 29.211773 -252.218134) (xy 29.265652 -252.216165)
			(xy 29.319243 -252.222062) (xy 29.371404 -252.235698) (xy 29.421024 -252.256785) (xy 29.467045 -252.284871)
			(xy 29.508487 -252.319359) (xy 29.544465 -252.359513) (xy 29.574213 -252.404477) (xy 29.597098 -252.453294)
			(xy 29.61263 -252.504923) (xy 29.62048 -252.558263) (xy 29.620972 -252.58522) (xy 36.426663 -252.58522)
			(xy 36.430598 -252.531449) (xy 36.442321 -252.478825) (xy 36.461581 -252.428468) (xy 36.487967 -252.381451)
			(xy 36.520919 -252.338778) (xy 36.559732 -252.301357) (xy 36.60358 -252.269987) (xy 36.651528 -252.245335)
			(xy 36.702555 -252.227927) (xy 36.755573 -252.218134) (xy 36.809452 -252.216165) (xy 36.863043 -252.222062)
			(xy 36.915204 -252.235698) (xy 36.964824 -252.256785) (xy 37.010845 -252.284871) (xy 37.052287 -252.319359)
			(xy 37.088265 -252.359513) (xy 37.118013 -252.404477) (xy 37.140898 -252.453294) (xy 37.15643 -252.504923)
			(xy 37.16428 -252.558263) (xy 37.164772 -252.58522) (xy 43.970717 -252.58522) (xy 43.974652 -252.531449)
			(xy 43.986375 -252.478825) (xy 44.005635 -252.428468) (xy 44.032021 -252.381451) (xy 44.064973 -252.338778)
			(xy 44.103786 -252.301357) (xy 44.147634 -252.269987) (xy 44.195582 -252.245335) (xy 44.246609 -252.227927)
			(xy 44.299627 -252.218134) (xy 44.353506 -252.216165) (xy 44.407097 -252.222062) (xy 44.459258 -252.235698)
			(xy 44.508878 -252.256785) (xy 44.554899 -252.284871) (xy 44.596341 -252.319359) (xy 44.632319 -252.359513)
			(xy 44.662067 -252.404477) (xy 44.684952 -252.453294) (xy 44.700484 -252.504923) (xy 44.708334 -252.558263)
			(xy 44.708826 -252.58522) (xy 44.708334 -252.612177) (xy 44.700484 -252.665517) (xy 44.684952 -252.717146)
			(xy 44.662067 -252.765963) (xy 44.632319 -252.810927) (xy 44.596341 -252.851081) (xy 44.554899 -252.885569)
			(xy 44.508878 -252.913655) (xy 44.459258 -252.934742) (xy 44.407097 -252.948378) (xy 44.353506 -252.954275)
			(xy 44.299627 -252.952306) (xy 44.246609 -252.942513) (xy 44.195582 -252.925105) (xy 44.147634 -252.900453)
			(xy 44.103786 -252.869083) (xy 44.064973 -252.831662) (xy 44.032021 -252.788989) (xy 44.005635 -252.741972)
			(xy 43.986375 -252.691615) (xy 43.974652 -252.638991) (xy 43.970717 -252.58522) (xy 37.164772 -252.58522)
			(xy 37.16428 -252.612177) (xy 37.15643 -252.665517) (xy 37.140898 -252.717146) (xy 37.118013 -252.765963)
			(xy 37.088265 -252.810927) (xy 37.052287 -252.851081) (xy 37.010845 -252.885569) (xy 36.964824 -252.913655)
			(xy 36.915204 -252.934742) (xy 36.863043 -252.948378) (xy 36.809452 -252.954275) (xy 36.755573 -252.952306)
			(xy 36.702555 -252.942513) (xy 36.651528 -252.925105) (xy 36.60358 -252.900453) (xy 36.559732 -252.869083)
			(xy 36.520919 -252.831662) (xy 36.487967 -252.788989) (xy 36.461581 -252.741972) (xy 36.442321 -252.691615)
			(xy 36.430598 -252.638991) (xy 36.426663 -252.58522) (xy 29.620972 -252.58522) (xy 29.62048 -252.612177)
			(xy 29.61263 -252.665517) (xy 29.597098 -252.717146) (xy 29.574213 -252.765963) (xy 29.544465 -252.810927)
			(xy 29.508487 -252.851081) (xy 29.467045 -252.885569) (xy 29.421024 -252.913655) (xy 29.371404 -252.934742)
			(xy 29.319243 -252.948378) (xy 29.265652 -252.954275) (xy 29.211773 -252.952306) (xy 29.158755 -252.942513)
			(xy 29.107728 -252.925105) (xy 29.05978 -252.900453) (xy 29.015932 -252.869083) (xy 28.977119 -252.831662)
			(xy 28.944167 -252.788989) (xy 28.917781 -252.741972) (xy 28.898521 -252.691615) (xy 28.886798 -252.638991)
			(xy 28.882863 -252.58522) (xy 22.076918 -252.58522) (xy 22.076426 -252.612177) (xy 22.068576 -252.665517)
			(xy 22.053044 -252.717146) (xy 22.030159 -252.765963) (xy 22.000411 -252.810927) (xy 21.964433 -252.851081)
			(xy 21.922991 -252.885569) (xy 21.87697 -252.913655) (xy 21.82735 -252.934742) (xy 21.775189 -252.948378)
			(xy 21.721598 -252.954275) (xy 21.667719 -252.952306) (xy 21.614701 -252.942513) (xy 21.563674 -252.925105)
			(xy 21.515726 -252.900453) (xy 21.471878 -252.869083) (xy 21.433065 -252.831662) (xy 21.400113 -252.788989)
			(xy 21.373727 -252.741972) (xy 21.354467 -252.691615) (xy 21.342744 -252.638991) (xy 21.338809 -252.58522)
			(xy 15.598394 -252.58522) (xy 15.598394 -253.435358) (xy 17.238741 -253.435358) (xy 17.242676 -253.381587)
			(xy 17.254399 -253.328963) (xy 17.273659 -253.278606) (xy 17.300045 -253.231589) (xy 17.332997 -253.188916)
			(xy 17.37181 -253.151495) (xy 17.415658 -253.120125) (xy 17.463606 -253.095473) (xy 17.514633 -253.078065)
			(xy 17.567651 -253.068272) (xy 17.62153 -253.066303) (xy 17.675121 -253.0722) (xy 17.727282 -253.085836)
			(xy 17.776902 -253.106923) (xy 17.822923 -253.135009) (xy 17.864365 -253.169497) (xy 17.900343 -253.209651)
			(xy 17.930091 -253.254615) (xy 17.952976 -253.303432) (xy 17.968508 -253.355061) (xy 17.976358 -253.408401)
			(xy 17.97685 -253.435358) (xy 24.782795 -253.435358) (xy 24.78673 -253.381587) (xy 24.798453 -253.328963)
			(xy 24.817713 -253.278606) (xy 24.844099 -253.231589) (xy 24.877051 -253.188916) (xy 24.915864 -253.151495)
			(xy 24.959712 -253.120125) (xy 25.00766 -253.095473) (xy 25.058687 -253.078065) (xy 25.111705 -253.068272)
			(xy 25.165584 -253.066303) (xy 25.219175 -253.0722) (xy 25.271336 -253.085836) (xy 25.320956 -253.106923)
			(xy 25.366977 -253.135009) (xy 25.408419 -253.169497) (xy 25.444397 -253.209651) (xy 25.474145 -253.254615)
			(xy 25.49703 -253.303432) (xy 25.512562 -253.355061) (xy 25.520412 -253.408401) (xy 25.520904 -253.435358)
			(xy 32.326595 -253.435358) (xy 32.33053 -253.381587) (xy 32.342253 -253.328963) (xy 32.361513 -253.278606)
			(xy 32.387899 -253.231589) (xy 32.420851 -253.188916) (xy 32.459664 -253.151495) (xy 32.503512 -253.120125)
			(xy 32.55146 -253.095473) (xy 32.602487 -253.078065) (xy 32.655505 -253.068272) (xy 32.709384 -253.066303)
			(xy 32.762975 -253.0722) (xy 32.815136 -253.085836) (xy 32.864756 -253.106923) (xy 32.910777 -253.135009)
			(xy 32.952219 -253.169497) (xy 32.988197 -253.209651) (xy 33.017945 -253.254615) (xy 33.04083 -253.303432)
			(xy 33.056362 -253.355061) (xy 33.064212 -253.408401) (xy 33.064704 -253.435358) (xy 39.870649 -253.435358)
			(xy 39.874584 -253.381587) (xy 39.886307 -253.328963) (xy 39.905567 -253.278606) (xy 39.931953 -253.231589)
			(xy 39.964905 -253.188916) (xy 40.003718 -253.151495) (xy 40.047566 -253.120125) (xy 40.095514 -253.095473)
			(xy 40.146541 -253.078065) (xy 40.199559 -253.068272) (xy 40.253438 -253.066303) (xy 40.307029 -253.0722)
			(xy 40.35919 -253.085836) (xy 40.40881 -253.106923) (xy 40.454831 -253.135009) (xy 40.496273 -253.169497)
			(xy 40.532251 -253.209651) (xy 40.561999 -253.254615) (xy 40.584884 -253.303432) (xy 40.600416 -253.355061)
			(xy 40.608266 -253.408401) (xy 40.608758 -253.435358) (xy 40.608266 -253.462315) (xy 40.600416 -253.515655)
			(xy 40.584884 -253.567284) (xy 40.561999 -253.616101) (xy 40.532251 -253.661065) (xy 40.496273 -253.701219)
			(xy 40.454831 -253.735707) (xy 40.40881 -253.763793) (xy 40.35919 -253.78488) (xy 40.307029 -253.798516)
			(xy 40.253438 -253.804413) (xy 40.199559 -253.802444) (xy 40.146541 -253.792651) (xy 40.095514 -253.775243)
			(xy 40.047566 -253.750591) (xy 40.003718 -253.719221) (xy 39.964905 -253.6818) (xy 39.931953 -253.639127)
			(xy 39.905567 -253.59211) (xy 39.886307 -253.541753) (xy 39.874584 -253.489129) (xy 39.870649 -253.435358)
			(xy 33.064704 -253.435358) (xy 33.064212 -253.462315) (xy 33.056362 -253.515655) (xy 33.04083 -253.567284)
			(xy 33.017945 -253.616101) (xy 32.988197 -253.661065) (xy 32.952219 -253.701219) (xy 32.910777 -253.735707)
			(xy 32.864756 -253.763793) (xy 32.815136 -253.78488) (xy 32.762975 -253.798516) (xy 32.709384 -253.804413)
			(xy 32.655505 -253.802444) (xy 32.602487 -253.792651) (xy 32.55146 -253.775243) (xy 32.503512 -253.750591)
			(xy 32.459664 -253.719221) (xy 32.420851 -253.6818) (xy 32.387899 -253.639127) (xy 32.361513 -253.59211)
			(xy 32.342253 -253.541753) (xy 32.33053 -253.489129) (xy 32.326595 -253.435358) (xy 25.520904 -253.435358)
			(xy 25.520412 -253.462315) (xy 25.512562 -253.515655) (xy 25.49703 -253.567284) (xy 25.474145 -253.616101)
			(xy 25.444397 -253.661065) (xy 25.408419 -253.701219) (xy 25.366977 -253.735707) (xy 25.320956 -253.763793)
			(xy 25.271336 -253.78488) (xy 25.219175 -253.798516) (xy 25.165584 -253.804413) (xy 25.111705 -253.802444)
			(xy 25.058687 -253.792651) (xy 25.00766 -253.775243) (xy 24.959712 -253.750591) (xy 24.915864 -253.719221)
			(xy 24.877051 -253.6818) (xy 24.844099 -253.639127) (xy 24.817713 -253.59211) (xy 24.798453 -253.541753)
			(xy 24.78673 -253.489129) (xy 24.782795 -253.435358) (xy 17.97685 -253.435358) (xy 17.976358 -253.462315)
			(xy 17.968508 -253.515655) (xy 17.952976 -253.567284) (xy 17.930091 -253.616101) (xy 17.900343 -253.661065)
			(xy 17.864365 -253.701219) (xy 17.822923 -253.735707) (xy 17.776902 -253.763793) (xy 17.727282 -253.78488)
			(xy 17.675121 -253.798516) (xy 17.62153 -253.804413) (xy 17.567651 -253.802444) (xy 17.514633 -253.792651)
			(xy 17.463606 -253.775243) (xy 17.415658 -253.750591) (xy 17.37181 -253.719221) (xy 17.332997 -253.6818)
			(xy 17.300045 -253.639127) (xy 17.273659 -253.59211) (xy 17.254399 -253.541753) (xy 17.242676 -253.489129)
			(xy 17.238741 -253.435358) (xy 15.598394 -253.435358) (xy 15.598394 -254.285242) (xy 17.238741 -254.285242)
			(xy 17.242676 -254.231471) (xy 17.254399 -254.178847) (xy 17.273659 -254.12849) (xy 17.300045 -254.081473)
			(xy 17.332997 -254.0388) (xy 17.37181 -254.001379) (xy 17.415658 -253.970009) (xy 17.463606 -253.945357)
			(xy 17.514633 -253.927949) (xy 17.567651 -253.918156) (xy 17.62153 -253.916187) (xy 17.675121 -253.922084)
			(xy 17.727282 -253.93572) (xy 17.776902 -253.956807) (xy 17.822923 -253.984893) (xy 17.864365 -254.019381)
			(xy 17.900343 -254.059535) (xy 17.930091 -254.104499) (xy 17.952976 -254.153316) (xy 17.968508 -254.204945)
			(xy 17.976358 -254.258285) (xy 17.97685 -254.285242) (xy 21.338809 -254.285242) (xy 21.342744 -254.231471)
			(xy 21.354467 -254.178847) (xy 21.373727 -254.12849) (xy 21.400113 -254.081473) (xy 21.433065 -254.0388)
			(xy 21.471878 -254.001379) (xy 21.515726 -253.970009) (xy 21.563674 -253.945357) (xy 21.614701 -253.927949)
			(xy 21.667719 -253.918156) (xy 21.721598 -253.916187) (xy 21.775189 -253.922084) (xy 21.82735 -253.93572)
			(xy 21.87697 -253.956807) (xy 21.922991 -253.984893) (xy 21.964433 -254.019381) (xy 22.000411 -254.059535)
			(xy 22.030159 -254.104499) (xy 22.053044 -254.153316) (xy 22.068576 -254.204945) (xy 22.076426 -254.258285)
			(xy 22.076918 -254.285242) (xy 24.782795 -254.285242) (xy 24.78673 -254.231471) (xy 24.798453 -254.178847)
			(xy 24.817713 -254.12849) (xy 24.844099 -254.081473) (xy 24.877051 -254.0388) (xy 24.915864 -254.001379)
			(xy 24.959712 -253.970009) (xy 25.00766 -253.945357) (xy 25.058687 -253.927949) (xy 25.111705 -253.918156)
			(xy 25.165584 -253.916187) (xy 25.219175 -253.922084) (xy 25.271336 -253.93572) (xy 25.320956 -253.956807)
			(xy 25.366977 -253.984893) (xy 25.408419 -254.019381) (xy 25.444397 -254.059535) (xy 25.474145 -254.104499)
			(xy 25.49703 -254.153316) (xy 25.512562 -254.204945) (xy 25.520412 -254.258285) (xy 25.520904 -254.285242)
			(xy 28.882863 -254.285242) (xy 28.886798 -254.231471) (xy 28.898521 -254.178847) (xy 28.917781 -254.12849)
			(xy 28.944167 -254.081473) (xy 28.977119 -254.0388) (xy 29.015932 -254.001379) (xy 29.05978 -253.970009)
			(xy 29.107728 -253.945357) (xy 29.158755 -253.927949) (xy 29.211773 -253.918156) (xy 29.265652 -253.916187)
			(xy 29.319243 -253.922084) (xy 29.371404 -253.93572) (xy 29.421024 -253.956807) (xy 29.467045 -253.984893)
			(xy 29.508487 -254.019381) (xy 29.544465 -254.059535) (xy 29.574213 -254.104499) (xy 29.597098 -254.153316)
			(xy 29.61263 -254.204945) (xy 29.62048 -254.258285) (xy 29.620972 -254.285242) (xy 32.326595 -254.285242)
			(xy 32.33053 -254.231471) (xy 32.342253 -254.178847) (xy 32.361513 -254.12849) (xy 32.387899 -254.081473)
			(xy 32.420851 -254.0388) (xy 32.459664 -254.001379) (xy 32.503512 -253.970009) (xy 32.55146 -253.945357)
			(xy 32.602487 -253.927949) (xy 32.655505 -253.918156) (xy 32.709384 -253.916187) (xy 32.762975 -253.922084)
			(xy 32.815136 -253.93572) (xy 32.864756 -253.956807) (xy 32.910777 -253.984893) (xy 32.952219 -254.019381)
			(xy 32.988197 -254.059535) (xy 33.017945 -254.104499) (xy 33.04083 -254.153316) (xy 33.056362 -254.204945)
			(xy 33.064212 -254.258285) (xy 33.064704 -254.285242) (xy 36.426663 -254.285242) (xy 36.430598 -254.231471)
			(xy 36.442321 -254.178847) (xy 36.461581 -254.12849) (xy 36.487967 -254.081473) (xy 36.520919 -254.0388)
			(xy 36.559732 -254.001379) (xy 36.60358 -253.970009) (xy 36.651528 -253.945357) (xy 36.702555 -253.927949)
			(xy 36.755573 -253.918156) (xy 36.809452 -253.916187) (xy 36.863043 -253.922084) (xy 36.915204 -253.93572)
			(xy 36.964824 -253.956807) (xy 37.010845 -253.984893) (xy 37.052287 -254.019381) (xy 37.088265 -254.059535)
			(xy 37.118013 -254.104499) (xy 37.140898 -254.153316) (xy 37.15643 -254.204945) (xy 37.16428 -254.258285)
			(xy 37.164772 -254.285242) (xy 39.870649 -254.285242) (xy 39.874584 -254.231471) (xy 39.886307 -254.178847)
			(xy 39.905567 -254.12849) (xy 39.931953 -254.081473) (xy 39.964905 -254.0388) (xy 40.003718 -254.001379)
			(xy 40.047566 -253.970009) (xy 40.095514 -253.945357) (xy 40.146541 -253.927949) (xy 40.199559 -253.918156)
			(xy 40.253438 -253.916187) (xy 40.307029 -253.922084) (xy 40.35919 -253.93572) (xy 40.40881 -253.956807)
			(xy 40.454831 -253.984893) (xy 40.496273 -254.019381) (xy 40.532251 -254.059535) (xy 40.561999 -254.104499)
			(xy 40.584884 -254.153316) (xy 40.600416 -254.204945) (xy 40.608266 -254.258285) (xy 40.608758 -254.285242)
			(xy 43.970717 -254.285242) (xy 43.974652 -254.231471) (xy 43.986375 -254.178847) (xy 44.005635 -254.12849)
			(xy 44.032021 -254.081473) (xy 44.064973 -254.0388) (xy 44.103786 -254.001379) (xy 44.147634 -253.970009)
			(xy 44.195582 -253.945357) (xy 44.246609 -253.927949) (xy 44.299627 -253.918156) (xy 44.353506 -253.916187)
			(xy 44.407097 -253.922084) (xy 44.459258 -253.93572) (xy 44.508878 -253.956807) (xy 44.554899 -253.984893)
			(xy 44.596341 -254.019381) (xy 44.632319 -254.059535) (xy 44.662067 -254.104499) (xy 44.684952 -254.153316)
			(xy 44.700484 -254.204945) (xy 44.708334 -254.258285) (xy 44.708826 -254.285242) (xy 44.708334 -254.312199)
			(xy 44.700484 -254.365539) (xy 44.684952 -254.417168) (xy 44.662067 -254.465985) (xy 44.632319 -254.510949)
			(xy 44.596341 -254.551103) (xy 44.554899 -254.585591) (xy 44.508878 -254.613677) (xy 44.459258 -254.634764)
			(xy 44.407097 -254.6484) (xy 44.353506 -254.654297) (xy 44.299627 -254.652328) (xy 44.246609 -254.642535)
			(xy 44.195582 -254.625127) (xy 44.147634 -254.600475) (xy 44.103786 -254.569105) (xy 44.064973 -254.531684)
			(xy 44.032021 -254.489011) (xy 44.005635 -254.441994) (xy 43.986375 -254.391637) (xy 43.974652 -254.339013)
			(xy 43.970717 -254.285242) (xy 40.608758 -254.285242) (xy 40.608266 -254.312199) (xy 40.600416 -254.365539)
			(xy 40.584884 -254.417168) (xy 40.561999 -254.465985) (xy 40.532251 -254.510949) (xy 40.496273 -254.551103)
			(xy 40.454831 -254.585591) (xy 40.40881 -254.613677) (xy 40.35919 -254.634764) (xy 40.307029 -254.6484)
			(xy 40.253438 -254.654297) (xy 40.199559 -254.652328) (xy 40.146541 -254.642535) (xy 40.095514 -254.625127)
			(xy 40.047566 -254.600475) (xy 40.003718 -254.569105) (xy 39.964905 -254.531684) (xy 39.931953 -254.489011)
			(xy 39.905567 -254.441994) (xy 39.886307 -254.391637) (xy 39.874584 -254.339013) (xy 39.870649 -254.285242)
			(xy 37.164772 -254.285242) (xy 37.16428 -254.312199) (xy 37.15643 -254.365539) (xy 37.140898 -254.417168)
			(xy 37.118013 -254.465985) (xy 37.088265 -254.510949) (xy 37.052287 -254.551103) (xy 37.010845 -254.585591)
			(xy 36.964824 -254.613677) (xy 36.915204 -254.634764) (xy 36.863043 -254.6484) (xy 36.809452 -254.654297)
			(xy 36.755573 -254.652328) (xy 36.702555 -254.642535) (xy 36.651528 -254.625127) (xy 36.60358 -254.600475)
			(xy 36.559732 -254.569105) (xy 36.520919 -254.531684) (xy 36.487967 -254.489011) (xy 36.461581 -254.441994)
			(xy 36.442321 -254.391637) (xy 36.430598 -254.339013) (xy 36.426663 -254.285242) (xy 33.064704 -254.285242)
			(xy 33.064212 -254.312199) (xy 33.056362 -254.365539) (xy 33.04083 -254.417168) (xy 33.017945 -254.465985)
			(xy 32.988197 -254.510949) (xy 32.952219 -254.551103) (xy 32.910777 -254.585591) (xy 32.864756 -254.613677)
			(xy 32.815136 -254.634764) (xy 32.762975 -254.6484) (xy 32.709384 -254.654297) (xy 32.655505 -254.652328)
			(xy 32.602487 -254.642535) (xy 32.55146 -254.625127) (xy 32.503512 -254.600475) (xy 32.459664 -254.569105)
			(xy 32.420851 -254.531684) (xy 32.387899 -254.489011) (xy 32.361513 -254.441994) (xy 32.342253 -254.391637)
			(xy 32.33053 -254.339013) (xy 32.326595 -254.285242) (xy 29.620972 -254.285242) (xy 29.62048 -254.312199)
			(xy 29.61263 -254.365539) (xy 29.597098 -254.417168) (xy 29.574213 -254.465985) (xy 29.544465 -254.510949)
			(xy 29.508487 -254.551103) (xy 29.467045 -254.585591) (xy 29.421024 -254.613677) (xy 29.371404 -254.634764)
			(xy 29.319243 -254.6484) (xy 29.265652 -254.654297) (xy 29.211773 -254.652328) (xy 29.158755 -254.642535)
			(xy 29.107728 -254.625127) (xy 29.05978 -254.600475) (xy 29.015932 -254.569105) (xy 28.977119 -254.531684)
			(xy 28.944167 -254.489011) (xy 28.917781 -254.441994) (xy 28.898521 -254.391637) (xy 28.886798 -254.339013)
			(xy 28.882863 -254.285242) (xy 25.520904 -254.285242) (xy 25.520412 -254.312199) (xy 25.512562 -254.365539)
			(xy 25.49703 -254.417168) (xy 25.474145 -254.465985) (xy 25.444397 -254.510949) (xy 25.408419 -254.551103)
			(xy 25.366977 -254.585591) (xy 25.320956 -254.613677) (xy 25.271336 -254.634764) (xy 25.219175 -254.6484)
			(xy 25.165584 -254.654297) (xy 25.111705 -254.652328) (xy 25.058687 -254.642535) (xy 25.00766 -254.625127)
			(xy 24.959712 -254.600475) (xy 24.915864 -254.569105) (xy 24.877051 -254.531684) (xy 24.844099 -254.489011)
			(xy 24.817713 -254.441994) (xy 24.798453 -254.391637) (xy 24.78673 -254.339013) (xy 24.782795 -254.285242)
			(xy 22.076918 -254.285242) (xy 22.076426 -254.312199) (xy 22.068576 -254.365539) (xy 22.053044 -254.417168)
			(xy 22.030159 -254.465985) (xy 22.000411 -254.510949) (xy 21.964433 -254.551103) (xy 21.922991 -254.585591)
			(xy 21.87697 -254.613677) (xy 21.82735 -254.634764) (xy 21.775189 -254.6484) (xy 21.721598 -254.654297)
			(xy 21.667719 -254.652328) (xy 21.614701 -254.642535) (xy 21.563674 -254.625127) (xy 21.515726 -254.600475)
			(xy 21.471878 -254.569105) (xy 21.433065 -254.531684) (xy 21.400113 -254.489011) (xy 21.373727 -254.441994)
			(xy 21.354467 -254.391637) (xy 21.342744 -254.339013) (xy 21.338809 -254.285242) (xy 17.97685 -254.285242)
			(xy 17.976358 -254.312199) (xy 17.968508 -254.365539) (xy 17.952976 -254.417168) (xy 17.930091 -254.465985)
			(xy 17.900343 -254.510949) (xy 17.864365 -254.551103) (xy 17.822923 -254.585591) (xy 17.776902 -254.613677)
			(xy 17.727282 -254.634764) (xy 17.675121 -254.6484) (xy 17.62153 -254.654297) (xy 17.567651 -254.652328)
			(xy 17.514633 -254.642535) (xy 17.463606 -254.625127) (xy 17.415658 -254.600475) (xy 17.37181 -254.569105)
			(xy 17.332997 -254.531684) (xy 17.300045 -254.489011) (xy 17.273659 -254.441994) (xy 17.254399 -254.391637)
			(xy 17.242676 -254.339013) (xy 17.238741 -254.285242) (xy 15.598394 -254.285242) (xy 15.598394 -261.08533)
			(xy 21.338809 -261.08533) (xy 21.342744 -261.031559) (xy 21.354467 -260.978935) (xy 21.373727 -260.928578)
			(xy 21.400113 -260.881561) (xy 21.433065 -260.838888) (xy 21.471878 -260.801467) (xy 21.515726 -260.770097)
			(xy 21.563674 -260.745445) (xy 21.614701 -260.728037) (xy 21.667719 -260.718244) (xy 21.721598 -260.716275)
			(xy 21.775189 -260.722172) (xy 21.82735 -260.735808) (xy 21.87697 -260.756895) (xy 21.922991 -260.784981)
			(xy 21.964433 -260.819469) (xy 22.000411 -260.859623) (xy 22.030159 -260.904587) (xy 22.053044 -260.953404)
			(xy 22.068576 -261.005033) (xy 22.076426 -261.058373) (xy 22.076918 -261.08533) (xy 28.882863 -261.08533)
			(xy 28.886798 -261.031559) (xy 28.898521 -260.978935) (xy 28.917781 -260.928578) (xy 28.944167 -260.881561)
			(xy 28.977119 -260.838888) (xy 29.015932 -260.801467) (xy 29.05978 -260.770097) (xy 29.107728 -260.745445)
			(xy 29.158755 -260.728037) (xy 29.211773 -260.718244) (xy 29.265652 -260.716275) (xy 29.319243 -260.722172)
			(xy 29.371404 -260.735808) (xy 29.421024 -260.756895) (xy 29.467045 -260.784981) (xy 29.508487 -260.819469)
			(xy 29.544465 -260.859623) (xy 29.574213 -260.904587) (xy 29.597098 -260.953404) (xy 29.61263 -261.005033)
			(xy 29.62048 -261.058373) (xy 29.620972 -261.08533) (xy 36.426663 -261.08533) (xy 36.430598 -261.031559)
			(xy 36.442321 -260.978935) (xy 36.461581 -260.928578) (xy 36.487967 -260.881561) (xy 36.520919 -260.838888)
			(xy 36.559732 -260.801467) (xy 36.60358 -260.770097) (xy 36.651528 -260.745445) (xy 36.702555 -260.728037)
			(xy 36.755573 -260.718244) (xy 36.809452 -260.716275) (xy 36.863043 -260.722172) (xy 36.915204 -260.735808)
			(xy 36.964824 -260.756895) (xy 37.010845 -260.784981) (xy 37.052287 -260.819469) (xy 37.088265 -260.859623)
			(xy 37.118013 -260.904587) (xy 37.140898 -260.953404) (xy 37.15643 -261.005033) (xy 37.16428 -261.058373)
			(xy 37.164772 -261.08533) (xy 43.970717 -261.08533) (xy 43.974652 -261.031559) (xy 43.986375 -260.978935)
			(xy 44.005635 -260.928578) (xy 44.032021 -260.881561) (xy 44.064973 -260.838888) (xy 44.103786 -260.801467)
			(xy 44.147634 -260.770097) (xy 44.195582 -260.745445) (xy 44.246609 -260.728037) (xy 44.299627 -260.718244)
			(xy 44.353506 -260.716275) (xy 44.407097 -260.722172) (xy 44.459258 -260.735808) (xy 44.508878 -260.756895)
			(xy 44.554899 -260.784981) (xy 44.596341 -260.819469) (xy 44.632319 -260.859623) (xy 44.662067 -260.904587)
			(xy 44.684952 -260.953404) (xy 44.700484 -261.005033) (xy 44.708334 -261.058373) (xy 44.708826 -261.08533)
			(xy 44.708334 -261.112287) (xy 44.700484 -261.165627) (xy 44.684952 -261.217256) (xy 44.662067 -261.266073)
			(xy 44.632319 -261.311037) (xy 44.596341 -261.351191) (xy 44.554899 -261.385679) (xy 44.508878 -261.413765)
			(xy 44.459258 -261.434852) (xy 44.407097 -261.448488) (xy 44.353506 -261.454385) (xy 44.299627 -261.452416)
			(xy 44.246609 -261.442623) (xy 44.195582 -261.425215) (xy 44.147634 -261.400563) (xy 44.103786 -261.369193)
			(xy 44.064973 -261.331772) (xy 44.032021 -261.289099) (xy 44.005635 -261.242082) (xy 43.986375 -261.191725)
			(xy 43.974652 -261.139101) (xy 43.970717 -261.08533) (xy 37.164772 -261.08533) (xy 37.16428 -261.112287)
			(xy 37.15643 -261.165627) (xy 37.140898 -261.217256) (xy 37.118013 -261.266073) (xy 37.088265 -261.311037)
			(xy 37.052287 -261.351191) (xy 37.010845 -261.385679) (xy 36.964824 -261.413765) (xy 36.915204 -261.434852)
			(xy 36.863043 -261.448488) (xy 36.809452 -261.454385) (xy 36.755573 -261.452416) (xy 36.702555 -261.442623)
			(xy 36.651528 -261.425215) (xy 36.60358 -261.400563) (xy 36.559732 -261.369193) (xy 36.520919 -261.331772)
			(xy 36.487967 -261.289099) (xy 36.461581 -261.242082) (xy 36.442321 -261.191725) (xy 36.430598 -261.139101)
			(xy 36.426663 -261.08533) (xy 29.620972 -261.08533) (xy 29.62048 -261.112287) (xy 29.61263 -261.165627)
			(xy 29.597098 -261.217256) (xy 29.574213 -261.266073) (xy 29.544465 -261.311037) (xy 29.508487 -261.351191)
			(xy 29.467045 -261.385679) (xy 29.421024 -261.413765) (xy 29.371404 -261.434852) (xy 29.319243 -261.448488)
			(xy 29.265652 -261.454385) (xy 29.211773 -261.452416) (xy 29.158755 -261.442623) (xy 29.107728 -261.425215)
			(xy 29.05978 -261.400563) (xy 29.015932 -261.369193) (xy 28.977119 -261.331772) (xy 28.944167 -261.289099)
			(xy 28.917781 -261.242082) (xy 28.898521 -261.191725) (xy 28.886798 -261.139101) (xy 28.882863 -261.08533)
			(xy 22.076918 -261.08533) (xy 22.076426 -261.112287) (xy 22.068576 -261.165627) (xy 22.053044 -261.217256)
			(xy 22.030159 -261.266073) (xy 22.000411 -261.311037) (xy 21.964433 -261.351191) (xy 21.922991 -261.385679)
			(xy 21.87697 -261.413765) (xy 21.82735 -261.434852) (xy 21.775189 -261.448488) (xy 21.721598 -261.454385)
			(xy 21.667719 -261.452416) (xy 21.614701 -261.442623) (xy 21.563674 -261.425215) (xy 21.515726 -261.400563)
			(xy 21.471878 -261.369193) (xy 21.433065 -261.331772) (xy 21.400113 -261.289099) (xy 21.373727 -261.242082)
			(xy 21.354467 -261.191725) (xy 21.342744 -261.139101) (xy 21.338809 -261.08533) (xy 15.598394 -261.08533)
			(xy 15.598394 -261.935214) (xy 17.238741 -261.935214) (xy 17.242676 -261.881443) (xy 17.254399 -261.828819)
			(xy 17.273659 -261.778462) (xy 17.300045 -261.731445) (xy 17.332997 -261.688772) (xy 17.37181 -261.651351)
			(xy 17.415658 -261.619981) (xy 17.463606 -261.595329) (xy 17.514633 -261.577921) (xy 17.567651 -261.568128)
			(xy 17.62153 -261.566159) (xy 17.675121 -261.572056) (xy 17.727282 -261.585692) (xy 17.776902 -261.606779)
			(xy 17.822923 -261.634865) (xy 17.864365 -261.669353) (xy 17.900343 -261.709507) (xy 17.930091 -261.754471)
			(xy 17.952976 -261.803288) (xy 17.968508 -261.854917) (xy 17.976358 -261.908257) (xy 17.97685 -261.935214)
			(xy 24.782795 -261.935214) (xy 24.78673 -261.881443) (xy 24.798453 -261.828819) (xy 24.817713 -261.778462)
			(xy 24.844099 -261.731445) (xy 24.877051 -261.688772) (xy 24.915864 -261.651351) (xy 24.959712 -261.619981)
			(xy 25.00766 -261.595329) (xy 25.058687 -261.577921) (xy 25.111705 -261.568128) (xy 25.165584 -261.566159)
			(xy 25.219175 -261.572056) (xy 25.271336 -261.585692) (xy 25.320956 -261.606779) (xy 25.366977 -261.634865)
			(xy 25.408419 -261.669353) (xy 25.444397 -261.709507) (xy 25.474145 -261.754471) (xy 25.49703 -261.803288)
			(xy 25.512562 -261.854917) (xy 25.520412 -261.908257) (xy 25.520904 -261.935214) (xy 32.326595 -261.935214)
			(xy 32.33053 -261.881443) (xy 32.342253 -261.828819) (xy 32.361513 -261.778462) (xy 32.387899 -261.731445)
			(xy 32.420851 -261.688772) (xy 32.459664 -261.651351) (xy 32.503512 -261.619981) (xy 32.55146 -261.595329)
			(xy 32.602487 -261.577921) (xy 32.655505 -261.568128) (xy 32.709384 -261.566159) (xy 32.762975 -261.572056)
			(xy 32.815136 -261.585692) (xy 32.864756 -261.606779) (xy 32.910777 -261.634865) (xy 32.952219 -261.669353)
			(xy 32.988197 -261.709507) (xy 33.017945 -261.754471) (xy 33.04083 -261.803288) (xy 33.056362 -261.854917)
			(xy 33.064212 -261.908257) (xy 33.064704 -261.935214) (xy 39.870649 -261.935214) (xy 39.874584 -261.881443)
			(xy 39.886307 -261.828819) (xy 39.905567 -261.778462) (xy 39.931953 -261.731445) (xy 39.964905 -261.688772)
			(xy 40.003718 -261.651351) (xy 40.047566 -261.619981) (xy 40.095514 -261.595329) (xy 40.146541 -261.577921)
			(xy 40.199559 -261.568128) (xy 40.253438 -261.566159) (xy 40.307029 -261.572056) (xy 40.35919 -261.585692)
			(xy 40.40881 -261.606779) (xy 40.454831 -261.634865) (xy 40.496273 -261.669353) (xy 40.532251 -261.709507)
			(xy 40.561999 -261.754471) (xy 40.584884 -261.803288) (xy 40.600416 -261.854917) (xy 40.608266 -261.908257)
			(xy 40.608758 -261.935214) (xy 40.608266 -261.962171) (xy 40.600416 -262.015511) (xy 40.584884 -262.06714)
			(xy 40.561999 -262.115957) (xy 40.532251 -262.160921) (xy 40.496273 -262.201075) (xy 40.454831 -262.235563)
			(xy 40.40881 -262.263649) (xy 40.35919 -262.284736) (xy 40.307029 -262.298372) (xy 40.253438 -262.304269)
			(xy 40.199559 -262.3023) (xy 40.146541 -262.292507) (xy 40.095514 -262.275099) (xy 40.047566 -262.250447)
			(xy 40.003718 -262.219077) (xy 39.964905 -262.181656) (xy 39.931953 -262.138983) (xy 39.905567 -262.091966)
			(xy 39.886307 -262.041609) (xy 39.874584 -261.988985) (xy 39.870649 -261.935214) (xy 33.064704 -261.935214)
			(xy 33.064212 -261.962171) (xy 33.056362 -262.015511) (xy 33.04083 -262.06714) (xy 33.017945 -262.115957)
			(xy 32.988197 -262.160921) (xy 32.952219 -262.201075) (xy 32.910777 -262.235563) (xy 32.864756 -262.263649)
			(xy 32.815136 -262.284736) (xy 32.762975 -262.298372) (xy 32.709384 -262.304269) (xy 32.655505 -262.3023)
			(xy 32.602487 -262.292507) (xy 32.55146 -262.275099) (xy 32.503512 -262.250447) (xy 32.459664 -262.219077)
			(xy 32.420851 -262.181656) (xy 32.387899 -262.138983) (xy 32.361513 -262.091966) (xy 32.342253 -262.041609)
			(xy 32.33053 -261.988985) (xy 32.326595 -261.935214) (xy 25.520904 -261.935214) (xy 25.520412 -261.962171)
			(xy 25.512562 -262.015511) (xy 25.49703 -262.06714) (xy 25.474145 -262.115957) (xy 25.444397 -262.160921)
			(xy 25.408419 -262.201075) (xy 25.366977 -262.235563) (xy 25.320956 -262.263649) (xy 25.271336 -262.284736)
			(xy 25.219175 -262.298372) (xy 25.165584 -262.304269) (xy 25.111705 -262.3023) (xy 25.058687 -262.292507)
			(xy 25.00766 -262.275099) (xy 24.959712 -262.250447) (xy 24.915864 -262.219077) (xy 24.877051 -262.181656)
			(xy 24.844099 -262.138983) (xy 24.817713 -262.091966) (xy 24.798453 -262.041609) (xy 24.78673 -261.988985)
			(xy 24.782795 -261.935214) (xy 17.97685 -261.935214) (xy 17.976358 -261.962171) (xy 17.968508 -262.015511)
			(xy 17.952976 -262.06714) (xy 17.930091 -262.115957) (xy 17.900343 -262.160921) (xy 17.864365 -262.201075)
			(xy 17.822923 -262.235563) (xy 17.776902 -262.263649) (xy 17.727282 -262.284736) (xy 17.675121 -262.298372)
			(xy 17.62153 -262.304269) (xy 17.567651 -262.3023) (xy 17.514633 -262.292507) (xy 17.463606 -262.275099)
			(xy 17.415658 -262.250447) (xy 17.37181 -262.219077) (xy 17.332997 -262.181656) (xy 17.300045 -262.138983)
			(xy 17.273659 -262.091966) (xy 17.254399 -262.041609) (xy 17.242676 -261.988985) (xy 17.238741 -261.935214)
			(xy 15.598394 -261.935214) (xy 15.598394 -262.785352) (xy 21.338809 -262.785352) (xy 21.342744 -262.731581)
			(xy 21.354467 -262.678957) (xy 21.373727 -262.6286) (xy 21.400113 -262.581583) (xy 21.433065 -262.53891)
			(xy 21.471878 -262.501489) (xy 21.515726 -262.470119) (xy 21.563674 -262.445467) (xy 21.614701 -262.428059)
			(xy 21.667719 -262.418266) (xy 21.721598 -262.416297) (xy 21.775189 -262.422194) (xy 21.82735 -262.43583)
			(xy 21.87697 -262.456917) (xy 21.922991 -262.485003) (xy 21.964433 -262.519491) (xy 22.000411 -262.559645)
			(xy 22.030159 -262.604609) (xy 22.053044 -262.653426) (xy 22.068576 -262.705055) (xy 22.076426 -262.758395)
			(xy 22.076918 -262.785352) (xy 28.882863 -262.785352) (xy 28.886798 -262.731581) (xy 28.898521 -262.678957)
			(xy 28.917781 -262.6286) (xy 28.944167 -262.581583) (xy 28.977119 -262.53891) (xy 29.015932 -262.501489)
			(xy 29.05978 -262.470119) (xy 29.107728 -262.445467) (xy 29.158755 -262.428059) (xy 29.211773 -262.418266)
			(xy 29.265652 -262.416297) (xy 29.319243 -262.422194) (xy 29.371404 -262.43583) (xy 29.421024 -262.456917)
			(xy 29.467045 -262.485003) (xy 29.508487 -262.519491) (xy 29.544465 -262.559645) (xy 29.574213 -262.604609)
			(xy 29.597098 -262.653426) (xy 29.61263 -262.705055) (xy 29.62048 -262.758395) (xy 29.620972 -262.785352)
			(xy 36.426663 -262.785352) (xy 36.430598 -262.731581) (xy 36.442321 -262.678957) (xy 36.461581 -262.6286)
			(xy 36.487967 -262.581583) (xy 36.520919 -262.53891) (xy 36.559732 -262.501489) (xy 36.60358 -262.470119)
			(xy 36.651528 -262.445467) (xy 36.702555 -262.428059) (xy 36.755573 -262.418266) (xy 36.809452 -262.416297)
			(xy 36.863043 -262.422194) (xy 36.915204 -262.43583) (xy 36.964824 -262.456917) (xy 37.010845 -262.485003)
			(xy 37.052287 -262.519491) (xy 37.088265 -262.559645) (xy 37.118013 -262.604609) (xy 37.140898 -262.653426)
			(xy 37.15643 -262.705055) (xy 37.16428 -262.758395) (xy 37.164772 -262.785352) (xy 43.970717 -262.785352)
			(xy 43.974652 -262.731581) (xy 43.986375 -262.678957) (xy 44.005635 -262.6286) (xy 44.032021 -262.581583)
			(xy 44.064973 -262.53891) (xy 44.103786 -262.501489) (xy 44.147634 -262.470119) (xy 44.195582 -262.445467)
			(xy 44.246609 -262.428059) (xy 44.299627 -262.418266) (xy 44.353506 -262.416297) (xy 44.407097 -262.422194)
			(xy 44.459258 -262.43583) (xy 44.508878 -262.456917) (xy 44.554899 -262.485003) (xy 44.596341 -262.519491)
			(xy 44.632319 -262.559645) (xy 44.662067 -262.604609) (xy 44.684952 -262.653426) (xy 44.700484 -262.705055)
			(xy 44.708334 -262.758395) (xy 44.708826 -262.785352) (xy 44.708334 -262.812309) (xy 44.700484 -262.865649)
			(xy 44.684952 -262.917278) (xy 44.662067 -262.966095) (xy 44.632319 -263.011059) (xy 44.596341 -263.051213)
			(xy 44.554899 -263.085701) (xy 44.508878 -263.113787) (xy 44.459258 -263.134874) (xy 44.407097 -263.14851)
			(xy 44.353506 -263.154407) (xy 44.299627 -263.152438) (xy 44.246609 -263.142645) (xy 44.195582 -263.125237)
			(xy 44.147634 -263.100585) (xy 44.103786 -263.069215) (xy 44.064973 -263.031794) (xy 44.032021 -262.989121)
			(xy 44.005635 -262.942104) (xy 43.986375 -262.891747) (xy 43.974652 -262.839123) (xy 43.970717 -262.785352)
			(xy 37.164772 -262.785352) (xy 37.16428 -262.812309) (xy 37.15643 -262.865649) (xy 37.140898 -262.917278)
			(xy 37.118013 -262.966095) (xy 37.088265 -263.011059) (xy 37.052287 -263.051213) (xy 37.010845 -263.085701)
			(xy 36.964824 -263.113787) (xy 36.915204 -263.134874) (xy 36.863043 -263.14851) (xy 36.809452 -263.154407)
			(xy 36.755573 -263.152438) (xy 36.702555 -263.142645) (xy 36.651528 -263.125237) (xy 36.60358 -263.100585)
			(xy 36.559732 -263.069215) (xy 36.520919 -263.031794) (xy 36.487967 -262.989121) (xy 36.461581 -262.942104)
			(xy 36.442321 -262.891747) (xy 36.430598 -262.839123) (xy 36.426663 -262.785352) (xy 29.620972 -262.785352)
			(xy 29.62048 -262.812309) (xy 29.61263 -262.865649) (xy 29.597098 -262.917278) (xy 29.574213 -262.966095)
			(xy 29.544465 -263.011059) (xy 29.508487 -263.051213) (xy 29.467045 -263.085701) (xy 29.421024 -263.113787)
			(xy 29.371404 -263.134874) (xy 29.319243 -263.14851) (xy 29.265652 -263.154407) (xy 29.211773 -263.152438)
			(xy 29.158755 -263.142645) (xy 29.107728 -263.125237) (xy 29.05978 -263.100585) (xy 29.015932 -263.069215)
			(xy 28.977119 -263.031794) (xy 28.944167 -262.989121) (xy 28.917781 -262.942104) (xy 28.898521 -262.891747)
			(xy 28.886798 -262.839123) (xy 28.882863 -262.785352) (xy 22.076918 -262.785352) (xy 22.076426 -262.812309)
			(xy 22.068576 -262.865649) (xy 22.053044 -262.917278) (xy 22.030159 -262.966095) (xy 22.000411 -263.011059)
			(xy 21.964433 -263.051213) (xy 21.922991 -263.085701) (xy 21.87697 -263.113787) (xy 21.82735 -263.134874)
			(xy 21.775189 -263.14851) (xy 21.721598 -263.154407) (xy 21.667719 -263.152438) (xy 21.614701 -263.142645)
			(xy 21.563674 -263.125237) (xy 21.515726 -263.100585) (xy 21.471878 -263.069215) (xy 21.433065 -263.031794)
			(xy 21.400113 -262.989121) (xy 21.373727 -262.942104) (xy 21.354467 -262.891747) (xy 21.342744 -262.839123)
			(xy 21.338809 -262.785352) (xy 15.598394 -262.785352) (xy 15.598394 -263.635236) (xy 17.238741 -263.635236)
			(xy 17.242676 -263.581465) (xy 17.254399 -263.528841) (xy 17.273659 -263.478484) (xy 17.300045 -263.431467)
			(xy 17.332997 -263.388794) (xy 17.37181 -263.351373) (xy 17.415658 -263.320003) (xy 17.463606 -263.295351)
			(xy 17.514633 -263.277943) (xy 17.567651 -263.26815) (xy 17.62153 -263.266181) (xy 17.675121 -263.272078)
			(xy 17.727282 -263.285714) (xy 17.776902 -263.306801) (xy 17.822923 -263.334887) (xy 17.864365 -263.369375)
			(xy 17.900343 -263.409529) (xy 17.930091 -263.454493) (xy 17.952976 -263.50331) (xy 17.968508 -263.554939)
			(xy 17.976358 -263.608279) (xy 17.97685 -263.635236) (xy 24.782795 -263.635236) (xy 24.78673 -263.581465)
			(xy 24.798453 -263.528841) (xy 24.817713 -263.478484) (xy 24.844099 -263.431467) (xy 24.877051 -263.388794)
			(xy 24.915864 -263.351373) (xy 24.959712 -263.320003) (xy 25.00766 -263.295351) (xy 25.058687 -263.277943)
			(xy 25.111705 -263.26815) (xy 25.165584 -263.266181) (xy 25.219175 -263.272078) (xy 25.271336 -263.285714)
			(xy 25.320956 -263.306801) (xy 25.366977 -263.334887) (xy 25.408419 -263.369375) (xy 25.444397 -263.409529)
			(xy 25.474145 -263.454493) (xy 25.49703 -263.50331) (xy 25.512562 -263.554939) (xy 25.520412 -263.608279)
			(xy 25.520904 -263.635236) (xy 32.326595 -263.635236) (xy 32.33053 -263.581465) (xy 32.342253 -263.528841)
			(xy 32.361513 -263.478484) (xy 32.387899 -263.431467) (xy 32.420851 -263.388794) (xy 32.459664 -263.351373)
			(xy 32.503512 -263.320003) (xy 32.55146 -263.295351) (xy 32.602487 -263.277943) (xy 32.655505 -263.26815)
			(xy 32.709384 -263.266181) (xy 32.762975 -263.272078) (xy 32.815136 -263.285714) (xy 32.864756 -263.306801)
			(xy 32.910777 -263.334887) (xy 32.952219 -263.369375) (xy 32.988197 -263.409529) (xy 33.017945 -263.454493)
			(xy 33.04083 -263.50331) (xy 33.056362 -263.554939) (xy 33.064212 -263.608279) (xy 33.064704 -263.635236)
			(xy 39.870649 -263.635236) (xy 39.874584 -263.581465) (xy 39.886307 -263.528841) (xy 39.905567 -263.478484)
			(xy 39.931953 -263.431467) (xy 39.964905 -263.388794) (xy 40.003718 -263.351373) (xy 40.047566 -263.320003)
			(xy 40.095514 -263.295351) (xy 40.146541 -263.277943) (xy 40.199559 -263.26815) (xy 40.253438 -263.266181)
			(xy 40.307029 -263.272078) (xy 40.35919 -263.285714) (xy 40.40881 -263.306801) (xy 40.454831 -263.334887)
			(xy 40.496273 -263.369375) (xy 40.532251 -263.409529) (xy 40.561999 -263.454493) (xy 40.584884 -263.50331)
			(xy 40.600416 -263.554939) (xy 40.608266 -263.608279) (xy 40.608758 -263.635236) (xy 40.608266 -263.662193)
			(xy 40.600416 -263.715533) (xy 40.584884 -263.767162) (xy 40.561999 -263.815979) (xy 40.532251 -263.860943)
			(xy 40.496273 -263.901097) (xy 40.454831 -263.935585) (xy 40.40881 -263.963671) (xy 40.35919 -263.984758)
			(xy 40.307029 -263.998394) (xy 40.253438 -264.004291) (xy 40.199559 -264.002322) (xy 40.146541 -263.992529)
			(xy 40.095514 -263.975121) (xy 40.047566 -263.950469) (xy 40.003718 -263.919099) (xy 39.964905 -263.881678)
			(xy 39.931953 -263.839005) (xy 39.905567 -263.791988) (xy 39.886307 -263.741631) (xy 39.874584 -263.689007)
			(xy 39.870649 -263.635236) (xy 33.064704 -263.635236) (xy 33.064212 -263.662193) (xy 33.056362 -263.715533)
			(xy 33.04083 -263.767162) (xy 33.017945 -263.815979) (xy 32.988197 -263.860943) (xy 32.952219 -263.901097)
			(xy 32.910777 -263.935585) (xy 32.864756 -263.963671) (xy 32.815136 -263.984758) (xy 32.762975 -263.998394)
			(xy 32.709384 -264.004291) (xy 32.655505 -264.002322) (xy 32.602487 -263.992529) (xy 32.55146 -263.975121)
			(xy 32.503512 -263.950469) (xy 32.459664 -263.919099) (xy 32.420851 -263.881678) (xy 32.387899 -263.839005)
			(xy 32.361513 -263.791988) (xy 32.342253 -263.741631) (xy 32.33053 -263.689007) (xy 32.326595 -263.635236)
			(xy 25.520904 -263.635236) (xy 25.520412 -263.662193) (xy 25.512562 -263.715533) (xy 25.49703 -263.767162)
			(xy 25.474145 -263.815979) (xy 25.444397 -263.860943) (xy 25.408419 -263.901097) (xy 25.366977 -263.935585)
			(xy 25.320956 -263.963671) (xy 25.271336 -263.984758) (xy 25.219175 -263.998394) (xy 25.165584 -264.004291)
			(xy 25.111705 -264.002322) (xy 25.058687 -263.992529) (xy 25.00766 -263.975121) (xy 24.959712 -263.950469)
			(xy 24.915864 -263.919099) (xy 24.877051 -263.881678) (xy 24.844099 -263.839005) (xy 24.817713 -263.791988)
			(xy 24.798453 -263.741631) (xy 24.78673 -263.689007) (xy 24.782795 -263.635236) (xy 17.97685 -263.635236)
			(xy 17.976358 -263.662193) (xy 17.968508 -263.715533) (xy 17.952976 -263.767162) (xy 17.930091 -263.815979)
			(xy 17.900343 -263.860943) (xy 17.864365 -263.901097) (xy 17.822923 -263.935585) (xy 17.776902 -263.963671)
			(xy 17.727282 -263.984758) (xy 17.675121 -263.998394) (xy 17.62153 -264.004291) (xy 17.567651 -264.002322)
			(xy 17.514633 -263.992529) (xy 17.463606 -263.975121) (xy 17.415658 -263.950469) (xy 17.37181 -263.919099)
			(xy 17.332997 -263.881678) (xy 17.300045 -263.839005) (xy 17.273659 -263.791988) (xy 17.254399 -263.741631)
			(xy 17.242676 -263.689007) (xy 17.238741 -263.635236) (xy 15.598394 -263.635236) (xy 15.598394 -264.485374)
			(xy 21.338809 -264.485374) (xy 21.342744 -264.431603) (xy 21.354467 -264.378979) (xy 21.373727 -264.328622)
			(xy 21.400113 -264.281605) (xy 21.433065 -264.238932) (xy 21.471878 -264.201511) (xy 21.515726 -264.170141)
			(xy 21.563674 -264.145489) (xy 21.614701 -264.128081) (xy 21.667719 -264.118288) (xy 21.721598 -264.116319)
			(xy 21.775189 -264.122216) (xy 21.82735 -264.135852) (xy 21.87697 -264.156939) (xy 21.922991 -264.185025)
			(xy 21.964433 -264.219513) (xy 22.000411 -264.259667) (xy 22.030159 -264.304631) (xy 22.053044 -264.353448)
			(xy 22.068576 -264.405077) (xy 22.076426 -264.458417) (xy 22.076918 -264.485374) (xy 28.882863 -264.485374)
			(xy 28.886798 -264.431603) (xy 28.898521 -264.378979) (xy 28.917781 -264.328622) (xy 28.944167 -264.281605)
			(xy 28.977119 -264.238932) (xy 29.015932 -264.201511) (xy 29.05978 -264.170141) (xy 29.107728 -264.145489)
			(xy 29.158755 -264.128081) (xy 29.211773 -264.118288) (xy 29.265652 -264.116319) (xy 29.319243 -264.122216)
			(xy 29.371404 -264.135852) (xy 29.421024 -264.156939) (xy 29.467045 -264.185025) (xy 29.508487 -264.219513)
			(xy 29.544465 -264.259667) (xy 29.574213 -264.304631) (xy 29.597098 -264.353448) (xy 29.61263 -264.405077)
			(xy 29.62048 -264.458417) (xy 29.620972 -264.485374) (xy 36.426663 -264.485374) (xy 36.430598 -264.431603)
			(xy 36.442321 -264.378979) (xy 36.461581 -264.328622) (xy 36.487967 -264.281605) (xy 36.520919 -264.238932)
			(xy 36.559732 -264.201511) (xy 36.60358 -264.170141) (xy 36.651528 -264.145489) (xy 36.702555 -264.128081)
			(xy 36.755573 -264.118288) (xy 36.809452 -264.116319) (xy 36.863043 -264.122216) (xy 36.915204 -264.135852)
			(xy 36.964824 -264.156939) (xy 37.010845 -264.185025) (xy 37.052287 -264.219513) (xy 37.088265 -264.259667)
			(xy 37.118013 -264.304631) (xy 37.140898 -264.353448) (xy 37.15643 -264.405077) (xy 37.16428 -264.458417)
			(xy 37.164772 -264.485374) (xy 43.970717 -264.485374) (xy 43.974652 -264.431603) (xy 43.986375 -264.378979)
			(xy 44.005635 -264.328622) (xy 44.032021 -264.281605) (xy 44.064973 -264.238932) (xy 44.103786 -264.201511)
			(xy 44.147634 -264.170141) (xy 44.195582 -264.145489) (xy 44.246609 -264.128081) (xy 44.299627 -264.118288)
			(xy 44.353506 -264.116319) (xy 44.407097 -264.122216) (xy 44.459258 -264.135852) (xy 44.508878 -264.156939)
			(xy 44.554899 -264.185025) (xy 44.596341 -264.219513) (xy 44.632319 -264.259667) (xy 44.662067 -264.304631)
			(xy 44.684952 -264.353448) (xy 44.700484 -264.405077) (xy 44.708334 -264.458417) (xy 44.708826 -264.485374)
			(xy 44.708334 -264.512331) (xy 44.700484 -264.565671) (xy 44.684952 -264.6173) (xy 44.662067 -264.666117)
			(xy 44.632319 -264.711081) (xy 44.596341 -264.751235) (xy 44.554899 -264.785723) (xy 44.508878 -264.813809)
			(xy 44.459258 -264.834896) (xy 44.407097 -264.848532) (xy 44.353506 -264.854429) (xy 44.299627 -264.85246)
			(xy 44.246609 -264.842667) (xy 44.195582 -264.825259) (xy 44.147634 -264.800607) (xy 44.103786 -264.769237)
			(xy 44.064973 -264.731816) (xy 44.032021 -264.689143) (xy 44.005635 -264.642126) (xy 43.986375 -264.591769)
			(xy 43.974652 -264.539145) (xy 43.970717 -264.485374) (xy 37.164772 -264.485374) (xy 37.16428 -264.512331)
			(xy 37.15643 -264.565671) (xy 37.140898 -264.6173) (xy 37.118013 -264.666117) (xy 37.088265 -264.711081)
			(xy 37.052287 -264.751235) (xy 37.010845 -264.785723) (xy 36.964824 -264.813809) (xy 36.915204 -264.834896)
			(xy 36.863043 -264.848532) (xy 36.809452 -264.854429) (xy 36.755573 -264.85246) (xy 36.702555 -264.842667)
			(xy 36.651528 -264.825259) (xy 36.60358 -264.800607) (xy 36.559732 -264.769237) (xy 36.520919 -264.731816)
			(xy 36.487967 -264.689143) (xy 36.461581 -264.642126) (xy 36.442321 -264.591769) (xy 36.430598 -264.539145)
			(xy 36.426663 -264.485374) (xy 29.620972 -264.485374) (xy 29.62048 -264.512331) (xy 29.61263 -264.565671)
			(xy 29.597098 -264.6173) (xy 29.574213 -264.666117) (xy 29.544465 -264.711081) (xy 29.508487 -264.751235)
			(xy 29.467045 -264.785723) (xy 29.421024 -264.813809) (xy 29.371404 -264.834896) (xy 29.319243 -264.848532)
			(xy 29.265652 -264.854429) (xy 29.211773 -264.85246) (xy 29.158755 -264.842667) (xy 29.107728 -264.825259)
			(xy 29.05978 -264.800607) (xy 29.015932 -264.769237) (xy 28.977119 -264.731816) (xy 28.944167 -264.689143)
			(xy 28.917781 -264.642126) (xy 28.898521 -264.591769) (xy 28.886798 -264.539145) (xy 28.882863 -264.485374)
			(xy 22.076918 -264.485374) (xy 22.076426 -264.512331) (xy 22.068576 -264.565671) (xy 22.053044 -264.6173)
			(xy 22.030159 -264.666117) (xy 22.000411 -264.711081) (xy 21.964433 -264.751235) (xy 21.922991 -264.785723)
			(xy 21.87697 -264.813809) (xy 21.82735 -264.834896) (xy 21.775189 -264.848532) (xy 21.721598 -264.854429)
			(xy 21.667719 -264.85246) (xy 21.614701 -264.842667) (xy 21.563674 -264.825259) (xy 21.515726 -264.800607)
			(xy 21.471878 -264.769237) (xy 21.433065 -264.731816) (xy 21.400113 -264.689143) (xy 21.373727 -264.642126)
			(xy 21.354467 -264.591769) (xy 21.342744 -264.539145) (xy 21.338809 -264.485374) (xy 15.598394 -264.485374)
			(xy 15.598394 -265.335258) (xy 17.238741 -265.335258) (xy 17.242676 -265.281487) (xy 17.254399 -265.228863)
			(xy 17.273659 -265.178506) (xy 17.300045 -265.131489) (xy 17.332997 -265.088816) (xy 17.37181 -265.051395)
			(xy 17.415658 -265.020025) (xy 17.463606 -264.995373) (xy 17.514633 -264.977965) (xy 17.567651 -264.968172)
			(xy 17.62153 -264.966203) (xy 17.675121 -264.9721) (xy 17.727282 -264.985736) (xy 17.776902 -265.006823)
			(xy 17.822923 -265.034909) (xy 17.864365 -265.069397) (xy 17.900343 -265.109551) (xy 17.930091 -265.154515)
			(xy 17.952976 -265.203332) (xy 17.968508 -265.254961) (xy 17.976358 -265.308301) (xy 17.97685 -265.335258)
			(xy 24.782795 -265.335258) (xy 24.78673 -265.281487) (xy 24.798453 -265.228863) (xy 24.817713 -265.178506)
			(xy 24.844099 -265.131489) (xy 24.877051 -265.088816) (xy 24.915864 -265.051395) (xy 24.959712 -265.020025)
			(xy 25.00766 -264.995373) (xy 25.058687 -264.977965) (xy 25.111705 -264.968172) (xy 25.165584 -264.966203)
			(xy 25.219175 -264.9721) (xy 25.271336 -264.985736) (xy 25.320956 -265.006823) (xy 25.366977 -265.034909)
			(xy 25.408419 -265.069397) (xy 25.444397 -265.109551) (xy 25.474145 -265.154515) (xy 25.49703 -265.203332)
			(xy 25.512562 -265.254961) (xy 25.520412 -265.308301) (xy 25.520904 -265.335258) (xy 32.326595 -265.335258)
			(xy 32.33053 -265.281487) (xy 32.342253 -265.228863) (xy 32.361513 -265.178506) (xy 32.387899 -265.131489)
			(xy 32.420851 -265.088816) (xy 32.459664 -265.051395) (xy 32.503512 -265.020025) (xy 32.55146 -264.995373)
			(xy 32.602487 -264.977965) (xy 32.655505 -264.968172) (xy 32.709384 -264.966203) (xy 32.762975 -264.9721)
			(xy 32.815136 -264.985736) (xy 32.864756 -265.006823) (xy 32.910777 -265.034909) (xy 32.952219 -265.069397)
			(xy 32.988197 -265.109551) (xy 33.017945 -265.154515) (xy 33.04083 -265.203332) (xy 33.056362 -265.254961)
			(xy 33.064212 -265.308301) (xy 33.064704 -265.335258) (xy 39.870649 -265.335258) (xy 39.874584 -265.281487)
			(xy 39.886307 -265.228863) (xy 39.905567 -265.178506) (xy 39.931953 -265.131489) (xy 39.964905 -265.088816)
			(xy 40.003718 -265.051395) (xy 40.047566 -265.020025) (xy 40.095514 -264.995373) (xy 40.146541 -264.977965)
			(xy 40.199559 -264.968172) (xy 40.253438 -264.966203) (xy 40.307029 -264.9721) (xy 40.35919 -264.985736)
			(xy 40.40881 -265.006823) (xy 40.454831 -265.034909) (xy 40.496273 -265.069397) (xy 40.532251 -265.109551)
			(xy 40.561999 -265.154515) (xy 40.584884 -265.203332) (xy 40.600416 -265.254961) (xy 40.608266 -265.308301)
			(xy 40.608758 -265.335258) (xy 40.608266 -265.362215) (xy 40.600416 -265.415555) (xy 40.584884 -265.467184)
			(xy 40.561999 -265.516001) (xy 40.532251 -265.560965) (xy 40.496273 -265.601119) (xy 40.454831 -265.635607)
			(xy 40.40881 -265.663693) (xy 40.35919 -265.68478) (xy 40.307029 -265.698416) (xy 40.253438 -265.704313)
			(xy 40.199559 -265.702344) (xy 40.146541 -265.692551) (xy 40.095514 -265.675143) (xy 40.047566 -265.650491)
			(xy 40.003718 -265.619121) (xy 39.964905 -265.5817) (xy 39.931953 -265.539027) (xy 39.905567 -265.49201)
			(xy 39.886307 -265.441653) (xy 39.874584 -265.389029) (xy 39.870649 -265.335258) (xy 33.064704 -265.335258)
			(xy 33.064212 -265.362215) (xy 33.056362 -265.415555) (xy 33.04083 -265.467184) (xy 33.017945 -265.516001)
			(xy 32.988197 -265.560965) (xy 32.952219 -265.601119) (xy 32.910777 -265.635607) (xy 32.864756 -265.663693)
			(xy 32.815136 -265.68478) (xy 32.762975 -265.698416) (xy 32.709384 -265.704313) (xy 32.655505 -265.702344)
			(xy 32.602487 -265.692551) (xy 32.55146 -265.675143) (xy 32.503512 -265.650491) (xy 32.459664 -265.619121)
			(xy 32.420851 -265.5817) (xy 32.387899 -265.539027) (xy 32.361513 -265.49201) (xy 32.342253 -265.441653)
			(xy 32.33053 -265.389029) (xy 32.326595 -265.335258) (xy 25.520904 -265.335258) (xy 25.520412 -265.362215)
			(xy 25.512562 -265.415555) (xy 25.49703 -265.467184) (xy 25.474145 -265.516001) (xy 25.444397 -265.560965)
			(xy 25.408419 -265.601119) (xy 25.366977 -265.635607) (xy 25.320956 -265.663693) (xy 25.271336 -265.68478)
			(xy 25.219175 -265.698416) (xy 25.165584 -265.704313) (xy 25.111705 -265.702344) (xy 25.058687 -265.692551)
			(xy 25.00766 -265.675143) (xy 24.959712 -265.650491) (xy 24.915864 -265.619121) (xy 24.877051 -265.5817)
			(xy 24.844099 -265.539027) (xy 24.817713 -265.49201) (xy 24.798453 -265.441653) (xy 24.78673 -265.389029)
			(xy 24.782795 -265.335258) (xy 17.97685 -265.335258) (xy 17.976358 -265.362215) (xy 17.968508 -265.415555)
			(xy 17.952976 -265.467184) (xy 17.930091 -265.516001) (xy 17.900343 -265.560965) (xy 17.864365 -265.601119)
			(xy 17.822923 -265.635607) (xy 17.776902 -265.663693) (xy 17.727282 -265.68478) (xy 17.675121 -265.698416)
			(xy 17.62153 -265.704313) (xy 17.567651 -265.702344) (xy 17.514633 -265.692551) (xy 17.463606 -265.675143)
			(xy 17.415658 -265.650491) (xy 17.37181 -265.619121) (xy 17.332997 -265.5817) (xy 17.300045 -265.539027)
			(xy 17.273659 -265.49201) (xy 17.254399 -265.441653) (xy 17.242676 -265.389029) (xy 17.238741 -265.335258)
			(xy 15.598394 -265.335258) (xy 15.598394 -266.185396) (xy 21.338809 -266.185396) (xy 21.342744 -266.131625)
			(xy 21.354467 -266.079001) (xy 21.373727 -266.028644) (xy 21.400113 -265.981627) (xy 21.433065 -265.938954)
			(xy 21.471878 -265.901533) (xy 21.515726 -265.870163) (xy 21.563674 -265.845511) (xy 21.614701 -265.828103)
			(xy 21.667719 -265.81831) (xy 21.721598 -265.816341) (xy 21.775189 -265.822238) (xy 21.82735 -265.835874)
			(xy 21.87697 -265.856961) (xy 21.922991 -265.885047) (xy 21.964433 -265.919535) (xy 22.000411 -265.959689)
			(xy 22.030159 -266.004653) (xy 22.053044 -266.05347) (xy 22.068576 -266.105099) (xy 22.076426 -266.158439)
			(xy 22.076918 -266.185396) (xy 28.882863 -266.185396) (xy 28.886798 -266.131625) (xy 28.898521 -266.079001)
			(xy 28.917781 -266.028644) (xy 28.944167 -265.981627) (xy 28.977119 -265.938954) (xy 29.015932 -265.901533)
			(xy 29.05978 -265.870163) (xy 29.107728 -265.845511) (xy 29.158755 -265.828103) (xy 29.211773 -265.81831)
			(xy 29.265652 -265.816341) (xy 29.319243 -265.822238) (xy 29.371404 -265.835874) (xy 29.421024 -265.856961)
			(xy 29.467045 -265.885047) (xy 29.508487 -265.919535) (xy 29.544465 -265.959689) (xy 29.574213 -266.004653)
			(xy 29.597098 -266.05347) (xy 29.61263 -266.105099) (xy 29.62048 -266.158439) (xy 29.620972 -266.185396)
			(xy 36.426663 -266.185396) (xy 36.430598 -266.131625) (xy 36.442321 -266.079001) (xy 36.461581 -266.028644)
			(xy 36.487967 -265.981627) (xy 36.520919 -265.938954) (xy 36.559732 -265.901533) (xy 36.60358 -265.870163)
			(xy 36.651528 -265.845511) (xy 36.702555 -265.828103) (xy 36.755573 -265.81831) (xy 36.809452 -265.816341)
			(xy 36.863043 -265.822238) (xy 36.915204 -265.835874) (xy 36.964824 -265.856961) (xy 37.010845 -265.885047)
			(xy 37.052287 -265.919535) (xy 37.088265 -265.959689) (xy 37.118013 -266.004653) (xy 37.140898 -266.05347)
			(xy 37.15643 -266.105099) (xy 37.16428 -266.158439) (xy 37.164772 -266.185396) (xy 43.970717 -266.185396)
			(xy 43.974652 -266.131625) (xy 43.986375 -266.079001) (xy 44.005635 -266.028644) (xy 44.032021 -265.981627)
			(xy 44.064973 -265.938954) (xy 44.103786 -265.901533) (xy 44.147634 -265.870163) (xy 44.195582 -265.845511)
			(xy 44.246609 -265.828103) (xy 44.299627 -265.81831) (xy 44.353506 -265.816341) (xy 44.407097 -265.822238)
			(xy 44.459258 -265.835874) (xy 44.508878 -265.856961) (xy 44.554899 -265.885047) (xy 44.596341 -265.919535)
			(xy 44.632319 -265.959689) (xy 44.662067 -266.004653) (xy 44.684952 -266.05347) (xy 44.700484 -266.105099)
			(xy 44.708334 -266.158439) (xy 44.708826 -266.185396) (xy 44.708334 -266.212353) (xy 44.700484 -266.265693)
			(xy 44.684952 -266.317322) (xy 44.662067 -266.366139) (xy 44.632319 -266.411103) (xy 44.596341 -266.451257)
			(xy 44.554899 -266.485745) (xy 44.508878 -266.513831) (xy 44.459258 -266.534918) (xy 44.407097 -266.548554)
			(xy 44.353506 -266.554451) (xy 44.299627 -266.552482) (xy 44.246609 -266.542689) (xy 44.195582 -266.525281)
			(xy 44.147634 -266.500629) (xy 44.103786 -266.469259) (xy 44.064973 -266.431838) (xy 44.032021 -266.389165)
			(xy 44.005635 -266.342148) (xy 43.986375 -266.291791) (xy 43.974652 -266.239167) (xy 43.970717 -266.185396)
			(xy 37.164772 -266.185396) (xy 37.16428 -266.212353) (xy 37.15643 -266.265693) (xy 37.140898 -266.317322)
			(xy 37.118013 -266.366139) (xy 37.088265 -266.411103) (xy 37.052287 -266.451257) (xy 37.010845 -266.485745)
			(xy 36.964824 -266.513831) (xy 36.915204 -266.534918) (xy 36.863043 -266.548554) (xy 36.809452 -266.554451)
			(xy 36.755573 -266.552482) (xy 36.702555 -266.542689) (xy 36.651528 -266.525281) (xy 36.60358 -266.500629)
			(xy 36.559732 -266.469259) (xy 36.520919 -266.431838) (xy 36.487967 -266.389165) (xy 36.461581 -266.342148)
			(xy 36.442321 -266.291791) (xy 36.430598 -266.239167) (xy 36.426663 -266.185396) (xy 29.620972 -266.185396)
			(xy 29.62048 -266.212353) (xy 29.61263 -266.265693) (xy 29.597098 -266.317322) (xy 29.574213 -266.366139)
			(xy 29.544465 -266.411103) (xy 29.508487 -266.451257) (xy 29.467045 -266.485745) (xy 29.421024 -266.513831)
			(xy 29.371404 -266.534918) (xy 29.319243 -266.548554) (xy 29.265652 -266.554451) (xy 29.211773 -266.552482)
			(xy 29.158755 -266.542689) (xy 29.107728 -266.525281) (xy 29.05978 -266.500629) (xy 29.015932 -266.469259)
			(xy 28.977119 -266.431838) (xy 28.944167 -266.389165) (xy 28.917781 -266.342148) (xy 28.898521 -266.291791)
			(xy 28.886798 -266.239167) (xy 28.882863 -266.185396) (xy 22.076918 -266.185396) (xy 22.076426 -266.212353)
			(xy 22.068576 -266.265693) (xy 22.053044 -266.317322) (xy 22.030159 -266.366139) (xy 22.000411 -266.411103)
			(xy 21.964433 -266.451257) (xy 21.922991 -266.485745) (xy 21.87697 -266.513831) (xy 21.82735 -266.534918)
			(xy 21.775189 -266.548554) (xy 21.721598 -266.554451) (xy 21.667719 -266.552482) (xy 21.614701 -266.542689)
			(xy 21.563674 -266.525281) (xy 21.515726 -266.500629) (xy 21.471878 -266.469259) (xy 21.433065 -266.431838)
			(xy 21.400113 -266.389165) (xy 21.373727 -266.342148) (xy 21.354467 -266.291791) (xy 21.342744 -266.239167)
			(xy 21.338809 -266.185396) (xy 15.598394 -266.185396) (xy 15.598394 -267.03528) (xy 17.238741 -267.03528)
			(xy 17.242676 -266.981509) (xy 17.254399 -266.928885) (xy 17.273659 -266.878528) (xy 17.300045 -266.831511)
			(xy 17.332997 -266.788838) (xy 17.37181 -266.751417) (xy 17.415658 -266.720047) (xy 17.463606 -266.695395)
			(xy 17.514633 -266.677987) (xy 17.567651 -266.668194) (xy 17.62153 -266.666225) (xy 17.675121 -266.672122)
			(xy 17.727282 -266.685758) (xy 17.776902 -266.706845) (xy 17.822923 -266.734931) (xy 17.864365 -266.769419)
			(xy 17.900343 -266.809573) (xy 17.930091 -266.854537) (xy 17.952976 -266.903354) (xy 17.968508 -266.954983)
			(xy 17.976358 -267.008323) (xy 17.97685 -267.03528) (xy 24.782795 -267.03528) (xy 24.78673 -266.981509)
			(xy 24.798453 -266.928885) (xy 24.817713 -266.878528) (xy 24.844099 -266.831511) (xy 24.877051 -266.788838)
			(xy 24.915864 -266.751417) (xy 24.959712 -266.720047) (xy 25.00766 -266.695395) (xy 25.058687 -266.677987)
			(xy 25.111705 -266.668194) (xy 25.165584 -266.666225) (xy 25.219175 -266.672122) (xy 25.271336 -266.685758)
			(xy 25.320956 -266.706845) (xy 25.366977 -266.734931) (xy 25.408419 -266.769419) (xy 25.444397 -266.809573)
			(xy 25.474145 -266.854537) (xy 25.49703 -266.903354) (xy 25.512562 -266.954983) (xy 25.520412 -267.008323)
			(xy 25.520904 -267.03528) (xy 32.326595 -267.03528) (xy 32.33053 -266.981509) (xy 32.342253 -266.928885)
			(xy 32.361513 -266.878528) (xy 32.387899 -266.831511) (xy 32.420851 -266.788838) (xy 32.459664 -266.751417)
			(xy 32.503512 -266.720047) (xy 32.55146 -266.695395) (xy 32.602487 -266.677987) (xy 32.655505 -266.668194)
			(xy 32.709384 -266.666225) (xy 32.762975 -266.672122) (xy 32.815136 -266.685758) (xy 32.864756 -266.706845)
			(xy 32.910777 -266.734931) (xy 32.952219 -266.769419) (xy 32.988197 -266.809573) (xy 33.017945 -266.854537)
			(xy 33.04083 -266.903354) (xy 33.056362 -266.954983) (xy 33.064212 -267.008323) (xy 33.064704 -267.03528)
			(xy 39.870649 -267.03528) (xy 39.874584 -266.981509) (xy 39.886307 -266.928885) (xy 39.905567 -266.878528)
			(xy 39.931953 -266.831511) (xy 39.964905 -266.788838) (xy 40.003718 -266.751417) (xy 40.047566 -266.720047)
			(xy 40.095514 -266.695395) (xy 40.146541 -266.677987) (xy 40.199559 -266.668194) (xy 40.253438 -266.666225)
			(xy 40.307029 -266.672122) (xy 40.35919 -266.685758) (xy 40.40881 -266.706845) (xy 40.454831 -266.734931)
			(xy 40.496273 -266.769419) (xy 40.532251 -266.809573) (xy 40.561999 -266.854537) (xy 40.584884 -266.903354)
			(xy 40.600416 -266.954983) (xy 40.608266 -267.008323) (xy 40.608758 -267.03528) (xy 40.608266 -267.062237)
			(xy 40.600416 -267.115577) (xy 40.584884 -267.167206) (xy 40.561999 -267.216023) (xy 40.532251 -267.260987)
			(xy 40.496273 -267.301141) (xy 40.454831 -267.335629) (xy 40.40881 -267.363715) (xy 40.35919 -267.384802)
			(xy 40.307029 -267.398438) (xy 40.253438 -267.404335) (xy 40.199559 -267.402366) (xy 40.146541 -267.392573)
			(xy 40.095514 -267.375165) (xy 40.047566 -267.350513) (xy 40.003718 -267.319143) (xy 39.964905 -267.281722)
			(xy 39.931953 -267.239049) (xy 39.905567 -267.192032) (xy 39.886307 -267.141675) (xy 39.874584 -267.089051)
			(xy 39.870649 -267.03528) (xy 33.064704 -267.03528) (xy 33.064212 -267.062237) (xy 33.056362 -267.115577)
			(xy 33.04083 -267.167206) (xy 33.017945 -267.216023) (xy 32.988197 -267.260987) (xy 32.952219 -267.301141)
			(xy 32.910777 -267.335629) (xy 32.864756 -267.363715) (xy 32.815136 -267.384802) (xy 32.762975 -267.398438)
			(xy 32.709384 -267.404335) (xy 32.655505 -267.402366) (xy 32.602487 -267.392573) (xy 32.55146 -267.375165)
			(xy 32.503512 -267.350513) (xy 32.459664 -267.319143) (xy 32.420851 -267.281722) (xy 32.387899 -267.239049)
			(xy 32.361513 -267.192032) (xy 32.342253 -267.141675) (xy 32.33053 -267.089051) (xy 32.326595 -267.03528)
			(xy 25.520904 -267.03528) (xy 25.520412 -267.062237) (xy 25.512562 -267.115577) (xy 25.49703 -267.167206)
			(xy 25.474145 -267.216023) (xy 25.444397 -267.260987) (xy 25.408419 -267.301141) (xy 25.366977 -267.335629)
			(xy 25.320956 -267.363715) (xy 25.271336 -267.384802) (xy 25.219175 -267.398438) (xy 25.165584 -267.404335)
			(xy 25.111705 -267.402366) (xy 25.058687 -267.392573) (xy 25.00766 -267.375165) (xy 24.959712 -267.350513)
			(xy 24.915864 -267.319143) (xy 24.877051 -267.281722) (xy 24.844099 -267.239049) (xy 24.817713 -267.192032)
			(xy 24.798453 -267.141675) (xy 24.78673 -267.089051) (xy 24.782795 -267.03528) (xy 17.97685 -267.03528)
			(xy 17.976358 -267.062237) (xy 17.968508 -267.115577) (xy 17.952976 -267.167206) (xy 17.930091 -267.216023)
			(xy 17.900343 -267.260987) (xy 17.864365 -267.301141) (xy 17.822923 -267.335629) (xy 17.776902 -267.363715)
			(xy 17.727282 -267.384802) (xy 17.675121 -267.398438) (xy 17.62153 -267.404335) (xy 17.567651 -267.402366)
			(xy 17.514633 -267.392573) (xy 17.463606 -267.375165) (xy 17.415658 -267.350513) (xy 17.37181 -267.319143)
			(xy 17.332997 -267.281722) (xy 17.300045 -267.239049) (xy 17.273659 -267.192032) (xy 17.254399 -267.141675)
			(xy 17.242676 -267.089051) (xy 17.238741 -267.03528) (xy 15.598394 -267.03528) (xy 15.598394 -267.885418)
			(xy 21.338809 -267.885418) (xy 21.342744 -267.831647) (xy 21.354467 -267.779023) (xy 21.373727 -267.728666)
			(xy 21.400113 -267.681649) (xy 21.433065 -267.638976) (xy 21.471878 -267.601555) (xy 21.515726 -267.570185)
			(xy 21.563674 -267.545533) (xy 21.614701 -267.528125) (xy 21.667719 -267.518332) (xy 21.721598 -267.516363)
			(xy 21.775189 -267.52226) (xy 21.82735 -267.535896) (xy 21.87697 -267.556983) (xy 21.922991 -267.585069)
			(xy 21.964433 -267.619557) (xy 22.000411 -267.659711) (xy 22.030159 -267.704675) (xy 22.053044 -267.753492)
			(xy 22.068576 -267.805121) (xy 22.076426 -267.858461) (xy 22.076918 -267.885418) (xy 28.882863 -267.885418)
			(xy 28.886798 -267.831647) (xy 28.898521 -267.779023) (xy 28.917781 -267.728666) (xy 28.944167 -267.681649)
			(xy 28.977119 -267.638976) (xy 29.015932 -267.601555) (xy 29.05978 -267.570185) (xy 29.107728 -267.545533)
			(xy 29.158755 -267.528125) (xy 29.211773 -267.518332) (xy 29.265652 -267.516363) (xy 29.319243 -267.52226)
			(xy 29.371404 -267.535896) (xy 29.421024 -267.556983) (xy 29.467045 -267.585069) (xy 29.508487 -267.619557)
			(xy 29.544465 -267.659711) (xy 29.574213 -267.704675) (xy 29.597098 -267.753492) (xy 29.61263 -267.805121)
			(xy 29.62048 -267.858461) (xy 29.620972 -267.885418) (xy 36.426663 -267.885418) (xy 36.430598 -267.831647)
			(xy 36.442321 -267.779023) (xy 36.461581 -267.728666) (xy 36.487967 -267.681649) (xy 36.520919 -267.638976)
			(xy 36.559732 -267.601555) (xy 36.60358 -267.570185) (xy 36.651528 -267.545533) (xy 36.702555 -267.528125)
			(xy 36.755573 -267.518332) (xy 36.809452 -267.516363) (xy 36.863043 -267.52226) (xy 36.915204 -267.535896)
			(xy 36.964824 -267.556983) (xy 37.010845 -267.585069) (xy 37.052287 -267.619557) (xy 37.088265 -267.659711)
			(xy 37.118013 -267.704675) (xy 37.140898 -267.753492) (xy 37.15643 -267.805121) (xy 37.16428 -267.858461)
			(xy 37.164772 -267.885418) (xy 43.970717 -267.885418) (xy 43.974652 -267.831647) (xy 43.986375 -267.779023)
			(xy 44.005635 -267.728666) (xy 44.032021 -267.681649) (xy 44.064973 -267.638976) (xy 44.103786 -267.601555)
			(xy 44.147634 -267.570185) (xy 44.195582 -267.545533) (xy 44.246609 -267.528125) (xy 44.299627 -267.518332)
			(xy 44.353506 -267.516363) (xy 44.407097 -267.52226) (xy 44.459258 -267.535896) (xy 44.508878 -267.556983)
			(xy 44.554899 -267.585069) (xy 44.596341 -267.619557) (xy 44.632319 -267.659711) (xy 44.662067 -267.704675)
			(xy 44.684952 -267.753492) (xy 44.700484 -267.805121) (xy 44.708334 -267.858461) (xy 44.708826 -267.885418)
			(xy 44.708334 -267.912375) (xy 44.700484 -267.965715) (xy 44.684952 -268.017344) (xy 44.662067 -268.066161)
			(xy 44.632319 -268.111125) (xy 44.596341 -268.151279) (xy 44.554899 -268.185767) (xy 44.508878 -268.213853)
			(xy 44.459258 -268.23494) (xy 44.407097 -268.248576) (xy 44.353506 -268.254473) (xy 44.299627 -268.252504)
			(xy 44.246609 -268.242711) (xy 44.195582 -268.225303) (xy 44.147634 -268.200651) (xy 44.103786 -268.169281)
			(xy 44.064973 -268.13186) (xy 44.032021 -268.089187) (xy 44.005635 -268.04217) (xy 43.986375 -267.991813)
			(xy 43.974652 -267.939189) (xy 43.970717 -267.885418) (xy 37.164772 -267.885418) (xy 37.16428 -267.912375)
			(xy 37.15643 -267.965715) (xy 37.140898 -268.017344) (xy 37.118013 -268.066161) (xy 37.088265 -268.111125)
			(xy 37.052287 -268.151279) (xy 37.010845 -268.185767) (xy 36.964824 -268.213853) (xy 36.915204 -268.23494)
			(xy 36.863043 -268.248576) (xy 36.809452 -268.254473) (xy 36.755573 -268.252504) (xy 36.702555 -268.242711)
			(xy 36.651528 -268.225303) (xy 36.60358 -268.200651) (xy 36.559732 -268.169281) (xy 36.520919 -268.13186)
			(xy 36.487967 -268.089187) (xy 36.461581 -268.04217) (xy 36.442321 -267.991813) (xy 36.430598 -267.939189)
			(xy 36.426663 -267.885418) (xy 29.620972 -267.885418) (xy 29.62048 -267.912375) (xy 29.61263 -267.965715)
			(xy 29.597098 -268.017344) (xy 29.574213 -268.066161) (xy 29.544465 -268.111125) (xy 29.508487 -268.151279)
			(xy 29.467045 -268.185767) (xy 29.421024 -268.213853) (xy 29.371404 -268.23494) (xy 29.319243 -268.248576)
			(xy 29.265652 -268.254473) (xy 29.211773 -268.252504) (xy 29.158755 -268.242711) (xy 29.107728 -268.225303)
			(xy 29.05978 -268.200651) (xy 29.015932 -268.169281) (xy 28.977119 -268.13186) (xy 28.944167 -268.089187)
			(xy 28.917781 -268.04217) (xy 28.898521 -267.991813) (xy 28.886798 -267.939189) (xy 28.882863 -267.885418)
			(xy 22.076918 -267.885418) (xy 22.076426 -267.912375) (xy 22.068576 -267.965715) (xy 22.053044 -268.017344)
			(xy 22.030159 -268.066161) (xy 22.000411 -268.111125) (xy 21.964433 -268.151279) (xy 21.922991 -268.185767)
			(xy 21.87697 -268.213853) (xy 21.82735 -268.23494) (xy 21.775189 -268.248576) (xy 21.721598 -268.254473)
			(xy 21.667719 -268.252504) (xy 21.614701 -268.242711) (xy 21.563674 -268.225303) (xy 21.515726 -268.200651)
			(xy 21.471878 -268.169281) (xy 21.433065 -268.13186) (xy 21.400113 -268.089187) (xy 21.373727 -268.04217)
			(xy 21.354467 -267.991813) (xy 21.342744 -267.939189) (xy 21.338809 -267.885418) (xy 15.598394 -267.885418)
			(xy 15.598394 -268.735302) (xy 17.238741 -268.735302) (xy 17.242676 -268.681531) (xy 17.254399 -268.628907)
			(xy 17.273659 -268.57855) (xy 17.300045 -268.531533) (xy 17.332997 -268.48886) (xy 17.37181 -268.451439)
			(xy 17.415658 -268.420069) (xy 17.463606 -268.395417) (xy 17.514633 -268.378009) (xy 17.567651 -268.368216)
			(xy 17.62153 -268.366247) (xy 17.675121 -268.372144) (xy 17.727282 -268.38578) (xy 17.776902 -268.406867)
			(xy 17.822923 -268.434953) (xy 17.864365 -268.469441) (xy 17.900343 -268.509595) (xy 17.930091 -268.554559)
			(xy 17.952976 -268.603376) (xy 17.968508 -268.655005) (xy 17.976358 -268.708345) (xy 17.97685 -268.735302)
			(xy 24.782795 -268.735302) (xy 24.78673 -268.681531) (xy 24.798453 -268.628907) (xy 24.817713 -268.57855)
			(xy 24.844099 -268.531533) (xy 24.877051 -268.48886) (xy 24.915864 -268.451439) (xy 24.959712 -268.420069)
			(xy 25.00766 -268.395417) (xy 25.058687 -268.378009) (xy 25.111705 -268.368216) (xy 25.165584 -268.366247)
			(xy 25.219175 -268.372144) (xy 25.271336 -268.38578) (xy 25.320956 -268.406867) (xy 25.366977 -268.434953)
			(xy 25.408419 -268.469441) (xy 25.444397 -268.509595) (xy 25.474145 -268.554559) (xy 25.49703 -268.603376)
			(xy 25.512562 -268.655005) (xy 25.520412 -268.708345) (xy 25.520904 -268.735302) (xy 32.326595 -268.735302)
			(xy 32.33053 -268.681531) (xy 32.342253 -268.628907) (xy 32.361513 -268.57855) (xy 32.387899 -268.531533)
			(xy 32.420851 -268.48886) (xy 32.459664 -268.451439) (xy 32.503512 -268.420069) (xy 32.55146 -268.395417)
			(xy 32.602487 -268.378009) (xy 32.655505 -268.368216) (xy 32.709384 -268.366247) (xy 32.762975 -268.372144)
			(xy 32.815136 -268.38578) (xy 32.864756 -268.406867) (xy 32.910777 -268.434953) (xy 32.952219 -268.469441)
			(xy 32.988197 -268.509595) (xy 33.017945 -268.554559) (xy 33.04083 -268.603376) (xy 33.056362 -268.655005)
			(xy 33.064212 -268.708345) (xy 33.064704 -268.735302) (xy 39.870649 -268.735302) (xy 39.874584 -268.681531)
			(xy 39.886307 -268.628907) (xy 39.905567 -268.57855) (xy 39.931953 -268.531533) (xy 39.964905 -268.48886)
			(xy 40.003718 -268.451439) (xy 40.047566 -268.420069) (xy 40.095514 -268.395417) (xy 40.146541 -268.378009)
			(xy 40.199559 -268.368216) (xy 40.253438 -268.366247) (xy 40.307029 -268.372144) (xy 40.35919 -268.38578)
			(xy 40.40881 -268.406867) (xy 40.454831 -268.434953) (xy 40.496273 -268.469441) (xy 40.532251 -268.509595)
			(xy 40.561999 -268.554559) (xy 40.584884 -268.603376) (xy 40.600416 -268.655005) (xy 40.608266 -268.708345)
			(xy 40.608758 -268.735302) (xy 40.608266 -268.762259) (xy 40.600416 -268.815599) (xy 40.584884 -268.867228)
			(xy 40.561999 -268.916045) (xy 40.532251 -268.961009) (xy 40.496273 -269.001163) (xy 40.454831 -269.035651)
			(xy 40.40881 -269.063737) (xy 40.35919 -269.084824) (xy 40.307029 -269.09846) (xy 40.253438 -269.104357)
			(xy 40.199559 -269.102388) (xy 40.146541 -269.092595) (xy 40.095514 -269.075187) (xy 40.047566 -269.050535)
			(xy 40.003718 -269.019165) (xy 39.964905 -268.981744) (xy 39.931953 -268.939071) (xy 39.905567 -268.892054)
			(xy 39.886307 -268.841697) (xy 39.874584 -268.789073) (xy 39.870649 -268.735302) (xy 33.064704 -268.735302)
			(xy 33.064212 -268.762259) (xy 33.056362 -268.815599) (xy 33.04083 -268.867228) (xy 33.017945 -268.916045)
			(xy 32.988197 -268.961009) (xy 32.952219 -269.001163) (xy 32.910777 -269.035651) (xy 32.864756 -269.063737)
			(xy 32.815136 -269.084824) (xy 32.762975 -269.09846) (xy 32.709384 -269.104357) (xy 32.655505 -269.102388)
			(xy 32.602487 -269.092595) (xy 32.55146 -269.075187) (xy 32.503512 -269.050535) (xy 32.459664 -269.019165)
			(xy 32.420851 -268.981744) (xy 32.387899 -268.939071) (xy 32.361513 -268.892054) (xy 32.342253 -268.841697)
			(xy 32.33053 -268.789073) (xy 32.326595 -268.735302) (xy 25.520904 -268.735302) (xy 25.520412 -268.762259)
			(xy 25.512562 -268.815599) (xy 25.49703 -268.867228) (xy 25.474145 -268.916045) (xy 25.444397 -268.961009)
			(xy 25.408419 -269.001163) (xy 25.366977 -269.035651) (xy 25.320956 -269.063737) (xy 25.271336 -269.084824)
			(xy 25.219175 -269.09846) (xy 25.165584 -269.104357) (xy 25.111705 -269.102388) (xy 25.058687 -269.092595)
			(xy 25.00766 -269.075187) (xy 24.959712 -269.050535) (xy 24.915864 -269.019165) (xy 24.877051 -268.981744)
			(xy 24.844099 -268.939071) (xy 24.817713 -268.892054) (xy 24.798453 -268.841697) (xy 24.78673 -268.789073)
			(xy 24.782795 -268.735302) (xy 17.97685 -268.735302) (xy 17.976358 -268.762259) (xy 17.968508 -268.815599)
			(xy 17.952976 -268.867228) (xy 17.930091 -268.916045) (xy 17.900343 -268.961009) (xy 17.864365 -269.001163)
			(xy 17.822923 -269.035651) (xy 17.776902 -269.063737) (xy 17.727282 -269.084824) (xy 17.675121 -269.09846)
			(xy 17.62153 -269.104357) (xy 17.567651 -269.102388) (xy 17.514633 -269.092595) (xy 17.463606 -269.075187)
			(xy 17.415658 -269.050535) (xy 17.37181 -269.019165) (xy 17.332997 -268.981744) (xy 17.300045 -268.939071)
			(xy 17.273659 -268.892054) (xy 17.254399 -268.841697) (xy 17.242676 -268.789073) (xy 17.238741 -268.735302)
			(xy 15.598394 -268.735302) (xy 15.598394 -269.58544) (xy 21.338809 -269.58544) (xy 21.342744 -269.531669)
			(xy 21.354467 -269.479045) (xy 21.373727 -269.428688) (xy 21.400113 -269.381671) (xy 21.433065 -269.338998)
			(xy 21.471878 -269.301577) (xy 21.515726 -269.270207) (xy 21.563674 -269.245555) (xy 21.614701 -269.228147)
			(xy 21.667719 -269.218354) (xy 21.721598 -269.216385) (xy 21.775189 -269.222282) (xy 21.82735 -269.235918)
			(xy 21.87697 -269.257005) (xy 21.922991 -269.285091) (xy 21.964433 -269.319579) (xy 22.000411 -269.359733)
			(xy 22.030159 -269.404697) (xy 22.053044 -269.453514) (xy 22.068576 -269.505143) (xy 22.076426 -269.558483)
			(xy 22.076918 -269.58544) (xy 28.882863 -269.58544) (xy 28.886798 -269.531669) (xy 28.898521 -269.479045)
			(xy 28.917781 -269.428688) (xy 28.944167 -269.381671) (xy 28.977119 -269.338998) (xy 29.015932 -269.301577)
			(xy 29.05978 -269.270207) (xy 29.107728 -269.245555) (xy 29.158755 -269.228147) (xy 29.211773 -269.218354)
			(xy 29.265652 -269.216385) (xy 29.319243 -269.222282) (xy 29.371404 -269.235918) (xy 29.421024 -269.257005)
			(xy 29.467045 -269.285091) (xy 29.508487 -269.319579) (xy 29.544465 -269.359733) (xy 29.574213 -269.404697)
			(xy 29.597098 -269.453514) (xy 29.61263 -269.505143) (xy 29.62048 -269.558483) (xy 29.620972 -269.58544)
			(xy 36.426663 -269.58544) (xy 36.430598 -269.531669) (xy 36.442321 -269.479045) (xy 36.461581 -269.428688)
			(xy 36.487967 -269.381671) (xy 36.520919 -269.338998) (xy 36.559732 -269.301577) (xy 36.60358 -269.270207)
			(xy 36.651528 -269.245555) (xy 36.702555 -269.228147) (xy 36.755573 -269.218354) (xy 36.809452 -269.216385)
			(xy 36.863043 -269.222282) (xy 36.915204 -269.235918) (xy 36.964824 -269.257005) (xy 37.010845 -269.285091)
			(xy 37.052287 -269.319579) (xy 37.088265 -269.359733) (xy 37.118013 -269.404697) (xy 37.140898 -269.453514)
			(xy 37.15643 -269.505143) (xy 37.16428 -269.558483) (xy 37.164772 -269.58544) (xy 43.970717 -269.58544)
			(xy 43.974652 -269.531669) (xy 43.986375 -269.479045) (xy 44.005635 -269.428688) (xy 44.032021 -269.381671)
			(xy 44.064973 -269.338998) (xy 44.103786 -269.301577) (xy 44.147634 -269.270207) (xy 44.195582 -269.245555)
			(xy 44.246609 -269.228147) (xy 44.299627 -269.218354) (xy 44.353506 -269.216385) (xy 44.407097 -269.222282)
			(xy 44.459258 -269.235918) (xy 44.508878 -269.257005) (xy 44.554899 -269.285091) (xy 44.596341 -269.319579)
			(xy 44.632319 -269.359733) (xy 44.662067 -269.404697) (xy 44.684952 -269.453514) (xy 44.700484 -269.505143)
			(xy 44.708334 -269.558483) (xy 44.708826 -269.58544) (xy 44.708334 -269.612397) (xy 44.700484 -269.665737)
			(xy 44.684952 -269.717366) (xy 44.662067 -269.766183) (xy 44.632319 -269.811147) (xy 44.596341 -269.851301)
			(xy 44.554899 -269.885789) (xy 44.508878 -269.913875) (xy 44.459258 -269.934962) (xy 44.407097 -269.948598)
			(xy 44.353506 -269.954495) (xy 44.299627 -269.952526) (xy 44.246609 -269.942733) (xy 44.195582 -269.925325)
			(xy 44.147634 -269.900673) (xy 44.103786 -269.869303) (xy 44.064973 -269.831882) (xy 44.032021 -269.789209)
			(xy 44.005635 -269.742192) (xy 43.986375 -269.691835) (xy 43.974652 -269.639211) (xy 43.970717 -269.58544)
			(xy 37.164772 -269.58544) (xy 37.16428 -269.612397) (xy 37.15643 -269.665737) (xy 37.140898 -269.717366)
			(xy 37.118013 -269.766183) (xy 37.088265 -269.811147) (xy 37.052287 -269.851301) (xy 37.010845 -269.885789)
			(xy 36.964824 -269.913875) (xy 36.915204 -269.934962) (xy 36.863043 -269.948598) (xy 36.809452 -269.954495)
			(xy 36.755573 -269.952526) (xy 36.702555 -269.942733) (xy 36.651528 -269.925325) (xy 36.60358 -269.900673)
			(xy 36.559732 -269.869303) (xy 36.520919 -269.831882) (xy 36.487967 -269.789209) (xy 36.461581 -269.742192)
			(xy 36.442321 -269.691835) (xy 36.430598 -269.639211) (xy 36.426663 -269.58544) (xy 29.620972 -269.58544)
			(xy 29.62048 -269.612397) (xy 29.61263 -269.665737) (xy 29.597098 -269.717366) (xy 29.574213 -269.766183)
			(xy 29.544465 -269.811147) (xy 29.508487 -269.851301) (xy 29.467045 -269.885789) (xy 29.421024 -269.913875)
			(xy 29.371404 -269.934962) (xy 29.319243 -269.948598) (xy 29.265652 -269.954495) (xy 29.211773 -269.952526)
			(xy 29.158755 -269.942733) (xy 29.107728 -269.925325) (xy 29.05978 -269.900673) (xy 29.015932 -269.869303)
			(xy 28.977119 -269.831882) (xy 28.944167 -269.789209) (xy 28.917781 -269.742192) (xy 28.898521 -269.691835)
			(xy 28.886798 -269.639211) (xy 28.882863 -269.58544) (xy 22.076918 -269.58544) (xy 22.076426 -269.612397)
			(xy 22.068576 -269.665737) (xy 22.053044 -269.717366) (xy 22.030159 -269.766183) (xy 22.000411 -269.811147)
			(xy 21.964433 -269.851301) (xy 21.922991 -269.885789) (xy 21.87697 -269.913875) (xy 21.82735 -269.934962)
			(xy 21.775189 -269.948598) (xy 21.721598 -269.954495) (xy 21.667719 -269.952526) (xy 21.614701 -269.942733)
			(xy 21.563674 -269.925325) (xy 21.515726 -269.900673) (xy 21.471878 -269.869303) (xy 21.433065 -269.831882)
			(xy 21.400113 -269.789209) (xy 21.373727 -269.742192) (xy 21.354467 -269.691835) (xy 21.342744 -269.639211)
			(xy 21.338809 -269.58544) (xy 15.598394 -269.58544) (xy 15.598394 -270.435324) (xy 17.238741 -270.435324)
			(xy 17.242676 -270.381553) (xy 17.254399 -270.328929) (xy 17.273659 -270.278572) (xy 17.300045 -270.231555)
			(xy 17.332997 -270.188882) (xy 17.37181 -270.151461) (xy 17.415658 -270.120091) (xy 17.463606 -270.095439)
			(xy 17.514633 -270.078031) (xy 17.567651 -270.068238) (xy 17.62153 -270.066269) (xy 17.675121 -270.072166)
			(xy 17.727282 -270.085802) (xy 17.776902 -270.106889) (xy 17.822923 -270.134975) (xy 17.864365 -270.169463)
			(xy 17.900343 -270.209617) (xy 17.930091 -270.254581) (xy 17.952976 -270.303398) (xy 17.968508 -270.355027)
			(xy 17.976358 -270.408367) (xy 17.97685 -270.435324) (xy 21.338809 -270.435324) (xy 21.342744 -270.381553)
			(xy 21.354467 -270.328929) (xy 21.373727 -270.278572) (xy 21.400113 -270.231555) (xy 21.433065 -270.188882)
			(xy 21.471878 -270.151461) (xy 21.515726 -270.120091) (xy 21.563674 -270.095439) (xy 21.614701 -270.078031)
			(xy 21.667719 -270.068238) (xy 21.721598 -270.066269) (xy 21.775189 -270.072166) (xy 21.82735 -270.085802)
			(xy 21.87697 -270.106889) (xy 21.922991 -270.134975) (xy 21.964433 -270.169463) (xy 22.000411 -270.209617)
			(xy 22.030159 -270.254581) (xy 22.053044 -270.303398) (xy 22.068576 -270.355027) (xy 22.076426 -270.408367)
			(xy 22.076918 -270.435324) (xy 24.782795 -270.435324) (xy 24.78673 -270.381553) (xy 24.798453 -270.328929)
			(xy 24.817713 -270.278572) (xy 24.844099 -270.231555) (xy 24.877051 -270.188882) (xy 24.915864 -270.151461)
			(xy 24.959712 -270.120091) (xy 25.00766 -270.095439) (xy 25.058687 -270.078031) (xy 25.111705 -270.068238)
			(xy 25.165584 -270.066269) (xy 25.219175 -270.072166) (xy 25.271336 -270.085802) (xy 25.320956 -270.106889)
			(xy 25.366977 -270.134975) (xy 25.408419 -270.169463) (xy 25.444397 -270.209617) (xy 25.474145 -270.254581)
			(xy 25.49703 -270.303398) (xy 25.512562 -270.355027) (xy 25.520412 -270.408367) (xy 25.520904 -270.435324)
			(xy 28.882863 -270.435324) (xy 28.886798 -270.381553) (xy 28.898521 -270.328929) (xy 28.917781 -270.278572)
			(xy 28.944167 -270.231555) (xy 28.977119 -270.188882) (xy 29.015932 -270.151461) (xy 29.05978 -270.120091)
			(xy 29.107728 -270.095439) (xy 29.158755 -270.078031) (xy 29.211773 -270.068238) (xy 29.265652 -270.066269)
			(xy 29.319243 -270.072166) (xy 29.371404 -270.085802) (xy 29.421024 -270.106889) (xy 29.467045 -270.134975)
			(xy 29.508487 -270.169463) (xy 29.544465 -270.209617) (xy 29.574213 -270.254581) (xy 29.597098 -270.303398)
			(xy 29.61263 -270.355027) (xy 29.62048 -270.408367) (xy 29.620972 -270.435324) (xy 32.326595 -270.435324)
			(xy 32.33053 -270.381553) (xy 32.342253 -270.328929) (xy 32.361513 -270.278572) (xy 32.387899 -270.231555)
			(xy 32.420851 -270.188882) (xy 32.459664 -270.151461) (xy 32.503512 -270.120091) (xy 32.55146 -270.095439)
			(xy 32.602487 -270.078031) (xy 32.655505 -270.068238) (xy 32.709384 -270.066269) (xy 32.762975 -270.072166)
			(xy 32.815136 -270.085802) (xy 32.864756 -270.106889) (xy 32.910777 -270.134975) (xy 32.952219 -270.169463)
			(xy 32.988197 -270.209617) (xy 33.017945 -270.254581) (xy 33.04083 -270.303398) (xy 33.056362 -270.355027)
			(xy 33.064212 -270.408367) (xy 33.064704 -270.435324) (xy 36.426663 -270.435324) (xy 36.430598 -270.381553)
			(xy 36.442321 -270.328929) (xy 36.461581 -270.278572) (xy 36.487967 -270.231555) (xy 36.520919 -270.188882)
			(xy 36.559732 -270.151461) (xy 36.60358 -270.120091) (xy 36.651528 -270.095439) (xy 36.702555 -270.078031)
			(xy 36.755573 -270.068238) (xy 36.809452 -270.066269) (xy 36.863043 -270.072166) (xy 36.915204 -270.085802)
			(xy 36.964824 -270.106889) (xy 37.010845 -270.134975) (xy 37.052287 -270.169463) (xy 37.088265 -270.209617)
			(xy 37.118013 -270.254581) (xy 37.140898 -270.303398) (xy 37.15643 -270.355027) (xy 37.16428 -270.408367)
			(xy 37.164772 -270.435324) (xy 39.870649 -270.435324) (xy 39.874584 -270.381553) (xy 39.886307 -270.328929)
			(xy 39.905567 -270.278572) (xy 39.931953 -270.231555) (xy 39.964905 -270.188882) (xy 40.003718 -270.151461)
			(xy 40.047566 -270.120091) (xy 40.095514 -270.095439) (xy 40.146541 -270.078031) (xy 40.199559 -270.068238)
			(xy 40.253438 -270.066269) (xy 40.307029 -270.072166) (xy 40.35919 -270.085802) (xy 40.40881 -270.106889)
			(xy 40.454831 -270.134975) (xy 40.496273 -270.169463) (xy 40.532251 -270.209617) (xy 40.561999 -270.254581)
			(xy 40.584884 -270.303398) (xy 40.600416 -270.355027) (xy 40.608266 -270.408367) (xy 40.608758 -270.435324)
			(xy 43.970717 -270.435324) (xy 43.974652 -270.381553) (xy 43.986375 -270.328929) (xy 44.005635 -270.278572)
			(xy 44.032021 -270.231555) (xy 44.064973 -270.188882) (xy 44.103786 -270.151461) (xy 44.147634 -270.120091)
			(xy 44.195582 -270.095439) (xy 44.246609 -270.078031) (xy 44.299627 -270.068238) (xy 44.353506 -270.066269)
			(xy 44.407097 -270.072166) (xy 44.459258 -270.085802) (xy 44.508878 -270.106889) (xy 44.554899 -270.134975)
			(xy 44.596341 -270.169463) (xy 44.632319 -270.209617) (xy 44.662067 -270.254581) (xy 44.684952 -270.303398)
			(xy 44.700484 -270.355027) (xy 44.708334 -270.408367) (xy 44.708826 -270.435324) (xy 44.708334 -270.462281)
			(xy 44.700484 -270.515621) (xy 44.684952 -270.56725) (xy 44.662067 -270.616067) (xy 44.632319 -270.661031)
			(xy 44.596341 -270.701185) (xy 44.554899 -270.735673) (xy 44.508878 -270.763759) (xy 44.459258 -270.784846)
			(xy 44.407097 -270.798482) (xy 44.353506 -270.804379) (xy 44.299627 -270.80241) (xy 44.246609 -270.792617)
			(xy 44.195582 -270.775209) (xy 44.147634 -270.750557) (xy 44.103786 -270.719187) (xy 44.064973 -270.681766)
			(xy 44.032021 -270.639093) (xy 44.005635 -270.592076) (xy 43.986375 -270.541719) (xy 43.974652 -270.489095)
			(xy 43.970717 -270.435324) (xy 40.608758 -270.435324) (xy 40.608266 -270.462281) (xy 40.600416 -270.515621)
			(xy 40.584884 -270.56725) (xy 40.561999 -270.616067) (xy 40.532251 -270.661031) (xy 40.496273 -270.701185)
			(xy 40.454831 -270.735673) (xy 40.40881 -270.763759) (xy 40.35919 -270.784846) (xy 40.307029 -270.798482)
			(xy 40.253438 -270.804379) (xy 40.199559 -270.80241) (xy 40.146541 -270.792617) (xy 40.095514 -270.775209)
			(xy 40.047566 -270.750557) (xy 40.003718 -270.719187) (xy 39.964905 -270.681766) (xy 39.931953 -270.639093)
			(xy 39.905567 -270.592076) (xy 39.886307 -270.541719) (xy 39.874584 -270.489095) (xy 39.870649 -270.435324)
			(xy 37.164772 -270.435324) (xy 37.16428 -270.462281) (xy 37.15643 -270.515621) (xy 37.140898 -270.56725)
			(xy 37.118013 -270.616067) (xy 37.088265 -270.661031) (xy 37.052287 -270.701185) (xy 37.010845 -270.735673)
			(xy 36.964824 -270.763759) (xy 36.915204 -270.784846) (xy 36.863043 -270.798482) (xy 36.809452 -270.804379)
			(xy 36.755573 -270.80241) (xy 36.702555 -270.792617) (xy 36.651528 -270.775209) (xy 36.60358 -270.750557)
			(xy 36.559732 -270.719187) (xy 36.520919 -270.681766) (xy 36.487967 -270.639093) (xy 36.461581 -270.592076)
			(xy 36.442321 -270.541719) (xy 36.430598 -270.489095) (xy 36.426663 -270.435324) (xy 33.064704 -270.435324)
			(xy 33.064212 -270.462281) (xy 33.056362 -270.515621) (xy 33.04083 -270.56725) (xy 33.017945 -270.616067)
			(xy 32.988197 -270.661031) (xy 32.952219 -270.701185) (xy 32.910777 -270.735673) (xy 32.864756 -270.763759)
			(xy 32.815136 -270.784846) (xy 32.762975 -270.798482) (xy 32.709384 -270.804379) (xy 32.655505 -270.80241)
			(xy 32.602487 -270.792617) (xy 32.55146 -270.775209) (xy 32.503512 -270.750557) (xy 32.459664 -270.719187)
			(xy 32.420851 -270.681766) (xy 32.387899 -270.639093) (xy 32.361513 -270.592076) (xy 32.342253 -270.541719)
			(xy 32.33053 -270.489095) (xy 32.326595 -270.435324) (xy 29.620972 -270.435324) (xy 29.62048 -270.462281)
			(xy 29.61263 -270.515621) (xy 29.597098 -270.56725) (xy 29.574213 -270.616067) (xy 29.544465 -270.661031)
			(xy 29.508487 -270.701185) (xy 29.467045 -270.735673) (xy 29.421024 -270.763759) (xy 29.371404 -270.784846)
			(xy 29.319243 -270.798482) (xy 29.265652 -270.804379) (xy 29.211773 -270.80241) (xy 29.158755 -270.792617)
			(xy 29.107728 -270.775209) (xy 29.05978 -270.750557) (xy 29.015932 -270.719187) (xy 28.977119 -270.681766)
			(xy 28.944167 -270.639093) (xy 28.917781 -270.592076) (xy 28.898521 -270.541719) (xy 28.886798 -270.489095)
			(xy 28.882863 -270.435324) (xy 25.520904 -270.435324) (xy 25.520412 -270.462281) (xy 25.512562 -270.515621)
			(xy 25.49703 -270.56725) (xy 25.474145 -270.616067) (xy 25.444397 -270.661031) (xy 25.408419 -270.701185)
			(xy 25.366977 -270.735673) (xy 25.320956 -270.763759) (xy 25.271336 -270.784846) (xy 25.219175 -270.798482)
			(xy 25.165584 -270.804379) (xy 25.111705 -270.80241) (xy 25.058687 -270.792617) (xy 25.00766 -270.775209)
			(xy 24.959712 -270.750557) (xy 24.915864 -270.719187) (xy 24.877051 -270.681766) (xy 24.844099 -270.639093)
			(xy 24.817713 -270.592076) (xy 24.798453 -270.541719) (xy 24.78673 -270.489095) (xy 24.782795 -270.435324)
			(xy 22.076918 -270.435324) (xy 22.076426 -270.462281) (xy 22.068576 -270.515621) (xy 22.053044 -270.56725)
			(xy 22.030159 -270.616067) (xy 22.000411 -270.661031) (xy 21.964433 -270.701185) (xy 21.922991 -270.735673)
			(xy 21.87697 -270.763759) (xy 21.82735 -270.784846) (xy 21.775189 -270.798482) (xy 21.721598 -270.804379)
			(xy 21.667719 -270.80241) (xy 21.614701 -270.792617) (xy 21.563674 -270.775209) (xy 21.515726 -270.750557)
			(xy 21.471878 -270.719187) (xy 21.433065 -270.681766) (xy 21.400113 -270.639093) (xy 21.373727 -270.592076)
			(xy 21.354467 -270.541719) (xy 21.342744 -270.489095) (xy 21.338809 -270.435324) (xy 17.97685 -270.435324)
			(xy 17.976358 -270.462281) (xy 17.968508 -270.515621) (xy 17.952976 -270.56725) (xy 17.930091 -270.616067)
			(xy 17.900343 -270.661031) (xy 17.864365 -270.701185) (xy 17.822923 -270.735673) (xy 17.776902 -270.763759)
			(xy 17.727282 -270.784846) (xy 17.675121 -270.798482) (xy 17.62153 -270.804379) (xy 17.567651 -270.80241)
			(xy 17.514633 -270.792617) (xy 17.463606 -270.775209) (xy 17.415658 -270.750557) (xy 17.37181 -270.719187)
			(xy 17.332997 -270.681766) (xy 17.300045 -270.639093) (xy 17.273659 -270.592076) (xy 17.254399 -270.541719)
			(xy 17.242676 -270.489095) (xy 17.238741 -270.435324) (xy 15.598394 -270.435324) (xy 15.598394 -271.285208)
			(xy 17.238741 -271.285208) (xy 17.242676 -271.231437) (xy 17.254399 -271.178813) (xy 17.273659 -271.128456)
			(xy 17.300045 -271.081439) (xy 17.332997 -271.038766) (xy 17.37181 -271.001345) (xy 17.415658 -270.969975)
			(xy 17.463606 -270.945323) (xy 17.514633 -270.927915) (xy 17.567651 -270.918122) (xy 17.62153 -270.916153)
			(xy 17.675121 -270.92205) (xy 17.727282 -270.935686) (xy 17.776902 -270.956773) (xy 17.822923 -270.984859)
			(xy 17.864365 -271.019347) (xy 17.900343 -271.059501) (xy 17.930091 -271.104465) (xy 17.952976 -271.153282)
			(xy 17.968508 -271.204911) (xy 17.976358 -271.258251) (xy 17.97685 -271.285208) (xy 24.782795 -271.285208)
			(xy 24.78673 -271.231437) (xy 24.798453 -271.178813) (xy 24.817713 -271.128456) (xy 24.844099 -271.081439)
			(xy 24.877051 -271.038766) (xy 24.915864 -271.001345) (xy 24.959712 -270.969975) (xy 25.00766 -270.945323)
			(xy 25.058687 -270.927915) (xy 25.111705 -270.918122) (xy 25.165584 -270.916153) (xy 25.219175 -270.92205)
			(xy 25.271336 -270.935686) (xy 25.320956 -270.956773) (xy 25.366977 -270.984859) (xy 25.408419 -271.019347)
			(xy 25.444397 -271.059501) (xy 25.474145 -271.104465) (xy 25.49703 -271.153282) (xy 25.512562 -271.204911)
			(xy 25.520412 -271.258251) (xy 25.520904 -271.285208) (xy 32.326595 -271.285208) (xy 32.33053 -271.231437)
			(xy 32.342253 -271.178813) (xy 32.361513 -271.128456) (xy 32.387899 -271.081439) (xy 32.420851 -271.038766)
			(xy 32.459664 -271.001345) (xy 32.503512 -270.969975) (xy 32.55146 -270.945323) (xy 32.602487 -270.927915)
			(xy 32.655505 -270.918122) (xy 32.709384 -270.916153) (xy 32.762975 -270.92205) (xy 32.815136 -270.935686)
			(xy 32.864756 -270.956773) (xy 32.910777 -270.984859) (xy 32.952219 -271.019347) (xy 32.988197 -271.059501)
			(xy 33.017945 -271.104465) (xy 33.04083 -271.153282) (xy 33.056362 -271.204911) (xy 33.064212 -271.258251)
			(xy 33.064704 -271.285208) (xy 39.870649 -271.285208) (xy 39.874584 -271.231437) (xy 39.886307 -271.178813)
			(xy 39.905567 -271.128456) (xy 39.931953 -271.081439) (xy 39.964905 -271.038766) (xy 40.003718 -271.001345)
			(xy 40.047566 -270.969975) (xy 40.095514 -270.945323) (xy 40.146541 -270.927915) (xy 40.199559 -270.918122)
			(xy 40.253438 -270.916153) (xy 40.307029 -270.92205) (xy 40.35919 -270.935686) (xy 40.40881 -270.956773)
			(xy 40.454831 -270.984859) (xy 40.496273 -271.019347) (xy 40.532251 -271.059501) (xy 40.561999 -271.104465)
			(xy 40.584884 -271.153282) (xy 40.600416 -271.204911) (xy 40.608266 -271.258251) (xy 40.608758 -271.285208)
			(xy 40.608266 -271.312165) (xy 40.600416 -271.365505) (xy 40.584884 -271.417134) (xy 40.561999 -271.465951)
			(xy 40.532251 -271.510915) (xy 40.496273 -271.551069) (xy 40.454831 -271.585557) (xy 40.40881 -271.613643)
			(xy 40.35919 -271.63473) (xy 40.307029 -271.648366) (xy 40.253438 -271.654263) (xy 40.199559 -271.652294)
			(xy 40.146541 -271.642501) (xy 40.095514 -271.625093) (xy 40.047566 -271.600441) (xy 40.003718 -271.569071)
			(xy 39.964905 -271.53165) (xy 39.931953 -271.488977) (xy 39.905567 -271.44196) (xy 39.886307 -271.391603)
			(xy 39.874584 -271.338979) (xy 39.870649 -271.285208) (xy 33.064704 -271.285208) (xy 33.064212 -271.312165)
			(xy 33.056362 -271.365505) (xy 33.04083 -271.417134) (xy 33.017945 -271.465951) (xy 32.988197 -271.510915)
			(xy 32.952219 -271.551069) (xy 32.910777 -271.585557) (xy 32.864756 -271.613643) (xy 32.815136 -271.63473)
			(xy 32.762975 -271.648366) (xy 32.709384 -271.654263) (xy 32.655505 -271.652294) (xy 32.602487 -271.642501)
			(xy 32.55146 -271.625093) (xy 32.503512 -271.600441) (xy 32.459664 -271.569071) (xy 32.420851 -271.53165)
			(xy 32.387899 -271.488977) (xy 32.361513 -271.44196) (xy 32.342253 -271.391603) (xy 32.33053 -271.338979)
			(xy 32.326595 -271.285208) (xy 25.520904 -271.285208) (xy 25.520412 -271.312165) (xy 25.512562 -271.365505)
			(xy 25.49703 -271.417134) (xy 25.474145 -271.465951) (xy 25.444397 -271.510915) (xy 25.408419 -271.551069)
			(xy 25.366977 -271.585557) (xy 25.320956 -271.613643) (xy 25.271336 -271.63473) (xy 25.219175 -271.648366)
			(xy 25.165584 -271.654263) (xy 25.111705 -271.652294) (xy 25.058687 -271.642501) (xy 25.00766 -271.625093)
			(xy 24.959712 -271.600441) (xy 24.915864 -271.569071) (xy 24.877051 -271.53165) (xy 24.844099 -271.488977)
			(xy 24.817713 -271.44196) (xy 24.798453 -271.391603) (xy 24.78673 -271.338979) (xy 24.782795 -271.285208)
			(xy 17.97685 -271.285208) (xy 17.976358 -271.312165) (xy 17.968508 -271.365505) (xy 17.952976 -271.417134)
			(xy 17.930091 -271.465951) (xy 17.900343 -271.510915) (xy 17.864365 -271.551069) (xy 17.822923 -271.585557)
			(xy 17.776902 -271.613643) (xy 17.727282 -271.63473) (xy 17.675121 -271.648366) (xy 17.62153 -271.654263)
			(xy 17.567651 -271.652294) (xy 17.514633 -271.642501) (xy 17.463606 -271.625093) (xy 17.415658 -271.600441)
			(xy 17.37181 -271.569071) (xy 17.332997 -271.53165) (xy 17.300045 -271.488977) (xy 17.273659 -271.44196)
			(xy 17.254399 -271.391603) (xy 17.242676 -271.338979) (xy 17.238741 -271.285208) (xy 15.598394 -271.285208)
			(xy 15.598394 -272.135346) (xy 21.338809 -272.135346) (xy 21.342744 -272.081575) (xy 21.354467 -272.028951)
			(xy 21.373727 -271.978594) (xy 21.400113 -271.931577) (xy 21.433065 -271.888904) (xy 21.471878 -271.851483)
			(xy 21.515726 -271.820113) (xy 21.563674 -271.795461) (xy 21.614701 -271.778053) (xy 21.667719 -271.76826)
			(xy 21.721598 -271.766291) (xy 21.775189 -271.772188) (xy 21.82735 -271.785824) (xy 21.87697 -271.806911)
			(xy 21.922991 -271.834997) (xy 21.964433 -271.869485) (xy 22.000411 -271.909639) (xy 22.030159 -271.954603)
			(xy 22.053044 -272.00342) (xy 22.068576 -272.055049) (xy 22.076426 -272.108389) (xy 22.076918 -272.135346)
			(xy 28.882863 -272.135346) (xy 28.886798 -272.081575) (xy 28.898521 -272.028951) (xy 28.917781 -271.978594)
			(xy 28.944167 -271.931577) (xy 28.977119 -271.888904) (xy 29.015932 -271.851483) (xy 29.05978 -271.820113)
			(xy 29.107728 -271.795461) (xy 29.158755 -271.778053) (xy 29.211773 -271.76826) (xy 29.265652 -271.766291)
			(xy 29.319243 -271.772188) (xy 29.371404 -271.785824) (xy 29.421024 -271.806911) (xy 29.467045 -271.834997)
			(xy 29.508487 -271.869485) (xy 29.544465 -271.909639) (xy 29.574213 -271.954603) (xy 29.597098 -272.00342)
			(xy 29.61263 -272.055049) (xy 29.62048 -272.108389) (xy 29.620972 -272.135346) (xy 36.426663 -272.135346)
			(xy 36.430598 -272.081575) (xy 36.442321 -272.028951) (xy 36.461581 -271.978594) (xy 36.487967 -271.931577)
			(xy 36.520919 -271.888904) (xy 36.559732 -271.851483) (xy 36.60358 -271.820113) (xy 36.651528 -271.795461)
			(xy 36.702555 -271.778053) (xy 36.755573 -271.76826) (xy 36.809452 -271.766291) (xy 36.863043 -271.772188)
			(xy 36.915204 -271.785824) (xy 36.964824 -271.806911) (xy 37.010845 -271.834997) (xy 37.052287 -271.869485)
			(xy 37.088265 -271.909639) (xy 37.118013 -271.954603) (xy 37.140898 -272.00342) (xy 37.15643 -272.055049)
			(xy 37.16428 -272.108389) (xy 37.164772 -272.135346) (xy 43.970717 -272.135346) (xy 43.974652 -272.081575)
			(xy 43.986375 -272.028951) (xy 44.005635 -271.978594) (xy 44.032021 -271.931577) (xy 44.064973 -271.888904)
			(xy 44.103786 -271.851483) (xy 44.147634 -271.820113) (xy 44.195582 -271.795461) (xy 44.246609 -271.778053)
			(xy 44.299627 -271.76826) (xy 44.353506 -271.766291) (xy 44.407097 -271.772188) (xy 44.459258 -271.785824)
			(xy 44.508878 -271.806911) (xy 44.554899 -271.834997) (xy 44.596341 -271.869485) (xy 44.632319 -271.909639)
			(xy 44.662067 -271.954603) (xy 44.684952 -272.00342) (xy 44.700484 -272.055049) (xy 44.708334 -272.108389)
			(xy 44.708826 -272.135346) (xy 44.708334 -272.162303) (xy 44.700484 -272.215643) (xy 44.684952 -272.267272)
			(xy 44.662067 -272.316089) (xy 44.632319 -272.361053) (xy 44.596341 -272.401207) (xy 44.554899 -272.435695)
			(xy 44.508878 -272.463781) (xy 44.459258 -272.484868) (xy 44.407097 -272.498504) (xy 44.353506 -272.504401)
			(xy 44.299627 -272.502432) (xy 44.246609 -272.492639) (xy 44.195582 -272.475231) (xy 44.147634 -272.450579)
			(xy 44.103786 -272.419209) (xy 44.064973 -272.381788) (xy 44.032021 -272.339115) (xy 44.005635 -272.292098)
			(xy 43.986375 -272.241741) (xy 43.974652 -272.189117) (xy 43.970717 -272.135346) (xy 37.164772 -272.135346)
			(xy 37.16428 -272.162303) (xy 37.15643 -272.215643) (xy 37.140898 -272.267272) (xy 37.118013 -272.316089)
			(xy 37.088265 -272.361053) (xy 37.052287 -272.401207) (xy 37.010845 -272.435695) (xy 36.964824 -272.463781)
			(xy 36.915204 -272.484868) (xy 36.863043 -272.498504) (xy 36.809452 -272.504401) (xy 36.755573 -272.502432)
			(xy 36.702555 -272.492639) (xy 36.651528 -272.475231) (xy 36.60358 -272.450579) (xy 36.559732 -272.419209)
			(xy 36.520919 -272.381788) (xy 36.487967 -272.339115) (xy 36.461581 -272.292098) (xy 36.442321 -272.241741)
			(xy 36.430598 -272.189117) (xy 36.426663 -272.135346) (xy 29.620972 -272.135346) (xy 29.62048 -272.162303)
			(xy 29.61263 -272.215643) (xy 29.597098 -272.267272) (xy 29.574213 -272.316089) (xy 29.544465 -272.361053)
			(xy 29.508487 -272.401207) (xy 29.467045 -272.435695) (xy 29.421024 -272.463781) (xy 29.371404 -272.484868)
			(xy 29.319243 -272.498504) (xy 29.265652 -272.504401) (xy 29.211773 -272.502432) (xy 29.158755 -272.492639)
			(xy 29.107728 -272.475231) (xy 29.05978 -272.450579) (xy 29.015932 -272.419209) (xy 28.977119 -272.381788)
			(xy 28.944167 -272.339115) (xy 28.917781 -272.292098) (xy 28.898521 -272.241741) (xy 28.886798 -272.189117)
			(xy 28.882863 -272.135346) (xy 22.076918 -272.135346) (xy 22.076426 -272.162303) (xy 22.068576 -272.215643)
			(xy 22.053044 -272.267272) (xy 22.030159 -272.316089) (xy 22.000411 -272.361053) (xy 21.964433 -272.401207)
			(xy 21.922991 -272.435695) (xy 21.87697 -272.463781) (xy 21.82735 -272.484868) (xy 21.775189 -272.498504)
			(xy 21.721598 -272.504401) (xy 21.667719 -272.502432) (xy 21.614701 -272.492639) (xy 21.563674 -272.475231)
			(xy 21.515726 -272.450579) (xy 21.471878 -272.419209) (xy 21.433065 -272.381788) (xy 21.400113 -272.339115)
			(xy 21.373727 -272.292098) (xy 21.354467 -272.241741) (xy 21.342744 -272.189117) (xy 21.338809 -272.135346)
			(xy 15.598394 -272.135346) (xy 15.598394 -272.98523) (xy 17.238741 -272.98523) (xy 17.242676 -272.931459)
			(xy 17.254399 -272.878835) (xy 17.273659 -272.828478) (xy 17.300045 -272.781461) (xy 17.332997 -272.738788)
			(xy 17.37181 -272.701367) (xy 17.415658 -272.669997) (xy 17.463606 -272.645345) (xy 17.514633 -272.627937)
			(xy 17.567651 -272.618144) (xy 17.62153 -272.616175) (xy 17.675121 -272.622072) (xy 17.727282 -272.635708)
			(xy 17.776902 -272.656795) (xy 17.822923 -272.684881) (xy 17.864365 -272.719369) (xy 17.900343 -272.759523)
			(xy 17.930091 -272.804487) (xy 17.952976 -272.853304) (xy 17.968508 -272.904933) (xy 17.976358 -272.958273)
			(xy 17.97685 -272.98523) (xy 24.782795 -272.98523) (xy 24.78673 -272.931459) (xy 24.798453 -272.878835)
			(xy 24.817713 -272.828478) (xy 24.844099 -272.781461) (xy 24.877051 -272.738788) (xy 24.915864 -272.701367)
			(xy 24.959712 -272.669997) (xy 25.00766 -272.645345) (xy 25.058687 -272.627937) (xy 25.111705 -272.618144)
			(xy 25.165584 -272.616175) (xy 25.219175 -272.622072) (xy 25.271336 -272.635708) (xy 25.320956 -272.656795)
			(xy 25.366977 -272.684881) (xy 25.408419 -272.719369) (xy 25.444397 -272.759523) (xy 25.474145 -272.804487)
			(xy 25.49703 -272.853304) (xy 25.512562 -272.904933) (xy 25.520412 -272.958273) (xy 25.520904 -272.98523)
			(xy 32.326595 -272.98523) (xy 32.33053 -272.931459) (xy 32.342253 -272.878835) (xy 32.361513 -272.828478)
			(xy 32.387899 -272.781461) (xy 32.420851 -272.738788) (xy 32.459664 -272.701367) (xy 32.503512 -272.669997)
			(xy 32.55146 -272.645345) (xy 32.602487 -272.627937) (xy 32.655505 -272.618144) (xy 32.709384 -272.616175)
			(xy 32.762975 -272.622072) (xy 32.815136 -272.635708) (xy 32.864756 -272.656795) (xy 32.910777 -272.684881)
			(xy 32.952219 -272.719369) (xy 32.988197 -272.759523) (xy 33.017945 -272.804487) (xy 33.04083 -272.853304)
			(xy 33.056362 -272.904933) (xy 33.064212 -272.958273) (xy 33.064704 -272.98523) (xy 39.870649 -272.98523)
			(xy 39.874584 -272.931459) (xy 39.886307 -272.878835) (xy 39.905567 -272.828478) (xy 39.931953 -272.781461)
			(xy 39.964905 -272.738788) (xy 40.003718 -272.701367) (xy 40.047566 -272.669997) (xy 40.095514 -272.645345)
			(xy 40.146541 -272.627937) (xy 40.199559 -272.618144) (xy 40.253438 -272.616175) (xy 40.307029 -272.622072)
			(xy 40.35919 -272.635708) (xy 40.40881 -272.656795) (xy 40.454831 -272.684881) (xy 40.496273 -272.719369)
			(xy 40.532251 -272.759523) (xy 40.561999 -272.804487) (xy 40.584884 -272.853304) (xy 40.600416 -272.904933)
			(xy 40.608266 -272.958273) (xy 40.608758 -272.98523) (xy 40.608266 -273.012187) (xy 40.600416 -273.065527)
			(xy 40.584884 -273.117156) (xy 40.561999 -273.165973) (xy 40.532251 -273.210937) (xy 40.496273 -273.251091)
			(xy 40.454831 -273.285579) (xy 40.40881 -273.313665) (xy 40.35919 -273.334752) (xy 40.307029 -273.348388)
			(xy 40.253438 -273.354285) (xy 40.199559 -273.352316) (xy 40.146541 -273.342523) (xy 40.095514 -273.325115)
			(xy 40.047566 -273.300463) (xy 40.003718 -273.269093) (xy 39.964905 -273.231672) (xy 39.931953 -273.188999)
			(xy 39.905567 -273.141982) (xy 39.886307 -273.091625) (xy 39.874584 -273.039001) (xy 39.870649 -272.98523)
			(xy 33.064704 -272.98523) (xy 33.064212 -273.012187) (xy 33.056362 -273.065527) (xy 33.04083 -273.117156)
			(xy 33.017945 -273.165973) (xy 32.988197 -273.210937) (xy 32.952219 -273.251091) (xy 32.910777 -273.285579)
			(xy 32.864756 -273.313665) (xy 32.815136 -273.334752) (xy 32.762975 -273.348388) (xy 32.709384 -273.354285)
			(xy 32.655505 -273.352316) (xy 32.602487 -273.342523) (xy 32.55146 -273.325115) (xy 32.503512 -273.300463)
			(xy 32.459664 -273.269093) (xy 32.420851 -273.231672) (xy 32.387899 -273.188999) (xy 32.361513 -273.141982)
			(xy 32.342253 -273.091625) (xy 32.33053 -273.039001) (xy 32.326595 -272.98523) (xy 25.520904 -272.98523)
			(xy 25.520412 -273.012187) (xy 25.512562 -273.065527) (xy 25.49703 -273.117156) (xy 25.474145 -273.165973)
			(xy 25.444397 -273.210937) (xy 25.408419 -273.251091) (xy 25.366977 -273.285579) (xy 25.320956 -273.313665)
			(xy 25.271336 -273.334752) (xy 25.219175 -273.348388) (xy 25.165584 -273.354285) (xy 25.111705 -273.352316)
			(xy 25.058687 -273.342523) (xy 25.00766 -273.325115) (xy 24.959712 -273.300463) (xy 24.915864 -273.269093)
			(xy 24.877051 -273.231672) (xy 24.844099 -273.188999) (xy 24.817713 -273.141982) (xy 24.798453 -273.091625)
			(xy 24.78673 -273.039001) (xy 24.782795 -272.98523) (xy 17.97685 -272.98523) (xy 17.976358 -273.012187)
			(xy 17.968508 -273.065527) (xy 17.952976 -273.117156) (xy 17.930091 -273.165973) (xy 17.900343 -273.210937)
			(xy 17.864365 -273.251091) (xy 17.822923 -273.285579) (xy 17.776902 -273.313665) (xy 17.727282 -273.334752)
			(xy 17.675121 -273.348388) (xy 17.62153 -273.354285) (xy 17.567651 -273.352316) (xy 17.514633 -273.342523)
			(xy 17.463606 -273.325115) (xy 17.415658 -273.300463) (xy 17.37181 -273.269093) (xy 17.332997 -273.231672)
			(xy 17.300045 -273.188999) (xy 17.273659 -273.141982) (xy 17.254399 -273.091625) (xy 17.242676 -273.039001)
			(xy 17.238741 -272.98523) (xy 15.598394 -272.98523) (xy 15.598394 -273.835368) (xy 21.338809 -273.835368)
			(xy 21.342744 -273.781597) (xy 21.354467 -273.728973) (xy 21.373727 -273.678616) (xy 21.400113 -273.631599)
			(xy 21.433065 -273.588926) (xy 21.471878 -273.551505) (xy 21.515726 -273.520135) (xy 21.563674 -273.495483)
			(xy 21.614701 -273.478075) (xy 21.667719 -273.468282) (xy 21.721598 -273.466313) (xy 21.775189 -273.47221)
			(xy 21.82735 -273.485846) (xy 21.87697 -273.506933) (xy 21.922991 -273.535019) (xy 21.964433 -273.569507)
			(xy 22.000411 -273.609661) (xy 22.030159 -273.654625) (xy 22.053044 -273.703442) (xy 22.068576 -273.755071)
			(xy 22.076426 -273.808411) (xy 22.076918 -273.835368) (xy 28.882863 -273.835368) (xy 28.886798 -273.781597)
			(xy 28.898521 -273.728973) (xy 28.917781 -273.678616) (xy 28.944167 -273.631599) (xy 28.977119 -273.588926)
			(xy 29.015932 -273.551505) (xy 29.05978 -273.520135) (xy 29.107728 -273.495483) (xy 29.158755 -273.478075)
			(xy 29.211773 -273.468282) (xy 29.265652 -273.466313) (xy 29.319243 -273.47221) (xy 29.371404 -273.485846)
			(xy 29.421024 -273.506933) (xy 29.467045 -273.535019) (xy 29.508487 -273.569507) (xy 29.544465 -273.609661)
			(xy 29.574213 -273.654625) (xy 29.597098 -273.703442) (xy 29.61263 -273.755071) (xy 29.62048 -273.808411)
			(xy 29.620972 -273.835368) (xy 36.426663 -273.835368) (xy 36.430598 -273.781597) (xy 36.442321 -273.728973)
			(xy 36.461581 -273.678616) (xy 36.487967 -273.631599) (xy 36.520919 -273.588926) (xy 36.559732 -273.551505)
			(xy 36.60358 -273.520135) (xy 36.651528 -273.495483) (xy 36.702555 -273.478075) (xy 36.755573 -273.468282)
			(xy 36.809452 -273.466313) (xy 36.863043 -273.47221) (xy 36.915204 -273.485846) (xy 36.964824 -273.506933)
			(xy 37.010845 -273.535019) (xy 37.052287 -273.569507) (xy 37.088265 -273.609661) (xy 37.118013 -273.654625)
			(xy 37.140898 -273.703442) (xy 37.15643 -273.755071) (xy 37.16428 -273.808411) (xy 37.164772 -273.835368)
			(xy 43.970717 -273.835368) (xy 43.974652 -273.781597) (xy 43.986375 -273.728973) (xy 44.005635 -273.678616)
			(xy 44.032021 -273.631599) (xy 44.064973 -273.588926) (xy 44.103786 -273.551505) (xy 44.147634 -273.520135)
			(xy 44.195582 -273.495483) (xy 44.246609 -273.478075) (xy 44.299627 -273.468282) (xy 44.353506 -273.466313)
			(xy 44.407097 -273.47221) (xy 44.459258 -273.485846) (xy 44.508878 -273.506933) (xy 44.554899 -273.535019)
			(xy 44.596341 -273.569507) (xy 44.632319 -273.609661) (xy 44.662067 -273.654625) (xy 44.684952 -273.703442)
			(xy 44.700484 -273.755071) (xy 44.708334 -273.808411) (xy 44.708826 -273.835368) (xy 44.708334 -273.862325)
			(xy 44.700484 -273.915665) (xy 44.684952 -273.967294) (xy 44.662067 -274.016111) (xy 44.632319 -274.061075)
			(xy 44.596341 -274.101229) (xy 44.554899 -274.135717) (xy 44.508878 -274.163803) (xy 44.459258 -274.18489)
			(xy 44.407097 -274.198526) (xy 44.353506 -274.204423) (xy 44.299627 -274.202454) (xy 44.246609 -274.192661)
			(xy 44.195582 -274.175253) (xy 44.147634 -274.150601) (xy 44.103786 -274.119231) (xy 44.064973 -274.08181)
			(xy 44.032021 -274.039137) (xy 44.005635 -273.99212) (xy 43.986375 -273.941763) (xy 43.974652 -273.889139)
			(xy 43.970717 -273.835368) (xy 37.164772 -273.835368) (xy 37.16428 -273.862325) (xy 37.15643 -273.915665)
			(xy 37.140898 -273.967294) (xy 37.118013 -274.016111) (xy 37.088265 -274.061075) (xy 37.052287 -274.101229)
			(xy 37.010845 -274.135717) (xy 36.964824 -274.163803) (xy 36.915204 -274.18489) (xy 36.863043 -274.198526)
			(xy 36.809452 -274.204423) (xy 36.755573 -274.202454) (xy 36.702555 -274.192661) (xy 36.651528 -274.175253)
			(xy 36.60358 -274.150601) (xy 36.559732 -274.119231) (xy 36.520919 -274.08181) (xy 36.487967 -274.039137)
			(xy 36.461581 -273.99212) (xy 36.442321 -273.941763) (xy 36.430598 -273.889139) (xy 36.426663 -273.835368)
			(xy 29.620972 -273.835368) (xy 29.62048 -273.862325) (xy 29.61263 -273.915665) (xy 29.597098 -273.967294)
			(xy 29.574213 -274.016111) (xy 29.544465 -274.061075) (xy 29.508487 -274.101229) (xy 29.467045 -274.135717)
			(xy 29.421024 -274.163803) (xy 29.371404 -274.18489) (xy 29.319243 -274.198526) (xy 29.265652 -274.204423)
			(xy 29.211773 -274.202454) (xy 29.158755 -274.192661) (xy 29.107728 -274.175253) (xy 29.05978 -274.150601)
			(xy 29.015932 -274.119231) (xy 28.977119 -274.08181) (xy 28.944167 -274.039137) (xy 28.917781 -273.99212)
			(xy 28.898521 -273.941763) (xy 28.886798 -273.889139) (xy 28.882863 -273.835368) (xy 22.076918 -273.835368)
			(xy 22.076426 -273.862325) (xy 22.068576 -273.915665) (xy 22.053044 -273.967294) (xy 22.030159 -274.016111)
			(xy 22.000411 -274.061075) (xy 21.964433 -274.101229) (xy 21.922991 -274.135717) (xy 21.87697 -274.163803)
			(xy 21.82735 -274.18489) (xy 21.775189 -274.198526) (xy 21.721598 -274.204423) (xy 21.667719 -274.202454)
			(xy 21.614701 -274.192661) (xy 21.563674 -274.175253) (xy 21.515726 -274.150601) (xy 21.471878 -274.119231)
			(xy 21.433065 -274.08181) (xy 21.400113 -274.039137) (xy 21.373727 -273.99212) (xy 21.354467 -273.941763)
			(xy 21.342744 -273.889139) (xy 21.338809 -273.835368) (xy 15.598394 -273.835368) (xy 15.598394 -274.685252)
			(xy 17.238741 -274.685252) (xy 17.242676 -274.631481) (xy 17.254399 -274.578857) (xy 17.273659 -274.5285)
			(xy 17.300045 -274.481483) (xy 17.332997 -274.43881) (xy 17.37181 -274.401389) (xy 17.415658 -274.370019)
			(xy 17.463606 -274.345367) (xy 17.514633 -274.327959) (xy 17.567651 -274.318166) (xy 17.62153 -274.316197)
			(xy 17.675121 -274.322094) (xy 17.727282 -274.33573) (xy 17.776902 -274.356817) (xy 17.822923 -274.384903)
			(xy 17.864365 -274.419391) (xy 17.900343 -274.459545) (xy 17.930091 -274.504509) (xy 17.952976 -274.553326)
			(xy 17.968508 -274.604955) (xy 17.976358 -274.658295) (xy 17.97685 -274.685252) (xy 24.782795 -274.685252)
			(xy 24.78673 -274.631481) (xy 24.798453 -274.578857) (xy 24.817713 -274.5285) (xy 24.844099 -274.481483)
			(xy 24.877051 -274.43881) (xy 24.915864 -274.401389) (xy 24.959712 -274.370019) (xy 25.00766 -274.345367)
			(xy 25.058687 -274.327959) (xy 25.111705 -274.318166) (xy 25.165584 -274.316197) (xy 25.219175 -274.322094)
			(xy 25.271336 -274.33573) (xy 25.320956 -274.356817) (xy 25.366977 -274.384903) (xy 25.408419 -274.419391)
			(xy 25.444397 -274.459545) (xy 25.474145 -274.504509) (xy 25.49703 -274.553326) (xy 25.512562 -274.604955)
			(xy 25.520412 -274.658295) (xy 25.520904 -274.685252) (xy 32.326595 -274.685252) (xy 32.33053 -274.631481)
			(xy 32.342253 -274.578857) (xy 32.361513 -274.5285) (xy 32.387899 -274.481483) (xy 32.420851 -274.43881)
			(xy 32.459664 -274.401389) (xy 32.503512 -274.370019) (xy 32.55146 -274.345367) (xy 32.602487 -274.327959)
			(xy 32.655505 -274.318166) (xy 32.709384 -274.316197) (xy 32.762975 -274.322094) (xy 32.815136 -274.33573)
			(xy 32.864756 -274.356817) (xy 32.910777 -274.384903) (xy 32.952219 -274.419391) (xy 32.988197 -274.459545)
			(xy 33.017945 -274.504509) (xy 33.04083 -274.553326) (xy 33.056362 -274.604955) (xy 33.064212 -274.658295)
			(xy 33.064704 -274.685252) (xy 39.870649 -274.685252) (xy 39.874584 -274.631481) (xy 39.886307 -274.578857)
			(xy 39.905567 -274.5285) (xy 39.931953 -274.481483) (xy 39.964905 -274.43881) (xy 40.003718 -274.401389)
			(xy 40.047566 -274.370019) (xy 40.095514 -274.345367) (xy 40.146541 -274.327959) (xy 40.199559 -274.318166)
			(xy 40.253438 -274.316197) (xy 40.307029 -274.322094) (xy 40.35919 -274.33573) (xy 40.40881 -274.356817)
			(xy 40.454831 -274.384903) (xy 40.496273 -274.419391) (xy 40.532251 -274.459545) (xy 40.561999 -274.504509)
			(xy 40.584884 -274.553326) (xy 40.600416 -274.604955) (xy 40.608266 -274.658295) (xy 40.608758 -274.685252)
			(xy 40.608266 -274.712209) (xy 40.600416 -274.765549) (xy 40.584884 -274.817178) (xy 40.561999 -274.865995)
			(xy 40.532251 -274.910959) (xy 40.496273 -274.951113) (xy 40.454831 -274.985601) (xy 40.40881 -275.013687)
			(xy 40.35919 -275.034774) (xy 40.307029 -275.04841) (xy 40.253438 -275.054307) (xy 40.199559 -275.052338)
			(xy 40.146541 -275.042545) (xy 40.095514 -275.025137) (xy 40.047566 -275.000485) (xy 40.003718 -274.969115)
			(xy 39.964905 -274.931694) (xy 39.931953 -274.889021) (xy 39.905567 -274.842004) (xy 39.886307 -274.791647)
			(xy 39.874584 -274.739023) (xy 39.870649 -274.685252) (xy 33.064704 -274.685252) (xy 33.064212 -274.712209)
			(xy 33.056362 -274.765549) (xy 33.04083 -274.817178) (xy 33.017945 -274.865995) (xy 32.988197 -274.910959)
			(xy 32.952219 -274.951113) (xy 32.910777 -274.985601) (xy 32.864756 -275.013687) (xy 32.815136 -275.034774)
			(xy 32.762975 -275.04841) (xy 32.709384 -275.054307) (xy 32.655505 -275.052338) (xy 32.602487 -275.042545)
			(xy 32.55146 -275.025137) (xy 32.503512 -275.000485) (xy 32.459664 -274.969115) (xy 32.420851 -274.931694)
			(xy 32.387899 -274.889021) (xy 32.361513 -274.842004) (xy 32.342253 -274.791647) (xy 32.33053 -274.739023)
			(xy 32.326595 -274.685252) (xy 25.520904 -274.685252) (xy 25.520412 -274.712209) (xy 25.512562 -274.765549)
			(xy 25.49703 -274.817178) (xy 25.474145 -274.865995) (xy 25.444397 -274.910959) (xy 25.408419 -274.951113)
			(xy 25.366977 -274.985601) (xy 25.320956 -275.013687) (xy 25.271336 -275.034774) (xy 25.219175 -275.04841)
			(xy 25.165584 -275.054307) (xy 25.111705 -275.052338) (xy 25.058687 -275.042545) (xy 25.00766 -275.025137)
			(xy 24.959712 -275.000485) (xy 24.915864 -274.969115) (xy 24.877051 -274.931694) (xy 24.844099 -274.889021)
			(xy 24.817713 -274.842004) (xy 24.798453 -274.791647) (xy 24.78673 -274.739023) (xy 24.782795 -274.685252)
			(xy 17.97685 -274.685252) (xy 17.976358 -274.712209) (xy 17.968508 -274.765549) (xy 17.952976 -274.817178)
			(xy 17.930091 -274.865995) (xy 17.900343 -274.910959) (xy 17.864365 -274.951113) (xy 17.822923 -274.985601)
			(xy 17.776902 -275.013687) (xy 17.727282 -275.034774) (xy 17.675121 -275.04841) (xy 17.62153 -275.054307)
			(xy 17.567651 -275.052338) (xy 17.514633 -275.042545) (xy 17.463606 -275.025137) (xy 17.415658 -275.000485)
			(xy 17.37181 -274.969115) (xy 17.332997 -274.931694) (xy 17.300045 -274.889021) (xy 17.273659 -274.842004)
			(xy 17.254399 -274.791647) (xy 17.242676 -274.739023) (xy 17.238741 -274.685252) (xy 15.598394 -274.685252)
			(xy 15.598394 -275.53539) (xy 21.338809 -275.53539) (xy 21.342744 -275.481619) (xy 21.354467 -275.428995)
			(xy 21.373727 -275.378638) (xy 21.400113 -275.331621) (xy 21.433065 -275.288948) (xy 21.471878 -275.251527)
			(xy 21.515726 -275.220157) (xy 21.563674 -275.195505) (xy 21.614701 -275.178097) (xy 21.667719 -275.168304)
			(xy 21.721598 -275.166335) (xy 21.775189 -275.172232) (xy 21.82735 -275.185868) (xy 21.87697 -275.206955)
			(xy 21.922991 -275.235041) (xy 21.964433 -275.269529) (xy 22.000411 -275.309683) (xy 22.030159 -275.354647)
			(xy 22.053044 -275.403464) (xy 22.068576 -275.455093) (xy 22.076426 -275.508433) (xy 22.076918 -275.53539)
			(xy 28.882863 -275.53539) (xy 28.886798 -275.481619) (xy 28.898521 -275.428995) (xy 28.917781 -275.378638)
			(xy 28.944167 -275.331621) (xy 28.977119 -275.288948) (xy 29.015932 -275.251527) (xy 29.05978 -275.220157)
			(xy 29.107728 -275.195505) (xy 29.158755 -275.178097) (xy 29.211773 -275.168304) (xy 29.265652 -275.166335)
			(xy 29.319243 -275.172232) (xy 29.371404 -275.185868) (xy 29.421024 -275.206955) (xy 29.467045 -275.235041)
			(xy 29.508487 -275.269529) (xy 29.544465 -275.309683) (xy 29.574213 -275.354647) (xy 29.597098 -275.403464)
			(xy 29.61263 -275.455093) (xy 29.62048 -275.508433) (xy 29.620972 -275.53539) (xy 36.426663 -275.53539)
			(xy 36.430598 -275.481619) (xy 36.442321 -275.428995) (xy 36.461581 -275.378638) (xy 36.487967 -275.331621)
			(xy 36.520919 -275.288948) (xy 36.559732 -275.251527) (xy 36.60358 -275.220157) (xy 36.651528 -275.195505)
			(xy 36.702555 -275.178097) (xy 36.755573 -275.168304) (xy 36.809452 -275.166335) (xy 36.863043 -275.172232)
			(xy 36.915204 -275.185868) (xy 36.964824 -275.206955) (xy 37.010845 -275.235041) (xy 37.052287 -275.269529)
			(xy 37.088265 -275.309683) (xy 37.118013 -275.354647) (xy 37.140898 -275.403464) (xy 37.15643 -275.455093)
			(xy 37.16428 -275.508433) (xy 37.164772 -275.53539) (xy 43.970717 -275.53539) (xy 43.974652 -275.481619)
			(xy 43.986375 -275.428995) (xy 44.005635 -275.378638) (xy 44.032021 -275.331621) (xy 44.064973 -275.288948)
			(xy 44.103786 -275.251527) (xy 44.147634 -275.220157) (xy 44.195582 -275.195505) (xy 44.246609 -275.178097)
			(xy 44.299627 -275.168304) (xy 44.353506 -275.166335) (xy 44.407097 -275.172232) (xy 44.459258 -275.185868)
			(xy 44.508878 -275.206955) (xy 44.554899 -275.235041) (xy 44.596341 -275.269529) (xy 44.632319 -275.309683)
			(xy 44.662067 -275.354647) (xy 44.684952 -275.403464) (xy 44.700484 -275.455093) (xy 44.708334 -275.508433)
			(xy 44.708826 -275.53539) (xy 44.708334 -275.562347) (xy 44.700484 -275.615687) (xy 44.684952 -275.667316)
			(xy 44.662067 -275.716133) (xy 44.632319 -275.761097) (xy 44.596341 -275.801251) (xy 44.554899 -275.835739)
			(xy 44.508878 -275.863825) (xy 44.459258 -275.884912) (xy 44.407097 -275.898548) (xy 44.353506 -275.904445)
			(xy 44.299627 -275.902476) (xy 44.246609 -275.892683) (xy 44.195582 -275.875275) (xy 44.147634 -275.850623)
			(xy 44.103786 -275.819253) (xy 44.064973 -275.781832) (xy 44.032021 -275.739159) (xy 44.005635 -275.692142)
			(xy 43.986375 -275.641785) (xy 43.974652 -275.589161) (xy 43.970717 -275.53539) (xy 37.164772 -275.53539)
			(xy 37.16428 -275.562347) (xy 37.15643 -275.615687) (xy 37.140898 -275.667316) (xy 37.118013 -275.716133)
			(xy 37.088265 -275.761097) (xy 37.052287 -275.801251) (xy 37.010845 -275.835739) (xy 36.964824 -275.863825)
			(xy 36.915204 -275.884912) (xy 36.863043 -275.898548) (xy 36.809452 -275.904445) (xy 36.755573 -275.902476)
			(xy 36.702555 -275.892683) (xy 36.651528 -275.875275) (xy 36.60358 -275.850623) (xy 36.559732 -275.819253)
			(xy 36.520919 -275.781832) (xy 36.487967 -275.739159) (xy 36.461581 -275.692142) (xy 36.442321 -275.641785)
			(xy 36.430598 -275.589161) (xy 36.426663 -275.53539) (xy 29.620972 -275.53539) (xy 29.62048 -275.562347)
			(xy 29.61263 -275.615687) (xy 29.597098 -275.667316) (xy 29.574213 -275.716133) (xy 29.544465 -275.761097)
			(xy 29.508487 -275.801251) (xy 29.467045 -275.835739) (xy 29.421024 -275.863825) (xy 29.371404 -275.884912)
			(xy 29.319243 -275.898548) (xy 29.265652 -275.904445) (xy 29.211773 -275.902476) (xy 29.158755 -275.892683)
			(xy 29.107728 -275.875275) (xy 29.05978 -275.850623) (xy 29.015932 -275.819253) (xy 28.977119 -275.781832)
			(xy 28.944167 -275.739159) (xy 28.917781 -275.692142) (xy 28.898521 -275.641785) (xy 28.886798 -275.589161)
			(xy 28.882863 -275.53539) (xy 22.076918 -275.53539) (xy 22.076426 -275.562347) (xy 22.068576 -275.615687)
			(xy 22.053044 -275.667316) (xy 22.030159 -275.716133) (xy 22.000411 -275.761097) (xy 21.964433 -275.801251)
			(xy 21.922991 -275.835739) (xy 21.87697 -275.863825) (xy 21.82735 -275.884912) (xy 21.775189 -275.898548)
			(xy 21.721598 -275.904445) (xy 21.667719 -275.902476) (xy 21.614701 -275.892683) (xy 21.563674 -275.875275)
			(xy 21.515726 -275.850623) (xy 21.471878 -275.819253) (xy 21.433065 -275.781832) (xy 21.400113 -275.739159)
			(xy 21.373727 -275.692142) (xy 21.354467 -275.641785) (xy 21.342744 -275.589161) (xy 21.338809 -275.53539)
			(xy 15.598394 -275.53539) (xy 15.598394 -276.385274) (xy 17.238741 -276.385274) (xy 17.242676 -276.331503)
			(xy 17.254399 -276.278879) (xy 17.273659 -276.228522) (xy 17.300045 -276.181505) (xy 17.332997 -276.138832)
			(xy 17.37181 -276.101411) (xy 17.415658 -276.070041) (xy 17.463606 -276.045389) (xy 17.514633 -276.027981)
			(xy 17.567651 -276.018188) (xy 17.62153 -276.016219) (xy 17.675121 -276.022116) (xy 17.727282 -276.035752)
			(xy 17.776902 -276.056839) (xy 17.822923 -276.084925) (xy 17.864365 -276.119413) (xy 17.900343 -276.159567)
			(xy 17.930091 -276.204531) (xy 17.952976 -276.253348) (xy 17.968508 -276.304977) (xy 17.976358 -276.358317)
			(xy 17.97685 -276.385274) (xy 21.338809 -276.385274) (xy 21.342744 -276.331503) (xy 21.354467 -276.278879)
			(xy 21.373727 -276.228522) (xy 21.400113 -276.181505) (xy 21.433065 -276.138832) (xy 21.471878 -276.101411)
			(xy 21.515726 -276.070041) (xy 21.563674 -276.045389) (xy 21.614701 -276.027981) (xy 21.667719 -276.018188)
			(xy 21.721598 -276.016219) (xy 21.775189 -276.022116) (xy 21.82735 -276.035752) (xy 21.87697 -276.056839)
			(xy 21.922991 -276.084925) (xy 21.964433 -276.119413) (xy 22.000411 -276.159567) (xy 22.030159 -276.204531)
			(xy 22.053044 -276.253348) (xy 22.068576 -276.304977) (xy 22.076426 -276.358317) (xy 22.076918 -276.385274)
			(xy 24.782795 -276.385274) (xy 24.78673 -276.331503) (xy 24.798453 -276.278879) (xy 24.817713 -276.228522)
			(xy 24.844099 -276.181505) (xy 24.877051 -276.138832) (xy 24.915864 -276.101411) (xy 24.959712 -276.070041)
			(xy 25.00766 -276.045389) (xy 25.058687 -276.027981) (xy 25.111705 -276.018188) (xy 25.165584 -276.016219)
			(xy 25.219175 -276.022116) (xy 25.271336 -276.035752) (xy 25.320956 -276.056839) (xy 25.366977 -276.084925)
			(xy 25.408419 -276.119413) (xy 25.444397 -276.159567) (xy 25.474145 -276.204531) (xy 25.49703 -276.253348)
			(xy 25.512562 -276.304977) (xy 25.520412 -276.358317) (xy 25.520904 -276.385274) (xy 28.882863 -276.385274)
			(xy 28.886798 -276.331503) (xy 28.898521 -276.278879) (xy 28.917781 -276.228522) (xy 28.944167 -276.181505)
			(xy 28.977119 -276.138832) (xy 29.015932 -276.101411) (xy 29.05978 -276.070041) (xy 29.107728 -276.045389)
			(xy 29.158755 -276.027981) (xy 29.211773 -276.018188) (xy 29.265652 -276.016219) (xy 29.319243 -276.022116)
			(xy 29.371404 -276.035752) (xy 29.421024 -276.056839) (xy 29.467045 -276.084925) (xy 29.508487 -276.119413)
			(xy 29.544465 -276.159567) (xy 29.574213 -276.204531) (xy 29.597098 -276.253348) (xy 29.61263 -276.304977)
			(xy 29.62048 -276.358317) (xy 29.620972 -276.385274) (xy 32.326595 -276.385274) (xy 32.33053 -276.331503)
			(xy 32.342253 -276.278879) (xy 32.361513 -276.228522) (xy 32.387899 -276.181505) (xy 32.420851 -276.138832)
			(xy 32.459664 -276.101411) (xy 32.503512 -276.070041) (xy 32.55146 -276.045389) (xy 32.602487 -276.027981)
			(xy 32.655505 -276.018188) (xy 32.709384 -276.016219) (xy 32.762975 -276.022116) (xy 32.815136 -276.035752)
			(xy 32.864756 -276.056839) (xy 32.910777 -276.084925) (xy 32.952219 -276.119413) (xy 32.988197 -276.159567)
			(xy 33.017945 -276.204531) (xy 33.04083 -276.253348) (xy 33.056362 -276.304977) (xy 33.064212 -276.358317)
			(xy 33.064704 -276.385274) (xy 36.426663 -276.385274) (xy 36.430598 -276.331503) (xy 36.442321 -276.278879)
			(xy 36.461581 -276.228522) (xy 36.487967 -276.181505) (xy 36.520919 -276.138832) (xy 36.559732 -276.101411)
			(xy 36.60358 -276.070041) (xy 36.651528 -276.045389) (xy 36.702555 -276.027981) (xy 36.755573 -276.018188)
			(xy 36.809452 -276.016219) (xy 36.863043 -276.022116) (xy 36.915204 -276.035752) (xy 36.964824 -276.056839)
			(xy 37.010845 -276.084925) (xy 37.052287 -276.119413) (xy 37.088265 -276.159567) (xy 37.118013 -276.204531)
			(xy 37.140898 -276.253348) (xy 37.15643 -276.304977) (xy 37.16428 -276.358317) (xy 37.164772 -276.385274)
			(xy 39.870649 -276.385274) (xy 39.874584 -276.331503) (xy 39.886307 -276.278879) (xy 39.905567 -276.228522)
			(xy 39.931953 -276.181505) (xy 39.964905 -276.138832) (xy 40.003718 -276.101411) (xy 40.047566 -276.070041)
			(xy 40.095514 -276.045389) (xy 40.146541 -276.027981) (xy 40.199559 -276.018188) (xy 40.253438 -276.016219)
			(xy 40.307029 -276.022116) (xy 40.35919 -276.035752) (xy 40.40881 -276.056839) (xy 40.454831 -276.084925)
			(xy 40.496273 -276.119413) (xy 40.532251 -276.159567) (xy 40.561999 -276.204531) (xy 40.584884 -276.253348)
			(xy 40.600416 -276.304977) (xy 40.608266 -276.358317) (xy 40.608758 -276.385274) (xy 43.970717 -276.385274)
			(xy 43.974652 -276.331503) (xy 43.986375 -276.278879) (xy 44.005635 -276.228522) (xy 44.032021 -276.181505)
			(xy 44.064973 -276.138832) (xy 44.103786 -276.101411) (xy 44.147634 -276.070041) (xy 44.195582 -276.045389)
			(xy 44.246609 -276.027981) (xy 44.299627 -276.018188) (xy 44.353506 -276.016219) (xy 44.407097 -276.022116)
			(xy 44.459258 -276.035752) (xy 44.508878 -276.056839) (xy 44.554899 -276.084925) (xy 44.596341 -276.119413)
			(xy 44.632319 -276.159567) (xy 44.662067 -276.204531) (xy 44.684952 -276.253348) (xy 44.700484 -276.304977)
			(xy 44.708334 -276.358317) (xy 44.708826 -276.385274) (xy 44.708334 -276.412231) (xy 44.700484 -276.465571)
			(xy 44.684952 -276.5172) (xy 44.662067 -276.566017) (xy 44.632319 -276.610981) (xy 44.596341 -276.651135)
			(xy 44.554899 -276.685623) (xy 44.508878 -276.713709) (xy 44.459258 -276.734796) (xy 44.407097 -276.748432)
			(xy 44.353506 -276.754329) (xy 44.299627 -276.75236) (xy 44.246609 -276.742567) (xy 44.195582 -276.725159)
			(xy 44.147634 -276.700507) (xy 44.103786 -276.669137) (xy 44.064973 -276.631716) (xy 44.032021 -276.589043)
			(xy 44.005635 -276.542026) (xy 43.986375 -276.491669) (xy 43.974652 -276.439045) (xy 43.970717 -276.385274)
			(xy 40.608758 -276.385274) (xy 40.608266 -276.412231) (xy 40.600416 -276.465571) (xy 40.584884 -276.5172)
			(xy 40.561999 -276.566017) (xy 40.532251 -276.610981) (xy 40.496273 -276.651135) (xy 40.454831 -276.685623)
			(xy 40.40881 -276.713709) (xy 40.35919 -276.734796) (xy 40.307029 -276.748432) (xy 40.253438 -276.754329)
			(xy 40.199559 -276.75236) (xy 40.146541 -276.742567) (xy 40.095514 -276.725159) (xy 40.047566 -276.700507)
			(xy 40.003718 -276.669137) (xy 39.964905 -276.631716) (xy 39.931953 -276.589043) (xy 39.905567 -276.542026)
			(xy 39.886307 -276.491669) (xy 39.874584 -276.439045) (xy 39.870649 -276.385274) (xy 37.164772 -276.385274)
			(xy 37.16428 -276.412231) (xy 37.15643 -276.465571) (xy 37.140898 -276.5172) (xy 37.118013 -276.566017)
			(xy 37.088265 -276.610981) (xy 37.052287 -276.651135) (xy 37.010845 -276.685623) (xy 36.964824 -276.713709)
			(xy 36.915204 -276.734796) (xy 36.863043 -276.748432) (xy 36.809452 -276.754329) (xy 36.755573 -276.75236)
			(xy 36.702555 -276.742567) (xy 36.651528 -276.725159) (xy 36.60358 -276.700507) (xy 36.559732 -276.669137)
			(xy 36.520919 -276.631716) (xy 36.487967 -276.589043) (xy 36.461581 -276.542026) (xy 36.442321 -276.491669)
			(xy 36.430598 -276.439045) (xy 36.426663 -276.385274) (xy 33.064704 -276.385274) (xy 33.064212 -276.412231)
			(xy 33.056362 -276.465571) (xy 33.04083 -276.5172) (xy 33.017945 -276.566017) (xy 32.988197 -276.610981)
			(xy 32.952219 -276.651135) (xy 32.910777 -276.685623) (xy 32.864756 -276.713709) (xy 32.815136 -276.734796)
			(xy 32.762975 -276.748432) (xy 32.709384 -276.754329) (xy 32.655505 -276.75236) (xy 32.602487 -276.742567)
			(xy 32.55146 -276.725159) (xy 32.503512 -276.700507) (xy 32.459664 -276.669137) (xy 32.420851 -276.631716)
			(xy 32.387899 -276.589043) (xy 32.361513 -276.542026) (xy 32.342253 -276.491669) (xy 32.33053 -276.439045)
			(xy 32.326595 -276.385274) (xy 29.620972 -276.385274) (xy 29.62048 -276.412231) (xy 29.61263 -276.465571)
			(xy 29.597098 -276.5172) (xy 29.574213 -276.566017) (xy 29.544465 -276.610981) (xy 29.508487 -276.651135)
			(xy 29.467045 -276.685623) (xy 29.421024 -276.713709) (xy 29.371404 -276.734796) (xy 29.319243 -276.748432)
			(xy 29.265652 -276.754329) (xy 29.211773 -276.75236) (xy 29.158755 -276.742567) (xy 29.107728 -276.725159)
			(xy 29.05978 -276.700507) (xy 29.015932 -276.669137) (xy 28.977119 -276.631716) (xy 28.944167 -276.589043)
			(xy 28.917781 -276.542026) (xy 28.898521 -276.491669) (xy 28.886798 -276.439045) (xy 28.882863 -276.385274)
			(xy 25.520904 -276.385274) (xy 25.520412 -276.412231) (xy 25.512562 -276.465571) (xy 25.49703 -276.5172)
			(xy 25.474145 -276.566017) (xy 25.444397 -276.610981) (xy 25.408419 -276.651135) (xy 25.366977 -276.685623)
			(xy 25.320956 -276.713709) (xy 25.271336 -276.734796) (xy 25.219175 -276.748432) (xy 25.165584 -276.754329)
			(xy 25.111705 -276.75236) (xy 25.058687 -276.742567) (xy 25.00766 -276.725159) (xy 24.959712 -276.700507)
			(xy 24.915864 -276.669137) (xy 24.877051 -276.631716) (xy 24.844099 -276.589043) (xy 24.817713 -276.542026)
			(xy 24.798453 -276.491669) (xy 24.78673 -276.439045) (xy 24.782795 -276.385274) (xy 22.076918 -276.385274)
			(xy 22.076426 -276.412231) (xy 22.068576 -276.465571) (xy 22.053044 -276.5172) (xy 22.030159 -276.566017)
			(xy 22.000411 -276.610981) (xy 21.964433 -276.651135) (xy 21.922991 -276.685623) (xy 21.87697 -276.713709)
			(xy 21.82735 -276.734796) (xy 21.775189 -276.748432) (xy 21.721598 -276.754329) (xy 21.667719 -276.75236)
			(xy 21.614701 -276.742567) (xy 21.563674 -276.725159) (xy 21.515726 -276.700507) (xy 21.471878 -276.669137)
			(xy 21.433065 -276.631716) (xy 21.400113 -276.589043) (xy 21.373727 -276.542026) (xy 21.354467 -276.491669)
			(xy 21.342744 -276.439045) (xy 21.338809 -276.385274) (xy 17.97685 -276.385274) (xy 17.976358 -276.412231)
			(xy 17.968508 -276.465571) (xy 17.952976 -276.5172) (xy 17.930091 -276.566017) (xy 17.900343 -276.610981)
			(xy 17.864365 -276.651135) (xy 17.822923 -276.685623) (xy 17.776902 -276.713709) (xy 17.727282 -276.734796)
			(xy 17.675121 -276.748432) (xy 17.62153 -276.754329) (xy 17.567651 -276.75236) (xy 17.514633 -276.742567)
			(xy 17.463606 -276.725159) (xy 17.415658 -276.700507) (xy 17.37181 -276.669137) (xy 17.332997 -276.631716)
			(xy 17.300045 -276.589043) (xy 17.273659 -276.542026) (xy 17.254399 -276.491669) (xy 17.242676 -276.439045)
			(xy 17.238741 -276.385274) (xy 15.598394 -276.385274) (xy 15.598394 -277.235412) (xy 17.238741 -277.235412)
			(xy 17.242676 -277.181641) (xy 17.254399 -277.129017) (xy 17.273659 -277.07866) (xy 17.300045 -277.031643)
			(xy 17.332997 -276.98897) (xy 17.37181 -276.951549) (xy 17.415658 -276.920179) (xy 17.463606 -276.895527)
			(xy 17.514633 -276.878119) (xy 17.567651 -276.868326) (xy 17.62153 -276.866357) (xy 17.675121 -276.872254)
			(xy 17.727282 -276.88589) (xy 17.776902 -276.906977) (xy 17.822923 -276.935063) (xy 17.864365 -276.969551)
			(xy 17.900343 -277.009705) (xy 17.930091 -277.054669) (xy 17.952976 -277.103486) (xy 17.968508 -277.155115)
			(xy 17.976358 -277.208455) (xy 17.97685 -277.235412) (xy 24.782795 -277.235412) (xy 24.78673 -277.181641)
			(xy 24.798453 -277.129017) (xy 24.817713 -277.07866) (xy 24.844099 -277.031643) (xy 24.877051 -276.98897)
			(xy 24.915864 -276.951549) (xy 24.959712 -276.920179) (xy 25.00766 -276.895527) (xy 25.058687 -276.878119)
			(xy 25.111705 -276.868326) (xy 25.165584 -276.866357) (xy 25.219175 -276.872254) (xy 25.271336 -276.88589)
			(xy 25.320956 -276.906977) (xy 25.366977 -276.935063) (xy 25.408419 -276.969551) (xy 25.444397 -277.009705)
			(xy 25.474145 -277.054669) (xy 25.49703 -277.103486) (xy 25.512562 -277.155115) (xy 25.520412 -277.208455)
			(xy 25.520904 -277.235412) (xy 32.326595 -277.235412) (xy 32.33053 -277.181641) (xy 32.342253 -277.129017)
			(xy 32.361513 -277.07866) (xy 32.387899 -277.031643) (xy 32.420851 -276.98897) (xy 32.459664 -276.951549)
			(xy 32.503512 -276.920179) (xy 32.55146 -276.895527) (xy 32.602487 -276.878119) (xy 32.655505 -276.868326)
			(xy 32.709384 -276.866357) (xy 32.762975 -276.872254) (xy 32.815136 -276.88589) (xy 32.864756 -276.906977)
			(xy 32.910777 -276.935063) (xy 32.952219 -276.969551) (xy 32.988197 -277.009705) (xy 33.017945 -277.054669)
			(xy 33.04083 -277.103486) (xy 33.056362 -277.155115) (xy 33.064212 -277.208455) (xy 33.064704 -277.235412)
			(xy 39.870649 -277.235412) (xy 39.874584 -277.181641) (xy 39.886307 -277.129017) (xy 39.905567 -277.07866)
			(xy 39.931953 -277.031643) (xy 39.964905 -276.98897) (xy 40.003718 -276.951549) (xy 40.047566 -276.920179)
			(xy 40.095514 -276.895527) (xy 40.146541 -276.878119) (xy 40.199559 -276.868326) (xy 40.253438 -276.866357)
			(xy 40.307029 -276.872254) (xy 40.35919 -276.88589) (xy 40.40881 -276.906977) (xy 40.454831 -276.935063)
			(xy 40.496273 -276.969551) (xy 40.532251 -277.009705) (xy 40.561999 -277.054669) (xy 40.584884 -277.103486)
			(xy 40.600416 -277.155115) (xy 40.608266 -277.208455) (xy 40.608758 -277.235412) (xy 40.608266 -277.262369)
			(xy 40.600416 -277.315709) (xy 40.584884 -277.367338) (xy 40.561999 -277.416155) (xy 40.532251 -277.461119)
			(xy 40.496273 -277.501273) (xy 40.454831 -277.535761) (xy 40.40881 -277.563847) (xy 40.35919 -277.584934)
			(xy 40.307029 -277.59857) (xy 40.253438 -277.604467) (xy 40.199559 -277.602498) (xy 40.146541 -277.592705)
			(xy 40.095514 -277.575297) (xy 40.047566 -277.550645) (xy 40.003718 -277.519275) (xy 39.964905 -277.481854)
			(xy 39.931953 -277.439181) (xy 39.905567 -277.392164) (xy 39.886307 -277.341807) (xy 39.874584 -277.289183)
			(xy 39.870649 -277.235412) (xy 33.064704 -277.235412) (xy 33.064212 -277.262369) (xy 33.056362 -277.315709)
			(xy 33.04083 -277.367338) (xy 33.017945 -277.416155) (xy 32.988197 -277.461119) (xy 32.952219 -277.501273)
			(xy 32.910777 -277.535761) (xy 32.864756 -277.563847) (xy 32.815136 -277.584934) (xy 32.762975 -277.59857)
			(xy 32.709384 -277.604467) (xy 32.655505 -277.602498) (xy 32.602487 -277.592705) (xy 32.55146 -277.575297)
			(xy 32.503512 -277.550645) (xy 32.459664 -277.519275) (xy 32.420851 -277.481854) (xy 32.387899 -277.439181)
			(xy 32.361513 -277.392164) (xy 32.342253 -277.341807) (xy 32.33053 -277.289183) (xy 32.326595 -277.235412)
			(xy 25.520904 -277.235412) (xy 25.520412 -277.262369) (xy 25.512562 -277.315709) (xy 25.49703 -277.367338)
			(xy 25.474145 -277.416155) (xy 25.444397 -277.461119) (xy 25.408419 -277.501273) (xy 25.366977 -277.535761)
			(xy 25.320956 -277.563847) (xy 25.271336 -277.584934) (xy 25.219175 -277.59857) (xy 25.165584 -277.604467)
			(xy 25.111705 -277.602498) (xy 25.058687 -277.592705) (xy 25.00766 -277.575297) (xy 24.959712 -277.550645)
			(xy 24.915864 -277.519275) (xy 24.877051 -277.481854) (xy 24.844099 -277.439181) (xy 24.817713 -277.392164)
			(xy 24.798453 -277.341807) (xy 24.78673 -277.289183) (xy 24.782795 -277.235412) (xy 17.97685 -277.235412)
			(xy 17.976358 -277.262369) (xy 17.968508 -277.315709) (xy 17.952976 -277.367338) (xy 17.930091 -277.416155)
			(xy 17.900343 -277.461119) (xy 17.864365 -277.501273) (xy 17.822923 -277.535761) (xy 17.776902 -277.563847)
			(xy 17.727282 -277.584934) (xy 17.675121 -277.59857) (xy 17.62153 -277.604467) (xy 17.567651 -277.602498)
			(xy 17.514633 -277.592705) (xy 17.463606 -277.575297) (xy 17.415658 -277.550645) (xy 17.37181 -277.519275)
			(xy 17.332997 -277.481854) (xy 17.300045 -277.439181) (xy 17.273659 -277.392164) (xy 17.254399 -277.341807)
			(xy 17.242676 -277.289183) (xy 17.238741 -277.235412) (xy 15.598394 -277.235412) (xy 15.598394 -278.085296)
			(xy 21.338809 -278.085296) (xy 21.342744 -278.031525) (xy 21.354467 -277.978901) (xy 21.373727 -277.928544)
			(xy 21.400113 -277.881527) (xy 21.433065 -277.838854) (xy 21.471878 -277.801433) (xy 21.515726 -277.770063)
			(xy 21.563674 -277.745411) (xy 21.614701 -277.728003) (xy 21.667719 -277.71821) (xy 21.721598 -277.716241)
			(xy 21.775189 -277.722138) (xy 21.82735 -277.735774) (xy 21.87697 -277.756861) (xy 21.922991 -277.784947)
			(xy 21.964433 -277.819435) (xy 22.000411 -277.859589) (xy 22.030159 -277.904553) (xy 22.053044 -277.95337)
			(xy 22.068576 -278.004999) (xy 22.076426 -278.058339) (xy 22.076918 -278.085296) (xy 28.882863 -278.085296)
			(xy 28.886798 -278.031525) (xy 28.898521 -277.978901) (xy 28.917781 -277.928544) (xy 28.944167 -277.881527)
			(xy 28.977119 -277.838854) (xy 29.015932 -277.801433) (xy 29.05978 -277.770063) (xy 29.107728 -277.745411)
			(xy 29.158755 -277.728003) (xy 29.211773 -277.71821) (xy 29.265652 -277.716241) (xy 29.319243 -277.722138)
			(xy 29.371404 -277.735774) (xy 29.421024 -277.756861) (xy 29.467045 -277.784947) (xy 29.508487 -277.819435)
			(xy 29.544465 -277.859589) (xy 29.574213 -277.904553) (xy 29.597098 -277.95337) (xy 29.61263 -278.004999)
			(xy 29.62048 -278.058339) (xy 29.620972 -278.085296) (xy 36.426663 -278.085296) (xy 36.430598 -278.031525)
			(xy 36.442321 -277.978901) (xy 36.461581 -277.928544) (xy 36.487967 -277.881527) (xy 36.520919 -277.838854)
			(xy 36.559732 -277.801433) (xy 36.60358 -277.770063) (xy 36.651528 -277.745411) (xy 36.702555 -277.728003)
			(xy 36.755573 -277.71821) (xy 36.809452 -277.716241) (xy 36.863043 -277.722138) (xy 36.915204 -277.735774)
			(xy 36.964824 -277.756861) (xy 37.010845 -277.784947) (xy 37.052287 -277.819435) (xy 37.088265 -277.859589)
			(xy 37.118013 -277.904553) (xy 37.140898 -277.95337) (xy 37.15643 -278.004999) (xy 37.16428 -278.058339)
			(xy 37.164772 -278.085296) (xy 43.970717 -278.085296) (xy 43.974652 -278.031525) (xy 43.986375 -277.978901)
			(xy 44.005635 -277.928544) (xy 44.032021 -277.881527) (xy 44.064973 -277.838854) (xy 44.103786 -277.801433)
			(xy 44.147634 -277.770063) (xy 44.195582 -277.745411) (xy 44.246609 -277.728003) (xy 44.299627 -277.71821)
			(xy 44.353506 -277.716241) (xy 44.407097 -277.722138) (xy 44.459258 -277.735774) (xy 44.508878 -277.756861)
			(xy 44.554899 -277.784947) (xy 44.596341 -277.819435) (xy 44.632319 -277.859589) (xy 44.662067 -277.904553)
			(xy 44.684952 -277.95337) (xy 44.700484 -278.004999) (xy 44.708334 -278.058339) (xy 44.708826 -278.085296)
			(xy 44.708334 -278.112253) (xy 44.700484 -278.165593) (xy 44.684952 -278.217222) (xy 44.662067 -278.266039)
			(xy 44.632319 -278.311003) (xy 44.596341 -278.351157) (xy 44.554899 -278.385645) (xy 44.508878 -278.413731)
			(xy 44.459258 -278.434818) (xy 44.407097 -278.448454) (xy 44.353506 -278.454351) (xy 44.299627 -278.452382)
			(xy 44.246609 -278.442589) (xy 44.195582 -278.425181) (xy 44.147634 -278.400529) (xy 44.103786 -278.369159)
			(xy 44.064973 -278.331738) (xy 44.032021 -278.289065) (xy 44.005635 -278.242048) (xy 43.986375 -278.191691)
			(xy 43.974652 -278.139067) (xy 43.970717 -278.085296) (xy 37.164772 -278.085296) (xy 37.16428 -278.112253)
			(xy 37.15643 -278.165593) (xy 37.140898 -278.217222) (xy 37.118013 -278.266039) (xy 37.088265 -278.311003)
			(xy 37.052287 -278.351157) (xy 37.010845 -278.385645) (xy 36.964824 -278.413731) (xy 36.915204 -278.434818)
			(xy 36.863043 -278.448454) (xy 36.809452 -278.454351) (xy 36.755573 -278.452382) (xy 36.702555 -278.442589)
			(xy 36.651528 -278.425181) (xy 36.60358 -278.400529) (xy 36.559732 -278.369159) (xy 36.520919 -278.331738)
			(xy 36.487967 -278.289065) (xy 36.461581 -278.242048) (xy 36.442321 -278.191691) (xy 36.430598 -278.139067)
			(xy 36.426663 -278.085296) (xy 29.620972 -278.085296) (xy 29.62048 -278.112253) (xy 29.61263 -278.165593)
			(xy 29.597098 -278.217222) (xy 29.574213 -278.266039) (xy 29.544465 -278.311003) (xy 29.508487 -278.351157)
			(xy 29.467045 -278.385645) (xy 29.421024 -278.413731) (xy 29.371404 -278.434818) (xy 29.319243 -278.448454)
			(xy 29.265652 -278.454351) (xy 29.211773 -278.452382) (xy 29.158755 -278.442589) (xy 29.107728 -278.425181)
			(xy 29.05978 -278.400529) (xy 29.015932 -278.369159) (xy 28.977119 -278.331738) (xy 28.944167 -278.289065)
			(xy 28.917781 -278.242048) (xy 28.898521 -278.191691) (xy 28.886798 -278.139067) (xy 28.882863 -278.085296)
			(xy 22.076918 -278.085296) (xy 22.076426 -278.112253) (xy 22.068576 -278.165593) (xy 22.053044 -278.217222)
			(xy 22.030159 -278.266039) (xy 22.000411 -278.311003) (xy 21.964433 -278.351157) (xy 21.922991 -278.385645)
			(xy 21.87697 -278.413731) (xy 21.82735 -278.434818) (xy 21.775189 -278.448454) (xy 21.721598 -278.454351)
			(xy 21.667719 -278.452382) (xy 21.614701 -278.442589) (xy 21.563674 -278.425181) (xy 21.515726 -278.400529)
			(xy 21.471878 -278.369159) (xy 21.433065 -278.331738) (xy 21.400113 -278.289065) (xy 21.373727 -278.242048)
			(xy 21.354467 -278.191691) (xy 21.342744 -278.139067) (xy 21.338809 -278.085296) (xy 15.598394 -278.085296)
			(xy 15.598394 -278.935434) (xy 17.238741 -278.935434) (xy 17.242676 -278.881663) (xy 17.254399 -278.829039)
			(xy 17.273659 -278.778682) (xy 17.300045 -278.731665) (xy 17.332997 -278.688992) (xy 17.37181 -278.651571)
			(xy 17.415658 -278.620201) (xy 17.463606 -278.595549) (xy 17.514633 -278.578141) (xy 17.567651 -278.568348)
			(xy 17.62153 -278.566379) (xy 17.675121 -278.572276) (xy 17.727282 -278.585912) (xy 17.776902 -278.606999)
			(xy 17.822923 -278.635085) (xy 17.864365 -278.669573) (xy 17.900343 -278.709727) (xy 17.930091 -278.754691)
			(xy 17.952976 -278.803508) (xy 17.968508 -278.855137) (xy 17.976358 -278.908477) (xy 17.97685 -278.935434)
			(xy 24.782795 -278.935434) (xy 24.78673 -278.881663) (xy 24.798453 -278.829039) (xy 24.817713 -278.778682)
			(xy 24.844099 -278.731665) (xy 24.877051 -278.688992) (xy 24.915864 -278.651571) (xy 24.959712 -278.620201)
			(xy 25.00766 -278.595549) (xy 25.058687 -278.578141) (xy 25.111705 -278.568348) (xy 25.165584 -278.566379)
			(xy 25.219175 -278.572276) (xy 25.271336 -278.585912) (xy 25.320956 -278.606999) (xy 25.366977 -278.635085)
			(xy 25.408419 -278.669573) (xy 25.444397 -278.709727) (xy 25.474145 -278.754691) (xy 25.49703 -278.803508)
			(xy 25.512562 -278.855137) (xy 25.520412 -278.908477) (xy 25.520904 -278.935434) (xy 32.326595 -278.935434)
			(xy 32.33053 -278.881663) (xy 32.342253 -278.829039) (xy 32.361513 -278.778682) (xy 32.387899 -278.731665)
			(xy 32.420851 -278.688992) (xy 32.459664 -278.651571) (xy 32.503512 -278.620201) (xy 32.55146 -278.595549)
			(xy 32.602487 -278.578141) (xy 32.655505 -278.568348) (xy 32.709384 -278.566379) (xy 32.762975 -278.572276)
			(xy 32.815136 -278.585912) (xy 32.864756 -278.606999) (xy 32.910777 -278.635085) (xy 32.952219 -278.669573)
			(xy 32.988197 -278.709727) (xy 33.017945 -278.754691) (xy 33.04083 -278.803508) (xy 33.056362 -278.855137)
			(xy 33.064212 -278.908477) (xy 33.064704 -278.935434) (xy 39.870649 -278.935434) (xy 39.874584 -278.881663)
			(xy 39.886307 -278.829039) (xy 39.905567 -278.778682) (xy 39.931953 -278.731665) (xy 39.964905 -278.688992)
			(xy 40.003718 -278.651571) (xy 40.047566 -278.620201) (xy 40.095514 -278.595549) (xy 40.146541 -278.578141)
			(xy 40.199559 -278.568348) (xy 40.253438 -278.566379) (xy 40.307029 -278.572276) (xy 40.35919 -278.585912)
			(xy 40.40881 -278.606999) (xy 40.454831 -278.635085) (xy 40.496273 -278.669573) (xy 40.532251 -278.709727)
			(xy 40.561999 -278.754691) (xy 40.584884 -278.803508) (xy 40.600416 -278.855137) (xy 40.608266 -278.908477)
			(xy 40.608758 -278.935434) (xy 40.608266 -278.962391) (xy 40.600416 -279.015731) (xy 40.584884 -279.06736)
			(xy 40.561999 -279.116177) (xy 40.532251 -279.161141) (xy 40.496273 -279.201295) (xy 40.454831 -279.235783)
			(xy 40.40881 -279.263869) (xy 40.35919 -279.284956) (xy 40.307029 -279.298592) (xy 40.253438 -279.304489)
			(xy 40.199559 -279.30252) (xy 40.146541 -279.292727) (xy 40.095514 -279.275319) (xy 40.047566 -279.250667)
			(xy 40.003718 -279.219297) (xy 39.964905 -279.181876) (xy 39.931953 -279.139203) (xy 39.905567 -279.092186)
			(xy 39.886307 -279.041829) (xy 39.874584 -278.989205) (xy 39.870649 -278.935434) (xy 33.064704 -278.935434)
			(xy 33.064212 -278.962391) (xy 33.056362 -279.015731) (xy 33.04083 -279.06736) (xy 33.017945 -279.116177)
			(xy 32.988197 -279.161141) (xy 32.952219 -279.201295) (xy 32.910777 -279.235783) (xy 32.864756 -279.263869)
			(xy 32.815136 -279.284956) (xy 32.762975 -279.298592) (xy 32.709384 -279.304489) (xy 32.655505 -279.30252)
			(xy 32.602487 -279.292727) (xy 32.55146 -279.275319) (xy 32.503512 -279.250667) (xy 32.459664 -279.219297)
			(xy 32.420851 -279.181876) (xy 32.387899 -279.139203) (xy 32.361513 -279.092186) (xy 32.342253 -279.041829)
			(xy 32.33053 -278.989205) (xy 32.326595 -278.935434) (xy 25.520904 -278.935434) (xy 25.520412 -278.962391)
			(xy 25.512562 -279.015731) (xy 25.49703 -279.06736) (xy 25.474145 -279.116177) (xy 25.444397 -279.161141)
			(xy 25.408419 -279.201295) (xy 25.366977 -279.235783) (xy 25.320956 -279.263869) (xy 25.271336 -279.284956)
			(xy 25.219175 -279.298592) (xy 25.165584 -279.304489) (xy 25.111705 -279.30252) (xy 25.058687 -279.292727)
			(xy 25.00766 -279.275319) (xy 24.959712 -279.250667) (xy 24.915864 -279.219297) (xy 24.877051 -279.181876)
			(xy 24.844099 -279.139203) (xy 24.817713 -279.092186) (xy 24.798453 -279.041829) (xy 24.78673 -278.989205)
			(xy 24.782795 -278.935434) (xy 17.97685 -278.935434) (xy 17.976358 -278.962391) (xy 17.968508 -279.015731)
			(xy 17.952976 -279.06736) (xy 17.930091 -279.116177) (xy 17.900343 -279.161141) (xy 17.864365 -279.201295)
			(xy 17.822923 -279.235783) (xy 17.776902 -279.263869) (xy 17.727282 -279.284956) (xy 17.675121 -279.298592)
			(xy 17.62153 -279.304489) (xy 17.567651 -279.30252) (xy 17.514633 -279.292727) (xy 17.463606 -279.275319)
			(xy 17.415658 -279.250667) (xy 17.37181 -279.219297) (xy 17.332997 -279.181876) (xy 17.300045 -279.139203)
			(xy 17.273659 -279.092186) (xy 17.254399 -279.041829) (xy 17.242676 -278.989205) (xy 17.238741 -278.935434)
			(xy 15.598394 -278.935434) (xy 15.598394 -279.785318) (xy 21.338809 -279.785318) (xy 21.342744 -279.731547)
			(xy 21.354467 -279.678923) (xy 21.373727 -279.628566) (xy 21.400113 -279.581549) (xy 21.433065 -279.538876)
			(xy 21.471878 -279.501455) (xy 21.515726 -279.470085) (xy 21.563674 -279.445433) (xy 21.614701 -279.428025)
			(xy 21.667719 -279.418232) (xy 21.721598 -279.416263) (xy 21.775189 -279.42216) (xy 21.82735 -279.435796)
			(xy 21.87697 -279.456883) (xy 21.922991 -279.484969) (xy 21.964433 -279.519457) (xy 22.000411 -279.559611)
			(xy 22.030159 -279.604575) (xy 22.053044 -279.653392) (xy 22.068576 -279.705021) (xy 22.076426 -279.758361)
			(xy 22.076918 -279.785318) (xy 28.882863 -279.785318) (xy 28.886798 -279.731547) (xy 28.898521 -279.678923)
			(xy 28.917781 -279.628566) (xy 28.944167 -279.581549) (xy 28.977119 -279.538876) (xy 29.015932 -279.501455)
			(xy 29.05978 -279.470085) (xy 29.107728 -279.445433) (xy 29.158755 -279.428025) (xy 29.211773 -279.418232)
			(xy 29.265652 -279.416263) (xy 29.319243 -279.42216) (xy 29.371404 -279.435796) (xy 29.421024 -279.456883)
			(xy 29.467045 -279.484969) (xy 29.508487 -279.519457) (xy 29.544465 -279.559611) (xy 29.574213 -279.604575)
			(xy 29.597098 -279.653392) (xy 29.61263 -279.705021) (xy 29.62048 -279.758361) (xy 29.620972 -279.785318)
			(xy 36.426663 -279.785318) (xy 36.430598 -279.731547) (xy 36.442321 -279.678923) (xy 36.461581 -279.628566)
			(xy 36.487967 -279.581549) (xy 36.520919 -279.538876) (xy 36.559732 -279.501455) (xy 36.60358 -279.470085)
			(xy 36.651528 -279.445433) (xy 36.702555 -279.428025) (xy 36.755573 -279.418232) (xy 36.809452 -279.416263)
			(xy 36.863043 -279.42216) (xy 36.915204 -279.435796) (xy 36.964824 -279.456883) (xy 37.010845 -279.484969)
			(xy 37.052287 -279.519457) (xy 37.088265 -279.559611) (xy 37.118013 -279.604575) (xy 37.140898 -279.653392)
			(xy 37.15643 -279.705021) (xy 37.16428 -279.758361) (xy 37.164772 -279.785318) (xy 43.970717 -279.785318)
			(xy 43.974652 -279.731547) (xy 43.986375 -279.678923) (xy 44.005635 -279.628566) (xy 44.032021 -279.581549)
			(xy 44.064973 -279.538876) (xy 44.103786 -279.501455) (xy 44.147634 -279.470085) (xy 44.195582 -279.445433)
			(xy 44.246609 -279.428025) (xy 44.299627 -279.418232) (xy 44.353506 -279.416263) (xy 44.407097 -279.42216)
			(xy 44.459258 -279.435796) (xy 44.508878 -279.456883) (xy 44.554899 -279.484969) (xy 44.596341 -279.519457)
			(xy 44.632319 -279.559611) (xy 44.662067 -279.604575) (xy 44.684952 -279.653392) (xy 44.700484 -279.705021)
			(xy 44.708334 -279.758361) (xy 44.708826 -279.785318) (xy 44.708334 -279.812275) (xy 44.700484 -279.865615)
			(xy 44.684952 -279.917244) (xy 44.662067 -279.966061) (xy 44.632319 -280.011025) (xy 44.596341 -280.051179)
			(xy 44.554899 -280.085667) (xy 44.508878 -280.113753) (xy 44.459258 -280.13484) (xy 44.407097 -280.148476)
			(xy 44.353506 -280.154373) (xy 44.299627 -280.152404) (xy 44.246609 -280.142611) (xy 44.195582 -280.125203)
			(xy 44.147634 -280.100551) (xy 44.103786 -280.069181) (xy 44.064973 -280.03176) (xy 44.032021 -279.989087)
			(xy 44.005635 -279.94207) (xy 43.986375 -279.891713) (xy 43.974652 -279.839089) (xy 43.970717 -279.785318)
			(xy 37.164772 -279.785318) (xy 37.16428 -279.812275) (xy 37.15643 -279.865615) (xy 37.140898 -279.917244)
			(xy 37.118013 -279.966061) (xy 37.088265 -280.011025) (xy 37.052287 -280.051179) (xy 37.010845 -280.085667)
			(xy 36.964824 -280.113753) (xy 36.915204 -280.13484) (xy 36.863043 -280.148476) (xy 36.809452 -280.154373)
			(xy 36.755573 -280.152404) (xy 36.702555 -280.142611) (xy 36.651528 -280.125203) (xy 36.60358 -280.100551)
			(xy 36.559732 -280.069181) (xy 36.520919 -280.03176) (xy 36.487967 -279.989087) (xy 36.461581 -279.94207)
			(xy 36.442321 -279.891713) (xy 36.430598 -279.839089) (xy 36.426663 -279.785318) (xy 29.620972 -279.785318)
			(xy 29.62048 -279.812275) (xy 29.61263 -279.865615) (xy 29.597098 -279.917244) (xy 29.574213 -279.966061)
			(xy 29.544465 -280.011025) (xy 29.508487 -280.051179) (xy 29.467045 -280.085667) (xy 29.421024 -280.113753)
			(xy 29.371404 -280.13484) (xy 29.319243 -280.148476) (xy 29.265652 -280.154373) (xy 29.211773 -280.152404)
			(xy 29.158755 -280.142611) (xy 29.107728 -280.125203) (xy 29.05978 -280.100551) (xy 29.015932 -280.069181)
			(xy 28.977119 -280.03176) (xy 28.944167 -279.989087) (xy 28.917781 -279.94207) (xy 28.898521 -279.891713)
			(xy 28.886798 -279.839089) (xy 28.882863 -279.785318) (xy 22.076918 -279.785318) (xy 22.076426 -279.812275)
			(xy 22.068576 -279.865615) (xy 22.053044 -279.917244) (xy 22.030159 -279.966061) (xy 22.000411 -280.011025)
			(xy 21.964433 -280.051179) (xy 21.922991 -280.085667) (xy 21.87697 -280.113753) (xy 21.82735 -280.13484)
			(xy 21.775189 -280.148476) (xy 21.721598 -280.154373) (xy 21.667719 -280.152404) (xy 21.614701 -280.142611)
			(xy 21.563674 -280.125203) (xy 21.515726 -280.100551) (xy 21.471878 -280.069181) (xy 21.433065 -280.03176)
			(xy 21.400113 -279.989087) (xy 21.373727 -279.94207) (xy 21.354467 -279.891713) (xy 21.342744 -279.839089)
			(xy 21.338809 -279.785318) (xy 15.598394 -279.785318) (xy 15.598394 -280.635202) (xy 17.238741 -280.635202)
			(xy 17.242676 -280.581431) (xy 17.254399 -280.528807) (xy 17.273659 -280.47845) (xy 17.300045 -280.431433)
			(xy 17.332997 -280.38876) (xy 17.37181 -280.351339) (xy 17.415658 -280.319969) (xy 17.463606 -280.295317)
			(xy 17.514633 -280.277909) (xy 17.567651 -280.268116) (xy 17.62153 -280.266147) (xy 17.675121 -280.272044)
			(xy 17.727282 -280.28568) (xy 17.776902 -280.306767) (xy 17.822923 -280.334853) (xy 17.864365 -280.369341)
			(xy 17.900343 -280.409495) (xy 17.930091 -280.454459) (xy 17.952976 -280.503276) (xy 17.968508 -280.554905)
			(xy 17.976358 -280.608245) (xy 17.97685 -280.635202) (xy 24.782795 -280.635202) (xy 24.78673 -280.581431)
			(xy 24.798453 -280.528807) (xy 24.817713 -280.47845) (xy 24.844099 -280.431433) (xy 24.877051 -280.38876)
			(xy 24.915864 -280.351339) (xy 24.959712 -280.319969) (xy 25.00766 -280.295317) (xy 25.058687 -280.277909)
			(xy 25.111705 -280.268116) (xy 25.165584 -280.266147) (xy 25.219175 -280.272044) (xy 25.271336 -280.28568)
			(xy 25.320956 -280.306767) (xy 25.366977 -280.334853) (xy 25.408419 -280.369341) (xy 25.444397 -280.409495)
			(xy 25.474145 -280.454459) (xy 25.49703 -280.503276) (xy 25.512562 -280.554905) (xy 25.520412 -280.608245)
			(xy 25.520904 -280.635202) (xy 32.326595 -280.635202) (xy 32.33053 -280.581431) (xy 32.342253 -280.528807)
			(xy 32.361513 -280.47845) (xy 32.387899 -280.431433) (xy 32.420851 -280.38876) (xy 32.459664 -280.351339)
			(xy 32.503512 -280.319969) (xy 32.55146 -280.295317) (xy 32.602487 -280.277909) (xy 32.655505 -280.268116)
			(xy 32.709384 -280.266147) (xy 32.762975 -280.272044) (xy 32.815136 -280.28568) (xy 32.864756 -280.306767)
			(xy 32.910777 -280.334853) (xy 32.952219 -280.369341) (xy 32.988197 -280.409495) (xy 33.017945 -280.454459)
			(xy 33.04083 -280.503276) (xy 33.056362 -280.554905) (xy 33.064212 -280.608245) (xy 33.064704 -280.635202)
			(xy 39.870649 -280.635202) (xy 39.874584 -280.581431) (xy 39.886307 -280.528807) (xy 39.905567 -280.47845)
			(xy 39.931953 -280.431433) (xy 39.964905 -280.38876) (xy 40.003718 -280.351339) (xy 40.047566 -280.319969)
			(xy 40.095514 -280.295317) (xy 40.146541 -280.277909) (xy 40.199559 -280.268116) (xy 40.253438 -280.266147)
			(xy 40.307029 -280.272044) (xy 40.35919 -280.28568) (xy 40.40881 -280.306767) (xy 40.454831 -280.334853)
			(xy 40.496273 -280.369341) (xy 40.532251 -280.409495) (xy 40.561999 -280.454459) (xy 40.584884 -280.503276)
			(xy 40.600416 -280.554905) (xy 40.608266 -280.608245) (xy 40.608758 -280.635202) (xy 40.608266 -280.662159)
			(xy 40.600416 -280.715499) (xy 40.584884 -280.767128) (xy 40.561999 -280.815945) (xy 40.532251 -280.860909)
			(xy 40.496273 -280.901063) (xy 40.454831 -280.935551) (xy 40.40881 -280.963637) (xy 40.35919 -280.984724)
			(xy 40.307029 -280.99836) (xy 40.253438 -281.004257) (xy 40.199559 -281.002288) (xy 40.146541 -280.992495)
			(xy 40.095514 -280.975087) (xy 40.047566 -280.950435) (xy 40.003718 -280.919065) (xy 39.964905 -280.881644)
			(xy 39.931953 -280.838971) (xy 39.905567 -280.791954) (xy 39.886307 -280.741597) (xy 39.874584 -280.688973)
			(xy 39.870649 -280.635202) (xy 33.064704 -280.635202) (xy 33.064212 -280.662159) (xy 33.056362 -280.715499)
			(xy 33.04083 -280.767128) (xy 33.017945 -280.815945) (xy 32.988197 -280.860909) (xy 32.952219 -280.901063)
			(xy 32.910777 -280.935551) (xy 32.864756 -280.963637) (xy 32.815136 -280.984724) (xy 32.762975 -280.99836)
			(xy 32.709384 -281.004257) (xy 32.655505 -281.002288) (xy 32.602487 -280.992495) (xy 32.55146 -280.975087)
			(xy 32.503512 -280.950435) (xy 32.459664 -280.919065) (xy 32.420851 -280.881644) (xy 32.387899 -280.838971)
			(xy 32.361513 -280.791954) (xy 32.342253 -280.741597) (xy 32.33053 -280.688973) (xy 32.326595 -280.635202)
			(xy 25.520904 -280.635202) (xy 25.520412 -280.662159) (xy 25.512562 -280.715499) (xy 25.49703 -280.767128)
			(xy 25.474145 -280.815945) (xy 25.444397 -280.860909) (xy 25.408419 -280.901063) (xy 25.366977 -280.935551)
			(xy 25.320956 -280.963637) (xy 25.271336 -280.984724) (xy 25.219175 -280.99836) (xy 25.165584 -281.004257)
			(xy 25.111705 -281.002288) (xy 25.058687 -280.992495) (xy 25.00766 -280.975087) (xy 24.959712 -280.950435)
			(xy 24.915864 -280.919065) (xy 24.877051 -280.881644) (xy 24.844099 -280.838971) (xy 24.817713 -280.791954)
			(xy 24.798453 -280.741597) (xy 24.78673 -280.688973) (xy 24.782795 -280.635202) (xy 17.97685 -280.635202)
			(xy 17.976358 -280.662159) (xy 17.968508 -280.715499) (xy 17.952976 -280.767128) (xy 17.930091 -280.815945)
			(xy 17.900343 -280.860909) (xy 17.864365 -280.901063) (xy 17.822923 -280.935551) (xy 17.776902 -280.963637)
			(xy 17.727282 -280.984724) (xy 17.675121 -280.99836) (xy 17.62153 -281.004257) (xy 17.567651 -281.002288)
			(xy 17.514633 -280.992495) (xy 17.463606 -280.975087) (xy 17.415658 -280.950435) (xy 17.37181 -280.919065)
			(xy 17.332997 -280.881644) (xy 17.300045 -280.838971) (xy 17.273659 -280.791954) (xy 17.254399 -280.741597)
			(xy 17.242676 -280.688973) (xy 17.238741 -280.635202) (xy 15.598394 -280.635202) (xy 15.598394 -281.48534)
			(xy 21.338809 -281.48534) (xy 21.342744 -281.431569) (xy 21.354467 -281.378945) (xy 21.373727 -281.328588)
			(xy 21.400113 -281.281571) (xy 21.433065 -281.238898) (xy 21.471878 -281.201477) (xy 21.515726 -281.170107)
			(xy 21.563674 -281.145455) (xy 21.614701 -281.128047) (xy 21.667719 -281.118254) (xy 21.721598 -281.116285)
			(xy 21.775189 -281.122182) (xy 21.82735 -281.135818) (xy 21.87697 -281.156905) (xy 21.922991 -281.184991)
			(xy 21.964433 -281.219479) (xy 22.000411 -281.259633) (xy 22.030159 -281.304597) (xy 22.053044 -281.353414)
			(xy 22.068576 -281.405043) (xy 22.076426 -281.458383) (xy 22.076918 -281.48534) (xy 28.882863 -281.48534)
			(xy 28.886798 -281.431569) (xy 28.898521 -281.378945) (xy 28.917781 -281.328588) (xy 28.944167 -281.281571)
			(xy 28.977119 -281.238898) (xy 29.015932 -281.201477) (xy 29.05978 -281.170107) (xy 29.107728 -281.145455)
			(xy 29.158755 -281.128047) (xy 29.211773 -281.118254) (xy 29.265652 -281.116285) (xy 29.319243 -281.122182)
			(xy 29.371404 -281.135818) (xy 29.421024 -281.156905) (xy 29.467045 -281.184991) (xy 29.508487 -281.219479)
			(xy 29.544465 -281.259633) (xy 29.574213 -281.304597) (xy 29.597098 -281.353414) (xy 29.61263 -281.405043)
			(xy 29.62048 -281.458383) (xy 29.620972 -281.48534) (xy 36.426663 -281.48534) (xy 36.430598 -281.431569)
			(xy 36.442321 -281.378945) (xy 36.461581 -281.328588) (xy 36.487967 -281.281571) (xy 36.520919 -281.238898)
			(xy 36.559732 -281.201477) (xy 36.60358 -281.170107) (xy 36.651528 -281.145455) (xy 36.702555 -281.128047)
			(xy 36.755573 -281.118254) (xy 36.809452 -281.116285) (xy 36.863043 -281.122182) (xy 36.915204 -281.135818)
			(xy 36.964824 -281.156905) (xy 37.010845 -281.184991) (xy 37.052287 -281.219479) (xy 37.088265 -281.259633)
			(xy 37.118013 -281.304597) (xy 37.140898 -281.353414) (xy 37.15643 -281.405043) (xy 37.16428 -281.458383)
			(xy 37.164772 -281.48534) (xy 43.970717 -281.48534) (xy 43.974652 -281.431569) (xy 43.986375 -281.378945)
			(xy 44.005635 -281.328588) (xy 44.032021 -281.281571) (xy 44.064973 -281.238898) (xy 44.103786 -281.201477)
			(xy 44.147634 -281.170107) (xy 44.195582 -281.145455) (xy 44.246609 -281.128047) (xy 44.299627 -281.118254)
			(xy 44.353506 -281.116285) (xy 44.407097 -281.122182) (xy 44.459258 -281.135818) (xy 44.508878 -281.156905)
			(xy 44.554899 -281.184991) (xy 44.596341 -281.219479) (xy 44.632319 -281.259633) (xy 44.662067 -281.304597)
			(xy 44.684952 -281.353414) (xy 44.700484 -281.405043) (xy 44.708334 -281.458383) (xy 44.708826 -281.48534)
			(xy 44.708334 -281.512297) (xy 44.700484 -281.565637) (xy 44.684952 -281.617266) (xy 44.662067 -281.666083)
			(xy 44.632319 -281.711047) (xy 44.596341 -281.751201) (xy 44.554899 -281.785689) (xy 44.508878 -281.813775)
			(xy 44.459258 -281.834862) (xy 44.407097 -281.848498) (xy 44.353506 -281.854395) (xy 44.299627 -281.852426)
			(xy 44.246609 -281.842633) (xy 44.195582 -281.825225) (xy 44.147634 -281.800573) (xy 44.103786 -281.769203)
			(xy 44.064973 -281.731782) (xy 44.032021 -281.689109) (xy 44.005635 -281.642092) (xy 43.986375 -281.591735)
			(xy 43.974652 -281.539111) (xy 43.970717 -281.48534) (xy 37.164772 -281.48534) (xy 37.16428 -281.512297)
			(xy 37.15643 -281.565637) (xy 37.140898 -281.617266) (xy 37.118013 -281.666083) (xy 37.088265 -281.711047)
			(xy 37.052287 -281.751201) (xy 37.010845 -281.785689) (xy 36.964824 -281.813775) (xy 36.915204 -281.834862)
			(xy 36.863043 -281.848498) (xy 36.809452 -281.854395) (xy 36.755573 -281.852426) (xy 36.702555 -281.842633)
			(xy 36.651528 -281.825225) (xy 36.60358 -281.800573) (xy 36.559732 -281.769203) (xy 36.520919 -281.731782)
			(xy 36.487967 -281.689109) (xy 36.461581 -281.642092) (xy 36.442321 -281.591735) (xy 36.430598 -281.539111)
			(xy 36.426663 -281.48534) (xy 29.620972 -281.48534) (xy 29.62048 -281.512297) (xy 29.61263 -281.565637)
			(xy 29.597098 -281.617266) (xy 29.574213 -281.666083) (xy 29.544465 -281.711047) (xy 29.508487 -281.751201)
			(xy 29.467045 -281.785689) (xy 29.421024 -281.813775) (xy 29.371404 -281.834862) (xy 29.319243 -281.848498)
			(xy 29.265652 -281.854395) (xy 29.211773 -281.852426) (xy 29.158755 -281.842633) (xy 29.107728 -281.825225)
			(xy 29.05978 -281.800573) (xy 29.015932 -281.769203) (xy 28.977119 -281.731782) (xy 28.944167 -281.689109)
			(xy 28.917781 -281.642092) (xy 28.898521 -281.591735) (xy 28.886798 -281.539111) (xy 28.882863 -281.48534)
			(xy 22.076918 -281.48534) (xy 22.076426 -281.512297) (xy 22.068576 -281.565637) (xy 22.053044 -281.617266)
			(xy 22.030159 -281.666083) (xy 22.000411 -281.711047) (xy 21.964433 -281.751201) (xy 21.922991 -281.785689)
			(xy 21.87697 -281.813775) (xy 21.82735 -281.834862) (xy 21.775189 -281.848498) (xy 21.721598 -281.854395)
			(xy 21.667719 -281.852426) (xy 21.614701 -281.842633) (xy 21.563674 -281.825225) (xy 21.515726 -281.800573)
			(xy 21.471878 -281.769203) (xy 21.433065 -281.731782) (xy 21.400113 -281.689109) (xy 21.373727 -281.642092)
			(xy 21.354467 -281.591735) (xy 21.342744 -281.539111) (xy 21.338809 -281.48534) (xy 15.598394 -281.48534)
			(xy 15.598394 -282.335224) (xy 17.238741 -282.335224) (xy 17.242676 -282.281453) (xy 17.254399 -282.228829)
			(xy 17.273659 -282.178472) (xy 17.300045 -282.131455) (xy 17.332997 -282.088782) (xy 17.37181 -282.051361)
			(xy 17.415658 -282.019991) (xy 17.463606 -281.995339) (xy 17.514633 -281.977931) (xy 17.567651 -281.968138)
			(xy 17.62153 -281.966169) (xy 17.675121 -281.972066) (xy 17.727282 -281.985702) (xy 17.776902 -282.006789)
			(xy 17.822923 -282.034875) (xy 17.864365 -282.069363) (xy 17.900343 -282.109517) (xy 17.930091 -282.154481)
			(xy 17.952976 -282.203298) (xy 17.968508 -282.254927) (xy 17.976358 -282.308267) (xy 17.97685 -282.335224)
			(xy 24.782795 -282.335224) (xy 24.78673 -282.281453) (xy 24.798453 -282.228829) (xy 24.817713 -282.178472)
			(xy 24.844099 -282.131455) (xy 24.877051 -282.088782) (xy 24.915864 -282.051361) (xy 24.959712 -282.019991)
			(xy 25.00766 -281.995339) (xy 25.058687 -281.977931) (xy 25.111705 -281.968138) (xy 25.165584 -281.966169)
			(xy 25.219175 -281.972066) (xy 25.271336 -281.985702) (xy 25.320956 -282.006789) (xy 25.366977 -282.034875)
			(xy 25.408419 -282.069363) (xy 25.444397 -282.109517) (xy 25.474145 -282.154481) (xy 25.49703 -282.203298)
			(xy 25.512562 -282.254927) (xy 25.520412 -282.308267) (xy 25.520904 -282.335224) (xy 32.326595 -282.335224)
			(xy 32.33053 -282.281453) (xy 32.342253 -282.228829) (xy 32.361513 -282.178472) (xy 32.387899 -282.131455)
			(xy 32.420851 -282.088782) (xy 32.459664 -282.051361) (xy 32.503512 -282.019991) (xy 32.55146 -281.995339)
			(xy 32.602487 -281.977931) (xy 32.655505 -281.968138) (xy 32.709384 -281.966169) (xy 32.762975 -281.972066)
			(xy 32.815136 -281.985702) (xy 32.864756 -282.006789) (xy 32.910777 -282.034875) (xy 32.952219 -282.069363)
			(xy 32.988197 -282.109517) (xy 33.017945 -282.154481) (xy 33.04083 -282.203298) (xy 33.056362 -282.254927)
			(xy 33.064212 -282.308267) (xy 33.064704 -282.335224) (xy 39.870649 -282.335224) (xy 39.874584 -282.281453)
			(xy 39.886307 -282.228829) (xy 39.905567 -282.178472) (xy 39.931953 -282.131455) (xy 39.964905 -282.088782)
			(xy 40.003718 -282.051361) (xy 40.047566 -282.019991) (xy 40.095514 -281.995339) (xy 40.146541 -281.977931)
			(xy 40.199559 -281.968138) (xy 40.253438 -281.966169) (xy 40.307029 -281.972066) (xy 40.35919 -281.985702)
			(xy 40.40881 -282.006789) (xy 40.454831 -282.034875) (xy 40.496273 -282.069363) (xy 40.532251 -282.109517)
			(xy 40.561999 -282.154481) (xy 40.584884 -282.203298) (xy 40.600416 -282.254927) (xy 40.608266 -282.308267)
			(xy 40.608758 -282.335224) (xy 40.608266 -282.362181) (xy 40.600416 -282.415521) (xy 40.584884 -282.46715)
			(xy 40.561999 -282.515967) (xy 40.532251 -282.560931) (xy 40.496273 -282.601085) (xy 40.454831 -282.635573)
			(xy 40.40881 -282.663659) (xy 40.35919 -282.684746) (xy 40.307029 -282.698382) (xy 40.253438 -282.704279)
			(xy 40.199559 -282.70231) (xy 40.146541 -282.692517) (xy 40.095514 -282.675109) (xy 40.047566 -282.650457)
			(xy 40.003718 -282.619087) (xy 39.964905 -282.581666) (xy 39.931953 -282.538993) (xy 39.905567 -282.491976)
			(xy 39.886307 -282.441619) (xy 39.874584 -282.388995) (xy 39.870649 -282.335224) (xy 33.064704 -282.335224)
			(xy 33.064212 -282.362181) (xy 33.056362 -282.415521) (xy 33.04083 -282.46715) (xy 33.017945 -282.515967)
			(xy 32.988197 -282.560931) (xy 32.952219 -282.601085) (xy 32.910777 -282.635573) (xy 32.864756 -282.663659)
			(xy 32.815136 -282.684746) (xy 32.762975 -282.698382) (xy 32.709384 -282.704279) (xy 32.655505 -282.70231)
			(xy 32.602487 -282.692517) (xy 32.55146 -282.675109) (xy 32.503512 -282.650457) (xy 32.459664 -282.619087)
			(xy 32.420851 -282.581666) (xy 32.387899 -282.538993) (xy 32.361513 -282.491976) (xy 32.342253 -282.441619)
			(xy 32.33053 -282.388995) (xy 32.326595 -282.335224) (xy 25.520904 -282.335224) (xy 25.520412 -282.362181)
			(xy 25.512562 -282.415521) (xy 25.49703 -282.46715) (xy 25.474145 -282.515967) (xy 25.444397 -282.560931)
			(xy 25.408419 -282.601085) (xy 25.366977 -282.635573) (xy 25.320956 -282.663659) (xy 25.271336 -282.684746)
			(xy 25.219175 -282.698382) (xy 25.165584 -282.704279) (xy 25.111705 -282.70231) (xy 25.058687 -282.692517)
			(xy 25.00766 -282.675109) (xy 24.959712 -282.650457) (xy 24.915864 -282.619087) (xy 24.877051 -282.581666)
			(xy 24.844099 -282.538993) (xy 24.817713 -282.491976) (xy 24.798453 -282.441619) (xy 24.78673 -282.388995)
			(xy 24.782795 -282.335224) (xy 17.97685 -282.335224) (xy 17.976358 -282.362181) (xy 17.968508 -282.415521)
			(xy 17.952976 -282.46715) (xy 17.930091 -282.515967) (xy 17.900343 -282.560931) (xy 17.864365 -282.601085)
			(xy 17.822923 -282.635573) (xy 17.776902 -282.663659) (xy 17.727282 -282.684746) (xy 17.675121 -282.698382)
			(xy 17.62153 -282.704279) (xy 17.567651 -282.70231) (xy 17.514633 -282.692517) (xy 17.463606 -282.675109)
			(xy 17.415658 -282.650457) (xy 17.37181 -282.619087) (xy 17.332997 -282.581666) (xy 17.300045 -282.538993)
			(xy 17.273659 -282.491976) (xy 17.254399 -282.441619) (xy 17.242676 -282.388995) (xy 17.238741 -282.335224)
			(xy 15.598394 -282.335224) (xy 15.598394 -283.185362) (xy 21.338809 -283.185362) (xy 21.342744 -283.131591)
			(xy 21.354467 -283.078967) (xy 21.373727 -283.02861) (xy 21.400113 -282.981593) (xy 21.433065 -282.93892)
			(xy 21.471878 -282.901499) (xy 21.515726 -282.870129) (xy 21.563674 -282.845477) (xy 21.614701 -282.828069)
			(xy 21.667719 -282.818276) (xy 21.721598 -282.816307) (xy 21.775189 -282.822204) (xy 21.82735 -282.83584)
			(xy 21.87697 -282.856927) (xy 21.922991 -282.885013) (xy 21.964433 -282.919501) (xy 22.000411 -282.959655)
			(xy 22.030159 -283.004619) (xy 22.053044 -283.053436) (xy 22.068576 -283.105065) (xy 22.076426 -283.158405)
			(xy 22.076918 -283.185362) (xy 28.882863 -283.185362) (xy 28.886798 -283.131591) (xy 28.898521 -283.078967)
			(xy 28.917781 -283.02861) (xy 28.944167 -282.981593) (xy 28.977119 -282.93892) (xy 29.015932 -282.901499)
			(xy 29.05978 -282.870129) (xy 29.107728 -282.845477) (xy 29.158755 -282.828069) (xy 29.211773 -282.818276)
			(xy 29.265652 -282.816307) (xy 29.319243 -282.822204) (xy 29.371404 -282.83584) (xy 29.421024 -282.856927)
			(xy 29.467045 -282.885013) (xy 29.508487 -282.919501) (xy 29.544465 -282.959655) (xy 29.574213 -283.004619)
			(xy 29.597098 -283.053436) (xy 29.61263 -283.105065) (xy 29.62048 -283.158405) (xy 29.620972 -283.185362)
			(xy 36.426663 -283.185362) (xy 36.430598 -283.131591) (xy 36.442321 -283.078967) (xy 36.461581 -283.02861)
			(xy 36.487967 -282.981593) (xy 36.520919 -282.93892) (xy 36.559732 -282.901499) (xy 36.60358 -282.870129)
			(xy 36.651528 -282.845477) (xy 36.702555 -282.828069) (xy 36.755573 -282.818276) (xy 36.809452 -282.816307)
			(xy 36.863043 -282.822204) (xy 36.915204 -282.83584) (xy 36.964824 -282.856927) (xy 37.010845 -282.885013)
			(xy 37.052287 -282.919501) (xy 37.088265 -282.959655) (xy 37.118013 -283.004619) (xy 37.140898 -283.053436)
			(xy 37.15643 -283.105065) (xy 37.16428 -283.158405) (xy 37.164772 -283.185362) (xy 43.970717 -283.185362)
			(xy 43.974652 -283.131591) (xy 43.986375 -283.078967) (xy 44.005635 -283.02861) (xy 44.032021 -282.981593)
			(xy 44.064973 -282.93892) (xy 44.103786 -282.901499) (xy 44.147634 -282.870129) (xy 44.195582 -282.845477)
			(xy 44.246609 -282.828069) (xy 44.299627 -282.818276) (xy 44.353506 -282.816307) (xy 44.407097 -282.822204)
			(xy 44.459258 -282.83584) (xy 44.508878 -282.856927) (xy 44.554899 -282.885013) (xy 44.596341 -282.919501)
			(xy 44.632319 -282.959655) (xy 44.662067 -283.004619) (xy 44.684952 -283.053436) (xy 44.700484 -283.105065)
			(xy 44.708334 -283.158405) (xy 44.708826 -283.185362) (xy 44.708334 -283.212319) (xy 44.700484 -283.265659)
			(xy 44.684952 -283.317288) (xy 44.662067 -283.366105) (xy 44.632319 -283.411069) (xy 44.596341 -283.451223)
			(xy 44.554899 -283.485711) (xy 44.508878 -283.513797) (xy 44.459258 -283.534884) (xy 44.407097 -283.54852)
			(xy 44.353506 -283.554417) (xy 44.299627 -283.552448) (xy 44.246609 -283.542655) (xy 44.195582 -283.525247)
			(xy 44.147634 -283.500595) (xy 44.103786 -283.469225) (xy 44.064973 -283.431804) (xy 44.032021 -283.389131)
			(xy 44.005635 -283.342114) (xy 43.986375 -283.291757) (xy 43.974652 -283.239133) (xy 43.970717 -283.185362)
			(xy 37.164772 -283.185362) (xy 37.16428 -283.212319) (xy 37.15643 -283.265659) (xy 37.140898 -283.317288)
			(xy 37.118013 -283.366105) (xy 37.088265 -283.411069) (xy 37.052287 -283.451223) (xy 37.010845 -283.485711)
			(xy 36.964824 -283.513797) (xy 36.915204 -283.534884) (xy 36.863043 -283.54852) (xy 36.809452 -283.554417)
			(xy 36.755573 -283.552448) (xy 36.702555 -283.542655) (xy 36.651528 -283.525247) (xy 36.60358 -283.500595)
			(xy 36.559732 -283.469225) (xy 36.520919 -283.431804) (xy 36.487967 -283.389131) (xy 36.461581 -283.342114)
			(xy 36.442321 -283.291757) (xy 36.430598 -283.239133) (xy 36.426663 -283.185362) (xy 29.620972 -283.185362)
			(xy 29.62048 -283.212319) (xy 29.61263 -283.265659) (xy 29.597098 -283.317288) (xy 29.574213 -283.366105)
			(xy 29.544465 -283.411069) (xy 29.508487 -283.451223) (xy 29.467045 -283.485711) (xy 29.421024 -283.513797)
			(xy 29.371404 -283.534884) (xy 29.319243 -283.54852) (xy 29.265652 -283.554417) (xy 29.211773 -283.552448)
			(xy 29.158755 -283.542655) (xy 29.107728 -283.525247) (xy 29.05978 -283.500595) (xy 29.015932 -283.469225)
			(xy 28.977119 -283.431804) (xy 28.944167 -283.389131) (xy 28.917781 -283.342114) (xy 28.898521 -283.291757)
			(xy 28.886798 -283.239133) (xy 28.882863 -283.185362) (xy 22.076918 -283.185362) (xy 22.076426 -283.212319)
			(xy 22.068576 -283.265659) (xy 22.053044 -283.317288) (xy 22.030159 -283.366105) (xy 22.000411 -283.411069)
			(xy 21.964433 -283.451223) (xy 21.922991 -283.485711) (xy 21.87697 -283.513797) (xy 21.82735 -283.534884)
			(xy 21.775189 -283.54852) (xy 21.721598 -283.554417) (xy 21.667719 -283.552448) (xy 21.614701 -283.542655)
			(xy 21.563674 -283.525247) (xy 21.515726 -283.500595) (xy 21.471878 -283.469225) (xy 21.433065 -283.431804)
			(xy 21.400113 -283.389131) (xy 21.373727 -283.342114) (xy 21.354467 -283.291757) (xy 21.342744 -283.239133)
			(xy 21.338809 -283.185362) (xy 15.598394 -283.185362) (xy 15.598394 -284.035246) (xy 17.238741 -284.035246)
			(xy 17.242676 -283.981475) (xy 17.254399 -283.928851) (xy 17.273659 -283.878494) (xy 17.300045 -283.831477)
			(xy 17.332997 -283.788804) (xy 17.37181 -283.751383) (xy 17.415658 -283.720013) (xy 17.463606 -283.695361)
			(xy 17.514633 -283.677953) (xy 17.567651 -283.66816) (xy 17.62153 -283.666191) (xy 17.675121 -283.672088)
			(xy 17.727282 -283.685724) (xy 17.776902 -283.706811) (xy 17.822923 -283.734897) (xy 17.864365 -283.769385)
			(xy 17.900343 -283.809539) (xy 17.930091 -283.854503) (xy 17.952976 -283.90332) (xy 17.968508 -283.954949)
			(xy 17.976358 -284.008289) (xy 17.97685 -284.035246) (xy 24.782795 -284.035246) (xy 24.78673 -283.981475)
			(xy 24.798453 -283.928851) (xy 24.817713 -283.878494) (xy 24.844099 -283.831477) (xy 24.877051 -283.788804)
			(xy 24.915864 -283.751383) (xy 24.959712 -283.720013) (xy 25.00766 -283.695361) (xy 25.058687 -283.677953)
			(xy 25.111705 -283.66816) (xy 25.165584 -283.666191) (xy 25.219175 -283.672088) (xy 25.271336 -283.685724)
			(xy 25.320956 -283.706811) (xy 25.366977 -283.734897) (xy 25.408419 -283.769385) (xy 25.444397 -283.809539)
			(xy 25.474145 -283.854503) (xy 25.49703 -283.90332) (xy 25.512562 -283.954949) (xy 25.520412 -284.008289)
			(xy 25.520904 -284.035246) (xy 32.326595 -284.035246) (xy 32.33053 -283.981475) (xy 32.342253 -283.928851)
			(xy 32.361513 -283.878494) (xy 32.387899 -283.831477) (xy 32.420851 -283.788804) (xy 32.459664 -283.751383)
			(xy 32.503512 -283.720013) (xy 32.55146 -283.695361) (xy 32.602487 -283.677953) (xy 32.655505 -283.66816)
			(xy 32.709384 -283.666191) (xy 32.762975 -283.672088) (xy 32.815136 -283.685724) (xy 32.864756 -283.706811)
			(xy 32.910777 -283.734897) (xy 32.952219 -283.769385) (xy 32.988197 -283.809539) (xy 33.017945 -283.854503)
			(xy 33.04083 -283.90332) (xy 33.056362 -283.954949) (xy 33.064212 -284.008289) (xy 33.064704 -284.035246)
			(xy 39.870649 -284.035246) (xy 39.874584 -283.981475) (xy 39.886307 -283.928851) (xy 39.905567 -283.878494)
			(xy 39.931953 -283.831477) (xy 39.964905 -283.788804) (xy 40.003718 -283.751383) (xy 40.047566 -283.720013)
			(xy 40.095514 -283.695361) (xy 40.146541 -283.677953) (xy 40.199559 -283.66816) (xy 40.253438 -283.666191)
			(xy 40.307029 -283.672088) (xy 40.35919 -283.685724) (xy 40.40881 -283.706811) (xy 40.454831 -283.734897)
			(xy 40.496273 -283.769385) (xy 40.532251 -283.809539) (xy 40.561999 -283.854503) (xy 40.584884 -283.90332)
			(xy 40.600416 -283.954949) (xy 40.608266 -284.008289) (xy 40.608758 -284.035246) (xy 40.608266 -284.062203)
			(xy 40.600416 -284.115543) (xy 40.584884 -284.167172) (xy 40.561999 -284.215989) (xy 40.532251 -284.260953)
			(xy 40.496273 -284.301107) (xy 40.454831 -284.335595) (xy 40.40881 -284.363681) (xy 40.35919 -284.384768)
			(xy 40.307029 -284.398404) (xy 40.253438 -284.404301) (xy 40.199559 -284.402332) (xy 40.146541 -284.392539)
			(xy 40.095514 -284.375131) (xy 40.047566 -284.350479) (xy 40.003718 -284.319109) (xy 39.964905 -284.281688)
			(xy 39.931953 -284.239015) (xy 39.905567 -284.191998) (xy 39.886307 -284.141641) (xy 39.874584 -284.089017)
			(xy 39.870649 -284.035246) (xy 33.064704 -284.035246) (xy 33.064212 -284.062203) (xy 33.056362 -284.115543)
			(xy 33.04083 -284.167172) (xy 33.017945 -284.215989) (xy 32.988197 -284.260953) (xy 32.952219 -284.301107)
			(xy 32.910777 -284.335595) (xy 32.864756 -284.363681) (xy 32.815136 -284.384768) (xy 32.762975 -284.398404)
			(xy 32.709384 -284.404301) (xy 32.655505 -284.402332) (xy 32.602487 -284.392539) (xy 32.55146 -284.375131)
			(xy 32.503512 -284.350479) (xy 32.459664 -284.319109) (xy 32.420851 -284.281688) (xy 32.387899 -284.239015)
			(xy 32.361513 -284.191998) (xy 32.342253 -284.141641) (xy 32.33053 -284.089017) (xy 32.326595 -284.035246)
			(xy 25.520904 -284.035246) (xy 25.520412 -284.062203) (xy 25.512562 -284.115543) (xy 25.49703 -284.167172)
			(xy 25.474145 -284.215989) (xy 25.444397 -284.260953) (xy 25.408419 -284.301107) (xy 25.366977 -284.335595)
			(xy 25.320956 -284.363681) (xy 25.271336 -284.384768) (xy 25.219175 -284.398404) (xy 25.165584 -284.404301)
			(xy 25.111705 -284.402332) (xy 25.058687 -284.392539) (xy 25.00766 -284.375131) (xy 24.959712 -284.350479)
			(xy 24.915864 -284.319109) (xy 24.877051 -284.281688) (xy 24.844099 -284.239015) (xy 24.817713 -284.191998)
			(xy 24.798453 -284.141641) (xy 24.78673 -284.089017) (xy 24.782795 -284.035246) (xy 17.97685 -284.035246)
			(xy 17.976358 -284.062203) (xy 17.968508 -284.115543) (xy 17.952976 -284.167172) (xy 17.930091 -284.215989)
			(xy 17.900343 -284.260953) (xy 17.864365 -284.301107) (xy 17.822923 -284.335595) (xy 17.776902 -284.363681)
			(xy 17.727282 -284.384768) (xy 17.675121 -284.398404) (xy 17.62153 -284.404301) (xy 17.567651 -284.402332)
			(xy 17.514633 -284.392539) (xy 17.463606 -284.375131) (xy 17.415658 -284.350479) (xy 17.37181 -284.319109)
			(xy 17.332997 -284.281688) (xy 17.300045 -284.239015) (xy 17.273659 -284.191998) (xy 17.254399 -284.141641)
			(xy 17.242676 -284.089017) (xy 17.238741 -284.035246) (xy 15.598394 -284.035246) (xy 15.598394 -284.885384)
			(xy 21.338809 -284.885384) (xy 21.342744 -284.831613) (xy 21.354467 -284.778989) (xy 21.373727 -284.728632)
			(xy 21.400113 -284.681615) (xy 21.433065 -284.638942) (xy 21.471878 -284.601521) (xy 21.515726 -284.570151)
			(xy 21.563674 -284.545499) (xy 21.614701 -284.528091) (xy 21.667719 -284.518298) (xy 21.721598 -284.516329)
			(xy 21.775189 -284.522226) (xy 21.82735 -284.535862) (xy 21.87697 -284.556949) (xy 21.922991 -284.585035)
			(xy 21.964433 -284.619523) (xy 22.000411 -284.659677) (xy 22.030159 -284.704641) (xy 22.053044 -284.753458)
			(xy 22.068576 -284.805087) (xy 22.076426 -284.858427) (xy 22.076918 -284.885384) (xy 28.882863 -284.885384)
			(xy 28.886798 -284.831613) (xy 28.898521 -284.778989) (xy 28.917781 -284.728632) (xy 28.944167 -284.681615)
			(xy 28.977119 -284.638942) (xy 29.015932 -284.601521) (xy 29.05978 -284.570151) (xy 29.107728 -284.545499)
			(xy 29.158755 -284.528091) (xy 29.211773 -284.518298) (xy 29.265652 -284.516329) (xy 29.319243 -284.522226)
			(xy 29.371404 -284.535862) (xy 29.421024 -284.556949) (xy 29.467045 -284.585035) (xy 29.508487 -284.619523)
			(xy 29.544465 -284.659677) (xy 29.574213 -284.704641) (xy 29.597098 -284.753458) (xy 29.61263 -284.805087)
			(xy 29.62048 -284.858427) (xy 29.620972 -284.885384) (xy 36.426663 -284.885384) (xy 36.430598 -284.831613)
			(xy 36.442321 -284.778989) (xy 36.461581 -284.728632) (xy 36.487967 -284.681615) (xy 36.520919 -284.638942)
			(xy 36.559732 -284.601521) (xy 36.60358 -284.570151) (xy 36.651528 -284.545499) (xy 36.702555 -284.528091)
			(xy 36.755573 -284.518298) (xy 36.809452 -284.516329) (xy 36.863043 -284.522226) (xy 36.915204 -284.535862)
			(xy 36.964824 -284.556949) (xy 37.010845 -284.585035) (xy 37.052287 -284.619523) (xy 37.088265 -284.659677)
			(xy 37.118013 -284.704641) (xy 37.140898 -284.753458) (xy 37.15643 -284.805087) (xy 37.16428 -284.858427)
			(xy 37.164772 -284.885384) (xy 43.970717 -284.885384) (xy 43.974652 -284.831613) (xy 43.986375 -284.778989)
			(xy 44.005635 -284.728632) (xy 44.032021 -284.681615) (xy 44.064973 -284.638942) (xy 44.103786 -284.601521)
			(xy 44.147634 -284.570151) (xy 44.195582 -284.545499) (xy 44.246609 -284.528091) (xy 44.299627 -284.518298)
			(xy 44.353506 -284.516329) (xy 44.407097 -284.522226) (xy 44.459258 -284.535862) (xy 44.508878 -284.556949)
			(xy 44.554899 -284.585035) (xy 44.596341 -284.619523) (xy 44.632319 -284.659677) (xy 44.662067 -284.704641)
			(xy 44.684952 -284.753458) (xy 44.700484 -284.805087) (xy 44.708334 -284.858427) (xy 44.708826 -284.885384)
			(xy 44.708334 -284.912341) (xy 44.700484 -284.965681) (xy 44.684952 -285.01731) (xy 44.662067 -285.066127)
			(xy 44.632319 -285.111091) (xy 44.596341 -285.151245) (xy 44.554899 -285.185733) (xy 44.508878 -285.213819)
			(xy 44.459258 -285.234906) (xy 44.407097 -285.248542) (xy 44.353506 -285.254439) (xy 44.299627 -285.25247)
			(xy 44.246609 -285.242677) (xy 44.195582 -285.225269) (xy 44.147634 -285.200617) (xy 44.103786 -285.169247)
			(xy 44.064973 -285.131826) (xy 44.032021 -285.089153) (xy 44.005635 -285.042136) (xy 43.986375 -284.991779)
			(xy 43.974652 -284.939155) (xy 43.970717 -284.885384) (xy 37.164772 -284.885384) (xy 37.16428 -284.912341)
			(xy 37.15643 -284.965681) (xy 37.140898 -285.01731) (xy 37.118013 -285.066127) (xy 37.088265 -285.111091)
			(xy 37.052287 -285.151245) (xy 37.010845 -285.185733) (xy 36.964824 -285.213819) (xy 36.915204 -285.234906)
			(xy 36.863043 -285.248542) (xy 36.809452 -285.254439) (xy 36.755573 -285.25247) (xy 36.702555 -285.242677)
			(xy 36.651528 -285.225269) (xy 36.60358 -285.200617) (xy 36.559732 -285.169247) (xy 36.520919 -285.131826)
			(xy 36.487967 -285.089153) (xy 36.461581 -285.042136) (xy 36.442321 -284.991779) (xy 36.430598 -284.939155)
			(xy 36.426663 -284.885384) (xy 29.620972 -284.885384) (xy 29.62048 -284.912341) (xy 29.61263 -284.965681)
			(xy 29.597098 -285.01731) (xy 29.574213 -285.066127) (xy 29.544465 -285.111091) (xy 29.508487 -285.151245)
			(xy 29.467045 -285.185733) (xy 29.421024 -285.213819) (xy 29.371404 -285.234906) (xy 29.319243 -285.248542)
			(xy 29.265652 -285.254439) (xy 29.211773 -285.25247) (xy 29.158755 -285.242677) (xy 29.107728 -285.225269)
			(xy 29.05978 -285.200617) (xy 29.015932 -285.169247) (xy 28.977119 -285.131826) (xy 28.944167 -285.089153)
			(xy 28.917781 -285.042136) (xy 28.898521 -284.991779) (xy 28.886798 -284.939155) (xy 28.882863 -284.885384)
			(xy 22.076918 -284.885384) (xy 22.076426 -284.912341) (xy 22.068576 -284.965681) (xy 22.053044 -285.01731)
			(xy 22.030159 -285.066127) (xy 22.000411 -285.111091) (xy 21.964433 -285.151245) (xy 21.922991 -285.185733)
			(xy 21.87697 -285.213819) (xy 21.82735 -285.234906) (xy 21.775189 -285.248542) (xy 21.721598 -285.254439)
			(xy 21.667719 -285.25247) (xy 21.614701 -285.242677) (xy 21.563674 -285.225269) (xy 21.515726 -285.200617)
			(xy 21.471878 -285.169247) (xy 21.433065 -285.131826) (xy 21.400113 -285.089153) (xy 21.373727 -285.042136)
			(xy 21.354467 -284.991779) (xy 21.342744 -284.939155) (xy 21.338809 -284.885384) (xy 15.598394 -284.885384)
			(xy 15.598394 -285.735268) (xy 17.238741 -285.735268) (xy 17.242676 -285.681497) (xy 17.254399 -285.628873)
			(xy 17.273659 -285.578516) (xy 17.300045 -285.531499) (xy 17.332997 -285.488826) (xy 17.37181 -285.451405)
			(xy 17.415658 -285.420035) (xy 17.463606 -285.395383) (xy 17.514633 -285.377975) (xy 17.567651 -285.368182)
			(xy 17.62153 -285.366213) (xy 17.675121 -285.37211) (xy 17.727282 -285.385746) (xy 17.776902 -285.406833)
			(xy 17.822923 -285.434919) (xy 17.864365 -285.469407) (xy 17.900343 -285.509561) (xy 17.930091 -285.554525)
			(xy 17.952976 -285.603342) (xy 17.968508 -285.654971) (xy 17.976358 -285.708311) (xy 17.97685 -285.735268)
			(xy 21.338809 -285.735268) (xy 21.342744 -285.681497) (xy 21.354467 -285.628873) (xy 21.373727 -285.578516)
			(xy 21.400113 -285.531499) (xy 21.433065 -285.488826) (xy 21.471878 -285.451405) (xy 21.515726 -285.420035)
			(xy 21.563674 -285.395383) (xy 21.614701 -285.377975) (xy 21.667719 -285.368182) (xy 21.721598 -285.366213)
			(xy 21.775189 -285.37211) (xy 21.82735 -285.385746) (xy 21.87697 -285.406833) (xy 21.922991 -285.434919)
			(xy 21.964433 -285.469407) (xy 22.000411 -285.509561) (xy 22.030159 -285.554525) (xy 22.053044 -285.603342)
			(xy 22.068576 -285.654971) (xy 22.076426 -285.708311) (xy 22.076918 -285.735268) (xy 24.782795 -285.735268)
			(xy 24.78673 -285.681497) (xy 24.798453 -285.628873) (xy 24.817713 -285.578516) (xy 24.844099 -285.531499)
			(xy 24.877051 -285.488826) (xy 24.915864 -285.451405) (xy 24.959712 -285.420035) (xy 25.00766 -285.395383)
			(xy 25.058687 -285.377975) (xy 25.111705 -285.368182) (xy 25.165584 -285.366213) (xy 25.219175 -285.37211)
			(xy 25.271336 -285.385746) (xy 25.320956 -285.406833) (xy 25.366977 -285.434919) (xy 25.408419 -285.469407)
			(xy 25.444397 -285.509561) (xy 25.474145 -285.554525) (xy 25.49703 -285.603342) (xy 25.512562 -285.654971)
			(xy 25.520412 -285.708311) (xy 25.520904 -285.735268) (xy 28.882863 -285.735268) (xy 28.886798 -285.681497)
			(xy 28.898521 -285.628873) (xy 28.917781 -285.578516) (xy 28.944167 -285.531499) (xy 28.977119 -285.488826)
			(xy 29.015932 -285.451405) (xy 29.05978 -285.420035) (xy 29.107728 -285.395383) (xy 29.158755 -285.377975)
			(xy 29.211773 -285.368182) (xy 29.265652 -285.366213) (xy 29.319243 -285.37211) (xy 29.371404 -285.385746)
			(xy 29.421024 -285.406833) (xy 29.467045 -285.434919) (xy 29.508487 -285.469407) (xy 29.544465 -285.509561)
			(xy 29.574213 -285.554525) (xy 29.597098 -285.603342) (xy 29.61263 -285.654971) (xy 29.62048 -285.708311)
			(xy 29.620972 -285.735268) (xy 32.326595 -285.735268) (xy 32.33053 -285.681497) (xy 32.342253 -285.628873)
			(xy 32.361513 -285.578516) (xy 32.387899 -285.531499) (xy 32.420851 -285.488826) (xy 32.459664 -285.451405)
			(xy 32.503512 -285.420035) (xy 32.55146 -285.395383) (xy 32.602487 -285.377975) (xy 32.655505 -285.368182)
			(xy 32.709384 -285.366213) (xy 32.762975 -285.37211) (xy 32.815136 -285.385746) (xy 32.864756 -285.406833)
			(xy 32.910777 -285.434919) (xy 32.952219 -285.469407) (xy 32.988197 -285.509561) (xy 33.017945 -285.554525)
			(xy 33.04083 -285.603342) (xy 33.056362 -285.654971) (xy 33.064212 -285.708311) (xy 33.064704 -285.735268)
			(xy 36.426663 -285.735268) (xy 36.430598 -285.681497) (xy 36.442321 -285.628873) (xy 36.461581 -285.578516)
			(xy 36.487967 -285.531499) (xy 36.520919 -285.488826) (xy 36.559732 -285.451405) (xy 36.60358 -285.420035)
			(xy 36.651528 -285.395383) (xy 36.702555 -285.377975) (xy 36.755573 -285.368182) (xy 36.809452 -285.366213)
			(xy 36.863043 -285.37211) (xy 36.915204 -285.385746) (xy 36.964824 -285.406833) (xy 37.010845 -285.434919)
			(xy 37.052287 -285.469407) (xy 37.088265 -285.509561) (xy 37.118013 -285.554525) (xy 37.140898 -285.603342)
			(xy 37.15643 -285.654971) (xy 37.16428 -285.708311) (xy 37.164772 -285.735268) (xy 39.870649 -285.735268)
			(xy 39.874584 -285.681497) (xy 39.886307 -285.628873) (xy 39.905567 -285.578516) (xy 39.931953 -285.531499)
			(xy 39.964905 -285.488826) (xy 40.003718 -285.451405) (xy 40.047566 -285.420035) (xy 40.095514 -285.395383)
			(xy 40.146541 -285.377975) (xy 40.199559 -285.368182) (xy 40.253438 -285.366213) (xy 40.307029 -285.37211)
			(xy 40.35919 -285.385746) (xy 40.40881 -285.406833) (xy 40.454831 -285.434919) (xy 40.496273 -285.469407)
			(xy 40.532251 -285.509561) (xy 40.561999 -285.554525) (xy 40.584884 -285.603342) (xy 40.600416 -285.654971)
			(xy 40.608266 -285.708311) (xy 40.608758 -285.735268) (xy 43.970717 -285.735268) (xy 43.974652 -285.681497)
			(xy 43.986375 -285.628873) (xy 44.005635 -285.578516) (xy 44.032021 -285.531499) (xy 44.064973 -285.488826)
			(xy 44.103786 -285.451405) (xy 44.147634 -285.420035) (xy 44.195582 -285.395383) (xy 44.246609 -285.377975)
			(xy 44.299627 -285.368182) (xy 44.353506 -285.366213) (xy 44.407097 -285.37211) (xy 44.459258 -285.385746)
			(xy 44.508878 -285.406833) (xy 44.554899 -285.434919) (xy 44.596341 -285.469407) (xy 44.632319 -285.509561)
			(xy 44.662067 -285.554525) (xy 44.684952 -285.603342) (xy 44.700484 -285.654971) (xy 44.708334 -285.708311)
			(xy 44.708826 -285.735268) (xy 44.708334 -285.762225) (xy 44.700484 -285.815565) (xy 44.684952 -285.867194)
			(xy 44.662067 -285.916011) (xy 44.632319 -285.960975) (xy 44.596341 -286.001129) (xy 44.554899 -286.035617)
			(xy 44.508878 -286.063703) (xy 44.459258 -286.08479) (xy 44.407097 -286.098426) (xy 44.353506 -286.104323)
			(xy 44.299627 -286.102354) (xy 44.246609 -286.092561) (xy 44.195582 -286.075153) (xy 44.147634 -286.050501)
			(xy 44.103786 -286.019131) (xy 44.064973 -285.98171) (xy 44.032021 -285.939037) (xy 44.005635 -285.89202)
			(xy 43.986375 -285.841663) (xy 43.974652 -285.789039) (xy 43.970717 -285.735268) (xy 40.608758 -285.735268)
			(xy 40.608266 -285.762225) (xy 40.600416 -285.815565) (xy 40.584884 -285.867194) (xy 40.561999 -285.916011)
			(xy 40.532251 -285.960975) (xy 40.496273 -286.001129) (xy 40.454831 -286.035617) (xy 40.40881 -286.063703)
			(xy 40.35919 -286.08479) (xy 40.307029 -286.098426) (xy 40.253438 -286.104323) (xy 40.199559 -286.102354)
			(xy 40.146541 -286.092561) (xy 40.095514 -286.075153) (xy 40.047566 -286.050501) (xy 40.003718 -286.019131)
			(xy 39.964905 -285.98171) (xy 39.931953 -285.939037) (xy 39.905567 -285.89202) (xy 39.886307 -285.841663)
			(xy 39.874584 -285.789039) (xy 39.870649 -285.735268) (xy 37.164772 -285.735268) (xy 37.16428 -285.762225)
			(xy 37.15643 -285.815565) (xy 37.140898 -285.867194) (xy 37.118013 -285.916011) (xy 37.088265 -285.960975)
			(xy 37.052287 -286.001129) (xy 37.010845 -286.035617) (xy 36.964824 -286.063703) (xy 36.915204 -286.08479)
			(xy 36.863043 -286.098426) (xy 36.809452 -286.104323) (xy 36.755573 -286.102354) (xy 36.702555 -286.092561)
			(xy 36.651528 -286.075153) (xy 36.60358 -286.050501) (xy 36.559732 -286.019131) (xy 36.520919 -285.98171)
			(xy 36.487967 -285.939037) (xy 36.461581 -285.89202) (xy 36.442321 -285.841663) (xy 36.430598 -285.789039)
			(xy 36.426663 -285.735268) (xy 33.064704 -285.735268) (xy 33.064212 -285.762225) (xy 33.056362 -285.815565)
			(xy 33.04083 -285.867194) (xy 33.017945 -285.916011) (xy 32.988197 -285.960975) (xy 32.952219 -286.001129)
			(xy 32.910777 -286.035617) (xy 32.864756 -286.063703) (xy 32.815136 -286.08479) (xy 32.762975 -286.098426)
			(xy 32.709384 -286.104323) (xy 32.655505 -286.102354) (xy 32.602487 -286.092561) (xy 32.55146 -286.075153)
			(xy 32.503512 -286.050501) (xy 32.459664 -286.019131) (xy 32.420851 -285.98171) (xy 32.387899 -285.939037)
			(xy 32.361513 -285.89202) (xy 32.342253 -285.841663) (xy 32.33053 -285.789039) (xy 32.326595 -285.735268)
			(xy 29.620972 -285.735268) (xy 29.62048 -285.762225) (xy 29.61263 -285.815565) (xy 29.597098 -285.867194)
			(xy 29.574213 -285.916011) (xy 29.544465 -285.960975) (xy 29.508487 -286.001129) (xy 29.467045 -286.035617)
			(xy 29.421024 -286.063703) (xy 29.371404 -286.08479) (xy 29.319243 -286.098426) (xy 29.265652 -286.104323)
			(xy 29.211773 -286.102354) (xy 29.158755 -286.092561) (xy 29.107728 -286.075153) (xy 29.05978 -286.050501)
			(xy 29.015932 -286.019131) (xy 28.977119 -285.98171) (xy 28.944167 -285.939037) (xy 28.917781 -285.89202)
			(xy 28.898521 -285.841663) (xy 28.886798 -285.789039) (xy 28.882863 -285.735268) (xy 25.520904 -285.735268)
			(xy 25.520412 -285.762225) (xy 25.512562 -285.815565) (xy 25.49703 -285.867194) (xy 25.474145 -285.916011)
			(xy 25.444397 -285.960975) (xy 25.408419 -286.001129) (xy 25.366977 -286.035617) (xy 25.320956 -286.063703)
			(xy 25.271336 -286.08479) (xy 25.219175 -286.098426) (xy 25.165584 -286.104323) (xy 25.111705 -286.102354)
			(xy 25.058687 -286.092561) (xy 25.00766 -286.075153) (xy 24.959712 -286.050501) (xy 24.915864 -286.019131)
			(xy 24.877051 -285.98171) (xy 24.844099 -285.939037) (xy 24.817713 -285.89202) (xy 24.798453 -285.841663)
			(xy 24.78673 -285.789039) (xy 24.782795 -285.735268) (xy 22.076918 -285.735268) (xy 22.076426 -285.762225)
			(xy 22.068576 -285.815565) (xy 22.053044 -285.867194) (xy 22.030159 -285.916011) (xy 22.000411 -285.960975)
			(xy 21.964433 -286.001129) (xy 21.922991 -286.035617) (xy 21.87697 -286.063703) (xy 21.82735 -286.08479)
			(xy 21.775189 -286.098426) (xy 21.721598 -286.104323) (xy 21.667719 -286.102354) (xy 21.614701 -286.092561)
			(xy 21.563674 -286.075153) (xy 21.515726 -286.050501) (xy 21.471878 -286.019131) (xy 21.433065 -285.98171)
			(xy 21.400113 -285.939037) (xy 21.373727 -285.89202) (xy 21.354467 -285.841663) (xy 21.342744 -285.789039)
			(xy 21.338809 -285.735268) (xy 17.97685 -285.735268) (xy 17.976358 -285.762225) (xy 17.968508 -285.815565)
			(xy 17.952976 -285.867194) (xy 17.930091 -285.916011) (xy 17.900343 -285.960975) (xy 17.864365 -286.001129)
			(xy 17.822923 -286.035617) (xy 17.776902 -286.063703) (xy 17.727282 -286.08479) (xy 17.675121 -286.098426)
			(xy 17.62153 -286.104323) (xy 17.567651 -286.102354) (xy 17.514633 -286.092561) (xy 17.463606 -286.075153)
			(xy 17.415658 -286.050501) (xy 17.37181 -286.019131) (xy 17.332997 -285.98171) (xy 17.300045 -285.939037)
			(xy 17.273659 -285.89202) (xy 17.254399 -285.841663) (xy 17.242676 -285.789039) (xy 17.238741 -285.735268)
			(xy 15.598394 -285.735268) (xy 15.598394 -286.585406) (xy 17.238741 -286.585406) (xy 17.242676 -286.531635)
			(xy 17.254399 -286.479011) (xy 17.273659 -286.428654) (xy 17.300045 -286.381637) (xy 17.332997 -286.338964)
			(xy 17.37181 -286.301543) (xy 17.415658 -286.270173) (xy 17.463606 -286.245521) (xy 17.514633 -286.228113)
			(xy 17.567651 -286.21832) (xy 17.62153 -286.216351) (xy 17.675121 -286.222248) (xy 17.727282 -286.235884)
			(xy 17.776902 -286.256971) (xy 17.822923 -286.285057) (xy 17.864365 -286.319545) (xy 17.900343 -286.359699)
			(xy 17.930091 -286.404663) (xy 17.952976 -286.45348) (xy 17.968508 -286.505109) (xy 17.976358 -286.558449)
			(xy 17.97685 -286.585406) (xy 24.782795 -286.585406) (xy 24.78673 -286.531635) (xy 24.798453 -286.479011)
			(xy 24.817713 -286.428654) (xy 24.844099 -286.381637) (xy 24.877051 -286.338964) (xy 24.915864 -286.301543)
			(xy 24.959712 -286.270173) (xy 25.00766 -286.245521) (xy 25.058687 -286.228113) (xy 25.111705 -286.21832)
			(xy 25.165584 -286.216351) (xy 25.219175 -286.222248) (xy 25.271336 -286.235884) (xy 25.320956 -286.256971)
			(xy 25.366977 -286.285057) (xy 25.408419 -286.319545) (xy 25.444397 -286.359699) (xy 25.474145 -286.404663)
			(xy 25.49703 -286.45348) (xy 25.512562 -286.505109) (xy 25.520412 -286.558449) (xy 25.520904 -286.585406)
			(xy 32.326595 -286.585406) (xy 32.33053 -286.531635) (xy 32.342253 -286.479011) (xy 32.361513 -286.428654)
			(xy 32.387899 -286.381637) (xy 32.420851 -286.338964) (xy 32.459664 -286.301543) (xy 32.503512 -286.270173)
			(xy 32.55146 -286.245521) (xy 32.602487 -286.228113) (xy 32.655505 -286.21832) (xy 32.709384 -286.216351)
			(xy 32.762975 -286.222248) (xy 32.815136 -286.235884) (xy 32.864756 -286.256971) (xy 32.910777 -286.285057)
			(xy 32.952219 -286.319545) (xy 32.988197 -286.359699) (xy 33.017945 -286.404663) (xy 33.04083 -286.45348)
			(xy 33.056362 -286.505109) (xy 33.064212 -286.558449) (xy 33.064704 -286.585406) (xy 39.870649 -286.585406)
			(xy 39.874584 -286.531635) (xy 39.886307 -286.479011) (xy 39.905567 -286.428654) (xy 39.931953 -286.381637)
			(xy 39.964905 -286.338964) (xy 40.003718 -286.301543) (xy 40.047566 -286.270173) (xy 40.095514 -286.245521)
			(xy 40.146541 -286.228113) (xy 40.199559 -286.21832) (xy 40.253438 -286.216351) (xy 40.307029 -286.222248)
			(xy 40.35919 -286.235884) (xy 40.40881 -286.256971) (xy 40.454831 -286.285057) (xy 40.496273 -286.319545)
			(xy 40.532251 -286.359699) (xy 40.561999 -286.404663) (xy 40.584884 -286.45348) (xy 40.600416 -286.505109)
			(xy 40.608266 -286.558449) (xy 40.608758 -286.585406) (xy 40.608266 -286.612363) (xy 40.600416 -286.665703)
			(xy 40.584884 -286.717332) (xy 40.561999 -286.766149) (xy 40.532251 -286.811113) (xy 40.496273 -286.851267)
			(xy 40.454831 -286.885755) (xy 40.40881 -286.913841) (xy 40.35919 -286.934928) (xy 40.307029 -286.948564)
			(xy 40.253438 -286.954461) (xy 40.199559 -286.952492) (xy 40.146541 -286.942699) (xy 40.095514 -286.925291)
			(xy 40.047566 -286.900639) (xy 40.003718 -286.869269) (xy 39.964905 -286.831848) (xy 39.931953 -286.789175)
			(xy 39.905567 -286.742158) (xy 39.886307 -286.691801) (xy 39.874584 -286.639177) (xy 39.870649 -286.585406)
			(xy 33.064704 -286.585406) (xy 33.064212 -286.612363) (xy 33.056362 -286.665703) (xy 33.04083 -286.717332)
			(xy 33.017945 -286.766149) (xy 32.988197 -286.811113) (xy 32.952219 -286.851267) (xy 32.910777 -286.885755)
			(xy 32.864756 -286.913841) (xy 32.815136 -286.934928) (xy 32.762975 -286.948564) (xy 32.709384 -286.954461)
			(xy 32.655505 -286.952492) (xy 32.602487 -286.942699) (xy 32.55146 -286.925291) (xy 32.503512 -286.900639)
			(xy 32.459664 -286.869269) (xy 32.420851 -286.831848) (xy 32.387899 -286.789175) (xy 32.361513 -286.742158)
			(xy 32.342253 -286.691801) (xy 32.33053 -286.639177) (xy 32.326595 -286.585406) (xy 25.520904 -286.585406)
			(xy 25.520412 -286.612363) (xy 25.512562 -286.665703) (xy 25.49703 -286.717332) (xy 25.474145 -286.766149)
			(xy 25.444397 -286.811113) (xy 25.408419 -286.851267) (xy 25.366977 -286.885755) (xy 25.320956 -286.913841)
			(xy 25.271336 -286.934928) (xy 25.219175 -286.948564) (xy 25.165584 -286.954461) (xy 25.111705 -286.952492)
			(xy 25.058687 -286.942699) (xy 25.00766 -286.925291) (xy 24.959712 -286.900639) (xy 24.915864 -286.869269)
			(xy 24.877051 -286.831848) (xy 24.844099 -286.789175) (xy 24.817713 -286.742158) (xy 24.798453 -286.691801)
			(xy 24.78673 -286.639177) (xy 24.782795 -286.585406) (xy 17.97685 -286.585406) (xy 17.976358 -286.612363)
			(xy 17.968508 -286.665703) (xy 17.952976 -286.717332) (xy 17.930091 -286.766149) (xy 17.900343 -286.811113)
			(xy 17.864365 -286.851267) (xy 17.822923 -286.885755) (xy 17.776902 -286.913841) (xy 17.727282 -286.934928)
			(xy 17.675121 -286.948564) (xy 17.62153 -286.954461) (xy 17.567651 -286.952492) (xy 17.514633 -286.942699)
			(xy 17.463606 -286.925291) (xy 17.415658 -286.900639) (xy 17.37181 -286.869269) (xy 17.332997 -286.831848)
			(xy 17.300045 -286.789175) (xy 17.273659 -286.742158) (xy 17.254399 -286.691801) (xy 17.242676 -286.639177)
			(xy 17.238741 -286.585406) (xy 15.598394 -286.585406) (xy 15.598394 -287.43529) (xy 21.338809 -287.43529)
			(xy 21.342744 -287.381519) (xy 21.354467 -287.328895) (xy 21.373727 -287.278538) (xy 21.400113 -287.231521)
			(xy 21.433065 -287.188848) (xy 21.471878 -287.151427) (xy 21.515726 -287.120057) (xy 21.563674 -287.095405)
			(xy 21.614701 -287.077997) (xy 21.667719 -287.068204) (xy 21.721598 -287.066235) (xy 21.775189 -287.072132)
			(xy 21.82735 -287.085768) (xy 21.87697 -287.106855) (xy 21.922991 -287.134941) (xy 21.964433 -287.169429)
			(xy 22.000411 -287.209583) (xy 22.030159 -287.254547) (xy 22.053044 -287.303364) (xy 22.068576 -287.354993)
			(xy 22.076426 -287.408333) (xy 22.076918 -287.43529) (xy 28.882863 -287.43529) (xy 28.886798 -287.381519)
			(xy 28.898521 -287.328895) (xy 28.917781 -287.278538) (xy 28.944167 -287.231521) (xy 28.977119 -287.188848)
			(xy 29.015932 -287.151427) (xy 29.05978 -287.120057) (xy 29.107728 -287.095405) (xy 29.158755 -287.077997)
			(xy 29.211773 -287.068204) (xy 29.265652 -287.066235) (xy 29.319243 -287.072132) (xy 29.371404 -287.085768)
			(xy 29.421024 -287.106855) (xy 29.467045 -287.134941) (xy 29.508487 -287.169429) (xy 29.544465 -287.209583)
			(xy 29.574213 -287.254547) (xy 29.597098 -287.303364) (xy 29.61263 -287.354993) (xy 29.62048 -287.408333)
			(xy 29.620972 -287.43529) (xy 36.426663 -287.43529) (xy 36.430598 -287.381519) (xy 36.442321 -287.328895)
			(xy 36.461581 -287.278538) (xy 36.487967 -287.231521) (xy 36.520919 -287.188848) (xy 36.559732 -287.151427)
			(xy 36.60358 -287.120057) (xy 36.651528 -287.095405) (xy 36.702555 -287.077997) (xy 36.755573 -287.068204)
			(xy 36.809452 -287.066235) (xy 36.863043 -287.072132) (xy 36.915204 -287.085768) (xy 36.964824 -287.106855)
			(xy 37.010845 -287.134941) (xy 37.052287 -287.169429) (xy 37.088265 -287.209583) (xy 37.118013 -287.254547)
			(xy 37.140898 -287.303364) (xy 37.15643 -287.354993) (xy 37.16428 -287.408333) (xy 37.164772 -287.43529)
			(xy 43.970717 -287.43529) (xy 43.974652 -287.381519) (xy 43.986375 -287.328895) (xy 44.005635 -287.278538)
			(xy 44.032021 -287.231521) (xy 44.064973 -287.188848) (xy 44.103786 -287.151427) (xy 44.147634 -287.120057)
			(xy 44.195582 -287.095405) (xy 44.246609 -287.077997) (xy 44.299627 -287.068204) (xy 44.353506 -287.066235)
			(xy 44.407097 -287.072132) (xy 44.459258 -287.085768) (xy 44.508878 -287.106855) (xy 44.554899 -287.134941)
			(xy 44.596341 -287.169429) (xy 44.632319 -287.209583) (xy 44.662067 -287.254547) (xy 44.684952 -287.303364)
			(xy 44.700484 -287.354993) (xy 44.708334 -287.408333) (xy 44.708826 -287.43529) (xy 44.708334 -287.462247)
			(xy 44.700484 -287.515587) (xy 44.684952 -287.567216) (xy 44.662067 -287.616033) (xy 44.632319 -287.660997)
			(xy 44.596341 -287.701151) (xy 44.554899 -287.735639) (xy 44.508878 -287.763725) (xy 44.459258 -287.784812)
			(xy 44.407097 -287.798448) (xy 44.353506 -287.804345) (xy 44.299627 -287.802376) (xy 44.246609 -287.792583)
			(xy 44.195582 -287.775175) (xy 44.147634 -287.750523) (xy 44.103786 -287.719153) (xy 44.064973 -287.681732)
			(xy 44.032021 -287.639059) (xy 44.005635 -287.592042) (xy 43.986375 -287.541685) (xy 43.974652 -287.489061)
			(xy 43.970717 -287.43529) (xy 37.164772 -287.43529) (xy 37.16428 -287.462247) (xy 37.15643 -287.515587)
			(xy 37.140898 -287.567216) (xy 37.118013 -287.616033) (xy 37.088265 -287.660997) (xy 37.052287 -287.701151)
			(xy 37.010845 -287.735639) (xy 36.964824 -287.763725) (xy 36.915204 -287.784812) (xy 36.863043 -287.798448)
			(xy 36.809452 -287.804345) (xy 36.755573 -287.802376) (xy 36.702555 -287.792583) (xy 36.651528 -287.775175)
			(xy 36.60358 -287.750523) (xy 36.559732 -287.719153) (xy 36.520919 -287.681732) (xy 36.487967 -287.639059)
			(xy 36.461581 -287.592042) (xy 36.442321 -287.541685) (xy 36.430598 -287.489061) (xy 36.426663 -287.43529)
			(xy 29.620972 -287.43529) (xy 29.62048 -287.462247) (xy 29.61263 -287.515587) (xy 29.597098 -287.567216)
			(xy 29.574213 -287.616033) (xy 29.544465 -287.660997) (xy 29.508487 -287.701151) (xy 29.467045 -287.735639)
			(xy 29.421024 -287.763725) (xy 29.371404 -287.784812) (xy 29.319243 -287.798448) (xy 29.265652 -287.804345)
			(xy 29.211773 -287.802376) (xy 29.158755 -287.792583) (xy 29.107728 -287.775175) (xy 29.05978 -287.750523)
			(xy 29.015932 -287.719153) (xy 28.977119 -287.681732) (xy 28.944167 -287.639059) (xy 28.917781 -287.592042)
			(xy 28.898521 -287.541685) (xy 28.886798 -287.489061) (xy 28.882863 -287.43529) (xy 22.076918 -287.43529)
			(xy 22.076426 -287.462247) (xy 22.068576 -287.515587) (xy 22.053044 -287.567216) (xy 22.030159 -287.616033)
			(xy 22.000411 -287.660997) (xy 21.964433 -287.701151) (xy 21.922991 -287.735639) (xy 21.87697 -287.763725)
			(xy 21.82735 -287.784812) (xy 21.775189 -287.798448) (xy 21.721598 -287.804345) (xy 21.667719 -287.802376)
			(xy 21.614701 -287.792583) (xy 21.563674 -287.775175) (xy 21.515726 -287.750523) (xy 21.471878 -287.719153)
			(xy 21.433065 -287.681732) (xy 21.400113 -287.639059) (xy 21.373727 -287.592042) (xy 21.354467 -287.541685)
			(xy 21.342744 -287.489061) (xy 21.338809 -287.43529) (xy 15.598394 -287.43529) (xy 15.598394 -288.285428)
			(xy 17.238741 -288.285428) (xy 17.242676 -288.231657) (xy 17.254399 -288.179033) (xy 17.273659 -288.128676)
			(xy 17.300045 -288.081659) (xy 17.332997 -288.038986) (xy 17.37181 -288.001565) (xy 17.415658 -287.970195)
			(xy 17.463606 -287.945543) (xy 17.514633 -287.928135) (xy 17.567651 -287.918342) (xy 17.62153 -287.916373)
			(xy 17.675121 -287.92227) (xy 17.727282 -287.935906) (xy 17.776902 -287.956993) (xy 17.822923 -287.985079)
			(xy 17.864365 -288.019567) (xy 17.900343 -288.059721) (xy 17.930091 -288.104685) (xy 17.952976 -288.153502)
			(xy 17.968508 -288.205131) (xy 17.976358 -288.258471) (xy 17.97685 -288.285428) (xy 24.782795 -288.285428)
			(xy 24.78673 -288.231657) (xy 24.798453 -288.179033) (xy 24.817713 -288.128676) (xy 24.844099 -288.081659)
			(xy 24.877051 -288.038986) (xy 24.915864 -288.001565) (xy 24.959712 -287.970195) (xy 25.00766 -287.945543)
			(xy 25.058687 -287.928135) (xy 25.111705 -287.918342) (xy 25.165584 -287.916373) (xy 25.219175 -287.92227)
			(xy 25.271336 -287.935906) (xy 25.320956 -287.956993) (xy 25.366977 -287.985079) (xy 25.408419 -288.019567)
			(xy 25.444397 -288.059721) (xy 25.474145 -288.104685) (xy 25.49703 -288.153502) (xy 25.512562 -288.205131)
			(xy 25.520412 -288.258471) (xy 25.520904 -288.285428) (xy 32.326595 -288.285428) (xy 32.33053 -288.231657)
			(xy 32.342253 -288.179033) (xy 32.361513 -288.128676) (xy 32.387899 -288.081659) (xy 32.420851 -288.038986)
			(xy 32.459664 -288.001565) (xy 32.503512 -287.970195) (xy 32.55146 -287.945543) (xy 32.602487 -287.928135)
			(xy 32.655505 -287.918342) (xy 32.709384 -287.916373) (xy 32.762975 -287.92227) (xy 32.815136 -287.935906)
			(xy 32.864756 -287.956993) (xy 32.910777 -287.985079) (xy 32.952219 -288.019567) (xy 32.988197 -288.059721)
			(xy 33.017945 -288.104685) (xy 33.04083 -288.153502) (xy 33.056362 -288.205131) (xy 33.064212 -288.258471)
			(xy 33.064704 -288.285428) (xy 39.870649 -288.285428) (xy 39.874584 -288.231657) (xy 39.886307 -288.179033)
			(xy 39.905567 -288.128676) (xy 39.931953 -288.081659) (xy 39.964905 -288.038986) (xy 40.003718 -288.001565)
			(xy 40.047566 -287.970195) (xy 40.095514 -287.945543) (xy 40.146541 -287.928135) (xy 40.199559 -287.918342)
			(xy 40.253438 -287.916373) (xy 40.307029 -287.92227) (xy 40.35919 -287.935906) (xy 40.40881 -287.956993)
			(xy 40.454831 -287.985079) (xy 40.496273 -288.019567) (xy 40.532251 -288.059721) (xy 40.561999 -288.104685)
			(xy 40.584884 -288.153502) (xy 40.600416 -288.205131) (xy 40.608266 -288.258471) (xy 40.608758 -288.285428)
			(xy 40.608266 -288.312385) (xy 40.600416 -288.365725) (xy 40.584884 -288.417354) (xy 40.561999 -288.466171)
			(xy 40.532251 -288.511135) (xy 40.496273 -288.551289) (xy 40.454831 -288.585777) (xy 40.40881 -288.613863)
			(xy 40.35919 -288.63495) (xy 40.307029 -288.648586) (xy 40.253438 -288.654483) (xy 40.199559 -288.652514)
			(xy 40.146541 -288.642721) (xy 40.095514 -288.625313) (xy 40.047566 -288.600661) (xy 40.003718 -288.569291)
			(xy 39.964905 -288.53187) (xy 39.931953 -288.489197) (xy 39.905567 -288.44218) (xy 39.886307 -288.391823)
			(xy 39.874584 -288.339199) (xy 39.870649 -288.285428) (xy 33.064704 -288.285428) (xy 33.064212 -288.312385)
			(xy 33.056362 -288.365725) (xy 33.04083 -288.417354) (xy 33.017945 -288.466171) (xy 32.988197 -288.511135)
			(xy 32.952219 -288.551289) (xy 32.910777 -288.585777) (xy 32.864756 -288.613863) (xy 32.815136 -288.63495)
			(xy 32.762975 -288.648586) (xy 32.709384 -288.654483) (xy 32.655505 -288.652514) (xy 32.602487 -288.642721)
			(xy 32.55146 -288.625313) (xy 32.503512 -288.600661) (xy 32.459664 -288.569291) (xy 32.420851 -288.53187)
			(xy 32.387899 -288.489197) (xy 32.361513 -288.44218) (xy 32.342253 -288.391823) (xy 32.33053 -288.339199)
			(xy 32.326595 -288.285428) (xy 25.520904 -288.285428) (xy 25.520412 -288.312385) (xy 25.512562 -288.365725)
			(xy 25.49703 -288.417354) (xy 25.474145 -288.466171) (xy 25.444397 -288.511135) (xy 25.408419 -288.551289)
			(xy 25.366977 -288.585777) (xy 25.320956 -288.613863) (xy 25.271336 -288.63495) (xy 25.219175 -288.648586)
			(xy 25.165584 -288.654483) (xy 25.111705 -288.652514) (xy 25.058687 -288.642721) (xy 25.00766 -288.625313)
			(xy 24.959712 -288.600661) (xy 24.915864 -288.569291) (xy 24.877051 -288.53187) (xy 24.844099 -288.489197)
			(xy 24.817713 -288.44218) (xy 24.798453 -288.391823) (xy 24.78673 -288.339199) (xy 24.782795 -288.285428)
			(xy 17.97685 -288.285428) (xy 17.976358 -288.312385) (xy 17.968508 -288.365725) (xy 17.952976 -288.417354)
			(xy 17.930091 -288.466171) (xy 17.900343 -288.511135) (xy 17.864365 -288.551289) (xy 17.822923 -288.585777)
			(xy 17.776902 -288.613863) (xy 17.727282 -288.63495) (xy 17.675121 -288.648586) (xy 17.62153 -288.654483)
			(xy 17.567651 -288.652514) (xy 17.514633 -288.642721) (xy 17.463606 -288.625313) (xy 17.415658 -288.600661)
			(xy 17.37181 -288.569291) (xy 17.332997 -288.53187) (xy 17.300045 -288.489197) (xy 17.273659 -288.44218)
			(xy 17.254399 -288.391823) (xy 17.242676 -288.339199) (xy 17.238741 -288.285428) (xy 15.598394 -288.285428)
			(xy 15.598394 -289.135312) (xy 21.338809 -289.135312) (xy 21.342744 -289.081541) (xy 21.354467 -289.028917)
			(xy 21.373727 -288.97856) (xy 21.400113 -288.931543) (xy 21.433065 -288.88887) (xy 21.471878 -288.851449)
			(xy 21.515726 -288.820079) (xy 21.563674 -288.795427) (xy 21.614701 -288.778019) (xy 21.667719 -288.768226)
			(xy 21.721598 -288.766257) (xy 21.775189 -288.772154) (xy 21.82735 -288.78579) (xy 21.87697 -288.806877)
			(xy 21.922991 -288.834963) (xy 21.964433 -288.869451) (xy 22.000411 -288.909605) (xy 22.030159 -288.954569)
			(xy 22.053044 -289.003386) (xy 22.068576 -289.055015) (xy 22.076426 -289.108355) (xy 22.076918 -289.135312)
			(xy 28.882863 -289.135312) (xy 28.886798 -289.081541) (xy 28.898521 -289.028917) (xy 28.917781 -288.97856)
			(xy 28.944167 -288.931543) (xy 28.977119 -288.88887) (xy 29.015932 -288.851449) (xy 29.05978 -288.820079)
			(xy 29.107728 -288.795427) (xy 29.158755 -288.778019) (xy 29.211773 -288.768226) (xy 29.265652 -288.766257)
			(xy 29.319243 -288.772154) (xy 29.371404 -288.78579) (xy 29.421024 -288.806877) (xy 29.467045 -288.834963)
			(xy 29.508487 -288.869451) (xy 29.544465 -288.909605) (xy 29.574213 -288.954569) (xy 29.597098 -289.003386)
			(xy 29.61263 -289.055015) (xy 29.62048 -289.108355) (xy 29.620972 -289.135312) (xy 36.426663 -289.135312)
			(xy 36.430598 -289.081541) (xy 36.442321 -289.028917) (xy 36.461581 -288.97856) (xy 36.487967 -288.931543)
			(xy 36.520919 -288.88887) (xy 36.559732 -288.851449) (xy 36.60358 -288.820079) (xy 36.651528 -288.795427)
			(xy 36.702555 -288.778019) (xy 36.755573 -288.768226) (xy 36.809452 -288.766257) (xy 36.863043 -288.772154)
			(xy 36.915204 -288.78579) (xy 36.964824 -288.806877) (xy 37.010845 -288.834963) (xy 37.052287 -288.869451)
			(xy 37.088265 -288.909605) (xy 37.118013 -288.954569) (xy 37.140898 -289.003386) (xy 37.15643 -289.055015)
			(xy 37.16428 -289.108355) (xy 37.164772 -289.135312) (xy 43.970717 -289.135312) (xy 43.974652 -289.081541)
			(xy 43.986375 -289.028917) (xy 44.005635 -288.97856) (xy 44.032021 -288.931543) (xy 44.064973 -288.88887)
			(xy 44.103786 -288.851449) (xy 44.147634 -288.820079) (xy 44.195582 -288.795427) (xy 44.246609 -288.778019)
			(xy 44.299627 -288.768226) (xy 44.353506 -288.766257) (xy 44.407097 -288.772154) (xy 44.459258 -288.78579)
			(xy 44.508878 -288.806877) (xy 44.554899 -288.834963) (xy 44.596341 -288.869451) (xy 44.632319 -288.909605)
			(xy 44.662067 -288.954569) (xy 44.684952 -289.003386) (xy 44.700484 -289.055015) (xy 44.708334 -289.108355)
			(xy 44.708826 -289.135312) (xy 44.708334 -289.162269) (xy 44.700484 -289.215609) (xy 44.684952 -289.267238)
			(xy 44.662067 -289.316055) (xy 44.632319 -289.361019) (xy 44.596341 -289.401173) (xy 44.554899 -289.435661)
			(xy 44.508878 -289.463747) (xy 44.459258 -289.484834) (xy 44.407097 -289.49847) (xy 44.353506 -289.504367)
			(xy 44.299627 -289.502398) (xy 44.246609 -289.492605) (xy 44.195582 -289.475197) (xy 44.147634 -289.450545)
			(xy 44.103786 -289.419175) (xy 44.064973 -289.381754) (xy 44.032021 -289.339081) (xy 44.005635 -289.292064)
			(xy 43.986375 -289.241707) (xy 43.974652 -289.189083) (xy 43.970717 -289.135312) (xy 37.164772 -289.135312)
			(xy 37.16428 -289.162269) (xy 37.15643 -289.215609) (xy 37.140898 -289.267238) (xy 37.118013 -289.316055)
			(xy 37.088265 -289.361019) (xy 37.052287 -289.401173) (xy 37.010845 -289.435661) (xy 36.964824 -289.463747)
			(xy 36.915204 -289.484834) (xy 36.863043 -289.49847) (xy 36.809452 -289.504367) (xy 36.755573 -289.502398)
			(xy 36.702555 -289.492605) (xy 36.651528 -289.475197) (xy 36.60358 -289.450545) (xy 36.559732 -289.419175)
			(xy 36.520919 -289.381754) (xy 36.487967 -289.339081) (xy 36.461581 -289.292064) (xy 36.442321 -289.241707)
			(xy 36.430598 -289.189083) (xy 36.426663 -289.135312) (xy 29.620972 -289.135312) (xy 29.62048 -289.162269)
			(xy 29.61263 -289.215609) (xy 29.597098 -289.267238) (xy 29.574213 -289.316055) (xy 29.544465 -289.361019)
			(xy 29.508487 -289.401173) (xy 29.467045 -289.435661) (xy 29.421024 -289.463747) (xy 29.371404 -289.484834)
			(xy 29.319243 -289.49847) (xy 29.265652 -289.504367) (xy 29.211773 -289.502398) (xy 29.158755 -289.492605)
			(xy 29.107728 -289.475197) (xy 29.05978 -289.450545) (xy 29.015932 -289.419175) (xy 28.977119 -289.381754)
			(xy 28.944167 -289.339081) (xy 28.917781 -289.292064) (xy 28.898521 -289.241707) (xy 28.886798 -289.189083)
			(xy 28.882863 -289.135312) (xy 22.076918 -289.135312) (xy 22.076426 -289.162269) (xy 22.068576 -289.215609)
			(xy 22.053044 -289.267238) (xy 22.030159 -289.316055) (xy 22.000411 -289.361019) (xy 21.964433 -289.401173)
			(xy 21.922991 -289.435661) (xy 21.87697 -289.463747) (xy 21.82735 -289.484834) (xy 21.775189 -289.49847)
			(xy 21.721598 -289.504367) (xy 21.667719 -289.502398) (xy 21.614701 -289.492605) (xy 21.563674 -289.475197)
			(xy 21.515726 -289.450545) (xy 21.471878 -289.419175) (xy 21.433065 -289.381754) (xy 21.400113 -289.339081)
			(xy 21.373727 -289.292064) (xy 21.354467 -289.241707) (xy 21.342744 -289.189083) (xy 21.338809 -289.135312)
			(xy 15.598394 -289.135312) (xy 15.598394 -289.98545) (xy 17.238741 -289.98545) (xy 17.242676 -289.931679)
			(xy 17.254399 -289.879055) (xy 17.273659 -289.828698) (xy 17.300045 -289.781681) (xy 17.332997 -289.739008)
			(xy 17.37181 -289.701587) (xy 17.415658 -289.670217) (xy 17.463606 -289.645565) (xy 17.514633 -289.628157)
			(xy 17.567651 -289.618364) (xy 17.62153 -289.616395) (xy 17.675121 -289.622292) (xy 17.727282 -289.635928)
			(xy 17.776902 -289.657015) (xy 17.822923 -289.685101) (xy 17.864365 -289.719589) (xy 17.900343 -289.759743)
			(xy 17.930091 -289.804707) (xy 17.952976 -289.853524) (xy 17.968508 -289.905153) (xy 17.976358 -289.958493)
			(xy 17.97685 -289.98545) (xy 24.782795 -289.98545) (xy 24.78673 -289.931679) (xy 24.798453 -289.879055)
			(xy 24.817713 -289.828698) (xy 24.844099 -289.781681) (xy 24.877051 -289.739008) (xy 24.915864 -289.701587)
			(xy 24.959712 -289.670217) (xy 25.00766 -289.645565) (xy 25.058687 -289.628157) (xy 25.111705 -289.618364)
			(xy 25.165584 -289.616395) (xy 25.219175 -289.622292) (xy 25.271336 -289.635928) (xy 25.320956 -289.657015)
			(xy 25.366977 -289.685101) (xy 25.408419 -289.719589) (xy 25.444397 -289.759743) (xy 25.474145 -289.804707)
			(xy 25.49703 -289.853524) (xy 25.512562 -289.905153) (xy 25.520412 -289.958493) (xy 25.520904 -289.98545)
			(xy 32.326595 -289.98545) (xy 32.33053 -289.931679) (xy 32.342253 -289.879055) (xy 32.361513 -289.828698)
			(xy 32.387899 -289.781681) (xy 32.420851 -289.739008) (xy 32.459664 -289.701587) (xy 32.503512 -289.670217)
			(xy 32.55146 -289.645565) (xy 32.602487 -289.628157) (xy 32.655505 -289.618364) (xy 32.709384 -289.616395)
			(xy 32.762975 -289.622292) (xy 32.815136 -289.635928) (xy 32.864756 -289.657015) (xy 32.910777 -289.685101)
			(xy 32.952219 -289.719589) (xy 32.988197 -289.759743) (xy 33.017945 -289.804707) (xy 33.04083 -289.853524)
			(xy 33.056362 -289.905153) (xy 33.064212 -289.958493) (xy 33.064704 -289.98545) (xy 39.870649 -289.98545)
			(xy 39.874584 -289.931679) (xy 39.886307 -289.879055) (xy 39.905567 -289.828698) (xy 39.931953 -289.781681)
			(xy 39.964905 -289.739008) (xy 40.003718 -289.701587) (xy 40.047566 -289.670217) (xy 40.095514 -289.645565)
			(xy 40.146541 -289.628157) (xy 40.199559 -289.618364) (xy 40.253438 -289.616395) (xy 40.307029 -289.622292)
			(xy 40.35919 -289.635928) (xy 40.40881 -289.657015) (xy 40.454831 -289.685101) (xy 40.496273 -289.719589)
			(xy 40.532251 -289.759743) (xy 40.561999 -289.804707) (xy 40.584884 -289.853524) (xy 40.600416 -289.905153)
			(xy 40.608266 -289.958493) (xy 40.608758 -289.98545) (xy 40.608266 -290.012407) (xy 40.600416 -290.065747)
			(xy 40.584884 -290.117376) (xy 40.561999 -290.166193) (xy 40.532251 -290.211157) (xy 40.496273 -290.251311)
			(xy 40.454831 -290.285799) (xy 40.40881 -290.313885) (xy 40.35919 -290.334972) (xy 40.307029 -290.348608)
			(xy 40.253438 -290.354505) (xy 40.199559 -290.352536) (xy 40.146541 -290.342743) (xy 40.095514 -290.325335)
			(xy 40.047566 -290.300683) (xy 40.003718 -290.269313) (xy 39.964905 -290.231892) (xy 39.931953 -290.189219)
			(xy 39.905567 -290.142202) (xy 39.886307 -290.091845) (xy 39.874584 -290.039221) (xy 39.870649 -289.98545)
			(xy 33.064704 -289.98545) (xy 33.064212 -290.012407) (xy 33.056362 -290.065747) (xy 33.04083 -290.117376)
			(xy 33.017945 -290.166193) (xy 32.988197 -290.211157) (xy 32.952219 -290.251311) (xy 32.910777 -290.285799)
			(xy 32.864756 -290.313885) (xy 32.815136 -290.334972) (xy 32.762975 -290.348608) (xy 32.709384 -290.354505)
			(xy 32.655505 -290.352536) (xy 32.602487 -290.342743) (xy 32.55146 -290.325335) (xy 32.503512 -290.300683)
			(xy 32.459664 -290.269313) (xy 32.420851 -290.231892) (xy 32.387899 -290.189219) (xy 32.361513 -290.142202)
			(xy 32.342253 -290.091845) (xy 32.33053 -290.039221) (xy 32.326595 -289.98545) (xy 25.520904 -289.98545)
			(xy 25.520412 -290.012407) (xy 25.512562 -290.065747) (xy 25.49703 -290.117376) (xy 25.474145 -290.166193)
			(xy 25.444397 -290.211157) (xy 25.408419 -290.251311) (xy 25.366977 -290.285799) (xy 25.320956 -290.313885)
			(xy 25.271336 -290.334972) (xy 25.219175 -290.348608) (xy 25.165584 -290.354505) (xy 25.111705 -290.352536)
			(xy 25.058687 -290.342743) (xy 25.00766 -290.325335) (xy 24.959712 -290.300683) (xy 24.915864 -290.269313)
			(xy 24.877051 -290.231892) (xy 24.844099 -290.189219) (xy 24.817713 -290.142202) (xy 24.798453 -290.091845)
			(xy 24.78673 -290.039221) (xy 24.782795 -289.98545) (xy 17.97685 -289.98545) (xy 17.976358 -290.012407)
			(xy 17.968508 -290.065747) (xy 17.952976 -290.117376) (xy 17.930091 -290.166193) (xy 17.900343 -290.211157)
			(xy 17.864365 -290.251311) (xy 17.822923 -290.285799) (xy 17.776902 -290.313885) (xy 17.727282 -290.334972)
			(xy 17.675121 -290.348608) (xy 17.62153 -290.354505) (xy 17.567651 -290.352536) (xy 17.514633 -290.342743)
			(xy 17.463606 -290.325335) (xy 17.415658 -290.300683) (xy 17.37181 -290.269313) (xy 17.332997 -290.231892)
			(xy 17.300045 -290.189219) (xy 17.273659 -290.142202) (xy 17.254399 -290.091845) (xy 17.242676 -290.039221)
			(xy 17.238741 -289.98545) (xy 15.598394 -289.98545) (xy 15.598394 -290.835334) (xy 21.338809 -290.835334)
			(xy 21.342744 -290.781563) (xy 21.354467 -290.728939) (xy 21.373727 -290.678582) (xy 21.400113 -290.631565)
			(xy 21.433065 -290.588892) (xy 21.471878 -290.551471) (xy 21.515726 -290.520101) (xy 21.563674 -290.495449)
			(xy 21.614701 -290.478041) (xy 21.667719 -290.468248) (xy 21.721598 -290.466279) (xy 21.775189 -290.472176)
			(xy 21.82735 -290.485812) (xy 21.87697 -290.506899) (xy 21.922991 -290.534985) (xy 21.964433 -290.569473)
			(xy 22.000411 -290.609627) (xy 22.030159 -290.654591) (xy 22.053044 -290.703408) (xy 22.068576 -290.755037)
			(xy 22.076426 -290.808377) (xy 22.076918 -290.835334) (xy 28.882863 -290.835334) (xy 28.886798 -290.781563)
			(xy 28.898521 -290.728939) (xy 28.917781 -290.678582) (xy 28.944167 -290.631565) (xy 28.977119 -290.588892)
			(xy 29.015932 -290.551471) (xy 29.05978 -290.520101) (xy 29.107728 -290.495449) (xy 29.158755 -290.478041)
			(xy 29.211773 -290.468248) (xy 29.265652 -290.466279) (xy 29.319243 -290.472176) (xy 29.371404 -290.485812)
			(xy 29.421024 -290.506899) (xy 29.467045 -290.534985) (xy 29.508487 -290.569473) (xy 29.544465 -290.609627)
			(xy 29.574213 -290.654591) (xy 29.597098 -290.703408) (xy 29.61263 -290.755037) (xy 29.62048 -290.808377)
			(xy 29.620972 -290.835334) (xy 36.426663 -290.835334) (xy 36.430598 -290.781563) (xy 36.442321 -290.728939)
			(xy 36.461581 -290.678582) (xy 36.487967 -290.631565) (xy 36.520919 -290.588892) (xy 36.559732 -290.551471)
			(xy 36.60358 -290.520101) (xy 36.651528 -290.495449) (xy 36.702555 -290.478041) (xy 36.755573 -290.468248)
			(xy 36.809452 -290.466279) (xy 36.863043 -290.472176) (xy 36.915204 -290.485812) (xy 36.964824 -290.506899)
			(xy 37.010845 -290.534985) (xy 37.052287 -290.569473) (xy 37.088265 -290.609627) (xy 37.118013 -290.654591)
			(xy 37.140898 -290.703408) (xy 37.15643 -290.755037) (xy 37.16428 -290.808377) (xy 37.164772 -290.835334)
			(xy 43.970717 -290.835334) (xy 43.974652 -290.781563) (xy 43.986375 -290.728939) (xy 44.005635 -290.678582)
			(xy 44.032021 -290.631565) (xy 44.064973 -290.588892) (xy 44.103786 -290.551471) (xy 44.147634 -290.520101)
			(xy 44.195582 -290.495449) (xy 44.246609 -290.478041) (xy 44.299627 -290.468248) (xy 44.353506 -290.466279)
			(xy 44.407097 -290.472176) (xy 44.459258 -290.485812) (xy 44.508878 -290.506899) (xy 44.554899 -290.534985)
			(xy 44.596341 -290.569473) (xy 44.632319 -290.609627) (xy 44.662067 -290.654591) (xy 44.684952 -290.703408)
			(xy 44.700484 -290.755037) (xy 44.708334 -290.808377) (xy 44.708826 -290.835334) (xy 44.708334 -290.862291)
			(xy 44.700484 -290.915631) (xy 44.684952 -290.96726) (xy 44.662067 -291.016077) (xy 44.632319 -291.061041)
			(xy 44.596341 -291.101195) (xy 44.554899 -291.135683) (xy 44.508878 -291.163769) (xy 44.459258 -291.184856)
			(xy 44.407097 -291.198492) (xy 44.353506 -291.204389) (xy 44.299627 -291.20242) (xy 44.246609 -291.192627)
			(xy 44.195582 -291.175219) (xy 44.147634 -291.150567) (xy 44.103786 -291.119197) (xy 44.064973 -291.081776)
			(xy 44.032021 -291.039103) (xy 44.005635 -290.992086) (xy 43.986375 -290.941729) (xy 43.974652 -290.889105)
			(xy 43.970717 -290.835334) (xy 37.164772 -290.835334) (xy 37.16428 -290.862291) (xy 37.15643 -290.915631)
			(xy 37.140898 -290.96726) (xy 37.118013 -291.016077) (xy 37.088265 -291.061041) (xy 37.052287 -291.101195)
			(xy 37.010845 -291.135683) (xy 36.964824 -291.163769) (xy 36.915204 -291.184856) (xy 36.863043 -291.198492)
			(xy 36.809452 -291.204389) (xy 36.755573 -291.20242) (xy 36.702555 -291.192627) (xy 36.651528 -291.175219)
			(xy 36.60358 -291.150567) (xy 36.559732 -291.119197) (xy 36.520919 -291.081776) (xy 36.487967 -291.039103)
			(xy 36.461581 -290.992086) (xy 36.442321 -290.941729) (xy 36.430598 -290.889105) (xy 36.426663 -290.835334)
			(xy 29.620972 -290.835334) (xy 29.62048 -290.862291) (xy 29.61263 -290.915631) (xy 29.597098 -290.96726)
			(xy 29.574213 -291.016077) (xy 29.544465 -291.061041) (xy 29.508487 -291.101195) (xy 29.467045 -291.135683)
			(xy 29.421024 -291.163769) (xy 29.371404 -291.184856) (xy 29.319243 -291.198492) (xy 29.265652 -291.204389)
			(xy 29.211773 -291.20242) (xy 29.158755 -291.192627) (xy 29.107728 -291.175219) (xy 29.05978 -291.150567)
			(xy 29.015932 -291.119197) (xy 28.977119 -291.081776) (xy 28.944167 -291.039103) (xy 28.917781 -290.992086)
			(xy 28.898521 -290.941729) (xy 28.886798 -290.889105) (xy 28.882863 -290.835334) (xy 22.076918 -290.835334)
			(xy 22.076426 -290.862291) (xy 22.068576 -290.915631) (xy 22.053044 -290.96726) (xy 22.030159 -291.016077)
			(xy 22.000411 -291.061041) (xy 21.964433 -291.101195) (xy 21.922991 -291.135683) (xy 21.87697 -291.163769)
			(xy 21.82735 -291.184856) (xy 21.775189 -291.198492) (xy 21.721598 -291.204389) (xy 21.667719 -291.20242)
			(xy 21.614701 -291.192627) (xy 21.563674 -291.175219) (xy 21.515726 -291.150567) (xy 21.471878 -291.119197)
			(xy 21.433065 -291.081776) (xy 21.400113 -291.039103) (xy 21.373727 -290.992086) (xy 21.354467 -290.941729)
			(xy 21.342744 -290.889105) (xy 21.338809 -290.835334) (xy 15.598394 -290.835334) (xy 15.598394 -291.685218)
			(xy 17.238741 -291.685218) (xy 17.242676 -291.631447) (xy 17.254399 -291.578823) (xy 17.273659 -291.528466)
			(xy 17.300045 -291.481449) (xy 17.332997 -291.438776) (xy 17.37181 -291.401355) (xy 17.415658 -291.369985)
			(xy 17.463606 -291.345333) (xy 17.514633 -291.327925) (xy 17.567651 -291.318132) (xy 17.62153 -291.316163)
			(xy 17.675121 -291.32206) (xy 17.727282 -291.335696) (xy 17.776902 -291.356783) (xy 17.822923 -291.384869)
			(xy 17.864365 -291.419357) (xy 17.900343 -291.459511) (xy 17.930091 -291.504475) (xy 17.952976 -291.553292)
			(xy 17.968508 -291.604921) (xy 17.976358 -291.658261) (xy 17.97685 -291.685218) (xy 24.782795 -291.685218)
			(xy 24.78673 -291.631447) (xy 24.798453 -291.578823) (xy 24.817713 -291.528466) (xy 24.844099 -291.481449)
			(xy 24.877051 -291.438776) (xy 24.915864 -291.401355) (xy 24.959712 -291.369985) (xy 25.00766 -291.345333)
			(xy 25.058687 -291.327925) (xy 25.111705 -291.318132) (xy 25.165584 -291.316163) (xy 25.219175 -291.32206)
			(xy 25.271336 -291.335696) (xy 25.320956 -291.356783) (xy 25.366977 -291.384869) (xy 25.408419 -291.419357)
			(xy 25.444397 -291.459511) (xy 25.474145 -291.504475) (xy 25.49703 -291.553292) (xy 25.512562 -291.604921)
			(xy 25.520412 -291.658261) (xy 25.520904 -291.685218) (xy 32.326595 -291.685218) (xy 32.33053 -291.631447)
			(xy 32.342253 -291.578823) (xy 32.361513 -291.528466) (xy 32.387899 -291.481449) (xy 32.420851 -291.438776)
			(xy 32.459664 -291.401355) (xy 32.503512 -291.369985) (xy 32.55146 -291.345333) (xy 32.602487 -291.327925)
			(xy 32.655505 -291.318132) (xy 32.709384 -291.316163) (xy 32.762975 -291.32206) (xy 32.815136 -291.335696)
			(xy 32.864756 -291.356783) (xy 32.910777 -291.384869) (xy 32.952219 -291.419357) (xy 32.988197 -291.459511)
			(xy 33.017945 -291.504475) (xy 33.04083 -291.553292) (xy 33.056362 -291.604921) (xy 33.064212 -291.658261)
			(xy 33.064704 -291.685218) (xy 39.870649 -291.685218) (xy 39.874584 -291.631447) (xy 39.886307 -291.578823)
			(xy 39.905567 -291.528466) (xy 39.931953 -291.481449) (xy 39.964905 -291.438776) (xy 40.003718 -291.401355)
			(xy 40.047566 -291.369985) (xy 40.095514 -291.345333) (xy 40.146541 -291.327925) (xy 40.199559 -291.318132)
			(xy 40.253438 -291.316163) (xy 40.307029 -291.32206) (xy 40.35919 -291.335696) (xy 40.40881 -291.356783)
			(xy 40.454831 -291.384869) (xy 40.496273 -291.419357) (xy 40.532251 -291.459511) (xy 40.561999 -291.504475)
			(xy 40.584884 -291.553292) (xy 40.600416 -291.604921) (xy 40.608266 -291.658261) (xy 40.608758 -291.685218)
			(xy 40.608266 -291.712175) (xy 40.600416 -291.765515) (xy 40.584884 -291.817144) (xy 40.561999 -291.865961)
			(xy 40.532251 -291.910925) (xy 40.496273 -291.951079) (xy 40.454831 -291.985567) (xy 40.40881 -292.013653)
			(xy 40.35919 -292.03474) (xy 40.307029 -292.048376) (xy 40.253438 -292.054273) (xy 40.199559 -292.052304)
			(xy 40.146541 -292.042511) (xy 40.095514 -292.025103) (xy 40.047566 -292.000451) (xy 40.003718 -291.969081)
			(xy 39.964905 -291.93166) (xy 39.931953 -291.888987) (xy 39.905567 -291.84197) (xy 39.886307 -291.791613)
			(xy 39.874584 -291.738989) (xy 39.870649 -291.685218) (xy 33.064704 -291.685218) (xy 33.064212 -291.712175)
			(xy 33.056362 -291.765515) (xy 33.04083 -291.817144) (xy 33.017945 -291.865961) (xy 32.988197 -291.910925)
			(xy 32.952219 -291.951079) (xy 32.910777 -291.985567) (xy 32.864756 -292.013653) (xy 32.815136 -292.03474)
			(xy 32.762975 -292.048376) (xy 32.709384 -292.054273) (xy 32.655505 -292.052304) (xy 32.602487 -292.042511)
			(xy 32.55146 -292.025103) (xy 32.503512 -292.000451) (xy 32.459664 -291.969081) (xy 32.420851 -291.93166)
			(xy 32.387899 -291.888987) (xy 32.361513 -291.84197) (xy 32.342253 -291.791613) (xy 32.33053 -291.738989)
			(xy 32.326595 -291.685218) (xy 25.520904 -291.685218) (xy 25.520412 -291.712175) (xy 25.512562 -291.765515)
			(xy 25.49703 -291.817144) (xy 25.474145 -291.865961) (xy 25.444397 -291.910925) (xy 25.408419 -291.951079)
			(xy 25.366977 -291.985567) (xy 25.320956 -292.013653) (xy 25.271336 -292.03474) (xy 25.219175 -292.048376)
			(xy 25.165584 -292.054273) (xy 25.111705 -292.052304) (xy 25.058687 -292.042511) (xy 25.00766 -292.025103)
			(xy 24.959712 -292.000451) (xy 24.915864 -291.969081) (xy 24.877051 -291.93166) (xy 24.844099 -291.888987)
			(xy 24.817713 -291.84197) (xy 24.798453 -291.791613) (xy 24.78673 -291.738989) (xy 24.782795 -291.685218)
			(xy 17.97685 -291.685218) (xy 17.976358 -291.712175) (xy 17.968508 -291.765515) (xy 17.952976 -291.817144)
			(xy 17.930091 -291.865961) (xy 17.900343 -291.910925) (xy 17.864365 -291.951079) (xy 17.822923 -291.985567)
			(xy 17.776902 -292.013653) (xy 17.727282 -292.03474) (xy 17.675121 -292.048376) (xy 17.62153 -292.054273)
			(xy 17.567651 -292.052304) (xy 17.514633 -292.042511) (xy 17.463606 -292.025103) (xy 17.415658 -292.000451)
			(xy 17.37181 -291.969081) (xy 17.332997 -291.93166) (xy 17.300045 -291.888987) (xy 17.273659 -291.84197)
			(xy 17.254399 -291.791613) (xy 17.242676 -291.738989) (xy 17.238741 -291.685218) (xy 15.598394 -291.685218)
			(xy 15.598394 -292.535356) (xy 21.338809 -292.535356) (xy 21.342744 -292.481585) (xy 21.354467 -292.428961)
			(xy 21.373727 -292.378604) (xy 21.400113 -292.331587) (xy 21.433065 -292.288914) (xy 21.471878 -292.251493)
			(xy 21.515726 -292.220123) (xy 21.563674 -292.195471) (xy 21.614701 -292.178063) (xy 21.667719 -292.16827)
			(xy 21.721598 -292.166301) (xy 21.775189 -292.172198) (xy 21.82735 -292.185834) (xy 21.87697 -292.206921)
			(xy 21.922991 -292.235007) (xy 21.964433 -292.269495) (xy 22.000411 -292.309649) (xy 22.030159 -292.354613)
			(xy 22.053044 -292.40343) (xy 22.068576 -292.455059) (xy 22.076426 -292.508399) (xy 22.076918 -292.535356)
			(xy 28.882863 -292.535356) (xy 28.886798 -292.481585) (xy 28.898521 -292.428961) (xy 28.917781 -292.378604)
			(xy 28.944167 -292.331587) (xy 28.977119 -292.288914) (xy 29.015932 -292.251493) (xy 29.05978 -292.220123)
			(xy 29.107728 -292.195471) (xy 29.158755 -292.178063) (xy 29.211773 -292.16827) (xy 29.265652 -292.166301)
			(xy 29.319243 -292.172198) (xy 29.371404 -292.185834) (xy 29.421024 -292.206921) (xy 29.467045 -292.235007)
			(xy 29.508487 -292.269495) (xy 29.544465 -292.309649) (xy 29.574213 -292.354613) (xy 29.597098 -292.40343)
			(xy 29.61263 -292.455059) (xy 29.62048 -292.508399) (xy 29.620972 -292.535356) (xy 36.426663 -292.535356)
			(xy 36.430598 -292.481585) (xy 36.442321 -292.428961) (xy 36.461581 -292.378604) (xy 36.487967 -292.331587)
			(xy 36.520919 -292.288914) (xy 36.559732 -292.251493) (xy 36.60358 -292.220123) (xy 36.651528 -292.195471)
			(xy 36.702555 -292.178063) (xy 36.755573 -292.16827) (xy 36.809452 -292.166301) (xy 36.863043 -292.172198)
			(xy 36.915204 -292.185834) (xy 36.964824 -292.206921) (xy 37.010845 -292.235007) (xy 37.052287 -292.269495)
			(xy 37.088265 -292.309649) (xy 37.118013 -292.354613) (xy 37.140898 -292.40343) (xy 37.15643 -292.455059)
			(xy 37.16428 -292.508399) (xy 37.164772 -292.535356) (xy 43.970717 -292.535356) (xy 43.974652 -292.481585)
			(xy 43.986375 -292.428961) (xy 44.005635 -292.378604) (xy 44.032021 -292.331587) (xy 44.064973 -292.288914)
			(xy 44.103786 -292.251493) (xy 44.147634 -292.220123) (xy 44.195582 -292.195471) (xy 44.246609 -292.178063)
			(xy 44.299627 -292.16827) (xy 44.353506 -292.166301) (xy 44.407097 -292.172198) (xy 44.459258 -292.185834)
			(xy 44.508878 -292.206921) (xy 44.554899 -292.235007) (xy 44.596341 -292.269495) (xy 44.632319 -292.309649)
			(xy 44.662067 -292.354613) (xy 44.684952 -292.40343) (xy 44.700484 -292.455059) (xy 44.708334 -292.508399)
			(xy 44.708826 -292.535356) (xy 44.708334 -292.562313) (xy 44.700484 -292.615653) (xy 44.684952 -292.667282)
			(xy 44.662067 -292.716099) (xy 44.632319 -292.761063) (xy 44.596341 -292.801217) (xy 44.554899 -292.835705)
			(xy 44.508878 -292.863791) (xy 44.459258 -292.884878) (xy 44.407097 -292.898514) (xy 44.353506 -292.904411)
			(xy 44.299627 -292.902442) (xy 44.246609 -292.892649) (xy 44.195582 -292.875241) (xy 44.147634 -292.850589)
			(xy 44.103786 -292.819219) (xy 44.064973 -292.781798) (xy 44.032021 -292.739125) (xy 44.005635 -292.692108)
			(xy 43.986375 -292.641751) (xy 43.974652 -292.589127) (xy 43.970717 -292.535356) (xy 37.164772 -292.535356)
			(xy 37.16428 -292.562313) (xy 37.15643 -292.615653) (xy 37.140898 -292.667282) (xy 37.118013 -292.716099)
			(xy 37.088265 -292.761063) (xy 37.052287 -292.801217) (xy 37.010845 -292.835705) (xy 36.964824 -292.863791)
			(xy 36.915204 -292.884878) (xy 36.863043 -292.898514) (xy 36.809452 -292.904411) (xy 36.755573 -292.902442)
			(xy 36.702555 -292.892649) (xy 36.651528 -292.875241) (xy 36.60358 -292.850589) (xy 36.559732 -292.819219)
			(xy 36.520919 -292.781798) (xy 36.487967 -292.739125) (xy 36.461581 -292.692108) (xy 36.442321 -292.641751)
			(xy 36.430598 -292.589127) (xy 36.426663 -292.535356) (xy 29.620972 -292.535356) (xy 29.62048 -292.562313)
			(xy 29.61263 -292.615653) (xy 29.597098 -292.667282) (xy 29.574213 -292.716099) (xy 29.544465 -292.761063)
			(xy 29.508487 -292.801217) (xy 29.467045 -292.835705) (xy 29.421024 -292.863791) (xy 29.371404 -292.884878)
			(xy 29.319243 -292.898514) (xy 29.265652 -292.904411) (xy 29.211773 -292.902442) (xy 29.158755 -292.892649)
			(xy 29.107728 -292.875241) (xy 29.05978 -292.850589) (xy 29.015932 -292.819219) (xy 28.977119 -292.781798)
			(xy 28.944167 -292.739125) (xy 28.917781 -292.692108) (xy 28.898521 -292.641751) (xy 28.886798 -292.589127)
			(xy 28.882863 -292.535356) (xy 22.076918 -292.535356) (xy 22.076426 -292.562313) (xy 22.068576 -292.615653)
			(xy 22.053044 -292.667282) (xy 22.030159 -292.716099) (xy 22.000411 -292.761063) (xy 21.964433 -292.801217)
			(xy 21.922991 -292.835705) (xy 21.87697 -292.863791) (xy 21.82735 -292.884878) (xy 21.775189 -292.898514)
			(xy 21.721598 -292.904411) (xy 21.667719 -292.902442) (xy 21.614701 -292.892649) (xy 21.563674 -292.875241)
			(xy 21.515726 -292.850589) (xy 21.471878 -292.819219) (xy 21.433065 -292.781798) (xy 21.400113 -292.739125)
			(xy 21.373727 -292.692108) (xy 21.354467 -292.641751) (xy 21.342744 -292.589127) (xy 21.338809 -292.535356)
			(xy 15.598394 -292.535356) (xy 15.598394 -293.38524) (xy 17.238741 -293.38524) (xy 17.242676 -293.331469)
			(xy 17.254399 -293.278845) (xy 17.273659 -293.228488) (xy 17.300045 -293.181471) (xy 17.332997 -293.138798)
			(xy 17.37181 -293.101377) (xy 17.415658 -293.070007) (xy 17.463606 -293.045355) (xy 17.514633 -293.027947)
			(xy 17.567651 -293.018154) (xy 17.62153 -293.016185) (xy 17.675121 -293.022082) (xy 17.727282 -293.035718)
			(xy 17.776902 -293.056805) (xy 17.822923 -293.084891) (xy 17.864365 -293.119379) (xy 17.900343 -293.159533)
			(xy 17.930091 -293.204497) (xy 17.952976 -293.253314) (xy 17.968508 -293.304943) (xy 17.976358 -293.358283)
			(xy 17.97685 -293.38524) (xy 24.782795 -293.38524) (xy 24.78673 -293.331469) (xy 24.798453 -293.278845)
			(xy 24.817713 -293.228488) (xy 24.844099 -293.181471) (xy 24.877051 -293.138798) (xy 24.915864 -293.101377)
			(xy 24.959712 -293.070007) (xy 25.00766 -293.045355) (xy 25.058687 -293.027947) (xy 25.111705 -293.018154)
			(xy 25.165584 -293.016185) (xy 25.219175 -293.022082) (xy 25.271336 -293.035718) (xy 25.320956 -293.056805)
			(xy 25.366977 -293.084891) (xy 25.408419 -293.119379) (xy 25.444397 -293.159533) (xy 25.474145 -293.204497)
			(xy 25.49703 -293.253314) (xy 25.512562 -293.304943) (xy 25.520412 -293.358283) (xy 25.520904 -293.38524)
			(xy 32.326595 -293.38524) (xy 32.33053 -293.331469) (xy 32.342253 -293.278845) (xy 32.361513 -293.228488)
			(xy 32.387899 -293.181471) (xy 32.420851 -293.138798) (xy 32.459664 -293.101377) (xy 32.503512 -293.070007)
			(xy 32.55146 -293.045355) (xy 32.602487 -293.027947) (xy 32.655505 -293.018154) (xy 32.709384 -293.016185)
			(xy 32.762975 -293.022082) (xy 32.815136 -293.035718) (xy 32.864756 -293.056805) (xy 32.910777 -293.084891)
			(xy 32.952219 -293.119379) (xy 32.988197 -293.159533) (xy 33.017945 -293.204497) (xy 33.04083 -293.253314)
			(xy 33.056362 -293.304943) (xy 33.064212 -293.358283) (xy 33.064704 -293.38524) (xy 39.870649 -293.38524)
			(xy 39.874584 -293.331469) (xy 39.886307 -293.278845) (xy 39.905567 -293.228488) (xy 39.931953 -293.181471)
			(xy 39.964905 -293.138798) (xy 40.003718 -293.101377) (xy 40.047566 -293.070007) (xy 40.095514 -293.045355)
			(xy 40.146541 -293.027947) (xy 40.199559 -293.018154) (xy 40.253438 -293.016185) (xy 40.307029 -293.022082)
			(xy 40.35919 -293.035718) (xy 40.40881 -293.056805) (xy 40.454831 -293.084891) (xy 40.496273 -293.119379)
			(xy 40.532251 -293.159533) (xy 40.561999 -293.204497) (xy 40.584884 -293.253314) (xy 40.600416 -293.304943)
			(xy 40.608266 -293.358283) (xy 40.608758 -293.38524) (xy 40.608266 -293.412197) (xy 40.600416 -293.465537)
			(xy 40.584884 -293.517166) (xy 40.561999 -293.565983) (xy 40.532251 -293.610947) (xy 40.496273 -293.651101)
			(xy 40.454831 -293.685589) (xy 40.40881 -293.713675) (xy 40.35919 -293.734762) (xy 40.307029 -293.748398)
			(xy 40.253438 -293.754295) (xy 40.199559 -293.752326) (xy 40.146541 -293.742533) (xy 40.095514 -293.725125)
			(xy 40.047566 -293.700473) (xy 40.003718 -293.669103) (xy 39.964905 -293.631682) (xy 39.931953 -293.589009)
			(xy 39.905567 -293.541992) (xy 39.886307 -293.491635) (xy 39.874584 -293.439011) (xy 39.870649 -293.38524)
			(xy 33.064704 -293.38524) (xy 33.064212 -293.412197) (xy 33.056362 -293.465537) (xy 33.04083 -293.517166)
			(xy 33.017945 -293.565983) (xy 32.988197 -293.610947) (xy 32.952219 -293.651101) (xy 32.910777 -293.685589)
			(xy 32.864756 -293.713675) (xy 32.815136 -293.734762) (xy 32.762975 -293.748398) (xy 32.709384 -293.754295)
			(xy 32.655505 -293.752326) (xy 32.602487 -293.742533) (xy 32.55146 -293.725125) (xy 32.503512 -293.700473)
			(xy 32.459664 -293.669103) (xy 32.420851 -293.631682) (xy 32.387899 -293.589009) (xy 32.361513 -293.541992)
			(xy 32.342253 -293.491635) (xy 32.33053 -293.439011) (xy 32.326595 -293.38524) (xy 25.520904 -293.38524)
			(xy 25.520412 -293.412197) (xy 25.512562 -293.465537) (xy 25.49703 -293.517166) (xy 25.474145 -293.565983)
			(xy 25.444397 -293.610947) (xy 25.408419 -293.651101) (xy 25.366977 -293.685589) (xy 25.320956 -293.713675)
			(xy 25.271336 -293.734762) (xy 25.219175 -293.748398) (xy 25.165584 -293.754295) (xy 25.111705 -293.752326)
			(xy 25.058687 -293.742533) (xy 25.00766 -293.725125) (xy 24.959712 -293.700473) (xy 24.915864 -293.669103)
			(xy 24.877051 -293.631682) (xy 24.844099 -293.589009) (xy 24.817713 -293.541992) (xy 24.798453 -293.491635)
			(xy 24.78673 -293.439011) (xy 24.782795 -293.38524) (xy 17.97685 -293.38524) (xy 17.976358 -293.412197)
			(xy 17.968508 -293.465537) (xy 17.952976 -293.517166) (xy 17.930091 -293.565983) (xy 17.900343 -293.610947)
			(xy 17.864365 -293.651101) (xy 17.822923 -293.685589) (xy 17.776902 -293.713675) (xy 17.727282 -293.734762)
			(xy 17.675121 -293.748398) (xy 17.62153 -293.754295) (xy 17.567651 -293.752326) (xy 17.514633 -293.742533)
			(xy 17.463606 -293.725125) (xy 17.415658 -293.700473) (xy 17.37181 -293.669103) (xy 17.332997 -293.631682)
			(xy 17.300045 -293.589009) (xy 17.273659 -293.541992) (xy 17.254399 -293.491635) (xy 17.242676 -293.439011)
			(xy 17.238741 -293.38524) (xy 15.598394 -293.38524) (xy 15.598394 -294.235378) (xy 21.338809 -294.235378)
			(xy 21.342744 -294.181607) (xy 21.354467 -294.128983) (xy 21.373727 -294.078626) (xy 21.400113 -294.031609)
			(xy 21.433065 -293.988936) (xy 21.471878 -293.951515) (xy 21.515726 -293.920145) (xy 21.563674 -293.895493)
			(xy 21.614701 -293.878085) (xy 21.667719 -293.868292) (xy 21.721598 -293.866323) (xy 21.775189 -293.87222)
			(xy 21.82735 -293.885856) (xy 21.87697 -293.906943) (xy 21.922991 -293.935029) (xy 21.964433 -293.969517)
			(xy 22.000411 -294.009671) (xy 22.030159 -294.054635) (xy 22.053044 -294.103452) (xy 22.068576 -294.155081)
			(xy 22.076426 -294.208421) (xy 22.076918 -294.235378) (xy 28.882863 -294.235378) (xy 28.886798 -294.181607)
			(xy 28.898521 -294.128983) (xy 28.917781 -294.078626) (xy 28.944167 -294.031609) (xy 28.977119 -293.988936)
			(xy 29.015932 -293.951515) (xy 29.05978 -293.920145) (xy 29.107728 -293.895493) (xy 29.158755 -293.878085)
			(xy 29.211773 -293.868292) (xy 29.265652 -293.866323) (xy 29.319243 -293.87222) (xy 29.371404 -293.885856)
			(xy 29.421024 -293.906943) (xy 29.467045 -293.935029) (xy 29.508487 -293.969517) (xy 29.544465 -294.009671)
			(xy 29.574213 -294.054635) (xy 29.597098 -294.103452) (xy 29.61263 -294.155081) (xy 29.62048 -294.208421)
			(xy 29.620972 -294.235378) (xy 36.426663 -294.235378) (xy 36.430598 -294.181607) (xy 36.442321 -294.128983)
			(xy 36.461581 -294.078626) (xy 36.487967 -294.031609) (xy 36.520919 -293.988936) (xy 36.559732 -293.951515)
			(xy 36.60358 -293.920145) (xy 36.651528 -293.895493) (xy 36.702555 -293.878085) (xy 36.755573 -293.868292)
			(xy 36.809452 -293.866323) (xy 36.863043 -293.87222) (xy 36.915204 -293.885856) (xy 36.964824 -293.906943)
			(xy 37.010845 -293.935029) (xy 37.052287 -293.969517) (xy 37.088265 -294.009671) (xy 37.118013 -294.054635)
			(xy 37.140898 -294.103452) (xy 37.15643 -294.155081) (xy 37.16428 -294.208421) (xy 37.164772 -294.235378)
			(xy 43.970717 -294.235378) (xy 43.974652 -294.181607) (xy 43.986375 -294.128983) (xy 44.005635 -294.078626)
			(xy 44.032021 -294.031609) (xy 44.064973 -293.988936) (xy 44.103786 -293.951515) (xy 44.147634 -293.920145)
			(xy 44.195582 -293.895493) (xy 44.246609 -293.878085) (xy 44.299627 -293.868292) (xy 44.353506 -293.866323)
			(xy 44.407097 -293.87222) (xy 44.459258 -293.885856) (xy 44.508878 -293.906943) (xy 44.554899 -293.935029)
			(xy 44.596341 -293.969517) (xy 44.632319 -294.009671) (xy 44.662067 -294.054635) (xy 44.684952 -294.103452)
			(xy 44.700484 -294.155081) (xy 44.708334 -294.208421) (xy 44.708826 -294.235378) (xy 44.708334 -294.262335)
			(xy 44.700484 -294.315675) (xy 44.684952 -294.367304) (xy 44.662067 -294.416121) (xy 44.632319 -294.461085)
			(xy 44.596341 -294.501239) (xy 44.554899 -294.535727) (xy 44.508878 -294.563813) (xy 44.459258 -294.5849)
			(xy 44.407097 -294.598536) (xy 44.353506 -294.604433) (xy 44.299627 -294.602464) (xy 44.246609 -294.592671)
			(xy 44.195582 -294.575263) (xy 44.147634 -294.550611) (xy 44.103786 -294.519241) (xy 44.064973 -294.48182)
			(xy 44.032021 -294.439147) (xy 44.005635 -294.39213) (xy 43.986375 -294.341773) (xy 43.974652 -294.289149)
			(xy 43.970717 -294.235378) (xy 37.164772 -294.235378) (xy 37.16428 -294.262335) (xy 37.15643 -294.315675)
			(xy 37.140898 -294.367304) (xy 37.118013 -294.416121) (xy 37.088265 -294.461085) (xy 37.052287 -294.501239)
			(xy 37.010845 -294.535727) (xy 36.964824 -294.563813) (xy 36.915204 -294.5849) (xy 36.863043 -294.598536)
			(xy 36.809452 -294.604433) (xy 36.755573 -294.602464) (xy 36.702555 -294.592671) (xy 36.651528 -294.575263)
			(xy 36.60358 -294.550611) (xy 36.559732 -294.519241) (xy 36.520919 -294.48182) (xy 36.487967 -294.439147)
			(xy 36.461581 -294.39213) (xy 36.442321 -294.341773) (xy 36.430598 -294.289149) (xy 36.426663 -294.235378)
			(xy 29.620972 -294.235378) (xy 29.62048 -294.262335) (xy 29.61263 -294.315675) (xy 29.597098 -294.367304)
			(xy 29.574213 -294.416121) (xy 29.544465 -294.461085) (xy 29.508487 -294.501239) (xy 29.467045 -294.535727)
			(xy 29.421024 -294.563813) (xy 29.371404 -294.5849) (xy 29.319243 -294.598536) (xy 29.265652 -294.604433)
			(xy 29.211773 -294.602464) (xy 29.158755 -294.592671) (xy 29.107728 -294.575263) (xy 29.05978 -294.550611)
			(xy 29.015932 -294.519241) (xy 28.977119 -294.48182) (xy 28.944167 -294.439147) (xy 28.917781 -294.39213)
			(xy 28.898521 -294.341773) (xy 28.886798 -294.289149) (xy 28.882863 -294.235378) (xy 22.076918 -294.235378)
			(xy 22.076426 -294.262335) (xy 22.068576 -294.315675) (xy 22.053044 -294.367304) (xy 22.030159 -294.416121)
			(xy 22.000411 -294.461085) (xy 21.964433 -294.501239) (xy 21.922991 -294.535727) (xy 21.87697 -294.563813)
			(xy 21.82735 -294.5849) (xy 21.775189 -294.598536) (xy 21.721598 -294.604433) (xy 21.667719 -294.602464)
			(xy 21.614701 -294.592671) (xy 21.563674 -294.575263) (xy 21.515726 -294.550611) (xy 21.471878 -294.519241)
			(xy 21.433065 -294.48182) (xy 21.400113 -294.439147) (xy 21.373727 -294.39213) (xy 21.354467 -294.341773)
			(xy 21.342744 -294.289149) (xy 21.338809 -294.235378) (xy 15.598394 -294.235378) (xy 15.598394 -295.085262)
			(xy 17.238741 -295.085262) (xy 17.242676 -295.031491) (xy 17.254399 -294.978867) (xy 17.273659 -294.92851)
			(xy 17.300045 -294.881493) (xy 17.332997 -294.83882) (xy 17.37181 -294.801399) (xy 17.415658 -294.770029)
			(xy 17.463606 -294.745377) (xy 17.514633 -294.727969) (xy 17.567651 -294.718176) (xy 17.62153 -294.716207)
			(xy 17.675121 -294.722104) (xy 17.727282 -294.73574) (xy 17.776902 -294.756827) (xy 17.822923 -294.784913)
			(xy 17.864365 -294.819401) (xy 17.900343 -294.859555) (xy 17.930091 -294.904519) (xy 17.952976 -294.953336)
			(xy 17.968508 -295.004965) (xy 17.976358 -295.058305) (xy 17.97685 -295.085262) (xy 21.338809 -295.085262)
			(xy 21.342744 -295.031491) (xy 21.354467 -294.978867) (xy 21.373727 -294.92851) (xy 21.400113 -294.881493)
			(xy 21.433065 -294.83882) (xy 21.471878 -294.801399) (xy 21.515726 -294.770029) (xy 21.563674 -294.745377)
			(xy 21.614701 -294.727969) (xy 21.667719 -294.718176) (xy 21.721598 -294.716207) (xy 21.775189 -294.722104)
			(xy 21.82735 -294.73574) (xy 21.87697 -294.756827) (xy 21.922991 -294.784913) (xy 21.964433 -294.819401)
			(xy 22.000411 -294.859555) (xy 22.030159 -294.904519) (xy 22.053044 -294.953336) (xy 22.068576 -295.004965)
			(xy 22.076426 -295.058305) (xy 22.076918 -295.085262) (xy 24.782795 -295.085262) (xy 24.78673 -295.031491)
			(xy 24.798453 -294.978867) (xy 24.817713 -294.92851) (xy 24.844099 -294.881493) (xy 24.877051 -294.83882)
			(xy 24.915864 -294.801399) (xy 24.959712 -294.770029) (xy 25.00766 -294.745377) (xy 25.058687 -294.727969)
			(xy 25.111705 -294.718176) (xy 25.165584 -294.716207) (xy 25.219175 -294.722104) (xy 25.271336 -294.73574)
			(xy 25.320956 -294.756827) (xy 25.366977 -294.784913) (xy 25.408419 -294.819401) (xy 25.444397 -294.859555)
			(xy 25.474145 -294.904519) (xy 25.49703 -294.953336) (xy 25.512562 -295.004965) (xy 25.520412 -295.058305)
			(xy 25.520904 -295.085262) (xy 28.882863 -295.085262) (xy 28.886798 -295.031491) (xy 28.898521 -294.978867)
			(xy 28.917781 -294.92851) (xy 28.944167 -294.881493) (xy 28.977119 -294.83882) (xy 29.015932 -294.801399)
			(xy 29.05978 -294.770029) (xy 29.107728 -294.745377) (xy 29.158755 -294.727969) (xy 29.211773 -294.718176)
			(xy 29.265652 -294.716207) (xy 29.319243 -294.722104) (xy 29.371404 -294.73574) (xy 29.421024 -294.756827)
			(xy 29.467045 -294.784913) (xy 29.508487 -294.819401) (xy 29.544465 -294.859555) (xy 29.574213 -294.904519)
			(xy 29.597098 -294.953336) (xy 29.61263 -295.004965) (xy 29.62048 -295.058305) (xy 29.620972 -295.085262)
			(xy 32.326595 -295.085262) (xy 32.33053 -295.031491) (xy 32.342253 -294.978867) (xy 32.361513 -294.92851)
			(xy 32.387899 -294.881493) (xy 32.420851 -294.83882) (xy 32.459664 -294.801399) (xy 32.503512 -294.770029)
			(xy 32.55146 -294.745377) (xy 32.602487 -294.727969) (xy 32.655505 -294.718176) (xy 32.709384 -294.716207)
			(xy 32.762975 -294.722104) (xy 32.815136 -294.73574) (xy 32.864756 -294.756827) (xy 32.910777 -294.784913)
			(xy 32.952219 -294.819401) (xy 32.988197 -294.859555) (xy 33.017945 -294.904519) (xy 33.04083 -294.953336)
			(xy 33.056362 -295.004965) (xy 33.064212 -295.058305) (xy 33.064704 -295.085262) (xy 36.426663 -295.085262)
			(xy 36.430598 -295.031491) (xy 36.442321 -294.978867) (xy 36.461581 -294.92851) (xy 36.487967 -294.881493)
			(xy 36.520919 -294.83882) (xy 36.559732 -294.801399) (xy 36.60358 -294.770029) (xy 36.651528 -294.745377)
			(xy 36.702555 -294.727969) (xy 36.755573 -294.718176) (xy 36.809452 -294.716207) (xy 36.863043 -294.722104)
			(xy 36.915204 -294.73574) (xy 36.964824 -294.756827) (xy 37.010845 -294.784913) (xy 37.052287 -294.819401)
			(xy 37.088265 -294.859555) (xy 37.118013 -294.904519) (xy 37.140898 -294.953336) (xy 37.15643 -295.004965)
			(xy 37.16428 -295.058305) (xy 37.164772 -295.085262) (xy 39.870649 -295.085262) (xy 39.874584 -295.031491)
			(xy 39.886307 -294.978867) (xy 39.905567 -294.92851) (xy 39.931953 -294.881493) (xy 39.964905 -294.83882)
			(xy 40.003718 -294.801399) (xy 40.047566 -294.770029) (xy 40.095514 -294.745377) (xy 40.146541 -294.727969)
			(xy 40.199559 -294.718176) (xy 40.253438 -294.716207) (xy 40.307029 -294.722104) (xy 40.35919 -294.73574)
			(xy 40.40881 -294.756827) (xy 40.454831 -294.784913) (xy 40.496273 -294.819401) (xy 40.532251 -294.859555)
			(xy 40.561999 -294.904519) (xy 40.584884 -294.953336) (xy 40.600416 -295.004965) (xy 40.608266 -295.058305)
			(xy 40.608758 -295.085262) (xy 43.970717 -295.085262) (xy 43.974652 -295.031491) (xy 43.986375 -294.978867)
			(xy 44.005635 -294.92851) (xy 44.032021 -294.881493) (xy 44.064973 -294.83882) (xy 44.103786 -294.801399)
			(xy 44.147634 -294.770029) (xy 44.195582 -294.745377) (xy 44.246609 -294.727969) (xy 44.299627 -294.718176)
			(xy 44.353506 -294.716207) (xy 44.407097 -294.722104) (xy 44.459258 -294.73574) (xy 44.508878 -294.756827)
			(xy 44.554899 -294.784913) (xy 44.596341 -294.819401) (xy 44.632319 -294.859555) (xy 44.662067 -294.904519)
			(xy 44.684952 -294.953336) (xy 44.700484 -295.004965) (xy 44.708334 -295.058305) (xy 44.708826 -295.085262)
			(xy 44.708334 -295.112219) (xy 44.700484 -295.165559) (xy 44.684952 -295.217188) (xy 44.662067 -295.266005)
			(xy 44.632319 -295.310969) (xy 44.596341 -295.351123) (xy 44.554899 -295.385611) (xy 44.508878 -295.413697)
			(xy 44.459258 -295.434784) (xy 44.407097 -295.44842) (xy 44.353506 -295.454317) (xy 44.299627 -295.452348)
			(xy 44.246609 -295.442555) (xy 44.195582 -295.425147) (xy 44.147634 -295.400495) (xy 44.103786 -295.369125)
			(xy 44.064973 -295.331704) (xy 44.032021 -295.289031) (xy 44.005635 -295.242014) (xy 43.986375 -295.191657)
			(xy 43.974652 -295.139033) (xy 43.970717 -295.085262) (xy 40.608758 -295.085262) (xy 40.608266 -295.112219)
			(xy 40.600416 -295.165559) (xy 40.584884 -295.217188) (xy 40.561999 -295.266005) (xy 40.532251 -295.310969)
			(xy 40.496273 -295.351123) (xy 40.454831 -295.385611) (xy 40.40881 -295.413697) (xy 40.35919 -295.434784)
			(xy 40.307029 -295.44842) (xy 40.253438 -295.454317) (xy 40.199559 -295.452348) (xy 40.146541 -295.442555)
			(xy 40.095514 -295.425147) (xy 40.047566 -295.400495) (xy 40.003718 -295.369125) (xy 39.964905 -295.331704)
			(xy 39.931953 -295.289031) (xy 39.905567 -295.242014) (xy 39.886307 -295.191657) (xy 39.874584 -295.139033)
			(xy 39.870649 -295.085262) (xy 37.164772 -295.085262) (xy 37.16428 -295.112219) (xy 37.15643 -295.165559)
			(xy 37.140898 -295.217188) (xy 37.118013 -295.266005) (xy 37.088265 -295.310969) (xy 37.052287 -295.351123)
			(xy 37.010845 -295.385611) (xy 36.964824 -295.413697) (xy 36.915204 -295.434784) (xy 36.863043 -295.44842)
			(xy 36.809452 -295.454317) (xy 36.755573 -295.452348) (xy 36.702555 -295.442555) (xy 36.651528 -295.425147)
			(xy 36.60358 -295.400495) (xy 36.559732 -295.369125) (xy 36.520919 -295.331704) (xy 36.487967 -295.289031)
			(xy 36.461581 -295.242014) (xy 36.442321 -295.191657) (xy 36.430598 -295.139033) (xy 36.426663 -295.085262)
			(xy 33.064704 -295.085262) (xy 33.064212 -295.112219) (xy 33.056362 -295.165559) (xy 33.04083 -295.217188)
			(xy 33.017945 -295.266005) (xy 32.988197 -295.310969) (xy 32.952219 -295.351123) (xy 32.910777 -295.385611)
			(xy 32.864756 -295.413697) (xy 32.815136 -295.434784) (xy 32.762975 -295.44842) (xy 32.709384 -295.454317)
			(xy 32.655505 -295.452348) (xy 32.602487 -295.442555) (xy 32.55146 -295.425147) (xy 32.503512 -295.400495)
			(xy 32.459664 -295.369125) (xy 32.420851 -295.331704) (xy 32.387899 -295.289031) (xy 32.361513 -295.242014)
			(xy 32.342253 -295.191657) (xy 32.33053 -295.139033) (xy 32.326595 -295.085262) (xy 29.620972 -295.085262)
			(xy 29.62048 -295.112219) (xy 29.61263 -295.165559) (xy 29.597098 -295.217188) (xy 29.574213 -295.266005)
			(xy 29.544465 -295.310969) (xy 29.508487 -295.351123) (xy 29.467045 -295.385611) (xy 29.421024 -295.413697)
			(xy 29.371404 -295.434784) (xy 29.319243 -295.44842) (xy 29.265652 -295.454317) (xy 29.211773 -295.452348)
			(xy 29.158755 -295.442555) (xy 29.107728 -295.425147) (xy 29.05978 -295.400495) (xy 29.015932 -295.369125)
			(xy 28.977119 -295.331704) (xy 28.944167 -295.289031) (xy 28.917781 -295.242014) (xy 28.898521 -295.191657)
			(xy 28.886798 -295.139033) (xy 28.882863 -295.085262) (xy 25.520904 -295.085262) (xy 25.520412 -295.112219)
			(xy 25.512562 -295.165559) (xy 25.49703 -295.217188) (xy 25.474145 -295.266005) (xy 25.444397 -295.310969)
			(xy 25.408419 -295.351123) (xy 25.366977 -295.385611) (xy 25.320956 -295.413697) (xy 25.271336 -295.434784)
			(xy 25.219175 -295.44842) (xy 25.165584 -295.454317) (xy 25.111705 -295.452348) (xy 25.058687 -295.442555)
			(xy 25.00766 -295.425147) (xy 24.959712 -295.400495) (xy 24.915864 -295.369125) (xy 24.877051 -295.331704)
			(xy 24.844099 -295.289031) (xy 24.817713 -295.242014) (xy 24.798453 -295.191657) (xy 24.78673 -295.139033)
			(xy 24.782795 -295.085262) (xy 22.076918 -295.085262) (xy 22.076426 -295.112219) (xy 22.068576 -295.165559)
			(xy 22.053044 -295.217188) (xy 22.030159 -295.266005) (xy 22.000411 -295.310969) (xy 21.964433 -295.351123)
			(xy 21.922991 -295.385611) (xy 21.87697 -295.413697) (xy 21.82735 -295.434784) (xy 21.775189 -295.44842)
			(xy 21.721598 -295.454317) (xy 21.667719 -295.452348) (xy 21.614701 -295.442555) (xy 21.563674 -295.425147)
			(xy 21.515726 -295.400495) (xy 21.471878 -295.369125) (xy 21.433065 -295.331704) (xy 21.400113 -295.289031)
			(xy 21.373727 -295.242014) (xy 21.354467 -295.191657) (xy 21.342744 -295.139033) (xy 21.338809 -295.085262)
			(xy 17.97685 -295.085262) (xy 17.976358 -295.112219) (xy 17.968508 -295.165559) (xy 17.952976 -295.217188)
			(xy 17.930091 -295.266005) (xy 17.900343 -295.310969) (xy 17.864365 -295.351123) (xy 17.822923 -295.385611)
			(xy 17.776902 -295.413697) (xy 17.727282 -295.434784) (xy 17.675121 -295.44842) (xy 17.62153 -295.454317)
			(xy 17.567651 -295.452348) (xy 17.514633 -295.442555) (xy 17.463606 -295.425147) (xy 17.415658 -295.400495)
			(xy 17.37181 -295.369125) (xy 17.332997 -295.331704) (xy 17.300045 -295.289031) (xy 17.273659 -295.242014)
			(xy 17.254399 -295.191657) (xy 17.242676 -295.139033) (xy 17.238741 -295.085262) (xy 15.598394 -295.085262)
			(xy 15.598394 -295.9354) (xy 17.238741 -295.9354) (xy 17.242676 -295.881629) (xy 17.254399 -295.829005)
			(xy 17.273659 -295.778648) (xy 17.300045 -295.731631) (xy 17.332997 -295.688958) (xy 17.37181 -295.651537)
			(xy 17.415658 -295.620167) (xy 17.463606 -295.595515) (xy 17.514633 -295.578107) (xy 17.567651 -295.568314)
			(xy 17.62153 -295.566345) (xy 17.675121 -295.572242) (xy 17.727282 -295.585878) (xy 17.776902 -295.606965)
			(xy 17.822923 -295.635051) (xy 17.864365 -295.669539) (xy 17.900343 -295.709693) (xy 17.930091 -295.754657)
			(xy 17.952976 -295.803474) (xy 17.968508 -295.855103) (xy 17.976358 -295.908443) (xy 17.97685 -295.9354)
			(xy 24.782795 -295.9354) (xy 24.78673 -295.881629) (xy 24.798453 -295.829005) (xy 24.817713 -295.778648)
			(xy 24.844099 -295.731631) (xy 24.877051 -295.688958) (xy 24.915864 -295.651537) (xy 24.959712 -295.620167)
			(xy 25.00766 -295.595515) (xy 25.058687 -295.578107) (xy 25.111705 -295.568314) (xy 25.165584 -295.566345)
			(xy 25.219175 -295.572242) (xy 25.271336 -295.585878) (xy 25.320956 -295.606965) (xy 25.366977 -295.635051)
			(xy 25.408419 -295.669539) (xy 25.444397 -295.709693) (xy 25.474145 -295.754657) (xy 25.49703 -295.803474)
			(xy 25.512562 -295.855103) (xy 25.520412 -295.908443) (xy 25.520904 -295.9354) (xy 32.326595 -295.9354)
			(xy 32.33053 -295.881629) (xy 32.342253 -295.829005) (xy 32.361513 -295.778648) (xy 32.387899 -295.731631)
			(xy 32.420851 -295.688958) (xy 32.459664 -295.651537) (xy 32.503512 -295.620167) (xy 32.55146 -295.595515)
			(xy 32.602487 -295.578107) (xy 32.655505 -295.568314) (xy 32.709384 -295.566345) (xy 32.762975 -295.572242)
			(xy 32.815136 -295.585878) (xy 32.864756 -295.606965) (xy 32.910777 -295.635051) (xy 32.952219 -295.669539)
			(xy 32.988197 -295.709693) (xy 33.017945 -295.754657) (xy 33.04083 -295.803474) (xy 33.056362 -295.855103)
			(xy 33.064212 -295.908443) (xy 33.064704 -295.9354) (xy 39.870649 -295.9354) (xy 39.874584 -295.881629)
			(xy 39.886307 -295.829005) (xy 39.905567 -295.778648) (xy 39.931953 -295.731631) (xy 39.964905 -295.688958)
			(xy 40.003718 -295.651537) (xy 40.047566 -295.620167) (xy 40.095514 -295.595515) (xy 40.146541 -295.578107)
			(xy 40.199559 -295.568314) (xy 40.253438 -295.566345) (xy 40.307029 -295.572242) (xy 40.35919 -295.585878)
			(xy 40.40881 -295.606965) (xy 40.454831 -295.635051) (xy 40.496273 -295.669539) (xy 40.532251 -295.709693)
			(xy 40.561999 -295.754657) (xy 40.584884 -295.803474) (xy 40.600416 -295.855103) (xy 40.608266 -295.908443)
			(xy 40.608758 -295.9354) (xy 40.608266 -295.962357) (xy 40.600416 -296.015697) (xy 40.584884 -296.067326)
			(xy 40.561999 -296.116143) (xy 40.532251 -296.161107) (xy 40.496273 -296.201261) (xy 40.454831 -296.235749)
			(xy 40.40881 -296.263835) (xy 40.35919 -296.284922) (xy 40.307029 -296.298558) (xy 40.253438 -296.304455)
			(xy 40.199559 -296.302486) (xy 40.146541 -296.292693) (xy 40.095514 -296.275285) (xy 40.047566 -296.250633)
			(xy 40.003718 -296.219263) (xy 39.964905 -296.181842) (xy 39.931953 -296.139169) (xy 39.905567 -296.092152)
			(xy 39.886307 -296.041795) (xy 39.874584 -295.989171) (xy 39.870649 -295.9354) (xy 33.064704 -295.9354)
			(xy 33.064212 -295.962357) (xy 33.056362 -296.015697) (xy 33.04083 -296.067326) (xy 33.017945 -296.116143)
			(xy 32.988197 -296.161107) (xy 32.952219 -296.201261) (xy 32.910777 -296.235749) (xy 32.864756 -296.263835)
			(xy 32.815136 -296.284922) (xy 32.762975 -296.298558) (xy 32.709384 -296.304455) (xy 32.655505 -296.302486)
			(xy 32.602487 -296.292693) (xy 32.55146 -296.275285) (xy 32.503512 -296.250633) (xy 32.459664 -296.219263)
			(xy 32.420851 -296.181842) (xy 32.387899 -296.139169) (xy 32.361513 -296.092152) (xy 32.342253 -296.041795)
			(xy 32.33053 -295.989171) (xy 32.326595 -295.9354) (xy 25.520904 -295.9354) (xy 25.520412 -295.962357)
			(xy 25.512562 -296.015697) (xy 25.49703 -296.067326) (xy 25.474145 -296.116143) (xy 25.444397 -296.161107)
			(xy 25.408419 -296.201261) (xy 25.366977 -296.235749) (xy 25.320956 -296.263835) (xy 25.271336 -296.284922)
			(xy 25.219175 -296.298558) (xy 25.165584 -296.304455) (xy 25.111705 -296.302486) (xy 25.058687 -296.292693)
			(xy 25.00766 -296.275285) (xy 24.959712 -296.250633) (xy 24.915864 -296.219263) (xy 24.877051 -296.181842)
			(xy 24.844099 -296.139169) (xy 24.817713 -296.092152) (xy 24.798453 -296.041795) (xy 24.78673 -295.989171)
			(xy 24.782795 -295.9354) (xy 17.97685 -295.9354) (xy 17.976358 -295.962357) (xy 17.968508 -296.015697)
			(xy 17.952976 -296.067326) (xy 17.930091 -296.116143) (xy 17.900343 -296.161107) (xy 17.864365 -296.201261)
			(xy 17.822923 -296.235749) (xy 17.776902 -296.263835) (xy 17.727282 -296.284922) (xy 17.675121 -296.298558)
			(xy 17.62153 -296.304455) (xy 17.567651 -296.302486) (xy 17.514633 -296.292693) (xy 17.463606 -296.275285)
			(xy 17.415658 -296.250633) (xy 17.37181 -296.219263) (xy 17.332997 -296.181842) (xy 17.300045 -296.139169)
			(xy 17.273659 -296.092152) (xy 17.254399 -296.041795) (xy 17.242676 -295.989171) (xy 17.238741 -295.9354)
			(xy 15.598394 -295.9354) (xy 15.598394 -296.785284) (xy 21.338809 -296.785284) (xy 21.342744 -296.731513)
			(xy 21.354467 -296.678889) (xy 21.373727 -296.628532) (xy 21.400113 -296.581515) (xy 21.433065 -296.538842)
			(xy 21.471878 -296.501421) (xy 21.515726 -296.470051) (xy 21.563674 -296.445399) (xy 21.614701 -296.427991)
			(xy 21.667719 -296.418198) (xy 21.721598 -296.416229) (xy 21.775189 -296.422126) (xy 21.82735 -296.435762)
			(xy 21.87697 -296.456849) (xy 21.922991 -296.484935) (xy 21.964433 -296.519423) (xy 22.000411 -296.559577)
			(xy 22.030159 -296.604541) (xy 22.053044 -296.653358) (xy 22.068576 -296.704987) (xy 22.076426 -296.758327)
			(xy 22.076918 -296.785284) (xy 28.882863 -296.785284) (xy 28.886798 -296.731513) (xy 28.898521 -296.678889)
			(xy 28.917781 -296.628532) (xy 28.944167 -296.581515) (xy 28.977119 -296.538842) (xy 29.015932 -296.501421)
			(xy 29.05978 -296.470051) (xy 29.107728 -296.445399) (xy 29.158755 -296.427991) (xy 29.211773 -296.418198)
			(xy 29.265652 -296.416229) (xy 29.319243 -296.422126) (xy 29.371404 -296.435762) (xy 29.421024 -296.456849)
			(xy 29.467045 -296.484935) (xy 29.508487 -296.519423) (xy 29.544465 -296.559577) (xy 29.574213 -296.604541)
			(xy 29.597098 -296.653358) (xy 29.61263 -296.704987) (xy 29.62048 -296.758327) (xy 29.620972 -296.785284)
			(xy 36.426663 -296.785284) (xy 36.430598 -296.731513) (xy 36.442321 -296.678889) (xy 36.461581 -296.628532)
			(xy 36.487967 -296.581515) (xy 36.520919 -296.538842) (xy 36.559732 -296.501421) (xy 36.60358 -296.470051)
			(xy 36.651528 -296.445399) (xy 36.702555 -296.427991) (xy 36.755573 -296.418198) (xy 36.809452 -296.416229)
			(xy 36.863043 -296.422126) (xy 36.915204 -296.435762) (xy 36.964824 -296.456849) (xy 37.010845 -296.484935)
			(xy 37.052287 -296.519423) (xy 37.088265 -296.559577) (xy 37.118013 -296.604541) (xy 37.140898 -296.653358)
			(xy 37.15643 -296.704987) (xy 37.16428 -296.758327) (xy 37.164772 -296.785284) (xy 43.970717 -296.785284)
			(xy 43.974652 -296.731513) (xy 43.986375 -296.678889) (xy 44.005635 -296.628532) (xy 44.032021 -296.581515)
			(xy 44.064973 -296.538842) (xy 44.103786 -296.501421) (xy 44.147634 -296.470051) (xy 44.195582 -296.445399)
			(xy 44.246609 -296.427991) (xy 44.299627 -296.418198) (xy 44.353506 -296.416229) (xy 44.407097 -296.422126)
			(xy 44.459258 -296.435762) (xy 44.508878 -296.456849) (xy 44.554899 -296.484935) (xy 44.596341 -296.519423)
			(xy 44.632319 -296.559577) (xy 44.662067 -296.604541) (xy 44.684952 -296.653358) (xy 44.700484 -296.704987)
			(xy 44.708334 -296.758327) (xy 44.708826 -296.785284) (xy 44.708334 -296.812241) (xy 44.700484 -296.865581)
			(xy 44.684952 -296.91721) (xy 44.662067 -296.966027) (xy 44.632319 -297.010991) (xy 44.596341 -297.051145)
			(xy 44.554899 -297.085633) (xy 44.508878 -297.113719) (xy 44.459258 -297.134806) (xy 44.407097 -297.148442)
			(xy 44.353506 -297.154339) (xy 44.299627 -297.15237) (xy 44.246609 -297.142577) (xy 44.195582 -297.125169)
			(xy 44.147634 -297.100517) (xy 44.103786 -297.069147) (xy 44.064973 -297.031726) (xy 44.032021 -296.989053)
			(xy 44.005635 -296.942036) (xy 43.986375 -296.891679) (xy 43.974652 -296.839055) (xy 43.970717 -296.785284)
			(xy 37.164772 -296.785284) (xy 37.16428 -296.812241) (xy 37.15643 -296.865581) (xy 37.140898 -296.91721)
			(xy 37.118013 -296.966027) (xy 37.088265 -297.010991) (xy 37.052287 -297.051145) (xy 37.010845 -297.085633)
			(xy 36.964824 -297.113719) (xy 36.915204 -297.134806) (xy 36.863043 -297.148442) (xy 36.809452 -297.154339)
			(xy 36.755573 -297.15237) (xy 36.702555 -297.142577) (xy 36.651528 -297.125169) (xy 36.60358 -297.100517)
			(xy 36.559732 -297.069147) (xy 36.520919 -297.031726) (xy 36.487967 -296.989053) (xy 36.461581 -296.942036)
			(xy 36.442321 -296.891679) (xy 36.430598 -296.839055) (xy 36.426663 -296.785284) (xy 29.620972 -296.785284)
			(xy 29.62048 -296.812241) (xy 29.61263 -296.865581) (xy 29.597098 -296.91721) (xy 29.574213 -296.966027)
			(xy 29.544465 -297.010991) (xy 29.508487 -297.051145) (xy 29.467045 -297.085633) (xy 29.421024 -297.113719)
			(xy 29.371404 -297.134806) (xy 29.319243 -297.148442) (xy 29.265652 -297.154339) (xy 29.211773 -297.15237)
			(xy 29.158755 -297.142577) (xy 29.107728 -297.125169) (xy 29.05978 -297.100517) (xy 29.015932 -297.069147)
			(xy 28.977119 -297.031726) (xy 28.944167 -296.989053) (xy 28.917781 -296.942036) (xy 28.898521 -296.891679)
			(xy 28.886798 -296.839055) (xy 28.882863 -296.785284) (xy 22.076918 -296.785284) (xy 22.076426 -296.812241)
			(xy 22.068576 -296.865581) (xy 22.053044 -296.91721) (xy 22.030159 -296.966027) (xy 22.000411 -297.010991)
			(xy 21.964433 -297.051145) (xy 21.922991 -297.085633) (xy 21.87697 -297.113719) (xy 21.82735 -297.134806)
			(xy 21.775189 -297.148442) (xy 21.721598 -297.154339) (xy 21.667719 -297.15237) (xy 21.614701 -297.142577)
			(xy 21.563674 -297.125169) (xy 21.515726 -297.100517) (xy 21.471878 -297.069147) (xy 21.433065 -297.031726)
			(xy 21.400113 -296.989053) (xy 21.373727 -296.942036) (xy 21.354467 -296.891679) (xy 21.342744 -296.839055)
			(xy 21.338809 -296.785284) (xy 15.598394 -296.785284) (xy 15.598394 -297.635422) (xy 17.238741 -297.635422)
			(xy 17.242676 -297.581651) (xy 17.254399 -297.529027) (xy 17.273659 -297.47867) (xy 17.300045 -297.431653)
			(xy 17.332997 -297.38898) (xy 17.37181 -297.351559) (xy 17.415658 -297.320189) (xy 17.463606 -297.295537)
			(xy 17.514633 -297.278129) (xy 17.567651 -297.268336) (xy 17.62153 -297.266367) (xy 17.675121 -297.272264)
			(xy 17.727282 -297.2859) (xy 17.776902 -297.306987) (xy 17.822923 -297.335073) (xy 17.864365 -297.369561)
			(xy 17.900343 -297.409715) (xy 17.930091 -297.454679) (xy 17.952976 -297.503496) (xy 17.968508 -297.555125)
			(xy 17.976358 -297.608465) (xy 17.97685 -297.635422) (xy 24.782795 -297.635422) (xy 24.78673 -297.581651)
			(xy 24.798453 -297.529027) (xy 24.817713 -297.47867) (xy 24.844099 -297.431653) (xy 24.877051 -297.38898)
			(xy 24.915864 -297.351559) (xy 24.959712 -297.320189) (xy 25.00766 -297.295537) (xy 25.058687 -297.278129)
			(xy 25.111705 -297.268336) (xy 25.165584 -297.266367) (xy 25.219175 -297.272264) (xy 25.271336 -297.2859)
			(xy 25.320956 -297.306987) (xy 25.366977 -297.335073) (xy 25.408419 -297.369561) (xy 25.444397 -297.409715)
			(xy 25.474145 -297.454679) (xy 25.49703 -297.503496) (xy 25.512562 -297.555125) (xy 25.520412 -297.608465)
			(xy 25.520904 -297.635422) (xy 32.326595 -297.635422) (xy 32.33053 -297.581651) (xy 32.342253 -297.529027)
			(xy 32.361513 -297.47867) (xy 32.387899 -297.431653) (xy 32.420851 -297.38898) (xy 32.459664 -297.351559)
			(xy 32.503512 -297.320189) (xy 32.55146 -297.295537) (xy 32.602487 -297.278129) (xy 32.655505 -297.268336)
			(xy 32.709384 -297.266367) (xy 32.762975 -297.272264) (xy 32.815136 -297.2859) (xy 32.864756 -297.306987)
			(xy 32.910777 -297.335073) (xy 32.952219 -297.369561) (xy 32.988197 -297.409715) (xy 33.017945 -297.454679)
			(xy 33.04083 -297.503496) (xy 33.056362 -297.555125) (xy 33.064212 -297.608465) (xy 33.064704 -297.635422)
			(xy 39.870649 -297.635422) (xy 39.874584 -297.581651) (xy 39.886307 -297.529027) (xy 39.905567 -297.47867)
			(xy 39.931953 -297.431653) (xy 39.964905 -297.38898) (xy 40.003718 -297.351559) (xy 40.047566 -297.320189)
			(xy 40.095514 -297.295537) (xy 40.146541 -297.278129) (xy 40.199559 -297.268336) (xy 40.253438 -297.266367)
			(xy 40.307029 -297.272264) (xy 40.35919 -297.2859) (xy 40.40881 -297.306987) (xy 40.454831 -297.335073)
			(xy 40.496273 -297.369561) (xy 40.532251 -297.409715) (xy 40.561999 -297.454679) (xy 40.584884 -297.503496)
			(xy 40.600416 -297.555125) (xy 40.608266 -297.608465) (xy 40.608758 -297.635422) (xy 40.608266 -297.662379)
			(xy 40.600416 -297.715719) (xy 40.584884 -297.767348) (xy 40.561999 -297.816165) (xy 40.532251 -297.861129)
			(xy 40.496273 -297.901283) (xy 40.454831 -297.935771) (xy 40.40881 -297.963857) (xy 40.35919 -297.984944)
			(xy 40.307029 -297.99858) (xy 40.253438 -298.004477) (xy 40.199559 -298.002508) (xy 40.146541 -297.992715)
			(xy 40.095514 -297.975307) (xy 40.047566 -297.950655) (xy 40.003718 -297.919285) (xy 39.964905 -297.881864)
			(xy 39.931953 -297.839191) (xy 39.905567 -297.792174) (xy 39.886307 -297.741817) (xy 39.874584 -297.689193)
			(xy 39.870649 -297.635422) (xy 33.064704 -297.635422) (xy 33.064212 -297.662379) (xy 33.056362 -297.715719)
			(xy 33.04083 -297.767348) (xy 33.017945 -297.816165) (xy 32.988197 -297.861129) (xy 32.952219 -297.901283)
			(xy 32.910777 -297.935771) (xy 32.864756 -297.963857) (xy 32.815136 -297.984944) (xy 32.762975 -297.99858)
			(xy 32.709384 -298.004477) (xy 32.655505 -298.002508) (xy 32.602487 -297.992715) (xy 32.55146 -297.975307)
			(xy 32.503512 -297.950655) (xy 32.459664 -297.919285) (xy 32.420851 -297.881864) (xy 32.387899 -297.839191)
			(xy 32.361513 -297.792174) (xy 32.342253 -297.741817) (xy 32.33053 -297.689193) (xy 32.326595 -297.635422)
			(xy 25.520904 -297.635422) (xy 25.520412 -297.662379) (xy 25.512562 -297.715719) (xy 25.49703 -297.767348)
			(xy 25.474145 -297.816165) (xy 25.444397 -297.861129) (xy 25.408419 -297.901283) (xy 25.366977 -297.935771)
			(xy 25.320956 -297.963857) (xy 25.271336 -297.984944) (xy 25.219175 -297.99858) (xy 25.165584 -298.004477)
			(xy 25.111705 -298.002508) (xy 25.058687 -297.992715) (xy 25.00766 -297.975307) (xy 24.959712 -297.950655)
			(xy 24.915864 -297.919285) (xy 24.877051 -297.881864) (xy 24.844099 -297.839191) (xy 24.817713 -297.792174)
			(xy 24.798453 -297.741817) (xy 24.78673 -297.689193) (xy 24.782795 -297.635422) (xy 17.97685 -297.635422)
			(xy 17.976358 -297.662379) (xy 17.968508 -297.715719) (xy 17.952976 -297.767348) (xy 17.930091 -297.816165)
			(xy 17.900343 -297.861129) (xy 17.864365 -297.901283) (xy 17.822923 -297.935771) (xy 17.776902 -297.963857)
			(xy 17.727282 -297.984944) (xy 17.675121 -297.99858) (xy 17.62153 -298.004477) (xy 17.567651 -298.002508)
			(xy 17.514633 -297.992715) (xy 17.463606 -297.975307) (xy 17.415658 -297.950655) (xy 17.37181 -297.919285)
			(xy 17.332997 -297.881864) (xy 17.300045 -297.839191) (xy 17.273659 -297.792174) (xy 17.254399 -297.741817)
			(xy 17.242676 -297.689193) (xy 17.238741 -297.635422) (xy 15.598394 -297.635422) (xy 15.598394 -298.485306)
			(xy 21.338809 -298.485306) (xy 21.342744 -298.431535) (xy 21.354467 -298.378911) (xy 21.373727 -298.328554)
			(xy 21.400113 -298.281537) (xy 21.433065 -298.238864) (xy 21.471878 -298.201443) (xy 21.515726 -298.170073)
			(xy 21.563674 -298.145421) (xy 21.614701 -298.128013) (xy 21.667719 -298.11822) (xy 21.721598 -298.116251)
			(xy 21.775189 -298.122148) (xy 21.82735 -298.135784) (xy 21.87697 -298.156871) (xy 21.922991 -298.184957)
			(xy 21.964433 -298.219445) (xy 22.000411 -298.259599) (xy 22.030159 -298.304563) (xy 22.053044 -298.35338)
			(xy 22.068576 -298.405009) (xy 22.076426 -298.458349) (xy 22.076918 -298.485306) (xy 28.882863 -298.485306)
			(xy 28.886798 -298.431535) (xy 28.898521 -298.378911) (xy 28.917781 -298.328554) (xy 28.944167 -298.281537)
			(xy 28.977119 -298.238864) (xy 29.015932 -298.201443) (xy 29.05978 -298.170073) (xy 29.107728 -298.145421)
			(xy 29.158755 -298.128013) (xy 29.211773 -298.11822) (xy 29.265652 -298.116251) (xy 29.319243 -298.122148)
			(xy 29.371404 -298.135784) (xy 29.421024 -298.156871) (xy 29.467045 -298.184957) (xy 29.508487 -298.219445)
			(xy 29.544465 -298.259599) (xy 29.574213 -298.304563) (xy 29.597098 -298.35338) (xy 29.61263 -298.405009)
			(xy 29.62048 -298.458349) (xy 29.620972 -298.485306) (xy 36.426663 -298.485306) (xy 36.430598 -298.431535)
			(xy 36.442321 -298.378911) (xy 36.461581 -298.328554) (xy 36.487967 -298.281537) (xy 36.520919 -298.238864)
			(xy 36.559732 -298.201443) (xy 36.60358 -298.170073) (xy 36.651528 -298.145421) (xy 36.702555 -298.128013)
			(xy 36.755573 -298.11822) (xy 36.809452 -298.116251) (xy 36.863043 -298.122148) (xy 36.915204 -298.135784)
			(xy 36.964824 -298.156871) (xy 37.010845 -298.184957) (xy 37.052287 -298.219445) (xy 37.088265 -298.259599)
			(xy 37.118013 -298.304563) (xy 37.140898 -298.35338) (xy 37.15643 -298.405009) (xy 37.16428 -298.458349)
			(xy 37.164772 -298.485306) (xy 43.970717 -298.485306) (xy 43.974652 -298.431535) (xy 43.986375 -298.378911)
			(xy 44.005635 -298.328554) (xy 44.032021 -298.281537) (xy 44.064973 -298.238864) (xy 44.103786 -298.201443)
			(xy 44.147634 -298.170073) (xy 44.195582 -298.145421) (xy 44.246609 -298.128013) (xy 44.299627 -298.11822)
			(xy 44.353506 -298.116251) (xy 44.407097 -298.122148) (xy 44.459258 -298.135784) (xy 44.508878 -298.156871)
			(xy 44.554899 -298.184957) (xy 44.596341 -298.219445) (xy 44.632319 -298.259599) (xy 44.662067 -298.304563)
			(xy 44.684952 -298.35338) (xy 44.700484 -298.405009) (xy 44.708334 -298.458349) (xy 44.708826 -298.485306)
			(xy 44.708334 -298.512263) (xy 44.700484 -298.565603) (xy 44.684952 -298.617232) (xy 44.662067 -298.666049)
			(xy 44.632319 -298.711013) (xy 44.596341 -298.751167) (xy 44.554899 -298.785655) (xy 44.508878 -298.813741)
			(xy 44.459258 -298.834828) (xy 44.407097 -298.848464) (xy 44.353506 -298.854361) (xy 44.299627 -298.852392)
			(xy 44.246609 -298.842599) (xy 44.195582 -298.825191) (xy 44.147634 -298.800539) (xy 44.103786 -298.769169)
			(xy 44.064973 -298.731748) (xy 44.032021 -298.689075) (xy 44.005635 -298.642058) (xy 43.986375 -298.591701)
			(xy 43.974652 -298.539077) (xy 43.970717 -298.485306) (xy 37.164772 -298.485306) (xy 37.16428 -298.512263)
			(xy 37.15643 -298.565603) (xy 37.140898 -298.617232) (xy 37.118013 -298.666049) (xy 37.088265 -298.711013)
			(xy 37.052287 -298.751167) (xy 37.010845 -298.785655) (xy 36.964824 -298.813741) (xy 36.915204 -298.834828)
			(xy 36.863043 -298.848464) (xy 36.809452 -298.854361) (xy 36.755573 -298.852392) (xy 36.702555 -298.842599)
			(xy 36.651528 -298.825191) (xy 36.60358 -298.800539) (xy 36.559732 -298.769169) (xy 36.520919 -298.731748)
			(xy 36.487967 -298.689075) (xy 36.461581 -298.642058) (xy 36.442321 -298.591701) (xy 36.430598 -298.539077)
			(xy 36.426663 -298.485306) (xy 29.620972 -298.485306) (xy 29.62048 -298.512263) (xy 29.61263 -298.565603)
			(xy 29.597098 -298.617232) (xy 29.574213 -298.666049) (xy 29.544465 -298.711013) (xy 29.508487 -298.751167)
			(xy 29.467045 -298.785655) (xy 29.421024 -298.813741) (xy 29.371404 -298.834828) (xy 29.319243 -298.848464)
			(xy 29.265652 -298.854361) (xy 29.211773 -298.852392) (xy 29.158755 -298.842599) (xy 29.107728 -298.825191)
			(xy 29.05978 -298.800539) (xy 29.015932 -298.769169) (xy 28.977119 -298.731748) (xy 28.944167 -298.689075)
			(xy 28.917781 -298.642058) (xy 28.898521 -298.591701) (xy 28.886798 -298.539077) (xy 28.882863 -298.485306)
			(xy 22.076918 -298.485306) (xy 22.076426 -298.512263) (xy 22.068576 -298.565603) (xy 22.053044 -298.617232)
			(xy 22.030159 -298.666049) (xy 22.000411 -298.711013) (xy 21.964433 -298.751167) (xy 21.922991 -298.785655)
			(xy 21.87697 -298.813741) (xy 21.82735 -298.834828) (xy 21.775189 -298.848464) (xy 21.721598 -298.854361)
			(xy 21.667719 -298.852392) (xy 21.614701 -298.842599) (xy 21.563674 -298.825191) (xy 21.515726 -298.800539)
			(xy 21.471878 -298.769169) (xy 21.433065 -298.731748) (xy 21.400113 -298.689075) (xy 21.373727 -298.642058)
			(xy 21.354467 -298.591701) (xy 21.342744 -298.539077) (xy 21.338809 -298.485306) (xy 15.598394 -298.485306)
			(xy 15.598394 -299.335444) (xy 17.238741 -299.335444) (xy 17.242676 -299.281673) (xy 17.254399 -299.229049)
			(xy 17.273659 -299.178692) (xy 17.300045 -299.131675) (xy 17.332997 -299.089002) (xy 17.37181 -299.051581)
			(xy 17.415658 -299.020211) (xy 17.463606 -298.995559) (xy 17.514633 -298.978151) (xy 17.567651 -298.968358)
			(xy 17.62153 -298.966389) (xy 17.675121 -298.972286) (xy 17.727282 -298.985922) (xy 17.776902 -299.007009)
			(xy 17.822923 -299.035095) (xy 17.864365 -299.069583) (xy 17.900343 -299.109737) (xy 17.930091 -299.154701)
			(xy 17.952976 -299.203518) (xy 17.968508 -299.255147) (xy 17.976358 -299.308487) (xy 17.97685 -299.335444)
			(xy 24.782795 -299.335444) (xy 24.78673 -299.281673) (xy 24.798453 -299.229049) (xy 24.817713 -299.178692)
			(xy 24.844099 -299.131675) (xy 24.877051 -299.089002) (xy 24.915864 -299.051581) (xy 24.959712 -299.020211)
			(xy 25.00766 -298.995559) (xy 25.058687 -298.978151) (xy 25.111705 -298.968358) (xy 25.165584 -298.966389)
			(xy 25.219175 -298.972286) (xy 25.271336 -298.985922) (xy 25.320956 -299.007009) (xy 25.366977 -299.035095)
			(xy 25.408419 -299.069583) (xy 25.444397 -299.109737) (xy 25.474145 -299.154701) (xy 25.49703 -299.203518)
			(xy 25.512562 -299.255147) (xy 25.520412 -299.308487) (xy 25.520904 -299.335444) (xy 32.326595 -299.335444)
			(xy 32.33053 -299.281673) (xy 32.342253 -299.229049) (xy 32.361513 -299.178692) (xy 32.387899 -299.131675)
			(xy 32.420851 -299.089002) (xy 32.459664 -299.051581) (xy 32.503512 -299.020211) (xy 32.55146 -298.995559)
			(xy 32.602487 -298.978151) (xy 32.655505 -298.968358) (xy 32.709384 -298.966389) (xy 32.762975 -298.972286)
			(xy 32.815136 -298.985922) (xy 32.864756 -299.007009) (xy 32.910777 -299.035095) (xy 32.952219 -299.069583)
			(xy 32.988197 -299.109737) (xy 33.017945 -299.154701) (xy 33.04083 -299.203518) (xy 33.056362 -299.255147)
			(xy 33.064212 -299.308487) (xy 33.064704 -299.335444) (xy 39.870649 -299.335444) (xy 39.874584 -299.281673)
			(xy 39.886307 -299.229049) (xy 39.905567 -299.178692) (xy 39.931953 -299.131675) (xy 39.964905 -299.089002)
			(xy 40.003718 -299.051581) (xy 40.047566 -299.020211) (xy 40.095514 -298.995559) (xy 40.146541 -298.978151)
			(xy 40.199559 -298.968358) (xy 40.253438 -298.966389) (xy 40.307029 -298.972286) (xy 40.35919 -298.985922)
			(xy 40.40881 -299.007009) (xy 40.454831 -299.035095) (xy 40.496273 -299.069583) (xy 40.532251 -299.109737)
			(xy 40.561999 -299.154701) (xy 40.584884 -299.203518) (xy 40.600416 -299.255147) (xy 40.608266 -299.308487)
			(xy 40.608758 -299.335444) (xy 40.608266 -299.362401) (xy 40.600416 -299.415741) (xy 40.584884 -299.46737)
			(xy 40.561999 -299.516187) (xy 40.532251 -299.561151) (xy 40.496273 -299.601305) (xy 40.454831 -299.635793)
			(xy 40.40881 -299.663879) (xy 40.35919 -299.684966) (xy 40.307029 -299.698602) (xy 40.253438 -299.704499)
			(xy 40.199559 -299.70253) (xy 40.146541 -299.692737) (xy 40.095514 -299.675329) (xy 40.047566 -299.650677)
			(xy 40.003718 -299.619307) (xy 39.964905 -299.581886) (xy 39.931953 -299.539213) (xy 39.905567 -299.492196)
			(xy 39.886307 -299.441839) (xy 39.874584 -299.389215) (xy 39.870649 -299.335444) (xy 33.064704 -299.335444)
			(xy 33.064212 -299.362401) (xy 33.056362 -299.415741) (xy 33.04083 -299.46737) (xy 33.017945 -299.516187)
			(xy 32.988197 -299.561151) (xy 32.952219 -299.601305) (xy 32.910777 -299.635793) (xy 32.864756 -299.663879)
			(xy 32.815136 -299.684966) (xy 32.762975 -299.698602) (xy 32.709384 -299.704499) (xy 32.655505 -299.70253)
			(xy 32.602487 -299.692737) (xy 32.55146 -299.675329) (xy 32.503512 -299.650677) (xy 32.459664 -299.619307)
			(xy 32.420851 -299.581886) (xy 32.387899 -299.539213) (xy 32.361513 -299.492196) (xy 32.342253 -299.441839)
			(xy 32.33053 -299.389215) (xy 32.326595 -299.335444) (xy 25.520904 -299.335444) (xy 25.520412 -299.362401)
			(xy 25.512562 -299.415741) (xy 25.49703 -299.46737) (xy 25.474145 -299.516187) (xy 25.444397 -299.561151)
			(xy 25.408419 -299.601305) (xy 25.366977 -299.635793) (xy 25.320956 -299.663879) (xy 25.271336 -299.684966)
			(xy 25.219175 -299.698602) (xy 25.165584 -299.704499) (xy 25.111705 -299.70253) (xy 25.058687 -299.692737)
			(xy 25.00766 -299.675329) (xy 24.959712 -299.650677) (xy 24.915864 -299.619307) (xy 24.877051 -299.581886)
			(xy 24.844099 -299.539213) (xy 24.817713 -299.492196) (xy 24.798453 -299.441839) (xy 24.78673 -299.389215)
			(xy 24.782795 -299.335444) (xy 17.97685 -299.335444) (xy 17.976358 -299.362401) (xy 17.968508 -299.415741)
			(xy 17.952976 -299.46737) (xy 17.930091 -299.516187) (xy 17.900343 -299.561151) (xy 17.864365 -299.601305)
			(xy 17.822923 -299.635793) (xy 17.776902 -299.663879) (xy 17.727282 -299.684966) (xy 17.675121 -299.698602)
			(xy 17.62153 -299.704499) (xy 17.567651 -299.70253) (xy 17.514633 -299.692737) (xy 17.463606 -299.675329)
			(xy 17.415658 -299.650677) (xy 17.37181 -299.619307) (xy 17.332997 -299.581886) (xy 17.300045 -299.539213)
			(xy 17.273659 -299.492196) (xy 17.254399 -299.441839) (xy 17.242676 -299.389215) (xy 17.238741 -299.335444)
			(xy 15.598394 -299.335444) (xy 15.598394 -300.185328) (xy 21.338809 -300.185328) (xy 21.342744 -300.131557)
			(xy 21.354467 -300.078933) (xy 21.373727 -300.028576) (xy 21.400113 -299.981559) (xy 21.433065 -299.938886)
			(xy 21.471878 -299.901465) (xy 21.515726 -299.870095) (xy 21.563674 -299.845443) (xy 21.614701 -299.828035)
			(xy 21.667719 -299.818242) (xy 21.721598 -299.816273) (xy 21.775189 -299.82217) (xy 21.82735 -299.835806)
			(xy 21.87697 -299.856893) (xy 21.922991 -299.884979) (xy 21.964433 -299.919467) (xy 22.000411 -299.959621)
			(xy 22.030159 -300.004585) (xy 22.053044 -300.053402) (xy 22.068576 -300.105031) (xy 22.076426 -300.158371)
			(xy 22.076918 -300.185328) (xy 28.882863 -300.185328) (xy 28.886798 -300.131557) (xy 28.898521 -300.078933)
			(xy 28.917781 -300.028576) (xy 28.944167 -299.981559) (xy 28.977119 -299.938886) (xy 29.015932 -299.901465)
			(xy 29.05978 -299.870095) (xy 29.107728 -299.845443) (xy 29.158755 -299.828035) (xy 29.211773 -299.818242)
			(xy 29.265652 -299.816273) (xy 29.319243 -299.82217) (xy 29.371404 -299.835806) (xy 29.421024 -299.856893)
			(xy 29.467045 -299.884979) (xy 29.508487 -299.919467) (xy 29.544465 -299.959621) (xy 29.574213 -300.004585)
			(xy 29.597098 -300.053402) (xy 29.61263 -300.105031) (xy 29.62048 -300.158371) (xy 29.620972 -300.185328)
			(xy 36.426663 -300.185328) (xy 36.430598 -300.131557) (xy 36.442321 -300.078933) (xy 36.461581 -300.028576)
			(xy 36.487967 -299.981559) (xy 36.520919 -299.938886) (xy 36.559732 -299.901465) (xy 36.60358 -299.870095)
			(xy 36.651528 -299.845443) (xy 36.702555 -299.828035) (xy 36.755573 -299.818242) (xy 36.809452 -299.816273)
			(xy 36.863043 -299.82217) (xy 36.915204 -299.835806) (xy 36.964824 -299.856893) (xy 37.010845 -299.884979)
			(xy 37.052287 -299.919467) (xy 37.088265 -299.959621) (xy 37.118013 -300.004585) (xy 37.140898 -300.053402)
			(xy 37.15643 -300.105031) (xy 37.16428 -300.158371) (xy 37.164772 -300.185328) (xy 43.970717 -300.185328)
			(xy 43.974652 -300.131557) (xy 43.986375 -300.078933) (xy 44.005635 -300.028576) (xy 44.032021 -299.981559)
			(xy 44.064973 -299.938886) (xy 44.103786 -299.901465) (xy 44.147634 -299.870095) (xy 44.195582 -299.845443)
			(xy 44.246609 -299.828035) (xy 44.299627 -299.818242) (xy 44.353506 -299.816273) (xy 44.407097 -299.82217)
			(xy 44.459258 -299.835806) (xy 44.508878 -299.856893) (xy 44.554899 -299.884979) (xy 44.596341 -299.919467)
			(xy 44.632319 -299.959621) (xy 44.662067 -300.004585) (xy 44.684952 -300.053402) (xy 44.700484 -300.105031)
			(xy 44.708334 -300.158371) (xy 44.708826 -300.185328) (xy 44.708334 -300.212285) (xy 44.700484 -300.265625)
			(xy 44.684952 -300.317254) (xy 44.662067 -300.366071) (xy 44.632319 -300.411035) (xy 44.596341 -300.451189)
			(xy 44.554899 -300.485677) (xy 44.508878 -300.513763) (xy 44.459258 -300.53485) (xy 44.407097 -300.548486)
			(xy 44.353506 -300.554383) (xy 44.299627 -300.552414) (xy 44.246609 -300.542621) (xy 44.195582 -300.525213)
			(xy 44.147634 -300.500561) (xy 44.103786 -300.469191) (xy 44.064973 -300.43177) (xy 44.032021 -300.389097)
			(xy 44.005635 -300.34208) (xy 43.986375 -300.291723) (xy 43.974652 -300.239099) (xy 43.970717 -300.185328)
			(xy 37.164772 -300.185328) (xy 37.16428 -300.212285) (xy 37.15643 -300.265625) (xy 37.140898 -300.317254)
			(xy 37.118013 -300.366071) (xy 37.088265 -300.411035) (xy 37.052287 -300.451189) (xy 37.010845 -300.485677)
			(xy 36.964824 -300.513763) (xy 36.915204 -300.53485) (xy 36.863043 -300.548486) (xy 36.809452 -300.554383)
			(xy 36.755573 -300.552414) (xy 36.702555 -300.542621) (xy 36.651528 -300.525213) (xy 36.60358 -300.500561)
			(xy 36.559732 -300.469191) (xy 36.520919 -300.43177) (xy 36.487967 -300.389097) (xy 36.461581 -300.34208)
			(xy 36.442321 -300.291723) (xy 36.430598 -300.239099) (xy 36.426663 -300.185328) (xy 29.620972 -300.185328)
			(xy 29.62048 -300.212285) (xy 29.61263 -300.265625) (xy 29.597098 -300.317254) (xy 29.574213 -300.366071)
			(xy 29.544465 -300.411035) (xy 29.508487 -300.451189) (xy 29.467045 -300.485677) (xy 29.421024 -300.513763)
			(xy 29.371404 -300.53485) (xy 29.319243 -300.548486) (xy 29.265652 -300.554383) (xy 29.211773 -300.552414)
			(xy 29.158755 -300.542621) (xy 29.107728 -300.525213) (xy 29.05978 -300.500561) (xy 29.015932 -300.469191)
			(xy 28.977119 -300.43177) (xy 28.944167 -300.389097) (xy 28.917781 -300.34208) (xy 28.898521 -300.291723)
			(xy 28.886798 -300.239099) (xy 28.882863 -300.185328) (xy 22.076918 -300.185328) (xy 22.076426 -300.212285)
			(xy 22.068576 -300.265625) (xy 22.053044 -300.317254) (xy 22.030159 -300.366071) (xy 22.000411 -300.411035)
			(xy 21.964433 -300.451189) (xy 21.922991 -300.485677) (xy 21.87697 -300.513763) (xy 21.82735 -300.53485)
			(xy 21.775189 -300.548486) (xy 21.721598 -300.554383) (xy 21.667719 -300.552414) (xy 21.614701 -300.542621)
			(xy 21.563674 -300.525213) (xy 21.515726 -300.500561) (xy 21.471878 -300.469191) (xy 21.433065 -300.43177)
			(xy 21.400113 -300.389097) (xy 21.373727 -300.34208) (xy 21.354467 -300.291723) (xy 21.342744 -300.239099)
			(xy 21.338809 -300.185328) (xy 15.598394 -300.185328) (xy 15.598394 -301.035212) (xy 17.238741 -301.035212)
			(xy 17.242676 -300.981441) (xy 17.254399 -300.928817) (xy 17.273659 -300.87846) (xy 17.300045 -300.831443)
			(xy 17.332997 -300.78877) (xy 17.37181 -300.751349) (xy 17.415658 -300.719979) (xy 17.463606 -300.695327)
			(xy 17.514633 -300.677919) (xy 17.567651 -300.668126) (xy 17.62153 -300.666157) (xy 17.675121 -300.672054)
			(xy 17.727282 -300.68569) (xy 17.776902 -300.706777) (xy 17.822923 -300.734863) (xy 17.864365 -300.769351)
			(xy 17.900343 -300.809505) (xy 17.930091 -300.854469) (xy 17.952976 -300.903286) (xy 17.968508 -300.954915)
			(xy 17.976358 -301.008255) (xy 17.97685 -301.035212) (xy 24.782795 -301.035212) (xy 24.78673 -300.981441)
			(xy 24.798453 -300.928817) (xy 24.817713 -300.87846) (xy 24.844099 -300.831443) (xy 24.877051 -300.78877)
			(xy 24.915864 -300.751349) (xy 24.959712 -300.719979) (xy 25.00766 -300.695327) (xy 25.058687 -300.677919)
			(xy 25.111705 -300.668126) (xy 25.165584 -300.666157) (xy 25.219175 -300.672054) (xy 25.271336 -300.68569)
			(xy 25.320956 -300.706777) (xy 25.366977 -300.734863) (xy 25.408419 -300.769351) (xy 25.444397 -300.809505)
			(xy 25.474145 -300.854469) (xy 25.49703 -300.903286) (xy 25.512562 -300.954915) (xy 25.520412 -301.008255)
			(xy 25.520904 -301.035212) (xy 32.326595 -301.035212) (xy 32.33053 -300.981441) (xy 32.342253 -300.928817)
			(xy 32.361513 -300.87846) (xy 32.387899 -300.831443) (xy 32.420851 -300.78877) (xy 32.459664 -300.751349)
			(xy 32.503512 -300.719979) (xy 32.55146 -300.695327) (xy 32.602487 -300.677919) (xy 32.655505 -300.668126)
			(xy 32.709384 -300.666157) (xy 32.762975 -300.672054) (xy 32.815136 -300.68569) (xy 32.864756 -300.706777)
			(xy 32.910777 -300.734863) (xy 32.952219 -300.769351) (xy 32.988197 -300.809505) (xy 33.017945 -300.854469)
			(xy 33.04083 -300.903286) (xy 33.056362 -300.954915) (xy 33.064212 -301.008255) (xy 33.064704 -301.035212)
			(xy 39.870649 -301.035212) (xy 39.874584 -300.981441) (xy 39.886307 -300.928817) (xy 39.905567 -300.87846)
			(xy 39.931953 -300.831443) (xy 39.964905 -300.78877) (xy 40.003718 -300.751349) (xy 40.047566 -300.719979)
			(xy 40.095514 -300.695327) (xy 40.146541 -300.677919) (xy 40.199559 -300.668126) (xy 40.253438 -300.666157)
			(xy 40.307029 -300.672054) (xy 40.35919 -300.68569) (xy 40.40881 -300.706777) (xy 40.454831 -300.734863)
			(xy 40.496273 -300.769351) (xy 40.532251 -300.809505) (xy 40.561999 -300.854469) (xy 40.584884 -300.903286)
			(xy 40.600416 -300.954915) (xy 40.608266 -301.008255) (xy 40.608758 -301.035212) (xy 40.608266 -301.062169)
			(xy 40.600416 -301.115509) (xy 40.584884 -301.167138) (xy 40.561999 -301.215955) (xy 40.532251 -301.260919)
			(xy 40.496273 -301.301073) (xy 40.454831 -301.335561) (xy 40.40881 -301.363647) (xy 40.35919 -301.384734)
			(xy 40.307029 -301.39837) (xy 40.253438 -301.404267) (xy 40.199559 -301.402298) (xy 40.146541 -301.392505)
			(xy 40.095514 -301.375097) (xy 40.047566 -301.350445) (xy 40.003718 -301.319075) (xy 39.964905 -301.281654)
			(xy 39.931953 -301.238981) (xy 39.905567 -301.191964) (xy 39.886307 -301.141607) (xy 39.874584 -301.088983)
			(xy 39.870649 -301.035212) (xy 33.064704 -301.035212) (xy 33.064212 -301.062169) (xy 33.056362 -301.115509)
			(xy 33.04083 -301.167138) (xy 33.017945 -301.215955) (xy 32.988197 -301.260919) (xy 32.952219 -301.301073)
			(xy 32.910777 -301.335561) (xy 32.864756 -301.363647) (xy 32.815136 -301.384734) (xy 32.762975 -301.39837)
			(xy 32.709384 -301.404267) (xy 32.655505 -301.402298) (xy 32.602487 -301.392505) (xy 32.55146 -301.375097)
			(xy 32.503512 -301.350445) (xy 32.459664 -301.319075) (xy 32.420851 -301.281654) (xy 32.387899 -301.238981)
			(xy 32.361513 -301.191964) (xy 32.342253 -301.141607) (xy 32.33053 -301.088983) (xy 32.326595 -301.035212)
			(xy 25.520904 -301.035212) (xy 25.520412 -301.062169) (xy 25.512562 -301.115509) (xy 25.49703 -301.167138)
			(xy 25.474145 -301.215955) (xy 25.444397 -301.260919) (xy 25.408419 -301.301073) (xy 25.366977 -301.335561)
			(xy 25.320956 -301.363647) (xy 25.271336 -301.384734) (xy 25.219175 -301.39837) (xy 25.165584 -301.404267)
			(xy 25.111705 -301.402298) (xy 25.058687 -301.392505) (xy 25.00766 -301.375097) (xy 24.959712 -301.350445)
			(xy 24.915864 -301.319075) (xy 24.877051 -301.281654) (xy 24.844099 -301.238981) (xy 24.817713 -301.191964)
			(xy 24.798453 -301.141607) (xy 24.78673 -301.088983) (xy 24.782795 -301.035212) (xy 17.97685 -301.035212)
			(xy 17.976358 -301.062169) (xy 17.968508 -301.115509) (xy 17.952976 -301.167138) (xy 17.930091 -301.215955)
			(xy 17.900343 -301.260919) (xy 17.864365 -301.301073) (xy 17.822923 -301.335561) (xy 17.776902 -301.363647)
			(xy 17.727282 -301.384734) (xy 17.675121 -301.39837) (xy 17.62153 -301.404267) (xy 17.567651 -301.402298)
			(xy 17.514633 -301.392505) (xy 17.463606 -301.375097) (xy 17.415658 -301.350445) (xy 17.37181 -301.319075)
			(xy 17.332997 -301.281654) (xy 17.300045 -301.238981) (xy 17.273659 -301.191964) (xy 17.254399 -301.141607)
			(xy 17.242676 -301.088983) (xy 17.238741 -301.035212) (xy 15.598394 -301.035212) (xy 15.598394 -301.88535)
			(xy 21.338809 -301.88535) (xy 21.342744 -301.831579) (xy 21.354467 -301.778955) (xy 21.373727 -301.728598)
			(xy 21.400113 -301.681581) (xy 21.433065 -301.638908) (xy 21.471878 -301.601487) (xy 21.515726 -301.570117)
			(xy 21.563674 -301.545465) (xy 21.614701 -301.528057) (xy 21.667719 -301.518264) (xy 21.721598 -301.516295)
			(xy 21.775189 -301.522192) (xy 21.82735 -301.535828) (xy 21.87697 -301.556915) (xy 21.922991 -301.585001)
			(xy 21.964433 -301.619489) (xy 22.000411 -301.659643) (xy 22.030159 -301.704607) (xy 22.053044 -301.753424)
			(xy 22.068576 -301.805053) (xy 22.076426 -301.858393) (xy 22.076918 -301.88535) (xy 28.882863 -301.88535)
			(xy 28.886798 -301.831579) (xy 28.898521 -301.778955) (xy 28.917781 -301.728598) (xy 28.944167 -301.681581)
			(xy 28.977119 -301.638908) (xy 29.015932 -301.601487) (xy 29.05978 -301.570117) (xy 29.107728 -301.545465)
			(xy 29.158755 -301.528057) (xy 29.211773 -301.518264) (xy 29.265652 -301.516295) (xy 29.319243 -301.522192)
			(xy 29.371404 -301.535828) (xy 29.421024 -301.556915) (xy 29.467045 -301.585001) (xy 29.508487 -301.619489)
			(xy 29.544465 -301.659643) (xy 29.574213 -301.704607) (xy 29.597098 -301.753424) (xy 29.61263 -301.805053)
			(xy 29.62048 -301.858393) (xy 29.620972 -301.88535) (xy 36.426663 -301.88535) (xy 36.430598 -301.831579)
			(xy 36.442321 -301.778955) (xy 36.461581 -301.728598) (xy 36.487967 -301.681581) (xy 36.520919 -301.638908)
			(xy 36.559732 -301.601487) (xy 36.60358 -301.570117) (xy 36.651528 -301.545465) (xy 36.702555 -301.528057)
			(xy 36.755573 -301.518264) (xy 36.809452 -301.516295) (xy 36.863043 -301.522192) (xy 36.915204 -301.535828)
			(xy 36.964824 -301.556915) (xy 37.010845 -301.585001) (xy 37.052287 -301.619489) (xy 37.088265 -301.659643)
			(xy 37.118013 -301.704607) (xy 37.140898 -301.753424) (xy 37.15643 -301.805053) (xy 37.16428 -301.858393)
			(xy 37.164772 -301.88535) (xy 43.970717 -301.88535) (xy 43.974652 -301.831579) (xy 43.986375 -301.778955)
			(xy 44.005635 -301.728598) (xy 44.032021 -301.681581) (xy 44.064973 -301.638908) (xy 44.103786 -301.601487)
			(xy 44.147634 -301.570117) (xy 44.195582 -301.545465) (xy 44.246609 -301.528057) (xy 44.299627 -301.518264)
			(xy 44.353506 -301.516295) (xy 44.407097 -301.522192) (xy 44.459258 -301.535828) (xy 44.508878 -301.556915)
			(xy 44.554899 -301.585001) (xy 44.596341 -301.619489) (xy 44.632319 -301.659643) (xy 44.662067 -301.704607)
			(xy 44.684952 -301.753424) (xy 44.700484 -301.805053) (xy 44.708334 -301.858393) (xy 44.708826 -301.88535)
			(xy 44.708334 -301.912307) (xy 44.700484 -301.965647) (xy 44.684952 -302.017276) (xy 44.662067 -302.066093)
			(xy 44.632319 -302.111057) (xy 44.596341 -302.151211) (xy 44.554899 -302.185699) (xy 44.508878 -302.213785)
			(xy 44.459258 -302.234872) (xy 44.407097 -302.248508) (xy 44.353506 -302.254405) (xy 44.299627 -302.252436)
			(xy 44.246609 -302.242643) (xy 44.195582 -302.225235) (xy 44.147634 -302.200583) (xy 44.103786 -302.169213)
			(xy 44.064973 -302.131792) (xy 44.032021 -302.089119) (xy 44.005635 -302.042102) (xy 43.986375 -301.991745)
			(xy 43.974652 -301.939121) (xy 43.970717 -301.88535) (xy 37.164772 -301.88535) (xy 37.16428 -301.912307)
			(xy 37.15643 -301.965647) (xy 37.140898 -302.017276) (xy 37.118013 -302.066093) (xy 37.088265 -302.111057)
			(xy 37.052287 -302.151211) (xy 37.010845 -302.185699) (xy 36.964824 -302.213785) (xy 36.915204 -302.234872)
			(xy 36.863043 -302.248508) (xy 36.809452 -302.254405) (xy 36.755573 -302.252436) (xy 36.702555 -302.242643)
			(xy 36.651528 -302.225235) (xy 36.60358 -302.200583) (xy 36.559732 -302.169213) (xy 36.520919 -302.131792)
			(xy 36.487967 -302.089119) (xy 36.461581 -302.042102) (xy 36.442321 -301.991745) (xy 36.430598 -301.939121)
			(xy 36.426663 -301.88535) (xy 29.620972 -301.88535) (xy 29.62048 -301.912307) (xy 29.61263 -301.965647)
			(xy 29.597098 -302.017276) (xy 29.574213 -302.066093) (xy 29.544465 -302.111057) (xy 29.508487 -302.151211)
			(xy 29.467045 -302.185699) (xy 29.421024 -302.213785) (xy 29.371404 -302.234872) (xy 29.319243 -302.248508)
			(xy 29.265652 -302.254405) (xy 29.211773 -302.252436) (xy 29.158755 -302.242643) (xy 29.107728 -302.225235)
			(xy 29.05978 -302.200583) (xy 29.015932 -302.169213) (xy 28.977119 -302.131792) (xy 28.944167 -302.089119)
			(xy 28.917781 -302.042102) (xy 28.898521 -301.991745) (xy 28.886798 -301.939121) (xy 28.882863 -301.88535)
			(xy 22.076918 -301.88535) (xy 22.076426 -301.912307) (xy 22.068576 -301.965647) (xy 22.053044 -302.017276)
			(xy 22.030159 -302.066093) (xy 22.000411 -302.111057) (xy 21.964433 -302.151211) (xy 21.922991 -302.185699)
			(xy 21.87697 -302.213785) (xy 21.82735 -302.234872) (xy 21.775189 -302.248508) (xy 21.721598 -302.254405)
			(xy 21.667719 -302.252436) (xy 21.614701 -302.242643) (xy 21.563674 -302.225235) (xy 21.515726 -302.200583)
			(xy 21.471878 -302.169213) (xy 21.433065 -302.131792) (xy 21.400113 -302.089119) (xy 21.373727 -302.042102)
			(xy 21.354467 -301.991745) (xy 21.342744 -301.939121) (xy 21.338809 -301.88535) (xy 15.598394 -301.88535)
			(xy 15.598394 -302.735234) (xy 17.238741 -302.735234) (xy 17.242676 -302.681463) (xy 17.254399 -302.628839)
			(xy 17.273659 -302.578482) (xy 17.300045 -302.531465) (xy 17.332997 -302.488792) (xy 17.37181 -302.451371)
			(xy 17.415658 -302.420001) (xy 17.463606 -302.395349) (xy 17.514633 -302.377941) (xy 17.567651 -302.368148)
			(xy 17.62153 -302.366179) (xy 17.675121 -302.372076) (xy 17.727282 -302.385712) (xy 17.776902 -302.406799)
			(xy 17.822923 -302.434885) (xy 17.864365 -302.469373) (xy 17.900343 -302.509527) (xy 17.930091 -302.554491)
			(xy 17.952976 -302.603308) (xy 17.968508 -302.654937) (xy 17.976358 -302.708277) (xy 17.97685 -302.735234)
			(xy 24.782795 -302.735234) (xy 24.78673 -302.681463) (xy 24.798453 -302.628839) (xy 24.817713 -302.578482)
			(xy 24.844099 -302.531465) (xy 24.877051 -302.488792) (xy 24.915864 -302.451371) (xy 24.959712 -302.420001)
			(xy 25.00766 -302.395349) (xy 25.058687 -302.377941) (xy 25.111705 -302.368148) (xy 25.165584 -302.366179)
			(xy 25.219175 -302.372076) (xy 25.271336 -302.385712) (xy 25.320956 -302.406799) (xy 25.366977 -302.434885)
			(xy 25.408419 -302.469373) (xy 25.444397 -302.509527) (xy 25.474145 -302.554491) (xy 25.49703 -302.603308)
			(xy 25.512562 -302.654937) (xy 25.520412 -302.708277) (xy 25.520904 -302.735234) (xy 32.326595 -302.735234)
			(xy 32.33053 -302.681463) (xy 32.342253 -302.628839) (xy 32.361513 -302.578482) (xy 32.387899 -302.531465)
			(xy 32.420851 -302.488792) (xy 32.459664 -302.451371) (xy 32.503512 -302.420001) (xy 32.55146 -302.395349)
			(xy 32.602487 -302.377941) (xy 32.655505 -302.368148) (xy 32.709384 -302.366179) (xy 32.762975 -302.372076)
			(xy 32.815136 -302.385712) (xy 32.864756 -302.406799) (xy 32.910777 -302.434885) (xy 32.952219 -302.469373)
			(xy 32.988197 -302.509527) (xy 33.017945 -302.554491) (xy 33.04083 -302.603308) (xy 33.056362 -302.654937)
			(xy 33.064212 -302.708277) (xy 33.064704 -302.735234) (xy 39.870649 -302.735234) (xy 39.874584 -302.681463)
			(xy 39.886307 -302.628839) (xy 39.905567 -302.578482) (xy 39.931953 -302.531465) (xy 39.964905 -302.488792)
			(xy 40.003718 -302.451371) (xy 40.047566 -302.420001) (xy 40.095514 -302.395349) (xy 40.146541 -302.377941)
			(xy 40.199559 -302.368148) (xy 40.253438 -302.366179) (xy 40.307029 -302.372076) (xy 40.35919 -302.385712)
			(xy 40.40881 -302.406799) (xy 40.454831 -302.434885) (xy 40.496273 -302.469373) (xy 40.532251 -302.509527)
			(xy 40.561999 -302.554491) (xy 40.584884 -302.603308) (xy 40.600416 -302.654937) (xy 40.608266 -302.708277)
			(xy 40.608758 -302.735234) (xy 40.608266 -302.762191) (xy 40.600416 -302.815531) (xy 40.584884 -302.86716)
			(xy 40.561999 -302.915977) (xy 40.532251 -302.960941) (xy 40.496273 -303.001095) (xy 40.454831 -303.035583)
			(xy 40.40881 -303.063669) (xy 40.35919 -303.084756) (xy 40.307029 -303.098392) (xy 40.253438 -303.104289)
			(xy 40.199559 -303.10232) (xy 40.146541 -303.092527) (xy 40.095514 -303.075119) (xy 40.047566 -303.050467)
			(xy 40.003718 -303.019097) (xy 39.964905 -302.981676) (xy 39.931953 -302.939003) (xy 39.905567 -302.891986)
			(xy 39.886307 -302.841629) (xy 39.874584 -302.789005) (xy 39.870649 -302.735234) (xy 33.064704 -302.735234)
			(xy 33.064212 -302.762191) (xy 33.056362 -302.815531) (xy 33.04083 -302.86716) (xy 33.017945 -302.915977)
			(xy 32.988197 -302.960941) (xy 32.952219 -303.001095) (xy 32.910777 -303.035583) (xy 32.864756 -303.063669)
			(xy 32.815136 -303.084756) (xy 32.762975 -303.098392) (xy 32.709384 -303.104289) (xy 32.655505 -303.10232)
			(xy 32.602487 -303.092527) (xy 32.55146 -303.075119) (xy 32.503512 -303.050467) (xy 32.459664 -303.019097)
			(xy 32.420851 -302.981676) (xy 32.387899 -302.939003) (xy 32.361513 -302.891986) (xy 32.342253 -302.841629)
			(xy 32.33053 -302.789005) (xy 32.326595 -302.735234) (xy 25.520904 -302.735234) (xy 25.520412 -302.762191)
			(xy 25.512562 -302.815531) (xy 25.49703 -302.86716) (xy 25.474145 -302.915977) (xy 25.444397 -302.960941)
			(xy 25.408419 -303.001095) (xy 25.366977 -303.035583) (xy 25.320956 -303.063669) (xy 25.271336 -303.084756)
			(xy 25.219175 -303.098392) (xy 25.165584 -303.104289) (xy 25.111705 -303.10232) (xy 25.058687 -303.092527)
			(xy 25.00766 -303.075119) (xy 24.959712 -303.050467) (xy 24.915864 -303.019097) (xy 24.877051 -302.981676)
			(xy 24.844099 -302.939003) (xy 24.817713 -302.891986) (xy 24.798453 -302.841629) (xy 24.78673 -302.789005)
			(xy 24.782795 -302.735234) (xy 17.97685 -302.735234) (xy 17.976358 -302.762191) (xy 17.968508 -302.815531)
			(xy 17.952976 -302.86716) (xy 17.930091 -302.915977) (xy 17.900343 -302.960941) (xy 17.864365 -303.001095)
			(xy 17.822923 -303.035583) (xy 17.776902 -303.063669) (xy 17.727282 -303.084756) (xy 17.675121 -303.098392)
			(xy 17.62153 -303.104289) (xy 17.567651 -303.10232) (xy 17.514633 -303.092527) (xy 17.463606 -303.075119)
			(xy 17.415658 -303.050467) (xy 17.37181 -303.019097) (xy 17.332997 -302.981676) (xy 17.300045 -302.939003)
			(xy 17.273659 -302.891986) (xy 17.254399 -302.841629) (xy 17.242676 -302.789005) (xy 17.238741 -302.735234)
			(xy 15.598394 -302.735234) (xy 15.598394 -303.585372) (xy 21.338809 -303.585372) (xy 21.342744 -303.531601)
			(xy 21.354467 -303.478977) (xy 21.373727 -303.42862) (xy 21.400113 -303.381603) (xy 21.433065 -303.33893)
			(xy 21.471878 -303.301509) (xy 21.515726 -303.270139) (xy 21.563674 -303.245487) (xy 21.614701 -303.228079)
			(xy 21.667719 -303.218286) (xy 21.721598 -303.216317) (xy 21.775189 -303.222214) (xy 21.82735 -303.23585)
			(xy 21.87697 -303.256937) (xy 21.922991 -303.285023) (xy 21.964433 -303.319511) (xy 22.000411 -303.359665)
			(xy 22.030159 -303.404629) (xy 22.053044 -303.453446) (xy 22.068576 -303.505075) (xy 22.076426 -303.558415)
			(xy 22.076918 -303.585372) (xy 28.882863 -303.585372) (xy 28.886798 -303.531601) (xy 28.898521 -303.478977)
			(xy 28.917781 -303.42862) (xy 28.944167 -303.381603) (xy 28.977119 -303.33893) (xy 29.015932 -303.301509)
			(xy 29.05978 -303.270139) (xy 29.107728 -303.245487) (xy 29.158755 -303.228079) (xy 29.211773 -303.218286)
			(xy 29.265652 -303.216317) (xy 29.319243 -303.222214) (xy 29.371404 -303.23585) (xy 29.421024 -303.256937)
			(xy 29.467045 -303.285023) (xy 29.508487 -303.319511) (xy 29.544465 -303.359665) (xy 29.574213 -303.404629)
			(xy 29.597098 -303.453446) (xy 29.61263 -303.505075) (xy 29.62048 -303.558415) (xy 29.620972 -303.585372)
			(xy 36.426663 -303.585372) (xy 36.430598 -303.531601) (xy 36.442321 -303.478977) (xy 36.461581 -303.42862)
			(xy 36.487967 -303.381603) (xy 36.520919 -303.33893) (xy 36.559732 -303.301509) (xy 36.60358 -303.270139)
			(xy 36.651528 -303.245487) (xy 36.702555 -303.228079) (xy 36.755573 -303.218286) (xy 36.809452 -303.216317)
			(xy 36.863043 -303.222214) (xy 36.915204 -303.23585) (xy 36.964824 -303.256937) (xy 37.010845 -303.285023)
			(xy 37.052287 -303.319511) (xy 37.088265 -303.359665) (xy 37.118013 -303.404629) (xy 37.140898 -303.453446)
			(xy 37.15643 -303.505075) (xy 37.16428 -303.558415) (xy 37.164772 -303.585372) (xy 43.970717 -303.585372)
			(xy 43.974652 -303.531601) (xy 43.986375 -303.478977) (xy 44.005635 -303.42862) (xy 44.032021 -303.381603)
			(xy 44.064973 -303.33893) (xy 44.103786 -303.301509) (xy 44.147634 -303.270139) (xy 44.195582 -303.245487)
			(xy 44.246609 -303.228079) (xy 44.299627 -303.218286) (xy 44.353506 -303.216317) (xy 44.407097 -303.222214)
			(xy 44.459258 -303.23585) (xy 44.508878 -303.256937) (xy 44.554899 -303.285023) (xy 44.596341 -303.319511)
			(xy 44.632319 -303.359665) (xy 44.662067 -303.404629) (xy 44.684952 -303.453446) (xy 44.700484 -303.505075)
			(xy 44.708334 -303.558415) (xy 44.708826 -303.585372) (xy 44.708334 -303.612329) (xy 44.700484 -303.665669)
			(xy 44.684952 -303.717298) (xy 44.662067 -303.766115) (xy 44.632319 -303.811079) (xy 44.596341 -303.851233)
			(xy 44.554899 -303.885721) (xy 44.508878 -303.913807) (xy 44.459258 -303.934894) (xy 44.407097 -303.94853)
			(xy 44.353506 -303.954427) (xy 44.299627 -303.952458) (xy 44.246609 -303.942665) (xy 44.195582 -303.925257)
			(xy 44.147634 -303.900605) (xy 44.103786 -303.869235) (xy 44.064973 -303.831814) (xy 44.032021 -303.789141)
			(xy 44.005635 -303.742124) (xy 43.986375 -303.691767) (xy 43.974652 -303.639143) (xy 43.970717 -303.585372)
			(xy 37.164772 -303.585372) (xy 37.16428 -303.612329) (xy 37.15643 -303.665669) (xy 37.140898 -303.717298)
			(xy 37.118013 -303.766115) (xy 37.088265 -303.811079) (xy 37.052287 -303.851233) (xy 37.010845 -303.885721)
			(xy 36.964824 -303.913807) (xy 36.915204 -303.934894) (xy 36.863043 -303.94853) (xy 36.809452 -303.954427)
			(xy 36.755573 -303.952458) (xy 36.702555 -303.942665) (xy 36.651528 -303.925257) (xy 36.60358 -303.900605)
			(xy 36.559732 -303.869235) (xy 36.520919 -303.831814) (xy 36.487967 -303.789141) (xy 36.461581 -303.742124)
			(xy 36.442321 -303.691767) (xy 36.430598 -303.639143) (xy 36.426663 -303.585372) (xy 29.620972 -303.585372)
			(xy 29.62048 -303.612329) (xy 29.61263 -303.665669) (xy 29.597098 -303.717298) (xy 29.574213 -303.766115)
			(xy 29.544465 -303.811079) (xy 29.508487 -303.851233) (xy 29.467045 -303.885721) (xy 29.421024 -303.913807)
			(xy 29.371404 -303.934894) (xy 29.319243 -303.94853) (xy 29.265652 -303.954427) (xy 29.211773 -303.952458)
			(xy 29.158755 -303.942665) (xy 29.107728 -303.925257) (xy 29.05978 -303.900605) (xy 29.015932 -303.869235)
			(xy 28.977119 -303.831814) (xy 28.944167 -303.789141) (xy 28.917781 -303.742124) (xy 28.898521 -303.691767)
			(xy 28.886798 -303.639143) (xy 28.882863 -303.585372) (xy 22.076918 -303.585372) (xy 22.076426 -303.612329)
			(xy 22.068576 -303.665669) (xy 22.053044 -303.717298) (xy 22.030159 -303.766115) (xy 22.000411 -303.811079)
			(xy 21.964433 -303.851233) (xy 21.922991 -303.885721) (xy 21.87697 -303.913807) (xy 21.82735 -303.934894)
			(xy 21.775189 -303.94853) (xy 21.721598 -303.954427) (xy 21.667719 -303.952458) (xy 21.614701 -303.942665)
			(xy 21.563674 -303.925257) (xy 21.515726 -303.900605) (xy 21.471878 -303.869235) (xy 21.433065 -303.831814)
			(xy 21.400113 -303.789141) (xy 21.373727 -303.742124) (xy 21.354467 -303.691767) (xy 21.342744 -303.639143)
			(xy 21.338809 -303.585372) (xy 15.598394 -303.585372) (xy 15.598394 -304.435256) (xy 17.238741 -304.435256)
			(xy 17.242676 -304.381485) (xy 17.254399 -304.328861) (xy 17.273659 -304.278504) (xy 17.300045 -304.231487)
			(xy 17.332997 -304.188814) (xy 17.37181 -304.151393) (xy 17.415658 -304.120023) (xy 17.463606 -304.095371)
			(xy 17.514633 -304.077963) (xy 17.567651 -304.06817) (xy 17.62153 -304.066201) (xy 17.675121 -304.072098)
			(xy 17.727282 -304.085734) (xy 17.776902 -304.106821) (xy 17.822923 -304.134907) (xy 17.864365 -304.169395)
			(xy 17.900343 -304.209549) (xy 17.930091 -304.254513) (xy 17.952976 -304.30333) (xy 17.968508 -304.354959)
			(xy 17.976358 -304.408299) (xy 17.97685 -304.435256) (xy 21.338809 -304.435256) (xy 21.342744 -304.381485)
			(xy 21.354467 -304.328861) (xy 21.373727 -304.278504) (xy 21.400113 -304.231487) (xy 21.433065 -304.188814)
			(xy 21.471878 -304.151393) (xy 21.515726 -304.120023) (xy 21.563674 -304.095371) (xy 21.614701 -304.077963)
			(xy 21.667719 -304.06817) (xy 21.721598 -304.066201) (xy 21.775189 -304.072098) (xy 21.82735 -304.085734)
			(xy 21.87697 -304.106821) (xy 21.922991 -304.134907) (xy 21.964433 -304.169395) (xy 22.000411 -304.209549)
			(xy 22.030159 -304.254513) (xy 22.053044 -304.30333) (xy 22.068576 -304.354959) (xy 22.076426 -304.408299)
			(xy 22.076918 -304.435256) (xy 24.782795 -304.435256) (xy 24.78673 -304.381485) (xy 24.798453 -304.328861)
			(xy 24.817713 -304.278504) (xy 24.844099 -304.231487) (xy 24.877051 -304.188814) (xy 24.915864 -304.151393)
			(xy 24.959712 -304.120023) (xy 25.00766 -304.095371) (xy 25.058687 -304.077963) (xy 25.111705 -304.06817)
			(xy 25.165584 -304.066201) (xy 25.219175 -304.072098) (xy 25.271336 -304.085734) (xy 25.320956 -304.106821)
			(xy 25.366977 -304.134907) (xy 25.408419 -304.169395) (xy 25.444397 -304.209549) (xy 25.474145 -304.254513)
			(xy 25.49703 -304.30333) (xy 25.512562 -304.354959) (xy 25.520412 -304.408299) (xy 25.520904 -304.435256)
			(xy 28.882863 -304.435256) (xy 28.886798 -304.381485) (xy 28.898521 -304.328861) (xy 28.917781 -304.278504)
			(xy 28.944167 -304.231487) (xy 28.977119 -304.188814) (xy 29.015932 -304.151393) (xy 29.05978 -304.120023)
			(xy 29.107728 -304.095371) (xy 29.158755 -304.077963) (xy 29.211773 -304.06817) (xy 29.265652 -304.066201)
			(xy 29.319243 -304.072098) (xy 29.371404 -304.085734) (xy 29.421024 -304.106821) (xy 29.467045 -304.134907)
			(xy 29.508487 -304.169395) (xy 29.544465 -304.209549) (xy 29.574213 -304.254513) (xy 29.597098 -304.30333)
			(xy 29.61263 -304.354959) (xy 29.62048 -304.408299) (xy 29.620972 -304.435256) (xy 32.326595 -304.435256)
			(xy 32.33053 -304.381485) (xy 32.342253 -304.328861) (xy 32.361513 -304.278504) (xy 32.387899 -304.231487)
			(xy 32.420851 -304.188814) (xy 32.459664 -304.151393) (xy 32.503512 -304.120023) (xy 32.55146 -304.095371)
			(xy 32.602487 -304.077963) (xy 32.655505 -304.06817) (xy 32.709384 -304.066201) (xy 32.762975 -304.072098)
			(xy 32.815136 -304.085734) (xy 32.864756 -304.106821) (xy 32.910777 -304.134907) (xy 32.952219 -304.169395)
			(xy 32.988197 -304.209549) (xy 33.017945 -304.254513) (xy 33.04083 -304.30333) (xy 33.056362 -304.354959)
			(xy 33.064212 -304.408299) (xy 33.064704 -304.435256) (xy 36.426663 -304.435256) (xy 36.430598 -304.381485)
			(xy 36.442321 -304.328861) (xy 36.461581 -304.278504) (xy 36.487967 -304.231487) (xy 36.520919 -304.188814)
			(xy 36.559732 -304.151393) (xy 36.60358 -304.120023) (xy 36.651528 -304.095371) (xy 36.702555 -304.077963)
			(xy 36.755573 -304.06817) (xy 36.809452 -304.066201) (xy 36.863043 -304.072098) (xy 36.915204 -304.085734)
			(xy 36.964824 -304.106821) (xy 37.010845 -304.134907) (xy 37.052287 -304.169395) (xy 37.088265 -304.209549)
			(xy 37.118013 -304.254513) (xy 37.140898 -304.30333) (xy 37.15643 -304.354959) (xy 37.16428 -304.408299)
			(xy 37.164772 -304.435256) (xy 39.870649 -304.435256) (xy 39.874584 -304.381485) (xy 39.886307 -304.328861)
			(xy 39.905567 -304.278504) (xy 39.931953 -304.231487) (xy 39.964905 -304.188814) (xy 40.003718 -304.151393)
			(xy 40.047566 -304.120023) (xy 40.095514 -304.095371) (xy 40.146541 -304.077963) (xy 40.199559 -304.06817)
			(xy 40.253438 -304.066201) (xy 40.307029 -304.072098) (xy 40.35919 -304.085734) (xy 40.40881 -304.106821)
			(xy 40.454831 -304.134907) (xy 40.496273 -304.169395) (xy 40.532251 -304.209549) (xy 40.561999 -304.254513)
			(xy 40.584884 -304.30333) (xy 40.600416 -304.354959) (xy 40.608266 -304.408299) (xy 40.608758 -304.435256)
			(xy 43.970717 -304.435256) (xy 43.974652 -304.381485) (xy 43.986375 -304.328861) (xy 44.005635 -304.278504)
			(xy 44.032021 -304.231487) (xy 44.064973 -304.188814) (xy 44.103786 -304.151393) (xy 44.147634 -304.120023)
			(xy 44.195582 -304.095371) (xy 44.246609 -304.077963) (xy 44.299627 -304.06817) (xy 44.353506 -304.066201)
			(xy 44.407097 -304.072098) (xy 44.459258 -304.085734) (xy 44.508878 -304.106821) (xy 44.554899 -304.134907)
			(xy 44.596341 -304.169395) (xy 44.632319 -304.209549) (xy 44.662067 -304.254513) (xy 44.684952 -304.30333)
			(xy 44.700484 -304.354959) (xy 44.708334 -304.408299) (xy 44.708826 -304.435256) (xy 44.708334 -304.462213)
			(xy 44.700484 -304.515553) (xy 44.684952 -304.567182) (xy 44.662067 -304.615999) (xy 44.632319 -304.660963)
			(xy 44.596341 -304.701117) (xy 44.554899 -304.735605) (xy 44.508878 -304.763691) (xy 44.459258 -304.784778)
			(xy 44.407097 -304.798414) (xy 44.353506 -304.804311) (xy 44.299627 -304.802342) (xy 44.246609 -304.792549)
			(xy 44.195582 -304.775141) (xy 44.147634 -304.750489) (xy 44.103786 -304.719119) (xy 44.064973 -304.681698)
			(xy 44.032021 -304.639025) (xy 44.005635 -304.592008) (xy 43.986375 -304.541651) (xy 43.974652 -304.489027)
			(xy 43.970717 -304.435256) (xy 40.608758 -304.435256) (xy 40.608266 -304.462213) (xy 40.600416 -304.515553)
			(xy 40.584884 -304.567182) (xy 40.561999 -304.615999) (xy 40.532251 -304.660963) (xy 40.496273 -304.701117)
			(xy 40.454831 -304.735605) (xy 40.40881 -304.763691) (xy 40.35919 -304.784778) (xy 40.307029 -304.798414)
			(xy 40.253438 -304.804311) (xy 40.199559 -304.802342) (xy 40.146541 -304.792549) (xy 40.095514 -304.775141)
			(xy 40.047566 -304.750489) (xy 40.003718 -304.719119) (xy 39.964905 -304.681698) (xy 39.931953 -304.639025)
			(xy 39.905567 -304.592008) (xy 39.886307 -304.541651) (xy 39.874584 -304.489027) (xy 39.870649 -304.435256)
			(xy 37.164772 -304.435256) (xy 37.16428 -304.462213) (xy 37.15643 -304.515553) (xy 37.140898 -304.567182)
			(xy 37.118013 -304.615999) (xy 37.088265 -304.660963) (xy 37.052287 -304.701117) (xy 37.010845 -304.735605)
			(xy 36.964824 -304.763691) (xy 36.915204 -304.784778) (xy 36.863043 -304.798414) (xy 36.809452 -304.804311)
			(xy 36.755573 -304.802342) (xy 36.702555 -304.792549) (xy 36.651528 -304.775141) (xy 36.60358 -304.750489)
			(xy 36.559732 -304.719119) (xy 36.520919 -304.681698) (xy 36.487967 -304.639025) (xy 36.461581 -304.592008)
			(xy 36.442321 -304.541651) (xy 36.430598 -304.489027) (xy 36.426663 -304.435256) (xy 33.064704 -304.435256)
			(xy 33.064212 -304.462213) (xy 33.056362 -304.515553) (xy 33.04083 -304.567182) (xy 33.017945 -304.615999)
			(xy 32.988197 -304.660963) (xy 32.952219 -304.701117) (xy 32.910777 -304.735605) (xy 32.864756 -304.763691)
			(xy 32.815136 -304.784778) (xy 32.762975 -304.798414) (xy 32.709384 -304.804311) (xy 32.655505 -304.802342)
			(xy 32.602487 -304.792549) (xy 32.55146 -304.775141) (xy 32.503512 -304.750489) (xy 32.459664 -304.719119)
			(xy 32.420851 -304.681698) (xy 32.387899 -304.639025) (xy 32.361513 -304.592008) (xy 32.342253 -304.541651)
			(xy 32.33053 -304.489027) (xy 32.326595 -304.435256) (xy 29.620972 -304.435256) (xy 29.62048 -304.462213)
			(xy 29.61263 -304.515553) (xy 29.597098 -304.567182) (xy 29.574213 -304.615999) (xy 29.544465 -304.660963)
			(xy 29.508487 -304.701117) (xy 29.467045 -304.735605) (xy 29.421024 -304.763691) (xy 29.371404 -304.784778)
			(xy 29.319243 -304.798414) (xy 29.265652 -304.804311) (xy 29.211773 -304.802342) (xy 29.158755 -304.792549)
			(xy 29.107728 -304.775141) (xy 29.05978 -304.750489) (xy 29.015932 -304.719119) (xy 28.977119 -304.681698)
			(xy 28.944167 -304.639025) (xy 28.917781 -304.592008) (xy 28.898521 -304.541651) (xy 28.886798 -304.489027)
			(xy 28.882863 -304.435256) (xy 25.520904 -304.435256) (xy 25.520412 -304.462213) (xy 25.512562 -304.515553)
			(xy 25.49703 -304.567182) (xy 25.474145 -304.615999) (xy 25.444397 -304.660963) (xy 25.408419 -304.701117)
			(xy 25.366977 -304.735605) (xy 25.320956 -304.763691) (xy 25.271336 -304.784778) (xy 25.219175 -304.798414)
			(xy 25.165584 -304.804311) (xy 25.111705 -304.802342) (xy 25.058687 -304.792549) (xy 25.00766 -304.775141)
			(xy 24.959712 -304.750489) (xy 24.915864 -304.719119) (xy 24.877051 -304.681698) (xy 24.844099 -304.639025)
			(xy 24.817713 -304.592008) (xy 24.798453 -304.541651) (xy 24.78673 -304.489027) (xy 24.782795 -304.435256)
			(xy 22.076918 -304.435256) (xy 22.076426 -304.462213) (xy 22.068576 -304.515553) (xy 22.053044 -304.567182)
			(xy 22.030159 -304.615999) (xy 22.000411 -304.660963) (xy 21.964433 -304.701117) (xy 21.922991 -304.735605)
			(xy 21.87697 -304.763691) (xy 21.82735 -304.784778) (xy 21.775189 -304.798414) (xy 21.721598 -304.804311)
			(xy 21.667719 -304.802342) (xy 21.614701 -304.792549) (xy 21.563674 -304.775141) (xy 21.515726 -304.750489)
			(xy 21.471878 -304.719119) (xy 21.433065 -304.681698) (xy 21.400113 -304.639025) (xy 21.373727 -304.592008)
			(xy 21.354467 -304.541651) (xy 21.342744 -304.489027) (xy 21.338809 -304.435256) (xy 17.97685 -304.435256)
			(xy 17.976358 -304.462213) (xy 17.968508 -304.515553) (xy 17.952976 -304.567182) (xy 17.930091 -304.615999)
			(xy 17.900343 -304.660963) (xy 17.864365 -304.701117) (xy 17.822923 -304.735605) (xy 17.776902 -304.763691)
			(xy 17.727282 -304.784778) (xy 17.675121 -304.798414) (xy 17.62153 -304.804311) (xy 17.567651 -304.802342)
			(xy 17.514633 -304.792549) (xy 17.463606 -304.775141) (xy 17.415658 -304.750489) (xy 17.37181 -304.719119)
			(xy 17.332997 -304.681698) (xy 17.300045 -304.639025) (xy 17.273659 -304.592008) (xy 17.254399 -304.541651)
			(xy 17.242676 -304.489027) (xy 17.238741 -304.435256) (xy 15.598394 -304.435256) (xy 15.598394 -305.285394)
			(xy 17.238741 -305.285394) (xy 17.242676 -305.231623) (xy 17.254399 -305.178999) (xy 17.273659 -305.128642)
			(xy 17.300045 -305.081625) (xy 17.332997 -305.038952) (xy 17.37181 -305.001531) (xy 17.415658 -304.970161)
			(xy 17.463606 -304.945509) (xy 17.514633 -304.928101) (xy 17.567651 -304.918308) (xy 17.62153 -304.916339)
			(xy 17.675121 -304.922236) (xy 17.727282 -304.935872) (xy 17.776902 -304.956959) (xy 17.822923 -304.985045)
			(xy 17.864365 -305.019533) (xy 17.900343 -305.059687) (xy 17.930091 -305.104651) (xy 17.952976 -305.153468)
			(xy 17.968508 -305.205097) (xy 17.976358 -305.258437) (xy 17.97685 -305.285394) (xy 24.782795 -305.285394)
			(xy 24.78673 -305.231623) (xy 24.798453 -305.178999) (xy 24.817713 -305.128642) (xy 24.844099 -305.081625)
			(xy 24.877051 -305.038952) (xy 24.915864 -305.001531) (xy 24.959712 -304.970161) (xy 25.00766 -304.945509)
			(xy 25.058687 -304.928101) (xy 25.111705 -304.918308) (xy 25.165584 -304.916339) (xy 25.219175 -304.922236)
			(xy 25.271336 -304.935872) (xy 25.320956 -304.956959) (xy 25.366977 -304.985045) (xy 25.408419 -305.019533)
			(xy 25.444397 -305.059687) (xy 25.474145 -305.104651) (xy 25.49703 -305.153468) (xy 25.512562 -305.205097)
			(xy 25.520412 -305.258437) (xy 25.520904 -305.285394) (xy 32.326595 -305.285394) (xy 32.33053 -305.231623)
			(xy 32.342253 -305.178999) (xy 32.361513 -305.128642) (xy 32.387899 -305.081625) (xy 32.420851 -305.038952)
			(xy 32.459664 -305.001531) (xy 32.503512 -304.970161) (xy 32.55146 -304.945509) (xy 32.602487 -304.928101)
			(xy 32.655505 -304.918308) (xy 32.709384 -304.916339) (xy 32.762975 -304.922236) (xy 32.815136 -304.935872)
			(xy 32.864756 -304.956959) (xy 32.910777 -304.985045) (xy 32.952219 -305.019533) (xy 32.988197 -305.059687)
			(xy 33.017945 -305.104651) (xy 33.04083 -305.153468) (xy 33.056362 -305.205097) (xy 33.064212 -305.258437)
			(xy 33.064704 -305.285394) (xy 39.870649 -305.285394) (xy 39.874584 -305.231623) (xy 39.886307 -305.178999)
			(xy 39.905567 -305.128642) (xy 39.931953 -305.081625) (xy 39.964905 -305.038952) (xy 40.003718 -305.001531)
			(xy 40.047566 -304.970161) (xy 40.095514 -304.945509) (xy 40.146541 -304.928101) (xy 40.199559 -304.918308)
			(xy 40.253438 -304.916339) (xy 40.307029 -304.922236) (xy 40.35919 -304.935872) (xy 40.40881 -304.956959)
			(xy 40.454831 -304.985045) (xy 40.496273 -305.019533) (xy 40.532251 -305.059687) (xy 40.561999 -305.104651)
			(xy 40.584884 -305.153468) (xy 40.600416 -305.205097) (xy 40.608266 -305.258437) (xy 40.608758 -305.285394)
			(xy 40.608266 -305.312351) (xy 40.600416 -305.365691) (xy 40.584884 -305.41732) (xy 40.561999 -305.466137)
			(xy 40.532251 -305.511101) (xy 40.496273 -305.551255) (xy 40.454831 -305.585743) (xy 40.40881 -305.613829)
			(xy 40.35919 -305.634916) (xy 40.307029 -305.648552) (xy 40.253438 -305.654449) (xy 40.199559 -305.65248)
			(xy 40.146541 -305.642687) (xy 40.095514 -305.625279) (xy 40.047566 -305.600627) (xy 40.003718 -305.569257)
			(xy 39.964905 -305.531836) (xy 39.931953 -305.489163) (xy 39.905567 -305.442146) (xy 39.886307 -305.391789)
			(xy 39.874584 -305.339165) (xy 39.870649 -305.285394) (xy 33.064704 -305.285394) (xy 33.064212 -305.312351)
			(xy 33.056362 -305.365691) (xy 33.04083 -305.41732) (xy 33.017945 -305.466137) (xy 32.988197 -305.511101)
			(xy 32.952219 -305.551255) (xy 32.910777 -305.585743) (xy 32.864756 -305.613829) (xy 32.815136 -305.634916)
			(xy 32.762975 -305.648552) (xy 32.709384 -305.654449) (xy 32.655505 -305.65248) (xy 32.602487 -305.642687)
			(xy 32.55146 -305.625279) (xy 32.503512 -305.600627) (xy 32.459664 -305.569257) (xy 32.420851 -305.531836)
			(xy 32.387899 -305.489163) (xy 32.361513 -305.442146) (xy 32.342253 -305.391789) (xy 32.33053 -305.339165)
			(xy 32.326595 -305.285394) (xy 25.520904 -305.285394) (xy 25.520412 -305.312351) (xy 25.512562 -305.365691)
			(xy 25.49703 -305.41732) (xy 25.474145 -305.466137) (xy 25.444397 -305.511101) (xy 25.408419 -305.551255)
			(xy 25.366977 -305.585743) (xy 25.320956 -305.613829) (xy 25.271336 -305.634916) (xy 25.219175 -305.648552)
			(xy 25.165584 -305.654449) (xy 25.111705 -305.65248) (xy 25.058687 -305.642687) (xy 25.00766 -305.625279)
			(xy 24.959712 -305.600627) (xy 24.915864 -305.569257) (xy 24.877051 -305.531836) (xy 24.844099 -305.489163)
			(xy 24.817713 -305.442146) (xy 24.798453 -305.391789) (xy 24.78673 -305.339165) (xy 24.782795 -305.285394)
			(xy 17.97685 -305.285394) (xy 17.976358 -305.312351) (xy 17.968508 -305.365691) (xy 17.952976 -305.41732)
			(xy 17.930091 -305.466137) (xy 17.900343 -305.511101) (xy 17.864365 -305.551255) (xy 17.822923 -305.585743)
			(xy 17.776902 -305.613829) (xy 17.727282 -305.634916) (xy 17.675121 -305.648552) (xy 17.62153 -305.654449)
			(xy 17.567651 -305.65248) (xy 17.514633 -305.642687) (xy 17.463606 -305.625279) (xy 17.415658 -305.600627)
			(xy 17.37181 -305.569257) (xy 17.332997 -305.531836) (xy 17.300045 -305.489163) (xy 17.273659 -305.442146)
			(xy 17.254399 -305.391789) (xy 17.242676 -305.339165) (xy 17.238741 -305.285394) (xy 15.598394 -305.285394)
			(xy 15.598394 -306.135278) (xy 21.338809 -306.135278) (xy 21.342744 -306.081507) (xy 21.354467 -306.028883)
			(xy 21.373727 -305.978526) (xy 21.400113 -305.931509) (xy 21.433065 -305.888836) (xy 21.471878 -305.851415)
			(xy 21.515726 -305.820045) (xy 21.563674 -305.795393) (xy 21.614701 -305.777985) (xy 21.667719 -305.768192)
			(xy 21.721598 -305.766223) (xy 21.775189 -305.77212) (xy 21.82735 -305.785756) (xy 21.87697 -305.806843)
			(xy 21.922991 -305.834929) (xy 21.964433 -305.869417) (xy 22.000411 -305.909571) (xy 22.030159 -305.954535)
			(xy 22.053044 -306.003352) (xy 22.068576 -306.054981) (xy 22.076426 -306.108321) (xy 22.076918 -306.135278)
			(xy 28.882863 -306.135278) (xy 28.886798 -306.081507) (xy 28.898521 -306.028883) (xy 28.917781 -305.978526)
			(xy 28.944167 -305.931509) (xy 28.977119 -305.888836) (xy 29.015932 -305.851415) (xy 29.05978 -305.820045)
			(xy 29.107728 -305.795393) (xy 29.158755 -305.777985) (xy 29.211773 -305.768192) (xy 29.265652 -305.766223)
			(xy 29.319243 -305.77212) (xy 29.371404 -305.785756) (xy 29.421024 -305.806843) (xy 29.467045 -305.834929)
			(xy 29.508487 -305.869417) (xy 29.544465 -305.909571) (xy 29.574213 -305.954535) (xy 29.597098 -306.003352)
			(xy 29.61263 -306.054981) (xy 29.62048 -306.108321) (xy 29.620972 -306.135278) (xy 36.426663 -306.135278)
			(xy 36.430598 -306.081507) (xy 36.442321 -306.028883) (xy 36.461581 -305.978526) (xy 36.487967 -305.931509)
			(xy 36.520919 -305.888836) (xy 36.559732 -305.851415) (xy 36.60358 -305.820045) (xy 36.651528 -305.795393)
			(xy 36.702555 -305.777985) (xy 36.755573 -305.768192) (xy 36.809452 -305.766223) (xy 36.863043 -305.77212)
			(xy 36.915204 -305.785756) (xy 36.964824 -305.806843) (xy 37.010845 -305.834929) (xy 37.052287 -305.869417)
			(xy 37.088265 -305.909571) (xy 37.118013 -305.954535) (xy 37.140898 -306.003352) (xy 37.15643 -306.054981)
			(xy 37.16428 -306.108321) (xy 37.164772 -306.135278) (xy 43.970717 -306.135278) (xy 43.974652 -306.081507)
			(xy 43.986375 -306.028883) (xy 44.005635 -305.978526) (xy 44.032021 -305.931509) (xy 44.064973 -305.888836)
			(xy 44.103786 -305.851415) (xy 44.147634 -305.820045) (xy 44.195582 -305.795393) (xy 44.246609 -305.777985)
			(xy 44.299627 -305.768192) (xy 44.353506 -305.766223) (xy 44.407097 -305.77212) (xy 44.459258 -305.785756)
			(xy 44.508878 -305.806843) (xy 44.554899 -305.834929) (xy 44.596341 -305.869417) (xy 44.632319 -305.909571)
			(xy 44.662067 -305.954535) (xy 44.684952 -306.003352) (xy 44.700484 -306.054981) (xy 44.708334 -306.108321)
			(xy 44.708826 -306.135278) (xy 44.708334 -306.162235) (xy 44.700484 -306.215575) (xy 44.684952 -306.267204)
			(xy 44.662067 -306.316021) (xy 44.632319 -306.360985) (xy 44.596341 -306.401139) (xy 44.554899 -306.435627)
			(xy 44.508878 -306.463713) (xy 44.459258 -306.4848) (xy 44.407097 -306.498436) (xy 44.353506 -306.504333)
			(xy 44.299627 -306.502364) (xy 44.246609 -306.492571) (xy 44.195582 -306.475163) (xy 44.147634 -306.450511)
			(xy 44.103786 -306.419141) (xy 44.064973 -306.38172) (xy 44.032021 -306.339047) (xy 44.005635 -306.29203)
			(xy 43.986375 -306.241673) (xy 43.974652 -306.189049) (xy 43.970717 -306.135278) (xy 37.164772 -306.135278)
			(xy 37.16428 -306.162235) (xy 37.15643 -306.215575) (xy 37.140898 -306.267204) (xy 37.118013 -306.316021)
			(xy 37.088265 -306.360985) (xy 37.052287 -306.401139) (xy 37.010845 -306.435627) (xy 36.964824 -306.463713)
			(xy 36.915204 -306.4848) (xy 36.863043 -306.498436) (xy 36.809452 -306.504333) (xy 36.755573 -306.502364)
			(xy 36.702555 -306.492571) (xy 36.651528 -306.475163) (xy 36.60358 -306.450511) (xy 36.559732 -306.419141)
			(xy 36.520919 -306.38172) (xy 36.487967 -306.339047) (xy 36.461581 -306.29203) (xy 36.442321 -306.241673)
			(xy 36.430598 -306.189049) (xy 36.426663 -306.135278) (xy 29.620972 -306.135278) (xy 29.62048 -306.162235)
			(xy 29.61263 -306.215575) (xy 29.597098 -306.267204) (xy 29.574213 -306.316021) (xy 29.544465 -306.360985)
			(xy 29.508487 -306.401139) (xy 29.467045 -306.435627) (xy 29.421024 -306.463713) (xy 29.371404 -306.4848)
			(xy 29.319243 -306.498436) (xy 29.265652 -306.504333) (xy 29.211773 -306.502364) (xy 29.158755 -306.492571)
			(xy 29.107728 -306.475163) (xy 29.05978 -306.450511) (xy 29.015932 -306.419141) (xy 28.977119 -306.38172)
			(xy 28.944167 -306.339047) (xy 28.917781 -306.29203) (xy 28.898521 -306.241673) (xy 28.886798 -306.189049)
			(xy 28.882863 -306.135278) (xy 22.076918 -306.135278) (xy 22.076426 -306.162235) (xy 22.068576 -306.215575)
			(xy 22.053044 -306.267204) (xy 22.030159 -306.316021) (xy 22.000411 -306.360985) (xy 21.964433 -306.401139)
			(xy 21.922991 -306.435627) (xy 21.87697 -306.463713) (xy 21.82735 -306.4848) (xy 21.775189 -306.498436)
			(xy 21.721598 -306.504333) (xy 21.667719 -306.502364) (xy 21.614701 -306.492571) (xy 21.563674 -306.475163)
			(xy 21.515726 -306.450511) (xy 21.471878 -306.419141) (xy 21.433065 -306.38172) (xy 21.400113 -306.339047)
			(xy 21.373727 -306.29203) (xy 21.354467 -306.241673) (xy 21.342744 -306.189049) (xy 21.338809 -306.135278)
			(xy 15.598394 -306.135278) (xy 15.598394 -306.985416) (xy 17.238741 -306.985416) (xy 17.242676 -306.931645)
			(xy 17.254399 -306.879021) (xy 17.273659 -306.828664) (xy 17.300045 -306.781647) (xy 17.332997 -306.738974)
			(xy 17.37181 -306.701553) (xy 17.415658 -306.670183) (xy 17.463606 -306.645531) (xy 17.514633 -306.628123)
			(xy 17.567651 -306.61833) (xy 17.62153 -306.616361) (xy 17.675121 -306.622258) (xy 17.727282 -306.635894)
			(xy 17.776902 -306.656981) (xy 17.822923 -306.685067) (xy 17.864365 -306.719555) (xy 17.900343 -306.759709)
			(xy 17.930091 -306.804673) (xy 17.952976 -306.85349) (xy 17.968508 -306.905119) (xy 17.976358 -306.958459)
			(xy 17.97685 -306.985416) (xy 24.782795 -306.985416) (xy 24.78673 -306.931645) (xy 24.798453 -306.879021)
			(xy 24.817713 -306.828664) (xy 24.844099 -306.781647) (xy 24.877051 -306.738974) (xy 24.915864 -306.701553)
			(xy 24.959712 -306.670183) (xy 25.00766 -306.645531) (xy 25.058687 -306.628123) (xy 25.111705 -306.61833)
			(xy 25.165584 -306.616361) (xy 25.219175 -306.622258) (xy 25.271336 -306.635894) (xy 25.320956 -306.656981)
			(xy 25.366977 -306.685067) (xy 25.408419 -306.719555) (xy 25.444397 -306.759709) (xy 25.474145 -306.804673)
			(xy 25.49703 -306.85349) (xy 25.512562 -306.905119) (xy 25.520412 -306.958459) (xy 25.520904 -306.985416)
			(xy 32.326595 -306.985416) (xy 32.33053 -306.931645) (xy 32.342253 -306.879021) (xy 32.361513 -306.828664)
			(xy 32.387899 -306.781647) (xy 32.420851 -306.738974) (xy 32.459664 -306.701553) (xy 32.503512 -306.670183)
			(xy 32.55146 -306.645531) (xy 32.602487 -306.628123) (xy 32.655505 -306.61833) (xy 32.709384 -306.616361)
			(xy 32.762975 -306.622258) (xy 32.815136 -306.635894) (xy 32.864756 -306.656981) (xy 32.910777 -306.685067)
			(xy 32.952219 -306.719555) (xy 32.988197 -306.759709) (xy 33.017945 -306.804673) (xy 33.04083 -306.85349)
			(xy 33.056362 -306.905119) (xy 33.064212 -306.958459) (xy 33.064704 -306.985416) (xy 39.870649 -306.985416)
			(xy 39.874584 -306.931645) (xy 39.886307 -306.879021) (xy 39.905567 -306.828664) (xy 39.931953 -306.781647)
			(xy 39.964905 -306.738974) (xy 40.003718 -306.701553) (xy 40.047566 -306.670183) (xy 40.095514 -306.645531)
			(xy 40.146541 -306.628123) (xy 40.199559 -306.61833) (xy 40.253438 -306.616361) (xy 40.307029 -306.622258)
			(xy 40.35919 -306.635894) (xy 40.40881 -306.656981) (xy 40.454831 -306.685067) (xy 40.496273 -306.719555)
			(xy 40.532251 -306.759709) (xy 40.561999 -306.804673) (xy 40.584884 -306.85349) (xy 40.600416 -306.905119)
			(xy 40.608266 -306.958459) (xy 40.608758 -306.985416) (xy 40.608266 -307.012373) (xy 40.600416 -307.065713)
			(xy 40.584884 -307.117342) (xy 40.561999 -307.166159) (xy 40.532251 -307.211123) (xy 40.496273 -307.251277)
			(xy 40.454831 -307.285765) (xy 40.40881 -307.313851) (xy 40.35919 -307.334938) (xy 40.307029 -307.348574)
			(xy 40.253438 -307.354471) (xy 40.199559 -307.352502) (xy 40.146541 -307.342709) (xy 40.095514 -307.325301)
			(xy 40.047566 -307.300649) (xy 40.003718 -307.269279) (xy 39.964905 -307.231858) (xy 39.931953 -307.189185)
			(xy 39.905567 -307.142168) (xy 39.886307 -307.091811) (xy 39.874584 -307.039187) (xy 39.870649 -306.985416)
			(xy 33.064704 -306.985416) (xy 33.064212 -307.012373) (xy 33.056362 -307.065713) (xy 33.04083 -307.117342)
			(xy 33.017945 -307.166159) (xy 32.988197 -307.211123) (xy 32.952219 -307.251277) (xy 32.910777 -307.285765)
			(xy 32.864756 -307.313851) (xy 32.815136 -307.334938) (xy 32.762975 -307.348574) (xy 32.709384 -307.354471)
			(xy 32.655505 -307.352502) (xy 32.602487 -307.342709) (xy 32.55146 -307.325301) (xy 32.503512 -307.300649)
			(xy 32.459664 -307.269279) (xy 32.420851 -307.231858) (xy 32.387899 -307.189185) (xy 32.361513 -307.142168)
			(xy 32.342253 -307.091811) (xy 32.33053 -307.039187) (xy 32.326595 -306.985416) (xy 25.520904 -306.985416)
			(xy 25.520412 -307.012373) (xy 25.512562 -307.065713) (xy 25.49703 -307.117342) (xy 25.474145 -307.166159)
			(xy 25.444397 -307.211123) (xy 25.408419 -307.251277) (xy 25.366977 -307.285765) (xy 25.320956 -307.313851)
			(xy 25.271336 -307.334938) (xy 25.219175 -307.348574) (xy 25.165584 -307.354471) (xy 25.111705 -307.352502)
			(xy 25.058687 -307.342709) (xy 25.00766 -307.325301) (xy 24.959712 -307.300649) (xy 24.915864 -307.269279)
			(xy 24.877051 -307.231858) (xy 24.844099 -307.189185) (xy 24.817713 -307.142168) (xy 24.798453 -307.091811)
			(xy 24.78673 -307.039187) (xy 24.782795 -306.985416) (xy 17.97685 -306.985416) (xy 17.976358 -307.012373)
			(xy 17.968508 -307.065713) (xy 17.952976 -307.117342) (xy 17.930091 -307.166159) (xy 17.900343 -307.211123)
			(xy 17.864365 -307.251277) (xy 17.822923 -307.285765) (xy 17.776902 -307.313851) (xy 17.727282 -307.334938)
			(xy 17.675121 -307.348574) (xy 17.62153 -307.354471) (xy 17.567651 -307.352502) (xy 17.514633 -307.342709)
			(xy 17.463606 -307.325301) (xy 17.415658 -307.300649) (xy 17.37181 -307.269279) (xy 17.332997 -307.231858)
			(xy 17.300045 -307.189185) (xy 17.273659 -307.142168) (xy 17.254399 -307.091811) (xy 17.242676 -307.039187)
			(xy 17.238741 -306.985416) (xy 15.598394 -306.985416) (xy 15.598394 -307.8353) (xy 21.338809 -307.8353)
			(xy 21.342744 -307.781529) (xy 21.354467 -307.728905) (xy 21.373727 -307.678548) (xy 21.400113 -307.631531)
			(xy 21.433065 -307.588858) (xy 21.471878 -307.551437) (xy 21.515726 -307.520067) (xy 21.563674 -307.495415)
			(xy 21.614701 -307.478007) (xy 21.667719 -307.468214) (xy 21.721598 -307.466245) (xy 21.775189 -307.472142)
			(xy 21.82735 -307.485778) (xy 21.87697 -307.506865) (xy 21.922991 -307.534951) (xy 21.964433 -307.569439)
			(xy 22.000411 -307.609593) (xy 22.030159 -307.654557) (xy 22.053044 -307.703374) (xy 22.068576 -307.755003)
			(xy 22.076426 -307.808343) (xy 22.076918 -307.8353) (xy 28.882863 -307.8353) (xy 28.886798 -307.781529)
			(xy 28.898521 -307.728905) (xy 28.917781 -307.678548) (xy 28.944167 -307.631531) (xy 28.977119 -307.588858)
			(xy 29.015932 -307.551437) (xy 29.05978 -307.520067) (xy 29.107728 -307.495415) (xy 29.158755 -307.478007)
			(xy 29.211773 -307.468214) (xy 29.265652 -307.466245) (xy 29.319243 -307.472142) (xy 29.371404 -307.485778)
			(xy 29.421024 -307.506865) (xy 29.467045 -307.534951) (xy 29.508487 -307.569439) (xy 29.544465 -307.609593)
			(xy 29.574213 -307.654557) (xy 29.597098 -307.703374) (xy 29.61263 -307.755003) (xy 29.62048 -307.808343)
			(xy 29.620972 -307.8353) (xy 36.426663 -307.8353) (xy 36.430598 -307.781529) (xy 36.442321 -307.728905)
			(xy 36.461581 -307.678548) (xy 36.487967 -307.631531) (xy 36.520919 -307.588858) (xy 36.559732 -307.551437)
			(xy 36.60358 -307.520067) (xy 36.651528 -307.495415) (xy 36.702555 -307.478007) (xy 36.755573 -307.468214)
			(xy 36.809452 -307.466245) (xy 36.863043 -307.472142) (xy 36.915204 -307.485778) (xy 36.964824 -307.506865)
			(xy 37.010845 -307.534951) (xy 37.052287 -307.569439) (xy 37.088265 -307.609593) (xy 37.118013 -307.654557)
			(xy 37.140898 -307.703374) (xy 37.15643 -307.755003) (xy 37.16428 -307.808343) (xy 37.164772 -307.8353)
			(xy 43.970717 -307.8353) (xy 43.974652 -307.781529) (xy 43.986375 -307.728905) (xy 44.005635 -307.678548)
			(xy 44.032021 -307.631531) (xy 44.064973 -307.588858) (xy 44.103786 -307.551437) (xy 44.147634 -307.520067)
			(xy 44.195582 -307.495415) (xy 44.246609 -307.478007) (xy 44.299627 -307.468214) (xy 44.353506 -307.466245)
			(xy 44.407097 -307.472142) (xy 44.459258 -307.485778) (xy 44.508878 -307.506865) (xy 44.554899 -307.534951)
			(xy 44.596341 -307.569439) (xy 44.632319 -307.609593) (xy 44.662067 -307.654557) (xy 44.684952 -307.703374)
			(xy 44.700484 -307.755003) (xy 44.708334 -307.808343) (xy 44.708826 -307.8353) (xy 44.708334 -307.862257)
			(xy 44.700484 -307.915597) (xy 44.684952 -307.967226) (xy 44.662067 -308.016043) (xy 44.632319 -308.061007)
			(xy 44.596341 -308.101161) (xy 44.554899 -308.135649) (xy 44.508878 -308.163735) (xy 44.459258 -308.184822)
			(xy 44.407097 -308.198458) (xy 44.353506 -308.204355) (xy 44.299627 -308.202386) (xy 44.246609 -308.192593)
			(xy 44.195582 -308.175185) (xy 44.147634 -308.150533) (xy 44.103786 -308.119163) (xy 44.064973 -308.081742)
			(xy 44.032021 -308.039069) (xy 44.005635 -307.992052) (xy 43.986375 -307.941695) (xy 43.974652 -307.889071)
			(xy 43.970717 -307.8353) (xy 37.164772 -307.8353) (xy 37.16428 -307.862257) (xy 37.15643 -307.915597)
			(xy 37.140898 -307.967226) (xy 37.118013 -308.016043) (xy 37.088265 -308.061007) (xy 37.052287 -308.101161)
			(xy 37.010845 -308.135649) (xy 36.964824 -308.163735) (xy 36.915204 -308.184822) (xy 36.863043 -308.198458)
			(xy 36.809452 -308.204355) (xy 36.755573 -308.202386) (xy 36.702555 -308.192593) (xy 36.651528 -308.175185)
			(xy 36.60358 -308.150533) (xy 36.559732 -308.119163) (xy 36.520919 -308.081742) (xy 36.487967 -308.039069)
			(xy 36.461581 -307.992052) (xy 36.442321 -307.941695) (xy 36.430598 -307.889071) (xy 36.426663 -307.8353)
			(xy 29.620972 -307.8353) (xy 29.62048 -307.862257) (xy 29.61263 -307.915597) (xy 29.597098 -307.967226)
			(xy 29.574213 -308.016043) (xy 29.544465 -308.061007) (xy 29.508487 -308.101161) (xy 29.467045 -308.135649)
			(xy 29.421024 -308.163735) (xy 29.371404 -308.184822) (xy 29.319243 -308.198458) (xy 29.265652 -308.204355)
			(xy 29.211773 -308.202386) (xy 29.158755 -308.192593) (xy 29.107728 -308.175185) (xy 29.05978 -308.150533)
			(xy 29.015932 -308.119163) (xy 28.977119 -308.081742) (xy 28.944167 -308.039069) (xy 28.917781 -307.992052)
			(xy 28.898521 -307.941695) (xy 28.886798 -307.889071) (xy 28.882863 -307.8353) (xy 22.076918 -307.8353)
			(xy 22.076426 -307.862257) (xy 22.068576 -307.915597) (xy 22.053044 -307.967226) (xy 22.030159 -308.016043)
			(xy 22.000411 -308.061007) (xy 21.964433 -308.101161) (xy 21.922991 -308.135649) (xy 21.87697 -308.163735)
			(xy 21.82735 -308.184822) (xy 21.775189 -308.198458) (xy 21.721598 -308.204355) (xy 21.667719 -308.202386)
			(xy 21.614701 -308.192593) (xy 21.563674 -308.175185) (xy 21.515726 -308.150533) (xy 21.471878 -308.119163)
			(xy 21.433065 -308.081742) (xy 21.400113 -308.039069) (xy 21.373727 -307.992052) (xy 21.354467 -307.941695)
			(xy 21.342744 -307.889071) (xy 21.338809 -307.8353) (xy 15.598394 -307.8353) (xy 15.598394 -308.685438)
			(xy 17.238741 -308.685438) (xy 17.242676 -308.631667) (xy 17.254399 -308.579043) (xy 17.273659 -308.528686)
			(xy 17.300045 -308.481669) (xy 17.332997 -308.438996) (xy 17.37181 -308.401575) (xy 17.415658 -308.370205)
			(xy 17.463606 -308.345553) (xy 17.514633 -308.328145) (xy 17.567651 -308.318352) (xy 17.62153 -308.316383)
			(xy 17.675121 -308.32228) (xy 17.727282 -308.335916) (xy 17.776902 -308.357003) (xy 17.822923 -308.385089)
			(xy 17.864365 -308.419577) (xy 17.900343 -308.459731) (xy 17.930091 -308.504695) (xy 17.952976 -308.553512)
			(xy 17.968508 -308.605141) (xy 17.976358 -308.658481) (xy 17.97685 -308.685438) (xy 24.782795 -308.685438)
			(xy 24.78673 -308.631667) (xy 24.798453 -308.579043) (xy 24.817713 -308.528686) (xy 24.844099 -308.481669)
			(xy 24.877051 -308.438996) (xy 24.915864 -308.401575) (xy 24.959712 -308.370205) (xy 25.00766 -308.345553)
			(xy 25.058687 -308.328145) (xy 25.111705 -308.318352) (xy 25.165584 -308.316383) (xy 25.219175 -308.32228)
			(xy 25.271336 -308.335916) (xy 25.320956 -308.357003) (xy 25.366977 -308.385089) (xy 25.408419 -308.419577)
			(xy 25.444397 -308.459731) (xy 25.474145 -308.504695) (xy 25.49703 -308.553512) (xy 25.512562 -308.605141)
			(xy 25.520412 -308.658481) (xy 25.520904 -308.685438) (xy 32.326595 -308.685438) (xy 32.33053 -308.631667)
			(xy 32.342253 -308.579043) (xy 32.361513 -308.528686) (xy 32.387899 -308.481669) (xy 32.420851 -308.438996)
			(xy 32.459664 -308.401575) (xy 32.503512 -308.370205) (xy 32.55146 -308.345553) (xy 32.602487 -308.328145)
			(xy 32.655505 -308.318352) (xy 32.709384 -308.316383) (xy 32.762975 -308.32228) (xy 32.815136 -308.335916)
			(xy 32.864756 -308.357003) (xy 32.910777 -308.385089) (xy 32.952219 -308.419577) (xy 32.988197 -308.459731)
			(xy 33.017945 -308.504695) (xy 33.04083 -308.553512) (xy 33.056362 -308.605141) (xy 33.064212 -308.658481)
			(xy 33.064704 -308.685438) (xy 39.870649 -308.685438) (xy 39.874584 -308.631667) (xy 39.886307 -308.579043)
			(xy 39.905567 -308.528686) (xy 39.931953 -308.481669) (xy 39.964905 -308.438996) (xy 40.003718 -308.401575)
			(xy 40.047566 -308.370205) (xy 40.095514 -308.345553) (xy 40.146541 -308.328145) (xy 40.199559 -308.318352)
			(xy 40.253438 -308.316383) (xy 40.307029 -308.32228) (xy 40.35919 -308.335916) (xy 40.40881 -308.357003)
			(xy 40.454831 -308.385089) (xy 40.496273 -308.419577) (xy 40.532251 -308.459731) (xy 40.561999 -308.504695)
			(xy 40.584884 -308.553512) (xy 40.600416 -308.605141) (xy 40.608266 -308.658481) (xy 40.608758 -308.685438)
			(xy 40.608266 -308.712395) (xy 40.600416 -308.765735) (xy 40.584884 -308.817364) (xy 40.561999 -308.866181)
			(xy 40.532251 -308.911145) (xy 40.496273 -308.951299) (xy 40.454831 -308.985787) (xy 40.40881 -309.013873)
			(xy 40.35919 -309.03496) (xy 40.307029 -309.048596) (xy 40.253438 -309.054493) (xy 40.199559 -309.052524)
			(xy 40.146541 -309.042731) (xy 40.095514 -309.025323) (xy 40.047566 -309.000671) (xy 40.003718 -308.969301)
			(xy 39.964905 -308.93188) (xy 39.931953 -308.889207) (xy 39.905567 -308.84219) (xy 39.886307 -308.791833)
			(xy 39.874584 -308.739209) (xy 39.870649 -308.685438) (xy 33.064704 -308.685438) (xy 33.064212 -308.712395)
			(xy 33.056362 -308.765735) (xy 33.04083 -308.817364) (xy 33.017945 -308.866181) (xy 32.988197 -308.911145)
			(xy 32.952219 -308.951299) (xy 32.910777 -308.985787) (xy 32.864756 -309.013873) (xy 32.815136 -309.03496)
			(xy 32.762975 -309.048596) (xy 32.709384 -309.054493) (xy 32.655505 -309.052524) (xy 32.602487 -309.042731)
			(xy 32.55146 -309.025323) (xy 32.503512 -309.000671) (xy 32.459664 -308.969301) (xy 32.420851 -308.93188)
			(xy 32.387899 -308.889207) (xy 32.361513 -308.84219) (xy 32.342253 -308.791833) (xy 32.33053 -308.739209)
			(xy 32.326595 -308.685438) (xy 25.520904 -308.685438) (xy 25.520412 -308.712395) (xy 25.512562 -308.765735)
			(xy 25.49703 -308.817364) (xy 25.474145 -308.866181) (xy 25.444397 -308.911145) (xy 25.408419 -308.951299)
			(xy 25.366977 -308.985787) (xy 25.320956 -309.013873) (xy 25.271336 -309.03496) (xy 25.219175 -309.048596)
			(xy 25.165584 -309.054493) (xy 25.111705 -309.052524) (xy 25.058687 -309.042731) (xy 25.00766 -309.025323)
			(xy 24.959712 -309.000671) (xy 24.915864 -308.969301) (xy 24.877051 -308.93188) (xy 24.844099 -308.889207)
			(xy 24.817713 -308.84219) (xy 24.798453 -308.791833) (xy 24.78673 -308.739209) (xy 24.782795 -308.685438)
			(xy 17.97685 -308.685438) (xy 17.976358 -308.712395) (xy 17.968508 -308.765735) (xy 17.952976 -308.817364)
			(xy 17.930091 -308.866181) (xy 17.900343 -308.911145) (xy 17.864365 -308.951299) (xy 17.822923 -308.985787)
			(xy 17.776902 -309.013873) (xy 17.727282 -309.03496) (xy 17.675121 -309.048596) (xy 17.62153 -309.054493)
			(xy 17.567651 -309.052524) (xy 17.514633 -309.042731) (xy 17.463606 -309.025323) (xy 17.415658 -309.000671)
			(xy 17.37181 -308.969301) (xy 17.332997 -308.93188) (xy 17.300045 -308.889207) (xy 17.273659 -308.84219)
			(xy 17.254399 -308.791833) (xy 17.242676 -308.739209) (xy 17.238741 -308.685438) (xy 15.598394 -308.685438)
			(xy 15.598394 -309.535322) (xy 21.338809 -309.535322) (xy 21.342744 -309.481551) (xy 21.354467 -309.428927)
			(xy 21.373727 -309.37857) (xy 21.400113 -309.331553) (xy 21.433065 -309.28888) (xy 21.471878 -309.251459)
			(xy 21.515726 -309.220089) (xy 21.563674 -309.195437) (xy 21.614701 -309.178029) (xy 21.667719 -309.168236)
			(xy 21.721598 -309.166267) (xy 21.775189 -309.172164) (xy 21.82735 -309.1858) (xy 21.87697 -309.206887)
			(xy 21.922991 -309.234973) (xy 21.964433 -309.269461) (xy 22.000411 -309.309615) (xy 22.030159 -309.354579)
			(xy 22.053044 -309.403396) (xy 22.068576 -309.455025) (xy 22.076426 -309.508365) (xy 22.076918 -309.535322)
			(xy 28.882863 -309.535322) (xy 28.886798 -309.481551) (xy 28.898521 -309.428927) (xy 28.917781 -309.37857)
			(xy 28.944167 -309.331553) (xy 28.977119 -309.28888) (xy 29.015932 -309.251459) (xy 29.05978 -309.220089)
			(xy 29.107728 -309.195437) (xy 29.158755 -309.178029) (xy 29.211773 -309.168236) (xy 29.265652 -309.166267)
			(xy 29.319243 -309.172164) (xy 29.371404 -309.1858) (xy 29.421024 -309.206887) (xy 29.467045 -309.234973)
			(xy 29.508487 -309.269461) (xy 29.544465 -309.309615) (xy 29.574213 -309.354579) (xy 29.597098 -309.403396)
			(xy 29.61263 -309.455025) (xy 29.62048 -309.508365) (xy 29.620972 -309.535322) (xy 36.426663 -309.535322)
			(xy 36.430598 -309.481551) (xy 36.442321 -309.428927) (xy 36.461581 -309.37857) (xy 36.487967 -309.331553)
			(xy 36.520919 -309.28888) (xy 36.559732 -309.251459) (xy 36.60358 -309.220089) (xy 36.651528 -309.195437)
			(xy 36.702555 -309.178029) (xy 36.755573 -309.168236) (xy 36.809452 -309.166267) (xy 36.863043 -309.172164)
			(xy 36.915204 -309.1858) (xy 36.964824 -309.206887) (xy 37.010845 -309.234973) (xy 37.052287 -309.269461)
			(xy 37.088265 -309.309615) (xy 37.118013 -309.354579) (xy 37.140898 -309.403396) (xy 37.15643 -309.455025)
			(xy 37.16428 -309.508365) (xy 37.164772 -309.535322) (xy 43.970717 -309.535322) (xy 43.974652 -309.481551)
			(xy 43.986375 -309.428927) (xy 44.005635 -309.37857) (xy 44.032021 -309.331553) (xy 44.064973 -309.28888)
			(xy 44.103786 -309.251459) (xy 44.147634 -309.220089) (xy 44.195582 -309.195437) (xy 44.246609 -309.178029)
			(xy 44.299627 -309.168236) (xy 44.353506 -309.166267) (xy 44.407097 -309.172164) (xy 44.459258 -309.1858)
			(xy 44.508878 -309.206887) (xy 44.554899 -309.234973) (xy 44.596341 -309.269461) (xy 44.632319 -309.309615)
			(xy 44.662067 -309.354579) (xy 44.684952 -309.403396) (xy 44.700484 -309.455025) (xy 44.708334 -309.508365)
			(xy 44.708826 -309.535322) (xy 44.708334 -309.562279) (xy 44.700484 -309.615619) (xy 44.684952 -309.667248)
			(xy 44.662067 -309.716065) (xy 44.632319 -309.761029) (xy 44.596341 -309.801183) (xy 44.554899 -309.835671)
			(xy 44.508878 -309.863757) (xy 44.459258 -309.884844) (xy 44.407097 -309.89848) (xy 44.353506 -309.904377)
			(xy 44.299627 -309.902408) (xy 44.246609 -309.892615) (xy 44.195582 -309.875207) (xy 44.147634 -309.850555)
			(xy 44.103786 -309.819185) (xy 44.064973 -309.781764) (xy 44.032021 -309.739091) (xy 44.005635 -309.692074)
			(xy 43.986375 -309.641717) (xy 43.974652 -309.589093) (xy 43.970717 -309.535322) (xy 37.164772 -309.535322)
			(xy 37.16428 -309.562279) (xy 37.15643 -309.615619) (xy 37.140898 -309.667248) (xy 37.118013 -309.716065)
			(xy 37.088265 -309.761029) (xy 37.052287 -309.801183) (xy 37.010845 -309.835671) (xy 36.964824 -309.863757)
			(xy 36.915204 -309.884844) (xy 36.863043 -309.89848) (xy 36.809452 -309.904377) (xy 36.755573 -309.902408)
			(xy 36.702555 -309.892615) (xy 36.651528 -309.875207) (xy 36.60358 -309.850555) (xy 36.559732 -309.819185)
			(xy 36.520919 -309.781764) (xy 36.487967 -309.739091) (xy 36.461581 -309.692074) (xy 36.442321 -309.641717)
			(xy 36.430598 -309.589093) (xy 36.426663 -309.535322) (xy 29.620972 -309.535322) (xy 29.62048 -309.562279)
			(xy 29.61263 -309.615619) (xy 29.597098 -309.667248) (xy 29.574213 -309.716065) (xy 29.544465 -309.761029)
			(xy 29.508487 -309.801183) (xy 29.467045 -309.835671) (xy 29.421024 -309.863757) (xy 29.371404 -309.884844)
			(xy 29.319243 -309.89848) (xy 29.265652 -309.904377) (xy 29.211773 -309.902408) (xy 29.158755 -309.892615)
			(xy 29.107728 -309.875207) (xy 29.05978 -309.850555) (xy 29.015932 -309.819185) (xy 28.977119 -309.781764)
			(xy 28.944167 -309.739091) (xy 28.917781 -309.692074) (xy 28.898521 -309.641717) (xy 28.886798 -309.589093)
			(xy 28.882863 -309.535322) (xy 22.076918 -309.535322) (xy 22.076426 -309.562279) (xy 22.068576 -309.615619)
			(xy 22.053044 -309.667248) (xy 22.030159 -309.716065) (xy 22.000411 -309.761029) (xy 21.964433 -309.801183)
			(xy 21.922991 -309.835671) (xy 21.87697 -309.863757) (xy 21.82735 -309.884844) (xy 21.775189 -309.89848)
			(xy 21.721598 -309.904377) (xy 21.667719 -309.902408) (xy 21.614701 -309.892615) (xy 21.563674 -309.875207)
			(xy 21.515726 -309.850555) (xy 21.471878 -309.819185) (xy 21.433065 -309.781764) (xy 21.400113 -309.739091)
			(xy 21.373727 -309.692074) (xy 21.354467 -309.641717) (xy 21.342744 -309.589093) (xy 21.338809 -309.535322)
			(xy 15.598394 -309.535322) (xy 15.598394 -310.385206) (xy 17.238741 -310.385206) (xy 17.242676 -310.331435)
			(xy 17.254399 -310.278811) (xy 17.273659 -310.228454) (xy 17.300045 -310.181437) (xy 17.332997 -310.138764)
			(xy 17.37181 -310.101343) (xy 17.415658 -310.069973) (xy 17.463606 -310.045321) (xy 17.514633 -310.027913)
			(xy 17.567651 -310.01812) (xy 17.62153 -310.016151) (xy 17.675121 -310.022048) (xy 17.727282 -310.035684)
			(xy 17.776902 -310.056771) (xy 17.822923 -310.084857) (xy 17.864365 -310.119345) (xy 17.900343 -310.159499)
			(xy 17.930091 -310.204463) (xy 17.952976 -310.25328) (xy 17.968508 -310.304909) (xy 17.976358 -310.358249)
			(xy 17.97685 -310.385206) (xy 24.782795 -310.385206) (xy 24.78673 -310.331435) (xy 24.798453 -310.278811)
			(xy 24.817713 -310.228454) (xy 24.844099 -310.181437) (xy 24.877051 -310.138764) (xy 24.915864 -310.101343)
			(xy 24.959712 -310.069973) (xy 25.00766 -310.045321) (xy 25.058687 -310.027913) (xy 25.111705 -310.01812)
			(xy 25.165584 -310.016151) (xy 25.219175 -310.022048) (xy 25.271336 -310.035684) (xy 25.320956 -310.056771)
			(xy 25.366977 -310.084857) (xy 25.408419 -310.119345) (xy 25.444397 -310.159499) (xy 25.474145 -310.204463)
			(xy 25.49703 -310.25328) (xy 25.512562 -310.304909) (xy 25.520412 -310.358249) (xy 25.520904 -310.385206)
			(xy 32.326595 -310.385206) (xy 32.33053 -310.331435) (xy 32.342253 -310.278811) (xy 32.361513 -310.228454)
			(xy 32.387899 -310.181437) (xy 32.420851 -310.138764) (xy 32.459664 -310.101343) (xy 32.503512 -310.069973)
			(xy 32.55146 -310.045321) (xy 32.602487 -310.027913) (xy 32.655505 -310.01812) (xy 32.709384 -310.016151)
			(xy 32.762975 -310.022048) (xy 32.815136 -310.035684) (xy 32.864756 -310.056771) (xy 32.910777 -310.084857)
			(xy 32.952219 -310.119345) (xy 32.988197 -310.159499) (xy 33.017945 -310.204463) (xy 33.04083 -310.25328)
			(xy 33.056362 -310.304909) (xy 33.064212 -310.358249) (xy 33.064704 -310.385206) (xy 39.870649 -310.385206)
			(xy 39.874584 -310.331435) (xy 39.886307 -310.278811) (xy 39.905567 -310.228454) (xy 39.931953 -310.181437)
			(xy 39.964905 -310.138764) (xy 40.003718 -310.101343) (xy 40.047566 -310.069973) (xy 40.095514 -310.045321)
			(xy 40.146541 -310.027913) (xy 40.199559 -310.01812) (xy 40.253438 -310.016151) (xy 40.307029 -310.022048)
			(xy 40.35919 -310.035684) (xy 40.40881 -310.056771) (xy 40.454831 -310.084857) (xy 40.496273 -310.119345)
			(xy 40.532251 -310.159499) (xy 40.561999 -310.204463) (xy 40.584884 -310.25328) (xy 40.600416 -310.304909)
			(xy 40.608266 -310.358249) (xy 40.608758 -310.385206) (xy 40.608266 -310.412163) (xy 40.600416 -310.465503)
			(xy 40.584884 -310.517132) (xy 40.561999 -310.565949) (xy 40.532251 -310.610913) (xy 40.496273 -310.651067)
			(xy 40.454831 -310.685555) (xy 40.40881 -310.713641) (xy 40.35919 -310.734728) (xy 40.307029 -310.748364)
			(xy 40.253438 -310.754261) (xy 40.199559 -310.752292) (xy 40.146541 -310.742499) (xy 40.095514 -310.725091)
			(xy 40.047566 -310.700439) (xy 40.003718 -310.669069) (xy 39.964905 -310.631648) (xy 39.931953 -310.588975)
			(xy 39.905567 -310.541958) (xy 39.886307 -310.491601) (xy 39.874584 -310.438977) (xy 39.870649 -310.385206)
			(xy 33.064704 -310.385206) (xy 33.064212 -310.412163) (xy 33.056362 -310.465503) (xy 33.04083 -310.517132)
			(xy 33.017945 -310.565949) (xy 32.988197 -310.610913) (xy 32.952219 -310.651067) (xy 32.910777 -310.685555)
			(xy 32.864756 -310.713641) (xy 32.815136 -310.734728) (xy 32.762975 -310.748364) (xy 32.709384 -310.754261)
			(xy 32.655505 -310.752292) (xy 32.602487 -310.742499) (xy 32.55146 -310.725091) (xy 32.503512 -310.700439)
			(xy 32.459664 -310.669069) (xy 32.420851 -310.631648) (xy 32.387899 -310.588975) (xy 32.361513 -310.541958)
			(xy 32.342253 -310.491601) (xy 32.33053 -310.438977) (xy 32.326595 -310.385206) (xy 25.520904 -310.385206)
			(xy 25.520412 -310.412163) (xy 25.512562 -310.465503) (xy 25.49703 -310.517132) (xy 25.474145 -310.565949)
			(xy 25.444397 -310.610913) (xy 25.408419 -310.651067) (xy 25.366977 -310.685555) (xy 25.320956 -310.713641)
			(xy 25.271336 -310.734728) (xy 25.219175 -310.748364) (xy 25.165584 -310.754261) (xy 25.111705 -310.752292)
			(xy 25.058687 -310.742499) (xy 25.00766 -310.725091) (xy 24.959712 -310.700439) (xy 24.915864 -310.669069)
			(xy 24.877051 -310.631648) (xy 24.844099 -310.588975) (xy 24.817713 -310.541958) (xy 24.798453 -310.491601)
			(xy 24.78673 -310.438977) (xy 24.782795 -310.385206) (xy 17.97685 -310.385206) (xy 17.976358 -310.412163)
			(xy 17.968508 -310.465503) (xy 17.952976 -310.517132) (xy 17.930091 -310.565949) (xy 17.900343 -310.610913)
			(xy 17.864365 -310.651067) (xy 17.822923 -310.685555) (xy 17.776902 -310.713641) (xy 17.727282 -310.734728)
			(xy 17.675121 -310.748364) (xy 17.62153 -310.754261) (xy 17.567651 -310.752292) (xy 17.514633 -310.742499)
			(xy 17.463606 -310.725091) (xy 17.415658 -310.700439) (xy 17.37181 -310.669069) (xy 17.332997 -310.631648)
			(xy 17.300045 -310.588975) (xy 17.273659 -310.541958) (xy 17.254399 -310.491601) (xy 17.242676 -310.438977)
			(xy 17.238741 -310.385206) (xy 15.598394 -310.385206) (xy 15.598394 -311.235344) (xy 21.338809 -311.235344)
			(xy 21.342744 -311.181573) (xy 21.354467 -311.128949) (xy 21.373727 -311.078592) (xy 21.400113 -311.031575)
			(xy 21.433065 -310.988902) (xy 21.471878 -310.951481) (xy 21.515726 -310.920111) (xy 21.563674 -310.895459)
			(xy 21.614701 -310.878051) (xy 21.667719 -310.868258) (xy 21.721598 -310.866289) (xy 21.775189 -310.872186)
			(xy 21.82735 -310.885822) (xy 21.87697 -310.906909) (xy 21.922991 -310.934995) (xy 21.964433 -310.969483)
			(xy 22.000411 -311.009637) (xy 22.030159 -311.054601) (xy 22.053044 -311.103418) (xy 22.068576 -311.155047)
			(xy 22.076426 -311.208387) (xy 22.076918 -311.235344) (xy 28.882863 -311.235344) (xy 28.886798 -311.181573)
			(xy 28.898521 -311.128949) (xy 28.917781 -311.078592) (xy 28.944167 -311.031575) (xy 28.977119 -310.988902)
			(xy 29.015932 -310.951481) (xy 29.05978 -310.920111) (xy 29.107728 -310.895459) (xy 29.158755 -310.878051)
			(xy 29.211773 -310.868258) (xy 29.265652 -310.866289) (xy 29.319243 -310.872186) (xy 29.371404 -310.885822)
			(xy 29.421024 -310.906909) (xy 29.467045 -310.934995) (xy 29.508487 -310.969483) (xy 29.544465 -311.009637)
			(xy 29.574213 -311.054601) (xy 29.597098 -311.103418) (xy 29.61263 -311.155047) (xy 29.62048 -311.208387)
			(xy 29.620972 -311.235344) (xy 36.426663 -311.235344) (xy 36.430598 -311.181573) (xy 36.442321 -311.128949)
			(xy 36.461581 -311.078592) (xy 36.487967 -311.031575) (xy 36.520919 -310.988902) (xy 36.559732 -310.951481)
			(xy 36.60358 -310.920111) (xy 36.651528 -310.895459) (xy 36.702555 -310.878051) (xy 36.755573 -310.868258)
			(xy 36.809452 -310.866289) (xy 36.863043 -310.872186) (xy 36.915204 -310.885822) (xy 36.964824 -310.906909)
			(xy 37.010845 -310.934995) (xy 37.052287 -310.969483) (xy 37.088265 -311.009637) (xy 37.118013 -311.054601)
			(xy 37.140898 -311.103418) (xy 37.15643 -311.155047) (xy 37.16428 -311.208387) (xy 37.164772 -311.235344)
			(xy 43.970717 -311.235344) (xy 43.974652 -311.181573) (xy 43.986375 -311.128949) (xy 44.005635 -311.078592)
			(xy 44.032021 -311.031575) (xy 44.064973 -310.988902) (xy 44.103786 -310.951481) (xy 44.147634 -310.920111)
			(xy 44.195582 -310.895459) (xy 44.246609 -310.878051) (xy 44.299627 -310.868258) (xy 44.353506 -310.866289)
			(xy 44.407097 -310.872186) (xy 44.459258 -310.885822) (xy 44.508878 -310.906909) (xy 44.554899 -310.934995)
			(xy 44.596341 -310.969483) (xy 44.632319 -311.009637) (xy 44.662067 -311.054601) (xy 44.684952 -311.103418)
			(xy 44.700484 -311.155047) (xy 44.708334 -311.208387) (xy 44.708826 -311.235344) (xy 44.708334 -311.262301)
			(xy 44.700484 -311.315641) (xy 44.684952 -311.36727) (xy 44.662067 -311.416087) (xy 44.632319 -311.461051)
			(xy 44.596341 -311.501205) (xy 44.554899 -311.535693) (xy 44.508878 -311.563779) (xy 44.459258 -311.584866)
			(xy 44.407097 -311.598502) (xy 44.353506 -311.604399) (xy 44.299627 -311.60243) (xy 44.246609 -311.592637)
			(xy 44.195582 -311.575229) (xy 44.147634 -311.550577) (xy 44.103786 -311.519207) (xy 44.064973 -311.481786)
			(xy 44.032021 -311.439113) (xy 44.005635 -311.392096) (xy 43.986375 -311.341739) (xy 43.974652 -311.289115)
			(xy 43.970717 -311.235344) (xy 37.164772 -311.235344) (xy 37.16428 -311.262301) (xy 37.15643 -311.315641)
			(xy 37.140898 -311.36727) (xy 37.118013 -311.416087) (xy 37.088265 -311.461051) (xy 37.052287 -311.501205)
			(xy 37.010845 -311.535693) (xy 36.964824 -311.563779) (xy 36.915204 -311.584866) (xy 36.863043 -311.598502)
			(xy 36.809452 -311.604399) (xy 36.755573 -311.60243) (xy 36.702555 -311.592637) (xy 36.651528 -311.575229)
			(xy 36.60358 -311.550577) (xy 36.559732 -311.519207) (xy 36.520919 -311.481786) (xy 36.487967 -311.439113)
			(xy 36.461581 -311.392096) (xy 36.442321 -311.341739) (xy 36.430598 -311.289115) (xy 36.426663 -311.235344)
			(xy 29.620972 -311.235344) (xy 29.62048 -311.262301) (xy 29.61263 -311.315641) (xy 29.597098 -311.36727)
			(xy 29.574213 -311.416087) (xy 29.544465 -311.461051) (xy 29.508487 -311.501205) (xy 29.467045 -311.535693)
			(xy 29.421024 -311.563779) (xy 29.371404 -311.584866) (xy 29.319243 -311.598502) (xy 29.265652 -311.604399)
			(xy 29.211773 -311.60243) (xy 29.158755 -311.592637) (xy 29.107728 -311.575229) (xy 29.05978 -311.550577)
			(xy 29.015932 -311.519207) (xy 28.977119 -311.481786) (xy 28.944167 -311.439113) (xy 28.917781 -311.392096)
			(xy 28.898521 -311.341739) (xy 28.886798 -311.289115) (xy 28.882863 -311.235344) (xy 22.076918 -311.235344)
			(xy 22.076426 -311.262301) (xy 22.068576 -311.315641) (xy 22.053044 -311.36727) (xy 22.030159 -311.416087)
			(xy 22.000411 -311.461051) (xy 21.964433 -311.501205) (xy 21.922991 -311.535693) (xy 21.87697 -311.563779)
			(xy 21.82735 -311.584866) (xy 21.775189 -311.598502) (xy 21.721598 -311.604399) (xy 21.667719 -311.60243)
			(xy 21.614701 -311.592637) (xy 21.563674 -311.575229) (xy 21.515726 -311.550577) (xy 21.471878 -311.519207)
			(xy 21.433065 -311.481786) (xy 21.400113 -311.439113) (xy 21.373727 -311.392096) (xy 21.354467 -311.341739)
			(xy 21.342744 -311.289115) (xy 21.338809 -311.235344) (xy 15.598394 -311.235344) (xy 15.598394 -312.085228)
			(xy 17.238741 -312.085228) (xy 17.242676 -312.031457) (xy 17.254399 -311.978833) (xy 17.273659 -311.928476)
			(xy 17.300045 -311.881459) (xy 17.332997 -311.838786) (xy 17.37181 -311.801365) (xy 17.415658 -311.769995)
			(xy 17.463606 -311.745343) (xy 17.514633 -311.727935) (xy 17.567651 -311.718142) (xy 17.62153 -311.716173)
			(xy 17.675121 -311.72207) (xy 17.727282 -311.735706) (xy 17.776902 -311.756793) (xy 17.822923 -311.784879)
			(xy 17.864365 -311.819367) (xy 17.900343 -311.859521) (xy 17.930091 -311.904485) (xy 17.952976 -311.953302)
			(xy 17.968508 -312.004931) (xy 17.976358 -312.058271) (xy 17.97685 -312.085228) (xy 24.782795 -312.085228)
			(xy 24.78673 -312.031457) (xy 24.798453 -311.978833) (xy 24.817713 -311.928476) (xy 24.844099 -311.881459)
			(xy 24.877051 -311.838786) (xy 24.915864 -311.801365) (xy 24.959712 -311.769995) (xy 25.00766 -311.745343)
			(xy 25.058687 -311.727935) (xy 25.111705 -311.718142) (xy 25.165584 -311.716173) (xy 25.219175 -311.72207)
			(xy 25.271336 -311.735706) (xy 25.320956 -311.756793) (xy 25.366977 -311.784879) (xy 25.408419 -311.819367)
			(xy 25.444397 -311.859521) (xy 25.474145 -311.904485) (xy 25.49703 -311.953302) (xy 25.512562 -312.004931)
			(xy 25.520412 -312.058271) (xy 25.520904 -312.085228) (xy 32.326595 -312.085228) (xy 32.33053 -312.031457)
			(xy 32.342253 -311.978833) (xy 32.361513 -311.928476) (xy 32.387899 -311.881459) (xy 32.420851 -311.838786)
			(xy 32.459664 -311.801365) (xy 32.503512 -311.769995) (xy 32.55146 -311.745343) (xy 32.602487 -311.727935)
			(xy 32.655505 -311.718142) (xy 32.709384 -311.716173) (xy 32.762975 -311.72207) (xy 32.815136 -311.735706)
			(xy 32.864756 -311.756793) (xy 32.910777 -311.784879) (xy 32.952219 -311.819367) (xy 32.988197 -311.859521)
			(xy 33.017945 -311.904485) (xy 33.04083 -311.953302) (xy 33.056362 -312.004931) (xy 33.064212 -312.058271)
			(xy 33.064704 -312.085228) (xy 39.870649 -312.085228) (xy 39.874584 -312.031457) (xy 39.886307 -311.978833)
			(xy 39.905567 -311.928476) (xy 39.931953 -311.881459) (xy 39.964905 -311.838786) (xy 40.003718 -311.801365)
			(xy 40.047566 -311.769995) (xy 40.095514 -311.745343) (xy 40.146541 -311.727935) (xy 40.199559 -311.718142)
			(xy 40.253438 -311.716173) (xy 40.307029 -311.72207) (xy 40.35919 -311.735706) (xy 40.40881 -311.756793)
			(xy 40.454831 -311.784879) (xy 40.496273 -311.819367) (xy 40.532251 -311.859521) (xy 40.561999 -311.904485)
			(xy 40.584884 -311.953302) (xy 40.600416 -312.004931) (xy 40.608266 -312.058271) (xy 40.608758 -312.085228)
			(xy 40.608266 -312.112185) (xy 40.600416 -312.165525) (xy 40.584884 -312.217154) (xy 40.561999 -312.265971)
			(xy 40.532251 -312.310935) (xy 40.496273 -312.351089) (xy 40.454831 -312.385577) (xy 40.40881 -312.413663)
			(xy 40.35919 -312.43475) (xy 40.307029 -312.448386) (xy 40.253438 -312.454283) (xy 40.199559 -312.452314)
			(xy 40.146541 -312.442521) (xy 40.095514 -312.425113) (xy 40.047566 -312.400461) (xy 40.003718 -312.369091)
			(xy 39.964905 -312.33167) (xy 39.931953 -312.288997) (xy 39.905567 -312.24198) (xy 39.886307 -312.191623)
			(xy 39.874584 -312.138999) (xy 39.870649 -312.085228) (xy 33.064704 -312.085228) (xy 33.064212 -312.112185)
			(xy 33.056362 -312.165525) (xy 33.04083 -312.217154) (xy 33.017945 -312.265971) (xy 32.988197 -312.310935)
			(xy 32.952219 -312.351089) (xy 32.910777 -312.385577) (xy 32.864756 -312.413663) (xy 32.815136 -312.43475)
			(xy 32.762975 -312.448386) (xy 32.709384 -312.454283) (xy 32.655505 -312.452314) (xy 32.602487 -312.442521)
			(xy 32.55146 -312.425113) (xy 32.503512 -312.400461) (xy 32.459664 -312.369091) (xy 32.420851 -312.33167)
			(xy 32.387899 -312.288997) (xy 32.361513 -312.24198) (xy 32.342253 -312.191623) (xy 32.33053 -312.138999)
			(xy 32.326595 -312.085228) (xy 25.520904 -312.085228) (xy 25.520412 -312.112185) (xy 25.512562 -312.165525)
			(xy 25.49703 -312.217154) (xy 25.474145 -312.265971) (xy 25.444397 -312.310935) (xy 25.408419 -312.351089)
			(xy 25.366977 -312.385577) (xy 25.320956 -312.413663) (xy 25.271336 -312.43475) (xy 25.219175 -312.448386)
			(xy 25.165584 -312.454283) (xy 25.111705 -312.452314) (xy 25.058687 -312.442521) (xy 25.00766 -312.425113)
			(xy 24.959712 -312.400461) (xy 24.915864 -312.369091) (xy 24.877051 -312.33167) (xy 24.844099 -312.288997)
			(xy 24.817713 -312.24198) (xy 24.798453 -312.191623) (xy 24.78673 -312.138999) (xy 24.782795 -312.085228)
			(xy 17.97685 -312.085228) (xy 17.976358 -312.112185) (xy 17.968508 -312.165525) (xy 17.952976 -312.217154)
			(xy 17.930091 -312.265971) (xy 17.900343 -312.310935) (xy 17.864365 -312.351089) (xy 17.822923 -312.385577)
			(xy 17.776902 -312.413663) (xy 17.727282 -312.43475) (xy 17.675121 -312.448386) (xy 17.62153 -312.454283)
			(xy 17.567651 -312.452314) (xy 17.514633 -312.442521) (xy 17.463606 -312.425113) (xy 17.415658 -312.400461)
			(xy 17.37181 -312.369091) (xy 17.332997 -312.33167) (xy 17.300045 -312.288997) (xy 17.273659 -312.24198)
			(xy 17.254399 -312.191623) (xy 17.242676 -312.138999) (xy 17.238741 -312.085228) (xy 15.598394 -312.085228)
			(xy 15.598394 -312.935366) (xy 21.338809 -312.935366) (xy 21.342744 -312.881595) (xy 21.354467 -312.828971)
			(xy 21.373727 -312.778614) (xy 21.400113 -312.731597) (xy 21.433065 -312.688924) (xy 21.471878 -312.651503)
			(xy 21.515726 -312.620133) (xy 21.563674 -312.595481) (xy 21.614701 -312.578073) (xy 21.667719 -312.56828)
			(xy 21.721598 -312.566311) (xy 21.775189 -312.572208) (xy 21.82735 -312.585844) (xy 21.87697 -312.606931)
			(xy 21.922991 -312.635017) (xy 21.964433 -312.669505) (xy 22.000411 -312.709659) (xy 22.030159 -312.754623)
			(xy 22.053044 -312.80344) (xy 22.068576 -312.855069) (xy 22.076426 -312.908409) (xy 22.076918 -312.935366)
			(xy 28.882863 -312.935366) (xy 28.886798 -312.881595) (xy 28.898521 -312.828971) (xy 28.917781 -312.778614)
			(xy 28.944167 -312.731597) (xy 28.977119 -312.688924) (xy 29.015932 -312.651503) (xy 29.05978 -312.620133)
			(xy 29.107728 -312.595481) (xy 29.158755 -312.578073) (xy 29.211773 -312.56828) (xy 29.265652 -312.566311)
			(xy 29.319243 -312.572208) (xy 29.371404 -312.585844) (xy 29.421024 -312.606931) (xy 29.467045 -312.635017)
			(xy 29.508487 -312.669505) (xy 29.544465 -312.709659) (xy 29.574213 -312.754623) (xy 29.597098 -312.80344)
			(xy 29.61263 -312.855069) (xy 29.62048 -312.908409) (xy 29.620972 -312.935366) (xy 36.426663 -312.935366)
			(xy 36.430598 -312.881595) (xy 36.442321 -312.828971) (xy 36.461581 -312.778614) (xy 36.487967 -312.731597)
			(xy 36.520919 -312.688924) (xy 36.559732 -312.651503) (xy 36.60358 -312.620133) (xy 36.651528 -312.595481)
			(xy 36.702555 -312.578073) (xy 36.755573 -312.56828) (xy 36.809452 -312.566311) (xy 36.863043 -312.572208)
			(xy 36.915204 -312.585844) (xy 36.964824 -312.606931) (xy 37.010845 -312.635017) (xy 37.052287 -312.669505)
			(xy 37.088265 -312.709659) (xy 37.118013 -312.754623) (xy 37.140898 -312.80344) (xy 37.15643 -312.855069)
			(xy 37.16428 -312.908409) (xy 37.164772 -312.935366) (xy 43.970717 -312.935366) (xy 43.974652 -312.881595)
			(xy 43.986375 -312.828971) (xy 44.005635 -312.778614) (xy 44.032021 -312.731597) (xy 44.064973 -312.688924)
			(xy 44.103786 -312.651503) (xy 44.147634 -312.620133) (xy 44.195582 -312.595481) (xy 44.246609 -312.578073)
			(xy 44.299627 -312.56828) (xy 44.353506 -312.566311) (xy 44.407097 -312.572208) (xy 44.459258 -312.585844)
			(xy 44.508878 -312.606931) (xy 44.554899 -312.635017) (xy 44.596341 -312.669505) (xy 44.632319 -312.709659)
			(xy 44.662067 -312.754623) (xy 44.684952 -312.80344) (xy 44.700484 -312.855069) (xy 44.708334 -312.908409)
			(xy 44.708826 -312.935366) (xy 44.708334 -312.962323) (xy 44.700484 -313.015663) (xy 44.684952 -313.067292)
			(xy 44.662067 -313.116109) (xy 44.632319 -313.161073) (xy 44.596341 -313.201227) (xy 44.554899 -313.235715)
			(xy 44.508878 -313.263801) (xy 44.459258 -313.284888) (xy 44.407097 -313.298524) (xy 44.353506 -313.304421)
			(xy 44.299627 -313.302452) (xy 44.246609 -313.292659) (xy 44.195582 -313.275251) (xy 44.147634 -313.250599)
			(xy 44.103786 -313.219229) (xy 44.064973 -313.181808) (xy 44.032021 -313.139135) (xy 44.005635 -313.092118)
			(xy 43.986375 -313.041761) (xy 43.974652 -312.989137) (xy 43.970717 -312.935366) (xy 37.164772 -312.935366)
			(xy 37.16428 -312.962323) (xy 37.15643 -313.015663) (xy 37.140898 -313.067292) (xy 37.118013 -313.116109)
			(xy 37.088265 -313.161073) (xy 37.052287 -313.201227) (xy 37.010845 -313.235715) (xy 36.964824 -313.263801)
			(xy 36.915204 -313.284888) (xy 36.863043 -313.298524) (xy 36.809452 -313.304421) (xy 36.755573 -313.302452)
			(xy 36.702555 -313.292659) (xy 36.651528 -313.275251) (xy 36.60358 -313.250599) (xy 36.559732 -313.219229)
			(xy 36.520919 -313.181808) (xy 36.487967 -313.139135) (xy 36.461581 -313.092118) (xy 36.442321 -313.041761)
			(xy 36.430598 -312.989137) (xy 36.426663 -312.935366) (xy 29.620972 -312.935366) (xy 29.62048 -312.962323)
			(xy 29.61263 -313.015663) (xy 29.597098 -313.067292) (xy 29.574213 -313.116109) (xy 29.544465 -313.161073)
			(xy 29.508487 -313.201227) (xy 29.467045 -313.235715) (xy 29.421024 -313.263801) (xy 29.371404 -313.284888)
			(xy 29.319243 -313.298524) (xy 29.265652 -313.304421) (xy 29.211773 -313.302452) (xy 29.158755 -313.292659)
			(xy 29.107728 -313.275251) (xy 29.05978 -313.250599) (xy 29.015932 -313.219229) (xy 28.977119 -313.181808)
			(xy 28.944167 -313.139135) (xy 28.917781 -313.092118) (xy 28.898521 -313.041761) (xy 28.886798 -312.989137)
			(xy 28.882863 -312.935366) (xy 22.076918 -312.935366) (xy 22.076426 -312.962323) (xy 22.068576 -313.015663)
			(xy 22.053044 -313.067292) (xy 22.030159 -313.116109) (xy 22.000411 -313.161073) (xy 21.964433 -313.201227)
			(xy 21.922991 -313.235715) (xy 21.87697 -313.263801) (xy 21.82735 -313.284888) (xy 21.775189 -313.298524)
			(xy 21.721598 -313.304421) (xy 21.667719 -313.302452) (xy 21.614701 -313.292659) (xy 21.563674 -313.275251)
			(xy 21.515726 -313.250599) (xy 21.471878 -313.219229) (xy 21.433065 -313.181808) (xy 21.400113 -313.139135)
			(xy 21.373727 -313.092118) (xy 21.354467 -313.041761) (xy 21.342744 -312.989137) (xy 21.338809 -312.935366)
			(xy 15.598394 -312.935366) (xy 15.598394 -313.78525) (xy 17.238741 -313.78525) (xy 17.242676 -313.731479)
			(xy 17.254399 -313.678855) (xy 17.273659 -313.628498) (xy 17.300045 -313.581481) (xy 17.332997 -313.538808)
			(xy 17.37181 -313.501387) (xy 17.415658 -313.470017) (xy 17.463606 -313.445365) (xy 17.514633 -313.427957)
			(xy 17.567651 -313.418164) (xy 17.62153 -313.416195) (xy 17.675121 -313.422092) (xy 17.727282 -313.435728)
			(xy 17.776902 -313.456815) (xy 17.822923 -313.484901) (xy 17.864365 -313.519389) (xy 17.900343 -313.559543)
			(xy 17.930091 -313.604507) (xy 17.952976 -313.653324) (xy 17.968508 -313.704953) (xy 17.976358 -313.758293)
			(xy 17.97685 -313.78525) (xy 21.338809 -313.78525) (xy 21.342744 -313.731479) (xy 21.354467 -313.678855)
			(xy 21.373727 -313.628498) (xy 21.400113 -313.581481) (xy 21.433065 -313.538808) (xy 21.471878 -313.501387)
			(xy 21.515726 -313.470017) (xy 21.563674 -313.445365) (xy 21.614701 -313.427957) (xy 21.667719 -313.418164)
			(xy 21.721598 -313.416195) (xy 21.775189 -313.422092) (xy 21.82735 -313.435728) (xy 21.87697 -313.456815)
			(xy 21.922991 -313.484901) (xy 21.964433 -313.519389) (xy 22.000411 -313.559543) (xy 22.030159 -313.604507)
			(xy 22.053044 -313.653324) (xy 22.068576 -313.704953) (xy 22.076426 -313.758293) (xy 22.076918 -313.78525)
			(xy 24.782795 -313.78525) (xy 24.78673 -313.731479) (xy 24.798453 -313.678855) (xy 24.817713 -313.628498)
			(xy 24.844099 -313.581481) (xy 24.877051 -313.538808) (xy 24.915864 -313.501387) (xy 24.959712 -313.470017)
			(xy 25.00766 -313.445365) (xy 25.058687 -313.427957) (xy 25.111705 -313.418164) (xy 25.165584 -313.416195)
			(xy 25.219175 -313.422092) (xy 25.271336 -313.435728) (xy 25.320956 -313.456815) (xy 25.366977 -313.484901)
			(xy 25.408419 -313.519389) (xy 25.444397 -313.559543) (xy 25.474145 -313.604507) (xy 25.49703 -313.653324)
			(xy 25.512562 -313.704953) (xy 25.520412 -313.758293) (xy 25.520904 -313.78525) (xy 28.882863 -313.78525)
			(xy 28.886798 -313.731479) (xy 28.898521 -313.678855) (xy 28.917781 -313.628498) (xy 28.944167 -313.581481)
			(xy 28.977119 -313.538808) (xy 29.015932 -313.501387) (xy 29.05978 -313.470017) (xy 29.107728 -313.445365)
			(xy 29.158755 -313.427957) (xy 29.211773 -313.418164) (xy 29.265652 -313.416195) (xy 29.319243 -313.422092)
			(xy 29.371404 -313.435728) (xy 29.421024 -313.456815) (xy 29.467045 -313.484901) (xy 29.508487 -313.519389)
			(xy 29.544465 -313.559543) (xy 29.574213 -313.604507) (xy 29.597098 -313.653324) (xy 29.61263 -313.704953)
			(xy 29.62048 -313.758293) (xy 29.620972 -313.78525) (xy 32.326595 -313.78525) (xy 32.33053 -313.731479)
			(xy 32.342253 -313.678855) (xy 32.361513 -313.628498) (xy 32.387899 -313.581481) (xy 32.420851 -313.538808)
			(xy 32.459664 -313.501387) (xy 32.503512 -313.470017) (xy 32.55146 -313.445365) (xy 32.602487 -313.427957)
			(xy 32.655505 -313.418164) (xy 32.709384 -313.416195) (xy 32.762975 -313.422092) (xy 32.815136 -313.435728)
			(xy 32.864756 -313.456815) (xy 32.910777 -313.484901) (xy 32.952219 -313.519389) (xy 32.988197 -313.559543)
			(xy 33.017945 -313.604507) (xy 33.04083 -313.653324) (xy 33.056362 -313.704953) (xy 33.064212 -313.758293)
			(xy 33.064704 -313.78525) (xy 36.426663 -313.78525) (xy 36.430598 -313.731479) (xy 36.442321 -313.678855)
			(xy 36.461581 -313.628498) (xy 36.487967 -313.581481) (xy 36.520919 -313.538808) (xy 36.559732 -313.501387)
			(xy 36.60358 -313.470017) (xy 36.651528 -313.445365) (xy 36.702555 -313.427957) (xy 36.755573 -313.418164)
			(xy 36.809452 -313.416195) (xy 36.863043 -313.422092) (xy 36.915204 -313.435728) (xy 36.964824 -313.456815)
			(xy 37.010845 -313.484901) (xy 37.052287 -313.519389) (xy 37.088265 -313.559543) (xy 37.118013 -313.604507)
			(xy 37.140898 -313.653324) (xy 37.15643 -313.704953) (xy 37.16428 -313.758293) (xy 37.164772 -313.78525)
			(xy 39.870649 -313.78525) (xy 39.874584 -313.731479) (xy 39.886307 -313.678855) (xy 39.905567 -313.628498)
			(xy 39.931953 -313.581481) (xy 39.964905 -313.538808) (xy 40.003718 -313.501387) (xy 40.047566 -313.470017)
			(xy 40.095514 -313.445365) (xy 40.146541 -313.427957) (xy 40.199559 -313.418164) (xy 40.253438 -313.416195)
			(xy 40.307029 -313.422092) (xy 40.35919 -313.435728) (xy 40.40881 -313.456815) (xy 40.454831 -313.484901)
			(xy 40.496273 -313.519389) (xy 40.532251 -313.559543) (xy 40.561999 -313.604507) (xy 40.584884 -313.653324)
			(xy 40.600416 -313.704953) (xy 40.608266 -313.758293) (xy 40.608758 -313.78525) (xy 43.970717 -313.78525)
			(xy 43.974652 -313.731479) (xy 43.986375 -313.678855) (xy 44.005635 -313.628498) (xy 44.032021 -313.581481)
			(xy 44.064973 -313.538808) (xy 44.103786 -313.501387) (xy 44.147634 -313.470017) (xy 44.195582 -313.445365)
			(xy 44.246609 -313.427957) (xy 44.299627 -313.418164) (xy 44.353506 -313.416195) (xy 44.407097 -313.422092)
			(xy 44.459258 -313.435728) (xy 44.508878 -313.456815) (xy 44.554899 -313.484901) (xy 44.596341 -313.519389)
			(xy 44.632319 -313.559543) (xy 44.662067 -313.604507) (xy 44.684952 -313.653324) (xy 44.700484 -313.704953)
			(xy 44.708334 -313.758293) (xy 44.708826 -313.78525) (xy 44.708334 -313.812207) (xy 44.700484 -313.865547)
			(xy 44.684952 -313.917176) (xy 44.662067 -313.965993) (xy 44.632319 -314.010957) (xy 44.596341 -314.051111)
			(xy 44.554899 -314.085599) (xy 44.508878 -314.113685) (xy 44.459258 -314.134772) (xy 44.407097 -314.148408)
			(xy 44.353506 -314.154305) (xy 44.299627 -314.152336) (xy 44.246609 -314.142543) (xy 44.195582 -314.125135)
			(xy 44.147634 -314.100483) (xy 44.103786 -314.069113) (xy 44.064973 -314.031692) (xy 44.032021 -313.989019)
			(xy 44.005635 -313.942002) (xy 43.986375 -313.891645) (xy 43.974652 -313.839021) (xy 43.970717 -313.78525)
			(xy 40.608758 -313.78525) (xy 40.608266 -313.812207) (xy 40.600416 -313.865547) (xy 40.584884 -313.917176)
			(xy 40.561999 -313.965993) (xy 40.532251 -314.010957) (xy 40.496273 -314.051111) (xy 40.454831 -314.085599)
			(xy 40.40881 -314.113685) (xy 40.35919 -314.134772) (xy 40.307029 -314.148408) (xy 40.253438 -314.154305)
			(xy 40.199559 -314.152336) (xy 40.146541 -314.142543) (xy 40.095514 -314.125135) (xy 40.047566 -314.100483)
			(xy 40.003718 -314.069113) (xy 39.964905 -314.031692) (xy 39.931953 -313.989019) (xy 39.905567 -313.942002)
			(xy 39.886307 -313.891645) (xy 39.874584 -313.839021) (xy 39.870649 -313.78525) (xy 37.164772 -313.78525)
			(xy 37.16428 -313.812207) (xy 37.15643 -313.865547) (xy 37.140898 -313.917176) (xy 37.118013 -313.965993)
			(xy 37.088265 -314.010957) (xy 37.052287 -314.051111) (xy 37.010845 -314.085599) (xy 36.964824 -314.113685)
			(xy 36.915204 -314.134772) (xy 36.863043 -314.148408) (xy 36.809452 -314.154305) (xy 36.755573 -314.152336)
			(xy 36.702555 -314.142543) (xy 36.651528 -314.125135) (xy 36.60358 -314.100483) (xy 36.559732 -314.069113)
			(xy 36.520919 -314.031692) (xy 36.487967 -313.989019) (xy 36.461581 -313.942002) (xy 36.442321 -313.891645)
			(xy 36.430598 -313.839021) (xy 36.426663 -313.78525) (xy 33.064704 -313.78525) (xy 33.064212 -313.812207)
			(xy 33.056362 -313.865547) (xy 33.04083 -313.917176) (xy 33.017945 -313.965993) (xy 32.988197 -314.010957)
			(xy 32.952219 -314.051111) (xy 32.910777 -314.085599) (xy 32.864756 -314.113685) (xy 32.815136 -314.134772)
			(xy 32.762975 -314.148408) (xy 32.709384 -314.154305) (xy 32.655505 -314.152336) (xy 32.602487 -314.142543)
			(xy 32.55146 -314.125135) (xy 32.503512 -314.100483) (xy 32.459664 -314.069113) (xy 32.420851 -314.031692)
			(xy 32.387899 -313.989019) (xy 32.361513 -313.942002) (xy 32.342253 -313.891645) (xy 32.33053 -313.839021)
			(xy 32.326595 -313.78525) (xy 29.620972 -313.78525) (xy 29.62048 -313.812207) (xy 29.61263 -313.865547)
			(xy 29.597098 -313.917176) (xy 29.574213 -313.965993) (xy 29.544465 -314.010957) (xy 29.508487 -314.051111)
			(xy 29.467045 -314.085599) (xy 29.421024 -314.113685) (xy 29.371404 -314.134772) (xy 29.319243 -314.148408)
			(xy 29.265652 -314.154305) (xy 29.211773 -314.152336) (xy 29.158755 -314.142543) (xy 29.107728 -314.125135)
			(xy 29.05978 -314.100483) (xy 29.015932 -314.069113) (xy 28.977119 -314.031692) (xy 28.944167 -313.989019)
			(xy 28.917781 -313.942002) (xy 28.898521 -313.891645) (xy 28.886798 -313.839021) (xy 28.882863 -313.78525)
			(xy 25.520904 -313.78525) (xy 25.520412 -313.812207) (xy 25.512562 -313.865547) (xy 25.49703 -313.917176)
			(xy 25.474145 -313.965993) (xy 25.444397 -314.010957) (xy 25.408419 -314.051111) (xy 25.366977 -314.085599)
			(xy 25.320956 -314.113685) (xy 25.271336 -314.134772) (xy 25.219175 -314.148408) (xy 25.165584 -314.154305)
			(xy 25.111705 -314.152336) (xy 25.058687 -314.142543) (xy 25.00766 -314.125135) (xy 24.959712 -314.100483)
			(xy 24.915864 -314.069113) (xy 24.877051 -314.031692) (xy 24.844099 -313.989019) (xy 24.817713 -313.942002)
			(xy 24.798453 -313.891645) (xy 24.78673 -313.839021) (xy 24.782795 -313.78525) (xy 22.076918 -313.78525)
			(xy 22.076426 -313.812207) (xy 22.068576 -313.865547) (xy 22.053044 -313.917176) (xy 22.030159 -313.965993)
			(xy 22.000411 -314.010957) (xy 21.964433 -314.051111) (xy 21.922991 -314.085599) (xy 21.87697 -314.113685)
			(xy 21.82735 -314.134772) (xy 21.775189 -314.148408) (xy 21.721598 -314.154305) (xy 21.667719 -314.152336)
			(xy 21.614701 -314.142543) (xy 21.563674 -314.125135) (xy 21.515726 -314.100483) (xy 21.471878 -314.069113)
			(xy 21.433065 -314.031692) (xy 21.400113 -313.989019) (xy 21.373727 -313.942002) (xy 21.354467 -313.891645)
			(xy 21.342744 -313.839021) (xy 21.338809 -313.78525) (xy 17.97685 -313.78525) (xy 17.976358 -313.812207)
			(xy 17.968508 -313.865547) (xy 17.952976 -313.917176) (xy 17.930091 -313.965993) (xy 17.900343 -314.010957)
			(xy 17.864365 -314.051111) (xy 17.822923 -314.085599) (xy 17.776902 -314.113685) (xy 17.727282 -314.134772)
			(xy 17.675121 -314.148408) (xy 17.62153 -314.154305) (xy 17.567651 -314.152336) (xy 17.514633 -314.142543)
			(xy 17.463606 -314.125135) (xy 17.415658 -314.100483) (xy 17.37181 -314.069113) (xy 17.332997 -314.031692)
			(xy 17.300045 -313.989019) (xy 17.273659 -313.942002) (xy 17.254399 -313.891645) (xy 17.242676 -313.839021)
			(xy 17.238741 -313.78525) (xy 15.598394 -313.78525) (xy 15.598394 -314.635388) (xy 17.238741 -314.635388)
			(xy 17.242676 -314.581617) (xy 17.254399 -314.528993) (xy 17.273659 -314.478636) (xy 17.300045 -314.431619)
			(xy 17.332997 -314.388946) (xy 17.37181 -314.351525) (xy 17.415658 -314.320155) (xy 17.463606 -314.295503)
			(xy 17.514633 -314.278095) (xy 17.567651 -314.268302) (xy 17.62153 -314.266333) (xy 17.675121 -314.27223)
			(xy 17.727282 -314.285866) (xy 17.776902 -314.306953) (xy 17.822923 -314.335039) (xy 17.864365 -314.369527)
			(xy 17.900343 -314.409681) (xy 17.930091 -314.454645) (xy 17.952976 -314.503462) (xy 17.968508 -314.555091)
			(xy 17.976358 -314.608431) (xy 17.97685 -314.635388) (xy 24.782795 -314.635388) (xy 24.78673 -314.581617)
			(xy 24.798453 -314.528993) (xy 24.817713 -314.478636) (xy 24.844099 -314.431619) (xy 24.877051 -314.388946)
			(xy 24.915864 -314.351525) (xy 24.959712 -314.320155) (xy 25.00766 -314.295503) (xy 25.058687 -314.278095)
			(xy 25.111705 -314.268302) (xy 25.165584 -314.266333) (xy 25.219175 -314.27223) (xy 25.271336 -314.285866)
			(xy 25.320956 -314.306953) (xy 25.366977 -314.335039) (xy 25.408419 -314.369527) (xy 25.444397 -314.409681)
			(xy 25.474145 -314.454645) (xy 25.49703 -314.503462) (xy 25.512562 -314.555091) (xy 25.520412 -314.608431)
			(xy 25.520904 -314.635388) (xy 32.326595 -314.635388) (xy 32.33053 -314.581617) (xy 32.342253 -314.528993)
			(xy 32.361513 -314.478636) (xy 32.387899 -314.431619) (xy 32.420851 -314.388946) (xy 32.459664 -314.351525)
			(xy 32.503512 -314.320155) (xy 32.55146 -314.295503) (xy 32.602487 -314.278095) (xy 32.655505 -314.268302)
			(xy 32.709384 -314.266333) (xy 32.762975 -314.27223) (xy 32.815136 -314.285866) (xy 32.864756 -314.306953)
			(xy 32.910777 -314.335039) (xy 32.952219 -314.369527) (xy 32.988197 -314.409681) (xy 33.017945 -314.454645)
			(xy 33.04083 -314.503462) (xy 33.056362 -314.555091) (xy 33.064212 -314.608431) (xy 33.064704 -314.635388)
			(xy 39.870649 -314.635388) (xy 39.874584 -314.581617) (xy 39.886307 -314.528993) (xy 39.905567 -314.478636)
			(xy 39.931953 -314.431619) (xy 39.964905 -314.388946) (xy 40.003718 -314.351525) (xy 40.047566 -314.320155)
			(xy 40.095514 -314.295503) (xy 40.146541 -314.278095) (xy 40.199559 -314.268302) (xy 40.253438 -314.266333)
			(xy 40.307029 -314.27223) (xy 40.35919 -314.285866) (xy 40.40881 -314.306953) (xy 40.454831 -314.335039)
			(xy 40.496273 -314.369527) (xy 40.532251 -314.409681) (xy 40.561999 -314.454645) (xy 40.584884 -314.503462)
			(xy 40.600416 -314.555091) (xy 40.608266 -314.608431) (xy 40.608758 -314.635388) (xy 40.608266 -314.662345)
			(xy 40.600416 -314.715685) (xy 40.584884 -314.767314) (xy 40.561999 -314.816131) (xy 40.532251 -314.861095)
			(xy 40.496273 -314.901249) (xy 40.454831 -314.935737) (xy 40.40881 -314.963823) (xy 40.35919 -314.98491)
			(xy 40.307029 -314.998546) (xy 40.253438 -315.004443) (xy 40.199559 -315.002474) (xy 40.146541 -314.992681)
			(xy 40.095514 -314.975273) (xy 40.047566 -314.950621) (xy 40.003718 -314.919251) (xy 39.964905 -314.88183)
			(xy 39.931953 -314.839157) (xy 39.905567 -314.79214) (xy 39.886307 -314.741783) (xy 39.874584 -314.689159)
			(xy 39.870649 -314.635388) (xy 33.064704 -314.635388) (xy 33.064212 -314.662345) (xy 33.056362 -314.715685)
			(xy 33.04083 -314.767314) (xy 33.017945 -314.816131) (xy 32.988197 -314.861095) (xy 32.952219 -314.901249)
			(xy 32.910777 -314.935737) (xy 32.864756 -314.963823) (xy 32.815136 -314.98491) (xy 32.762975 -314.998546)
			(xy 32.709384 -315.004443) (xy 32.655505 -315.002474) (xy 32.602487 -314.992681) (xy 32.55146 -314.975273)
			(xy 32.503512 -314.950621) (xy 32.459664 -314.919251) (xy 32.420851 -314.88183) (xy 32.387899 -314.839157)
			(xy 32.361513 -314.79214) (xy 32.342253 -314.741783) (xy 32.33053 -314.689159) (xy 32.326595 -314.635388)
			(xy 25.520904 -314.635388) (xy 25.520412 -314.662345) (xy 25.512562 -314.715685) (xy 25.49703 -314.767314)
			(xy 25.474145 -314.816131) (xy 25.444397 -314.861095) (xy 25.408419 -314.901249) (xy 25.366977 -314.935737)
			(xy 25.320956 -314.963823) (xy 25.271336 -314.98491) (xy 25.219175 -314.998546) (xy 25.165584 -315.004443)
			(xy 25.111705 -315.002474) (xy 25.058687 -314.992681) (xy 25.00766 -314.975273) (xy 24.959712 -314.950621)
			(xy 24.915864 -314.919251) (xy 24.877051 -314.88183) (xy 24.844099 -314.839157) (xy 24.817713 -314.79214)
			(xy 24.798453 -314.741783) (xy 24.78673 -314.689159) (xy 24.782795 -314.635388) (xy 17.97685 -314.635388)
			(xy 17.976358 -314.662345) (xy 17.968508 -314.715685) (xy 17.952976 -314.767314) (xy 17.930091 -314.816131)
			(xy 17.900343 -314.861095) (xy 17.864365 -314.901249) (xy 17.822923 -314.935737) (xy 17.776902 -314.963823)
			(xy 17.727282 -314.98491) (xy 17.675121 -314.998546) (xy 17.62153 -315.004443) (xy 17.567651 -315.002474)
			(xy 17.514633 -314.992681) (xy 17.463606 -314.975273) (xy 17.415658 -314.950621) (xy 17.37181 -314.919251)
			(xy 17.332997 -314.88183) (xy 17.300045 -314.839157) (xy 17.273659 -314.79214) (xy 17.254399 -314.741783)
			(xy 17.242676 -314.689159) (xy 17.238741 -314.635388) (xy 15.598394 -314.635388) (xy 15.598394 -315.485272)
			(xy 21.338809 -315.485272) (xy 21.342744 -315.431501) (xy 21.354467 -315.378877) (xy 21.373727 -315.32852)
			(xy 21.400113 -315.281503) (xy 21.433065 -315.23883) (xy 21.471878 -315.201409) (xy 21.515726 -315.170039)
			(xy 21.563674 -315.145387) (xy 21.614701 -315.127979) (xy 21.667719 -315.118186) (xy 21.721598 -315.116217)
			(xy 21.775189 -315.122114) (xy 21.82735 -315.13575) (xy 21.87697 -315.156837) (xy 21.922991 -315.184923)
			(xy 21.964433 -315.219411) (xy 22.000411 -315.259565) (xy 22.030159 -315.304529) (xy 22.053044 -315.353346)
			(xy 22.068576 -315.404975) (xy 22.076426 -315.458315) (xy 22.076918 -315.485272) (xy 28.882863 -315.485272)
			(xy 28.886798 -315.431501) (xy 28.898521 -315.378877) (xy 28.917781 -315.32852) (xy 28.944167 -315.281503)
			(xy 28.977119 -315.23883) (xy 29.015932 -315.201409) (xy 29.05978 -315.170039) (xy 29.107728 -315.145387)
			(xy 29.158755 -315.127979) (xy 29.211773 -315.118186) (xy 29.265652 -315.116217) (xy 29.319243 -315.122114)
			(xy 29.371404 -315.13575) (xy 29.421024 -315.156837) (xy 29.467045 -315.184923) (xy 29.508487 -315.219411)
			(xy 29.544465 -315.259565) (xy 29.574213 -315.304529) (xy 29.597098 -315.353346) (xy 29.61263 -315.404975)
			(xy 29.62048 -315.458315) (xy 29.620972 -315.485272) (xy 36.426663 -315.485272) (xy 36.430598 -315.431501)
			(xy 36.442321 -315.378877) (xy 36.461581 -315.32852) (xy 36.487967 -315.281503) (xy 36.520919 -315.23883)
			(xy 36.559732 -315.201409) (xy 36.60358 -315.170039) (xy 36.651528 -315.145387) (xy 36.702555 -315.127979)
			(xy 36.755573 -315.118186) (xy 36.809452 -315.116217) (xy 36.863043 -315.122114) (xy 36.915204 -315.13575)
			(xy 36.964824 -315.156837) (xy 37.010845 -315.184923) (xy 37.052287 -315.219411) (xy 37.088265 -315.259565)
			(xy 37.118013 -315.304529) (xy 37.140898 -315.353346) (xy 37.15643 -315.404975) (xy 37.16428 -315.458315)
			(xy 37.164772 -315.485272) (xy 43.970717 -315.485272) (xy 43.974652 -315.431501) (xy 43.986375 -315.378877)
			(xy 44.005635 -315.32852) (xy 44.032021 -315.281503) (xy 44.064973 -315.23883) (xy 44.103786 -315.201409)
			(xy 44.147634 -315.170039) (xy 44.195582 -315.145387) (xy 44.246609 -315.127979) (xy 44.299627 -315.118186)
			(xy 44.353506 -315.116217) (xy 44.407097 -315.122114) (xy 44.459258 -315.13575) (xy 44.508878 -315.156837)
			(xy 44.554899 -315.184923) (xy 44.596341 -315.219411) (xy 44.632319 -315.259565) (xy 44.662067 -315.304529)
			(xy 44.684952 -315.353346) (xy 44.700484 -315.404975) (xy 44.708334 -315.458315) (xy 44.708826 -315.485272)
			(xy 44.708334 -315.512229) (xy 44.700484 -315.565569) (xy 44.684952 -315.617198) (xy 44.662067 -315.666015)
			(xy 44.632319 -315.710979) (xy 44.596341 -315.751133) (xy 44.554899 -315.785621) (xy 44.508878 -315.813707)
			(xy 44.459258 -315.834794) (xy 44.407097 -315.84843) (xy 44.353506 -315.854327) (xy 44.299627 -315.852358)
			(xy 44.246609 -315.842565) (xy 44.195582 -315.825157) (xy 44.147634 -315.800505) (xy 44.103786 -315.769135)
			(xy 44.064973 -315.731714) (xy 44.032021 -315.689041) (xy 44.005635 -315.642024) (xy 43.986375 -315.591667)
			(xy 43.974652 -315.539043) (xy 43.970717 -315.485272) (xy 37.164772 -315.485272) (xy 37.16428 -315.512229)
			(xy 37.15643 -315.565569) (xy 37.140898 -315.617198) (xy 37.118013 -315.666015) (xy 37.088265 -315.710979)
			(xy 37.052287 -315.751133) (xy 37.010845 -315.785621) (xy 36.964824 -315.813707) (xy 36.915204 -315.834794)
			(xy 36.863043 -315.84843) (xy 36.809452 -315.854327) (xy 36.755573 -315.852358) (xy 36.702555 -315.842565)
			(xy 36.651528 -315.825157) (xy 36.60358 -315.800505) (xy 36.559732 -315.769135) (xy 36.520919 -315.731714)
			(xy 36.487967 -315.689041) (xy 36.461581 -315.642024) (xy 36.442321 -315.591667) (xy 36.430598 -315.539043)
			(xy 36.426663 -315.485272) (xy 29.620972 -315.485272) (xy 29.62048 -315.512229) (xy 29.61263 -315.565569)
			(xy 29.597098 -315.617198) (xy 29.574213 -315.666015) (xy 29.544465 -315.710979) (xy 29.508487 -315.751133)
			(xy 29.467045 -315.785621) (xy 29.421024 -315.813707) (xy 29.371404 -315.834794) (xy 29.319243 -315.84843)
			(xy 29.265652 -315.854327) (xy 29.211773 -315.852358) (xy 29.158755 -315.842565) (xy 29.107728 -315.825157)
			(xy 29.05978 -315.800505) (xy 29.015932 -315.769135) (xy 28.977119 -315.731714) (xy 28.944167 -315.689041)
			(xy 28.917781 -315.642024) (xy 28.898521 -315.591667) (xy 28.886798 -315.539043) (xy 28.882863 -315.485272)
			(xy 22.076918 -315.485272) (xy 22.076426 -315.512229) (xy 22.068576 -315.565569) (xy 22.053044 -315.617198)
			(xy 22.030159 -315.666015) (xy 22.000411 -315.710979) (xy 21.964433 -315.751133) (xy 21.922991 -315.785621)
			(xy 21.87697 -315.813707) (xy 21.82735 -315.834794) (xy 21.775189 -315.84843) (xy 21.721598 -315.854327)
			(xy 21.667719 -315.852358) (xy 21.614701 -315.842565) (xy 21.563674 -315.825157) (xy 21.515726 -315.800505)
			(xy 21.471878 -315.769135) (xy 21.433065 -315.731714) (xy 21.400113 -315.689041) (xy 21.373727 -315.642024)
			(xy 21.354467 -315.591667) (xy 21.342744 -315.539043) (xy 21.338809 -315.485272) (xy 15.598394 -315.485272)
			(xy 15.598394 -316.33541) (xy 17.238741 -316.33541) (xy 17.242676 -316.281639) (xy 17.254399 -316.229015)
			(xy 17.273659 -316.178658) (xy 17.300045 -316.131641) (xy 17.332997 -316.088968) (xy 17.37181 -316.051547)
			(xy 17.415658 -316.020177) (xy 17.463606 -315.995525) (xy 17.514633 -315.978117) (xy 17.567651 -315.968324)
			(xy 17.62153 -315.966355) (xy 17.675121 -315.972252) (xy 17.727282 -315.985888) (xy 17.776902 -316.006975)
			(xy 17.822923 -316.035061) (xy 17.864365 -316.069549) (xy 17.900343 -316.109703) (xy 17.930091 -316.154667)
			(xy 17.952976 -316.203484) (xy 17.968508 -316.255113) (xy 17.976358 -316.308453) (xy 17.97685 -316.33541)
			(xy 24.782795 -316.33541) (xy 24.78673 -316.281639) (xy 24.798453 -316.229015) (xy 24.817713 -316.178658)
			(xy 24.844099 -316.131641) (xy 24.877051 -316.088968) (xy 24.915864 -316.051547) (xy 24.959712 -316.020177)
			(xy 25.00766 -315.995525) (xy 25.058687 -315.978117) (xy 25.111705 -315.968324) (xy 25.165584 -315.966355)
			(xy 25.219175 -315.972252) (xy 25.271336 -315.985888) (xy 25.320956 -316.006975) (xy 25.366977 -316.035061)
			(xy 25.408419 -316.069549) (xy 25.444397 -316.109703) (xy 25.474145 -316.154667) (xy 25.49703 -316.203484)
			(xy 25.512562 -316.255113) (xy 25.520412 -316.308453) (xy 25.520904 -316.33541) (xy 32.326595 -316.33541)
			(xy 32.33053 -316.281639) (xy 32.342253 -316.229015) (xy 32.361513 -316.178658) (xy 32.387899 -316.131641)
			(xy 32.420851 -316.088968) (xy 32.459664 -316.051547) (xy 32.503512 -316.020177) (xy 32.55146 -315.995525)
			(xy 32.602487 -315.978117) (xy 32.655505 -315.968324) (xy 32.709384 -315.966355) (xy 32.762975 -315.972252)
			(xy 32.815136 -315.985888) (xy 32.864756 -316.006975) (xy 32.910777 -316.035061) (xy 32.952219 -316.069549)
			(xy 32.988197 -316.109703) (xy 33.017945 -316.154667) (xy 33.04083 -316.203484) (xy 33.056362 -316.255113)
			(xy 33.064212 -316.308453) (xy 33.064704 -316.33541) (xy 39.870649 -316.33541) (xy 39.874584 -316.281639)
			(xy 39.886307 -316.229015) (xy 39.905567 -316.178658) (xy 39.931953 -316.131641) (xy 39.964905 -316.088968)
			(xy 40.003718 -316.051547) (xy 40.047566 -316.020177) (xy 40.095514 -315.995525) (xy 40.146541 -315.978117)
			(xy 40.199559 -315.968324) (xy 40.253438 -315.966355) (xy 40.307029 -315.972252) (xy 40.35919 -315.985888)
			(xy 40.40881 -316.006975) (xy 40.454831 -316.035061) (xy 40.496273 -316.069549) (xy 40.532251 -316.109703)
			(xy 40.561999 -316.154667) (xy 40.584884 -316.203484) (xy 40.600416 -316.255113) (xy 40.608266 -316.308453)
			(xy 40.608758 -316.33541) (xy 40.608266 -316.362367) (xy 40.600416 -316.415707) (xy 40.584884 -316.467336)
			(xy 40.561999 -316.516153) (xy 40.532251 -316.561117) (xy 40.496273 -316.601271) (xy 40.454831 -316.635759)
			(xy 40.40881 -316.663845) (xy 40.35919 -316.684932) (xy 40.307029 -316.698568) (xy 40.253438 -316.704465)
			(xy 40.199559 -316.702496) (xy 40.146541 -316.692703) (xy 40.095514 -316.675295) (xy 40.047566 -316.650643)
			(xy 40.003718 -316.619273) (xy 39.964905 -316.581852) (xy 39.931953 -316.539179) (xy 39.905567 -316.492162)
			(xy 39.886307 -316.441805) (xy 39.874584 -316.389181) (xy 39.870649 -316.33541) (xy 33.064704 -316.33541)
			(xy 33.064212 -316.362367) (xy 33.056362 -316.415707) (xy 33.04083 -316.467336) (xy 33.017945 -316.516153)
			(xy 32.988197 -316.561117) (xy 32.952219 -316.601271) (xy 32.910777 -316.635759) (xy 32.864756 -316.663845)
			(xy 32.815136 -316.684932) (xy 32.762975 -316.698568) (xy 32.709384 -316.704465) (xy 32.655505 -316.702496)
			(xy 32.602487 -316.692703) (xy 32.55146 -316.675295) (xy 32.503512 -316.650643) (xy 32.459664 -316.619273)
			(xy 32.420851 -316.581852) (xy 32.387899 -316.539179) (xy 32.361513 -316.492162) (xy 32.342253 -316.441805)
			(xy 32.33053 -316.389181) (xy 32.326595 -316.33541) (xy 25.520904 -316.33541) (xy 25.520412 -316.362367)
			(xy 25.512562 -316.415707) (xy 25.49703 -316.467336) (xy 25.474145 -316.516153) (xy 25.444397 -316.561117)
			(xy 25.408419 -316.601271) (xy 25.366977 -316.635759) (xy 25.320956 -316.663845) (xy 25.271336 -316.684932)
			(xy 25.219175 -316.698568) (xy 25.165584 -316.704465) (xy 25.111705 -316.702496) (xy 25.058687 -316.692703)
			(xy 25.00766 -316.675295) (xy 24.959712 -316.650643) (xy 24.915864 -316.619273) (xy 24.877051 -316.581852)
			(xy 24.844099 -316.539179) (xy 24.817713 -316.492162) (xy 24.798453 -316.441805) (xy 24.78673 -316.389181)
			(xy 24.782795 -316.33541) (xy 17.97685 -316.33541) (xy 17.976358 -316.362367) (xy 17.968508 -316.415707)
			(xy 17.952976 -316.467336) (xy 17.930091 -316.516153) (xy 17.900343 -316.561117) (xy 17.864365 -316.601271)
			(xy 17.822923 -316.635759) (xy 17.776902 -316.663845) (xy 17.727282 -316.684932) (xy 17.675121 -316.698568)
			(xy 17.62153 -316.704465) (xy 17.567651 -316.702496) (xy 17.514633 -316.692703) (xy 17.463606 -316.675295)
			(xy 17.415658 -316.650643) (xy 17.37181 -316.619273) (xy 17.332997 -316.581852) (xy 17.300045 -316.539179)
			(xy 17.273659 -316.492162) (xy 17.254399 -316.441805) (xy 17.242676 -316.389181) (xy 17.238741 -316.33541)
			(xy 15.598394 -316.33541) (xy 15.598394 -317.185294) (xy 21.338809 -317.185294) (xy 21.342744 -317.131523)
			(xy 21.354467 -317.078899) (xy 21.373727 -317.028542) (xy 21.400113 -316.981525) (xy 21.433065 -316.938852)
			(xy 21.471878 -316.901431) (xy 21.515726 -316.870061) (xy 21.563674 -316.845409) (xy 21.614701 -316.828001)
			(xy 21.667719 -316.818208) (xy 21.721598 -316.816239) (xy 21.775189 -316.822136) (xy 21.82735 -316.835772)
			(xy 21.87697 -316.856859) (xy 21.922991 -316.884945) (xy 21.964433 -316.919433) (xy 22.000411 -316.959587)
			(xy 22.030159 -317.004551) (xy 22.053044 -317.053368) (xy 22.068576 -317.104997) (xy 22.076426 -317.158337)
			(xy 22.076918 -317.185294) (xy 28.882863 -317.185294) (xy 28.886798 -317.131523) (xy 28.898521 -317.078899)
			(xy 28.917781 -317.028542) (xy 28.944167 -316.981525) (xy 28.977119 -316.938852) (xy 29.015932 -316.901431)
			(xy 29.05978 -316.870061) (xy 29.107728 -316.845409) (xy 29.158755 -316.828001) (xy 29.211773 -316.818208)
			(xy 29.265652 -316.816239) (xy 29.319243 -316.822136) (xy 29.371404 -316.835772) (xy 29.421024 -316.856859)
			(xy 29.467045 -316.884945) (xy 29.508487 -316.919433) (xy 29.544465 -316.959587) (xy 29.574213 -317.004551)
			(xy 29.597098 -317.053368) (xy 29.61263 -317.104997) (xy 29.62048 -317.158337) (xy 29.620972 -317.185294)
			(xy 36.426663 -317.185294) (xy 36.430598 -317.131523) (xy 36.442321 -317.078899) (xy 36.461581 -317.028542)
			(xy 36.487967 -316.981525) (xy 36.520919 -316.938852) (xy 36.559732 -316.901431) (xy 36.60358 -316.870061)
			(xy 36.651528 -316.845409) (xy 36.702555 -316.828001) (xy 36.755573 -316.818208) (xy 36.809452 -316.816239)
			(xy 36.863043 -316.822136) (xy 36.915204 -316.835772) (xy 36.964824 -316.856859) (xy 37.010845 -316.884945)
			(xy 37.052287 -316.919433) (xy 37.088265 -316.959587) (xy 37.118013 -317.004551) (xy 37.140898 -317.053368)
			(xy 37.15643 -317.104997) (xy 37.16428 -317.158337) (xy 37.164772 -317.185294) (xy 43.970717 -317.185294)
			(xy 43.974652 -317.131523) (xy 43.986375 -317.078899) (xy 44.005635 -317.028542) (xy 44.032021 -316.981525)
			(xy 44.064973 -316.938852) (xy 44.103786 -316.901431) (xy 44.147634 -316.870061) (xy 44.195582 -316.845409)
			(xy 44.246609 -316.828001) (xy 44.299627 -316.818208) (xy 44.353506 -316.816239) (xy 44.407097 -316.822136)
			(xy 44.459258 -316.835772) (xy 44.508878 -316.856859) (xy 44.554899 -316.884945) (xy 44.596341 -316.919433)
			(xy 44.632319 -316.959587) (xy 44.662067 -317.004551) (xy 44.684952 -317.053368) (xy 44.700484 -317.104997)
			(xy 44.708334 -317.158337) (xy 44.708826 -317.185294) (xy 44.708334 -317.212251) (xy 44.700484 -317.265591)
			(xy 44.684952 -317.31722) (xy 44.662067 -317.366037) (xy 44.632319 -317.411001) (xy 44.596341 -317.451155)
			(xy 44.554899 -317.485643) (xy 44.508878 -317.513729) (xy 44.459258 -317.534816) (xy 44.407097 -317.548452)
			(xy 44.353506 -317.554349) (xy 44.299627 -317.55238) (xy 44.246609 -317.542587) (xy 44.195582 -317.525179)
			(xy 44.147634 -317.500527) (xy 44.103786 -317.469157) (xy 44.064973 -317.431736) (xy 44.032021 -317.389063)
			(xy 44.005635 -317.342046) (xy 43.986375 -317.291689) (xy 43.974652 -317.239065) (xy 43.970717 -317.185294)
			(xy 37.164772 -317.185294) (xy 37.16428 -317.212251) (xy 37.15643 -317.265591) (xy 37.140898 -317.31722)
			(xy 37.118013 -317.366037) (xy 37.088265 -317.411001) (xy 37.052287 -317.451155) (xy 37.010845 -317.485643)
			(xy 36.964824 -317.513729) (xy 36.915204 -317.534816) (xy 36.863043 -317.548452) (xy 36.809452 -317.554349)
			(xy 36.755573 -317.55238) (xy 36.702555 -317.542587) (xy 36.651528 -317.525179) (xy 36.60358 -317.500527)
			(xy 36.559732 -317.469157) (xy 36.520919 -317.431736) (xy 36.487967 -317.389063) (xy 36.461581 -317.342046)
			(xy 36.442321 -317.291689) (xy 36.430598 -317.239065) (xy 36.426663 -317.185294) (xy 29.620972 -317.185294)
			(xy 29.62048 -317.212251) (xy 29.61263 -317.265591) (xy 29.597098 -317.31722) (xy 29.574213 -317.366037)
			(xy 29.544465 -317.411001) (xy 29.508487 -317.451155) (xy 29.467045 -317.485643) (xy 29.421024 -317.513729)
			(xy 29.371404 -317.534816) (xy 29.319243 -317.548452) (xy 29.265652 -317.554349) (xy 29.211773 -317.55238)
			(xy 29.158755 -317.542587) (xy 29.107728 -317.525179) (xy 29.05978 -317.500527) (xy 29.015932 -317.469157)
			(xy 28.977119 -317.431736) (xy 28.944167 -317.389063) (xy 28.917781 -317.342046) (xy 28.898521 -317.291689)
			(xy 28.886798 -317.239065) (xy 28.882863 -317.185294) (xy 22.076918 -317.185294) (xy 22.076426 -317.212251)
			(xy 22.068576 -317.265591) (xy 22.053044 -317.31722) (xy 22.030159 -317.366037) (xy 22.000411 -317.411001)
			(xy 21.964433 -317.451155) (xy 21.922991 -317.485643) (xy 21.87697 -317.513729) (xy 21.82735 -317.534816)
			(xy 21.775189 -317.548452) (xy 21.721598 -317.554349) (xy 21.667719 -317.55238) (xy 21.614701 -317.542587)
			(xy 21.563674 -317.525179) (xy 21.515726 -317.500527) (xy 21.471878 -317.469157) (xy 21.433065 -317.431736)
			(xy 21.400113 -317.389063) (xy 21.373727 -317.342046) (xy 21.354467 -317.291689) (xy 21.342744 -317.239065)
			(xy 21.338809 -317.185294) (xy 15.598394 -317.185294) (xy 15.598394 -318.035432) (xy 17.238741 -318.035432)
			(xy 17.242676 -317.981661) (xy 17.254399 -317.929037) (xy 17.273659 -317.87868) (xy 17.300045 -317.831663)
			(xy 17.332997 -317.78899) (xy 17.37181 -317.751569) (xy 17.415658 -317.720199) (xy 17.463606 -317.695547)
			(xy 17.514633 -317.678139) (xy 17.567651 -317.668346) (xy 17.62153 -317.666377) (xy 17.675121 -317.672274)
			(xy 17.727282 -317.68591) (xy 17.776902 -317.706997) (xy 17.822923 -317.735083) (xy 17.864365 -317.769571)
			(xy 17.900343 -317.809725) (xy 17.930091 -317.854689) (xy 17.952976 -317.903506) (xy 17.968508 -317.955135)
			(xy 17.976358 -318.008475) (xy 17.97685 -318.035432) (xy 24.782795 -318.035432) (xy 24.78673 -317.981661)
			(xy 24.798453 -317.929037) (xy 24.817713 -317.87868) (xy 24.844099 -317.831663) (xy 24.877051 -317.78899)
			(xy 24.915864 -317.751569) (xy 24.959712 -317.720199) (xy 25.00766 -317.695547) (xy 25.058687 -317.678139)
			(xy 25.111705 -317.668346) (xy 25.165584 -317.666377) (xy 25.219175 -317.672274) (xy 25.271336 -317.68591)
			(xy 25.320956 -317.706997) (xy 25.366977 -317.735083) (xy 25.408419 -317.769571) (xy 25.444397 -317.809725)
			(xy 25.474145 -317.854689) (xy 25.49703 -317.903506) (xy 25.512562 -317.955135) (xy 25.520412 -318.008475)
			(xy 25.520904 -318.035432) (xy 32.326595 -318.035432) (xy 32.33053 -317.981661) (xy 32.342253 -317.929037)
			(xy 32.361513 -317.87868) (xy 32.387899 -317.831663) (xy 32.420851 -317.78899) (xy 32.459664 -317.751569)
			(xy 32.503512 -317.720199) (xy 32.55146 -317.695547) (xy 32.602487 -317.678139) (xy 32.655505 -317.668346)
			(xy 32.709384 -317.666377) (xy 32.762975 -317.672274) (xy 32.815136 -317.68591) (xy 32.864756 -317.706997)
			(xy 32.910777 -317.735083) (xy 32.952219 -317.769571) (xy 32.988197 -317.809725) (xy 33.017945 -317.854689)
			(xy 33.04083 -317.903506) (xy 33.056362 -317.955135) (xy 33.064212 -318.008475) (xy 33.064704 -318.035432)
			(xy 39.870649 -318.035432) (xy 39.874584 -317.981661) (xy 39.886307 -317.929037) (xy 39.905567 -317.87868)
			(xy 39.931953 -317.831663) (xy 39.964905 -317.78899) (xy 40.003718 -317.751569) (xy 40.047566 -317.720199)
			(xy 40.095514 -317.695547) (xy 40.146541 -317.678139) (xy 40.199559 -317.668346) (xy 40.253438 -317.666377)
			(xy 40.307029 -317.672274) (xy 40.35919 -317.68591) (xy 40.40881 -317.706997) (xy 40.454831 -317.735083)
			(xy 40.496273 -317.769571) (xy 40.532251 -317.809725) (xy 40.561999 -317.854689) (xy 40.584884 -317.903506)
			(xy 40.600416 -317.955135) (xy 40.608266 -318.008475) (xy 40.608758 -318.035432) (xy 40.608266 -318.062389)
			(xy 40.600416 -318.115729) (xy 40.584884 -318.167358) (xy 40.561999 -318.216175) (xy 40.532251 -318.261139)
			(xy 40.496273 -318.301293) (xy 40.454831 -318.335781) (xy 40.40881 -318.363867) (xy 40.35919 -318.384954)
			(xy 40.307029 -318.39859) (xy 40.253438 -318.404487) (xy 40.199559 -318.402518) (xy 40.146541 -318.392725)
			(xy 40.095514 -318.375317) (xy 40.047566 -318.350665) (xy 40.003718 -318.319295) (xy 39.964905 -318.281874)
			(xy 39.931953 -318.239201) (xy 39.905567 -318.192184) (xy 39.886307 -318.141827) (xy 39.874584 -318.089203)
			(xy 39.870649 -318.035432) (xy 33.064704 -318.035432) (xy 33.064212 -318.062389) (xy 33.056362 -318.115729)
			(xy 33.04083 -318.167358) (xy 33.017945 -318.216175) (xy 32.988197 -318.261139) (xy 32.952219 -318.301293)
			(xy 32.910777 -318.335781) (xy 32.864756 -318.363867) (xy 32.815136 -318.384954) (xy 32.762975 -318.39859)
			(xy 32.709384 -318.404487) (xy 32.655505 -318.402518) (xy 32.602487 -318.392725) (xy 32.55146 -318.375317)
			(xy 32.503512 -318.350665) (xy 32.459664 -318.319295) (xy 32.420851 -318.281874) (xy 32.387899 -318.239201)
			(xy 32.361513 -318.192184) (xy 32.342253 -318.141827) (xy 32.33053 -318.089203) (xy 32.326595 -318.035432)
			(xy 25.520904 -318.035432) (xy 25.520412 -318.062389) (xy 25.512562 -318.115729) (xy 25.49703 -318.167358)
			(xy 25.474145 -318.216175) (xy 25.444397 -318.261139) (xy 25.408419 -318.301293) (xy 25.366977 -318.335781)
			(xy 25.320956 -318.363867) (xy 25.271336 -318.384954) (xy 25.219175 -318.39859) (xy 25.165584 -318.404487)
			(xy 25.111705 -318.402518) (xy 25.058687 -318.392725) (xy 25.00766 -318.375317) (xy 24.959712 -318.350665)
			(xy 24.915864 -318.319295) (xy 24.877051 -318.281874) (xy 24.844099 -318.239201) (xy 24.817713 -318.192184)
			(xy 24.798453 -318.141827) (xy 24.78673 -318.089203) (xy 24.782795 -318.035432) (xy 17.97685 -318.035432)
			(xy 17.976358 -318.062389) (xy 17.968508 -318.115729) (xy 17.952976 -318.167358) (xy 17.930091 -318.216175)
			(xy 17.900343 -318.261139) (xy 17.864365 -318.301293) (xy 17.822923 -318.335781) (xy 17.776902 -318.363867)
			(xy 17.727282 -318.384954) (xy 17.675121 -318.39859) (xy 17.62153 -318.404487) (xy 17.567651 -318.402518)
			(xy 17.514633 -318.392725) (xy 17.463606 -318.375317) (xy 17.415658 -318.350665) (xy 17.37181 -318.319295)
			(xy 17.332997 -318.281874) (xy 17.300045 -318.239201) (xy 17.273659 -318.192184) (xy 17.254399 -318.141827)
			(xy 17.242676 -318.089203) (xy 17.238741 -318.035432) (xy 15.598394 -318.035432) (xy 15.598394 -318.64681)
			(xy 15.598819 -318.65688) (xy 15.606535 -318.675482) (xy 15.61338 -318.682878) (xy 16.548608 -319.618106)
			(xy 16.556007 -319.624951) (xy 16.574605 -319.632681) (xy 16.584676 -319.633092)
		)
		(stroke
			(width 0)
			(type solid)
		)
		(fill yes)
		(layer "B.Cu")
		(net "GND")
	)
	(gr_poly
		(pts
			(xy 136.670542 -295.00322) (xy 136.676047 -295.003101) (xy 136.686811 -295.000802) (xy 136.691878 -294.998648)
			(xy 136.70153 -294.993314) (xy 136.710674 -294.984424) (xy 136.713976 -294.97909) (xy 136.727455 -294.958156)
			(xy 136.759876 -294.920371) (xy 136.797791 -294.888102) (xy 136.840271 -294.862137) (xy 136.88628 -294.84311)
			(xy 136.934692 -294.831487) (xy 136.984324 -294.827552) (xy 137.033962 -294.831401) (xy 137.082394 -294.84294)
			(xy 137.128436 -294.861887) (xy 137.170961 -294.887778) (xy 137.208932 -294.919981) (xy 137.241419 -294.957709)
			(xy 137.254996 -294.978582) (xy 137.258552 -294.98417) (xy 137.263886 -294.98925) (xy 137.268003 -294.992926)
			(xy 137.277485 -294.998569) (xy 137.282682 -295.000426) (xy 137.29081 -295.00322) (xy 137.610596 -295.00322)
			(xy 137.616099 -295.003096) (xy 137.626859 -295.000786) (xy 137.631932 -294.998648) (xy 137.641584 -294.993314)
			(xy 137.650728 -294.984424) (xy 137.65403 -294.97909) (xy 137.667509 -294.958152) (xy 137.699932 -294.920361)
			(xy 137.737848 -294.888084) (xy 137.780332 -294.862113) (xy 137.826345 -294.84308) (xy 137.874762 -294.831452)
			(xy 137.924399 -294.827513) (xy 137.974044 -294.831359) (xy 138.022483 -294.842895) (xy 138.068532 -294.861841)
			(xy 138.111065 -294.887732) (xy 138.149042 -294.919937) (xy 138.181536 -294.957667) (xy 138.19505 -294.978582)
			(xy 138.198606 -294.98417) (xy 138.20394 -294.98925) (xy 138.208059 -294.992922) (xy 138.217544 -294.998555)
			(xy 138.222736 -295.000426) (xy 138.230864 -295.00322) (xy 138.55065 -295.00322) (xy 138.556154 -295.003101)
			(xy 138.566918 -295.000799) (xy 138.571986 -294.998648) (xy 138.581638 -294.993314) (xy 138.590782 -294.984424)
			(xy 138.594084 -294.97909) (xy 138.607563 -294.958148) (xy 138.639987 -294.92035) (xy 138.677906 -294.888067)
			(xy 138.720393 -294.862089) (xy 138.76641 -294.843051) (xy 138.814832 -294.831418) (xy 138.864475 -294.827474)
			(xy 138.914126 -294.831316) (xy 138.962572 -294.842851) (xy 139.008628 -294.861795) (xy 139.051168 -294.887686)
			(xy 139.089152 -294.919892) (xy 139.121653 -294.957624) (xy 139.135104 -294.978582) (xy 139.13866 -294.98417)
			(xy 139.143994 -294.98925) (xy 139.148111 -294.992925) (xy 139.157594 -294.998567) (xy 139.16279 -295.000426)
			(xy 139.170918 -295.00322) (xy 140.430504 -295.00322) (xy 140.436007 -295.003095) (xy 140.446766 -295.000783)
			(xy 140.45184 -294.998648) (xy 140.461492 -294.993314) (xy 140.470636 -294.984424) (xy 140.473938 -294.97909)
			(xy 140.487417 -294.958153) (xy 140.519839 -294.920362) (xy 140.557756 -294.888088) (xy 140.600239 -294.862117)
			(xy 140.646251 -294.843086) (xy 140.694667 -294.831458) (xy 140.744304 -294.82752) (xy 140.793947 -294.831366)
			(xy 140.842385 -294.842903) (xy 140.888432 -294.861849) (xy 140.930964 -294.88774) (xy 140.96894 -294.919944)
			(xy 141.001433 -294.957674) (xy 141.014958 -294.978582) (xy 141.018514 -294.98417) (xy 141.023848 -294.98925)
			(xy 141.027967 -294.992921) (xy 141.037453 -294.998553) (xy 141.042644 -295.000426) (xy 141.050772 -295.00322)
			(xy 141.370558 -295.00322) (xy 141.376062 -295.0031) (xy 141.386825 -295.000797) (xy 141.391894 -294.998648)
			(xy 141.401546 -294.993314) (xy 141.41069 -294.984424) (xy 141.413992 -294.97909) (xy 141.427471 -294.958149)
			(xy 141.459895 -294.920352) (xy 141.497813 -294.88807) (xy 141.5403 -294.862093) (xy 141.586316 -294.843056)
			(xy 141.634737 -294.831424) (xy 141.684379 -294.827481) (xy 141.73403 -294.831324) (xy 141.782474 -294.842858)
			(xy 141.828528 -294.861803) (xy 141.871067 -294.887694) (xy 141.909051 -294.9199) (xy 141.94155 -294.957631)
			(xy 141.955012 -294.978582) (xy 141.958568 -294.98417) (xy 141.963902 -294.98925) (xy 141.968019 -294.992925)
			(xy 141.977503 -294.998565) (xy 141.982698 -295.000426) (xy 141.990826 -295.00322) (xy 143.250666 -295.00322)
			(xy 143.255746 -295.002966) (xy 143.266414 -295.00068) (xy 143.277336 -294.99687) (xy 143.27759 -294.996616)
			(xy 143.290798 -294.98417) (xy 143.294354 -294.978582) (xy 143.307888 -294.957692) (xy 143.340403 -294.920007)
			(xy 143.378388 -294.887844) (xy 143.420919 -294.861988) (xy 143.466956 -294.84307) (xy 143.515378 -294.83155)
			(xy 143.565003 -294.82771) (xy 143.61462 -294.831644) (xy 143.66302 -294.843256) (xy 143.709021 -294.862262)
			(xy 143.751502 -294.888198) (xy 143.789427 -294.920433) (xy 143.82187 -294.95818) (xy 143.835374 -294.97909)
			(xy 143.835628 -294.979344) (xy 143.839149 -294.984708) (xy 143.8484 -294.993594) (xy 143.853916 -294.99687)
			(xy 143.859504 -294.999918) (xy 143.87195 -295.00322) (xy 143.882618 -295.00322) (xy 143.892496 -295.002761)
			(xy 143.910796 -294.99532) (xy 143.918178 -294.988742) (xy 144.079976 -294.826944) (xy 144.089968 -294.816289)
			(xy 144.103941 -294.790649) (xy 144.110088 -294.762104) (xy 144.107905 -294.732986) (xy 144.097572 -294.705676)
			(xy 144.079934 -294.682406) (xy 144.056431 -294.665078) (xy 144.028986 -294.655109) (xy 144.014444 -294.653716)
			(xy 143.987883 -294.651465) (xy 143.936004 -294.63923) (xy 143.886887 -294.618526) (xy 143.841903 -294.589931)
			(xy 143.80231 -294.554245) (xy 143.769213 -294.512463) (xy 143.743536 -294.465753) (xy 143.725997 -294.415419)
			(xy 143.717084 -294.362867) (xy 143.716502 -294.336216) (xy 143.716991 -294.311205) (xy 143.724814 -294.261798)
			(xy 143.740268 -294.214224) (xy 143.762975 -294.169652) (xy 143.792374 -294.129181) (xy 143.827742 -294.093808)
			(xy 143.868208 -294.064402) (xy 143.912776 -294.041688) (xy 143.960348 -294.026226) (xy 144.009753 -294.018395)
			(xy 144.034764 -294.017954) (xy 144.058752 -294.018388) (xy 144.106184 -294.025588) (xy 144.151997 -294.039831)
			(xy 144.195151 -294.060793) (xy 144.234667 -294.087999) (xy 144.269649 -294.120832) (xy 144.299302 -294.158546)
			(xy 144.322954 -294.200286) (xy 144.340069 -294.245106) (xy 144.350258 -294.291987) (xy 144.352264 -294.315896)
			(xy 144.353655 -294.330431) (xy 144.363649 -294.357853) (xy 144.380987 -294.381333) (xy 144.404253 -294.398955)
			(xy 144.431552 -294.409283) (xy 144.460657 -294.411474) (xy 144.489194 -294.405351) (xy 144.514837 -294.391411)
			(xy 144.525492 -294.381428) (xy 144.973802 -293.933118) (xy 144.978794 -293.927621) (xy 144.985649 -293.914457)
			(xy 144.987264 -293.90721) (xy 144.98828 -293.897558) (xy 144.98828 -268.783562) (xy 144.98828 -268.7828)
			(xy 144.987729 -268.77354) (xy 144.980861 -268.756324) (xy 144.968316 -268.742679) (xy 144.951736 -268.734392)
			(xy 144.94256 -268.733016) (xy 144.917238 -268.729932) (xy 144.867966 -268.716741) (xy 144.821427 -268.695863)
			(xy 144.778813 -268.667831) (xy 144.741214 -268.633363) (xy 144.709592 -268.59334) (xy 144.684756 -268.548787)
			(xy 144.667342 -268.500845) (xy 144.657794 -268.450739) (xy 144.656359 -268.399751) (xy 144.663072 -268.349188)
			(xy 144.677761 -268.300341) (xy 144.700051 -268.254462) (xy 144.729372 -268.212724) (xy 144.764972 -268.176194)
			(xy 144.805941 -268.145809) (xy 144.851232 -268.122345) (xy 144.899684 -268.106403) (xy 144.92478 -268.101826)
			(xy 144.925288 -268.101826) (xy 144.933924 -268.100302) (xy 144.94129 -268.096492) (xy 144.945184 -268.094318)
			(xy 144.952208 -268.088822) (xy 144.95526 -268.08557) (xy 144.976596 -268.061694) (xy 144.981932 -268.054715)
			(xy 144.98792 -268.038213) (xy 144.98828 -268.029436) (xy 144.98828 -266.853162) (xy 144.988114 -266.847152)
			(xy 144.985292 -266.835469) (xy 144.982692 -266.830048) (xy 144.98085 -266.826575) (xy 144.976253 -266.8202)
			(xy 144.973548 -266.817348) (xy 144.571212 -266.415012) (xy 144.567484 -266.411487) (xy 144.558912 -266.405851)
			(xy 144.554194 -266.403836) (xy 144.545558 -266.40028) (xy 144.333976 -266.40028) (xy 144.319074 -266.400846)
			(xy 144.290561 -266.409539) (xy 144.26577 -266.426089) (xy 144.246809 -266.449089) (xy 144.235291 -266.476582)
			(xy 144.232197 -266.506229) (xy 144.23779 -266.535507) (xy 144.251593 -266.561927) (xy 144.261586 -266.573)
			(xy 144.278616 -266.590976) (xy 144.307463 -266.63122) (xy 144.329728 -266.675447) (xy 144.344872 -266.722589)
			(xy 144.352532 -266.771508) (xy 144.353026 -266.796266) (xy 144.352535 -266.821275) (xy 144.344711 -266.870678)
			(xy 144.329254 -266.918248) (xy 144.306546 -266.962815) (xy 144.277146 -267.00328) (xy 144.241778 -267.038648)
			(xy 144.201313 -267.068048) (xy 144.156746 -267.090756) (xy 144.109176 -267.106213) (xy 144.059773 -267.114037)
			(xy 144.009755 -267.114037) (xy 143.960352 -267.106213) (xy 143.912782 -267.090756) (xy 143.868215 -267.068048)
			(xy 143.82775 -267.038648) (xy 143.792382 -267.00328) (xy 143.762982 -266.962815) (xy 143.740274 -266.918248)
			(xy 143.724817 -266.870678) (xy 143.716993 -266.821275) (xy 143.716502 -266.796266) (xy 143.716975 -266.771509)
			(xy 143.724648 -266.722592) (xy 143.739803 -266.675453) (xy 143.762075 -266.63123) (xy 143.790926 -266.590989)
			(xy 143.807942 -266.573) (xy 143.81801 -266.561983) (xy 143.831846 -266.535554) (xy 143.837456 -266.506256)
			(xy 143.834362 -266.476585) (xy 143.822829 -266.449074) (xy 143.803839 -266.426068) (xy 143.779013 -266.409529)
			(xy 143.750467 -266.400868) (xy 143.735552 -266.40028) (xy 143.393922 -266.40028) (xy 143.379015 -266.40084)
			(xy 143.35049 -266.409525) (xy 143.325686 -266.426074) (xy 143.306715 -266.449079) (xy 143.295192 -266.47658)
			(xy 143.292098 -266.506236) (xy 143.297695 -266.535524) (xy 143.311509 -266.561949) (xy 143.321532 -266.573)
			(xy 143.338565 -266.590974) (xy 143.367416 -266.631217) (xy 143.389685 -266.675444) (xy 143.404832 -266.722587)
			(xy 143.412494 -266.771508) (xy 143.412972 -266.796266) (xy 143.412481 -266.821275) (xy 143.404657 -266.870678)
			(xy 143.3892 -266.918248) (xy 143.366492 -266.962815) (xy 143.337092 -267.00328) (xy 143.301724 -267.038648)
			(xy 143.261259 -267.068048) (xy 143.216692 -267.090756) (xy 143.169122 -267.106213) (xy 143.119719 -267.114037)
			(xy 143.069701 -267.114037) (xy 143.020298 -267.106213) (xy 142.972728 -267.090756) (xy 142.928161 -267.068048)
			(xy 142.887696 -267.038648) (xy 142.852328 -267.00328) (xy 142.822928 -266.962815) (xy 142.80022 -266.918248)
			(xy 142.784763 -266.870678) (xy 142.776939 -266.821275) (xy 142.776448 -266.796266) (xy 142.776921 -266.771508)
			(xy 142.784593 -266.722591) (xy 142.799746 -266.675451) (xy 142.822015 -266.631225) (xy 142.850862 -266.590981)
			(xy 142.867888 -266.573) (xy 142.877953 -266.56198) (xy 142.891783 -266.535549) (xy 142.89739 -266.506249)
			(xy 142.894295 -266.476579) (xy 142.882764 -266.449067) (xy 142.863778 -266.426058) (xy 142.838955 -266.409513)
			(xy 142.810412 -266.400842) (xy 142.795498 -266.40028) (xy 142.453868 -266.40028) (xy 142.438967 -266.400847)
			(xy 142.410456 -266.409541) (xy 142.385667 -266.426091) (xy 142.366708 -266.44909) (xy 142.355191 -266.476582)
			(xy 142.352097 -266.506227) (xy 142.357688 -266.535504) (xy 142.37149 -266.561923) (xy 142.381478 -266.573)
			(xy 142.398509 -266.590975) (xy 142.427356 -266.63122) (xy 142.449621 -266.675447) (xy 142.464767 -266.722589)
			(xy 142.472427 -266.771508) (xy 142.472918 -266.796266) (xy 142.472427 -266.821275) (xy 142.464603 -266.870678)
			(xy 142.449146 -266.918248) (xy 142.426438 -266.962815) (xy 142.397038 -267.00328) (xy 142.36167 -267.038648)
			(xy 142.321205 -267.068048) (xy 142.276638 -267.090756) (xy 142.229068 -267.106213) (xy 142.179665 -267.114037)
			(xy 142.129647 -267.114037) (xy 142.080244 -267.106213) (xy 142.032674 -267.090756) (xy 141.988107 -267.068048)
			(xy 141.947642 -267.038648) (xy 141.912274 -267.00328) (xy 141.882874 -266.962815) (xy 141.860166 -266.918248)
			(xy 141.844709 -266.870678) (xy 141.836885 -266.821275) (xy 141.836394 -266.796266) (xy 141.836867 -266.771509)
			(xy 141.84454 -266.722592) (xy 141.859695 -266.675453) (xy 141.881966 -266.63123) (xy 141.910816 -266.590988)
			(xy 141.927834 -266.573) (xy 141.937896 -266.561977) (xy 141.95172 -266.535543) (xy 141.957323 -266.506243)
			(xy 141.954228 -266.476573) (xy 141.942698 -266.44906) (xy 141.923716 -266.426048) (xy 141.898898 -266.409496)
			(xy 141.870358 -266.400815) (xy 141.855444 -266.40028) (xy 141.514068 -266.40028) (xy 141.499167 -266.400847)
			(xy 141.470656 -266.409541) (xy 141.445867 -266.426091) (xy 141.426908 -266.44909) (xy 141.415391 -266.476582)
			(xy 141.412297 -266.506227) (xy 141.417888 -266.535504) (xy 141.43169 -266.561923) (xy 141.441678 -266.573)
			(xy 141.458709 -266.590975) (xy 141.487556 -266.63122) (xy 141.509821 -266.675447) (xy 141.524967 -266.722589)
			(xy 141.532627 -266.771508) (xy 141.533118 -266.796266) (xy 141.532627 -266.821275) (xy 141.524803 -266.870678)
			(xy 141.509346 -266.918248) (xy 141.486638 -266.962815) (xy 141.457238 -267.00328) (xy 141.42187 -267.038648)
			(xy 141.381405 -267.068048) (xy 141.336838 -267.090756) (xy 141.289268 -267.106213) (xy 141.239865 -267.114037)
			(xy 141.189847 -267.114037) (xy 141.140444 -267.106213) (xy 141.092874 -267.090756) (xy 141.048307 -267.068048)
			(xy 141.007842 -267.038648) (xy 140.972474 -267.00328) (xy 140.943074 -266.962815) (xy 140.920366 -266.918248)
			(xy 140.904909 -266.870678) (xy 140.897085 -266.821275) (xy 140.896594 -266.796266) (xy 140.897067 -266.771509)
			(xy 140.90474 -266.722592) (xy 140.919895 -266.675453) (xy 140.942166 -266.63123) (xy 140.971016 -266.590988)
			(xy 140.988034 -266.573) (xy 140.998096 -266.561977) (xy 141.01192 -266.535543) (xy 141.017523 -266.506243)
			(xy 141.014428 -266.476573) (xy 141.002898 -266.44906) (xy 140.983916 -266.426048) (xy 140.959098 -266.409496)
			(xy 140.930558 -266.400815) (xy 140.915644 -266.40028) (xy 140.574014 -266.40028) (xy 140.559108 -266.400841)
			(xy 140.530585 -266.409527) (xy 140.505783 -266.426077) (xy 140.486814 -266.44908) (xy 140.475292 -266.47658)
			(xy 140.472198 -266.506235) (xy 140.477794 -266.535521) (xy 140.491606 -266.561945) (xy 140.501624 -266.573)
			(xy 140.518653 -266.590977) (xy 140.547496 -266.631222) (xy 140.569758 -266.675449) (xy 140.584901 -266.722591)
			(xy 140.592559 -266.771509) (xy 140.593064 -266.796266) (xy 140.592573 -266.821275) (xy 140.584749 -266.870678)
			(xy 140.569292 -266.918248) (xy 140.546584 -266.962815) (xy 140.517184 -267.00328) (xy 140.481816 -267.038648)
			(xy 140.441351 -267.068048) (xy 140.396784 -267.090756) (xy 140.349214 -267.106213) (xy 140.299811 -267.114037)
			(xy 140.249793 -267.114037) (xy 140.20039 -267.106213) (xy 140.15282 -267.090756) (xy 140.108253 -267.068048)
			(xy 140.067788 -267.038648) (xy 140.03242 -267.00328) (xy 140.00302 -266.962815) (xy 139.980312 -266.918248)
			(xy 139.964855 -266.870678) (xy 139.957031 -266.821275) (xy 139.95654 -266.796266) (xy 139.957013 -266.771508)
			(xy 139.964685 -266.72259) (xy 139.979837 -266.67545) (xy 140.002106 -266.631224) (xy 140.030953 -266.590979)
			(xy 140.04798 -266.573) (xy 140.058046 -266.561981) (xy 140.071877 -266.53555) (xy 140.077484 -266.50625)
			(xy 140.07439 -266.47658) (xy 140.062858 -266.449068) (xy 140.043871 -266.42606) (xy 140.019048 -266.409516)
			(xy 139.990504 -266.400846) (xy 139.97559 -266.40028) (xy 139.63396 -266.40028) (xy 139.619048 -266.400835)
			(xy 139.590513 -266.409514) (xy 139.5657 -266.426062) (xy 139.54672 -266.44907) (xy 139.535193 -266.476578)
			(xy 139.532098 -266.506243) (xy 139.5377 -266.535537) (xy 139.551522 -266.561967) (xy 139.56157 -266.573)
			(xy 139.578601 -266.590975) (xy 139.607449 -266.631219) (xy 139.629715 -266.675446) (xy 139.644861 -266.722589)
			(xy 139.652521 -266.771508) (xy 139.65301 -266.796266) (xy 139.652519 -266.821275) (xy 139.644695 -266.870678)
			(xy 139.629238 -266.918248) (xy 139.60653 -266.962815) (xy 139.57713 -267.00328) (xy 139.541762 -267.038648)
			(xy 139.501297 -267.068048) (xy 139.45673 -267.090756) (xy 139.40916 -267.106213) (xy 139.359757 -267.114037)
			(xy 139.309739 -267.114037) (xy 139.260336 -267.106213) (xy 139.212766 -267.090756) (xy 139.168199 -267.068048)
			(xy 139.127734 -267.038648) (xy 139.092366 -267.00328) (xy 139.062966 -266.962815) (xy 139.040258 -266.918248)
			(xy 139.024801 -266.870678) (xy 139.016977 -266.821275) (xy 139.016486 -266.796266) (xy 139.016959 -266.771509)
			(xy 139.024632 -266.722592) (xy 139.039786 -266.675453) (xy 139.062057 -266.631229) (xy 139.090907 -266.590987)
			(xy 139.107926 -266.573) (xy 139.117989 -266.561978) (xy 139.131813 -266.535544) (xy 139.137417 -266.506244)
			(xy 139.134322 -266.476574) (xy 139.122792 -266.449061) (xy 139.103809 -266.42605) (xy 139.078991 -266.409499)
			(xy 139.05045 -266.40082) (xy 139.035536 -266.40028) (xy 138.693906 -266.40028) (xy 138.679 -266.400842)
			(xy 138.65048 -266.40953) (xy 138.625681 -266.426079) (xy 138.606713 -266.449082) (xy 138.595192 -266.47658)
			(xy 138.592097 -266.506234) (xy 138.597693 -266.535518) (xy 138.611503 -266.561941) (xy 138.621516 -266.573)
			(xy 138.638545 -266.590976) (xy 138.667389 -266.631222) (xy 138.689651 -266.675449) (xy 138.704795 -266.722591)
			(xy 138.712454 -266.771509) (xy 138.712956 -266.796266) (xy 138.712465 -266.821275) (xy 138.704641 -266.870678)
			(xy 138.689184 -266.918248) (xy 138.666476 -266.962815) (xy 138.637076 -267.00328) (xy 138.601708 -267.038648)
			(xy 138.561243 -267.068048) (xy 138.516676 -267.090756) (xy 138.469106 -267.106213) (xy 138.419703 -267.114037)
			(xy 138.369685 -267.114037) (xy 138.320282 -267.106213) (xy 138.272712 -267.090756) (xy 138.228145 -267.068048)
			(xy 138.18768 -267.038648) (xy 138.152312 -267.00328) (xy 138.122912 -266.962815) (xy 138.100204 -266.918248)
			(xy 138.084747 -266.870678) (xy 138.076923 -266.821275) (xy 138.076432 -266.796266) (xy 138.076906 -266.771509)
			(xy 138.084579 -266.722593) (xy 138.099735 -266.675455) (xy 138.122008 -266.631233) (xy 138.150861 -266.590994)
			(xy 138.167872 -266.573) (xy 138.177938 -266.561981) (xy 138.19177 -266.535551) (xy 138.197378 -266.506252)
			(xy 138.194284 -266.476581) (xy 138.182752 -266.44907) (xy 138.163764 -266.426061) (xy 138.138941 -266.409518)
			(xy 138.110397 -266.400851) (xy 138.095482 -266.40028) (xy 137.904982 -266.40028) (xy 137.894914 -266.399853)
			(xy 137.876316 -266.392132) (xy 137.868914 -266.385294) (xy 137.159492 -265.675872) (xy 137.155761 -265.672351)
			(xy 137.147187 -265.666722) (xy 137.142474 -265.664696) (xy 137.133838 -265.66114) (xy 136.400032 -265.66114)
			(xy 136.386471 -265.661565) (xy 136.360308 -265.668708) (xy 136.336955 -265.682497) (xy 136.318064 -265.701957)
			(xy 136.304973 -265.725709) (xy 136.298608 -265.752072) (xy 136.29942 -265.779181) (xy 136.307352 -265.805115)
			(xy 136.31418 -265.816842) (xy 136.325737 -265.835927) (xy 136.343971 -265.876647) (xy 136.356325 -265.919519)
			(xy 136.362556 -265.963698) (xy 136.362948 -265.986006) (xy 136.362948 -265.98626) (xy 136.362457 -266.011269)
			(xy 136.354633 -266.060672) (xy 136.339176 -266.108242) (xy 136.316468 -266.152809) (xy 136.287068 -266.193274)
			(xy 136.2517 -266.228642) (xy 136.211235 -266.258042) (xy 136.166668 -266.28075) (xy 136.119098 -266.296207)
			(xy 136.069695 -266.304031) (xy 136.019677 -266.304031) (xy 135.970274 -266.296207) (xy 135.922704 -266.28075)
			(xy 135.878137 -266.258042) (xy 135.837672 -266.228642) (xy 135.802304 -266.193274) (xy 135.772904 -266.152809)
			(xy 135.750196 -266.108242) (xy 135.734739 -266.060672) (xy 135.726915 -266.011269) (xy 135.726424 -265.98626)
			(xy 135.726424 -265.986006) (xy 135.726824 -265.963701) (xy 135.733092 -265.919532) (xy 135.745453 -265.876667)
			(xy 135.763663 -265.835941) (xy 135.775192 -265.816842) (xy 135.782055 -265.80514) (xy 135.789953 -265.779196)
			(xy 135.790741 -265.752088) (xy 135.784365 -265.725729) (xy 135.771274 -265.701979) (xy 135.752392 -265.682513)
			(xy 135.729052 -265.668705) (xy 135.702899 -265.661529) (xy 135.68934 -265.66114) (xy 135.459978 -265.66114)
			(xy 135.446413 -265.661559) (xy 135.420239 -265.668695) (xy 135.396874 -265.682482) (xy 135.377973 -265.701944)
			(xy 135.364875 -265.725703) (xy 135.358508 -265.752075) (xy 135.359322 -265.779192) (xy 135.367261 -265.805134)
			(xy 135.374126 -265.816842) (xy 135.385682 -265.835927) (xy 135.403913 -265.876648) (xy 135.416265 -265.91952)
			(xy 135.422495 -265.963698) (xy 135.422894 -265.986006) (xy 135.422894 -265.98626) (xy 135.422403 -266.011269)
			(xy 135.414579 -266.060672) (xy 135.399122 -266.108242) (xy 135.376414 -266.152809) (xy 135.347014 -266.193274)
			(xy 135.311646 -266.228642) (xy 135.271181 -266.258042) (xy 135.226614 -266.28075) (xy 135.179044 -266.296207)
			(xy 135.129641 -266.304031) (xy 135.079623 -266.304031) (xy 135.03022 -266.296207) (xy 134.98265 -266.28075)
			(xy 134.938083 -266.258042) (xy 134.897618 -266.228642) (xy 134.86225 -266.193274) (xy 134.83285 -266.152809)
			(xy 134.810142 -266.108242) (xy 134.794685 -266.060672) (xy 134.786861 -266.011269) (xy 134.78637 -265.98626)
			(xy 134.78637 -265.986006) (xy 134.78677 -265.963701) (xy 134.793039 -265.919532) (xy 134.805401 -265.876668)
			(xy 134.823614 -265.835944) (xy 134.835138 -265.816842) (xy 134.842 -265.805138) (xy 134.849894 -265.779191)
			(xy 134.85068 -265.752082) (xy 134.844304 -265.725721) (xy 134.831215 -265.701968) (xy 134.812336 -265.682497)
			(xy 134.788997 -265.668681) (xy 134.762846 -265.661495) (xy 134.749286 -265.66114) (xy 134.520178 -265.66114)
			(xy 134.506613 -265.661559) (xy 134.480439 -265.668695) (xy 134.457074 -265.682482) (xy 134.438173 -265.701944)
			(xy 134.425075 -265.725703) (xy 134.418708 -265.752075) (xy 134.419522 -265.779192) (xy 134.427461 -265.805134)
			(xy 134.434326 -265.816842) (xy 134.445882 -265.835927) (xy 134.464113 -265.876648) (xy 134.476465 -265.91952)
			(xy 134.482695 -265.963698) (xy 134.483094 -265.986006) (xy 134.483094 -265.98626) (xy 134.482603 -266.011269)
			(xy 134.474779 -266.060672) (xy 134.459322 -266.108242) (xy 134.436614 -266.152809) (xy 134.407214 -266.193274)
			(xy 134.371846 -266.228642) (xy 134.331381 -266.258042) (xy 134.286814 -266.28075) (xy 134.239244 -266.296207)
			(xy 134.189841 -266.304031) (xy 134.139823 -266.304031) (xy 134.09042 -266.296207) (xy 134.04285 -266.28075)
			(xy 133.998283 -266.258042) (xy 133.957818 -266.228642) (xy 133.92245 -266.193274) (xy 133.89305 -266.152809)
			(xy 133.870342 -266.108242) (xy 133.854885 -266.060672) (xy 133.847061 -266.011269) (xy 133.84657 -265.98626)
			(xy 133.84657 -265.986006) (xy 133.84697 -265.963701) (xy 133.853239 -265.919532) (xy 133.865601 -265.876668)
			(xy 133.883814 -265.835944) (xy 133.895338 -265.816842) (xy 133.9022 -265.805138) (xy 133.910094 -265.779191)
			(xy 133.91088 -265.752082) (xy 133.904504 -265.725721) (xy 133.891415 -265.701968) (xy 133.872536 -265.682497)
			(xy 133.849197 -265.668681) (xy 133.823046 -265.661495) (xy 133.809486 -265.66114) (xy 133.686042 -265.66114)
			(xy 133.675978 -265.660705) (xy 133.657394 -265.652969) (xy 133.649974 -265.646154) (xy 133.268466 -265.264646)
			(xy 133.261621 -265.257248) (xy 133.253896 -265.238649) (xy 133.25348 -265.228578) (xy 133.25348 -264.754614)
			(xy 133.25348 -264.752582) (xy 133.252806 -264.744004) (xy 133.246446 -264.728029) (xy 133.241034 -264.72134)
			(xy 133.222746 -264.70229) (xy 133.212078 -264.69467) (xy 133.188202 -264.682732) (xy 133.180074 -264.681462)
			(xy 133.155092 -264.677429) (xy 133.106745 -264.662488) (xy 133.061374 -264.640081) (xy 133.020122 -264.610774)
			(xy 132.98403 -264.575307) (xy 132.954009 -264.534572) (xy 132.930814 -264.489599) (xy 132.915032 -264.44152)
			(xy 132.907061 -264.39155) (xy 132.906516 -264.366248) (xy 132.906979 -264.341224) (xy 132.914806 -264.291791)
			(xy 132.930276 -264.244194) (xy 132.953007 -264.199606) (xy 132.982438 -264.159125) (xy 133.017844 -264.123752)
			(xy 133.037834 -264.108692) (xy 133.049435 -264.099685) (xy 133.06733 -264.076411) (xy 133.077869 -264.04901)
			(xy 133.080185 -264.019743) (xy 133.074085 -263.991026) (xy 133.060072 -263.965227) (xy 133.050026 -263.954514)
			(xy 132.948934 -263.853422) (xy 132.943231 -263.848081) (xy 132.929395 -263.84084) (xy 132.921756 -263.839198)
			(xy 132.914136 -263.837928) (xy 132.898388 -263.83996) (xy 132.891276 -263.843516) (xy 132.869866 -263.853251)
			(xy 132.824897 -263.867026) (xy 132.778393 -263.874046) (xy 132.754878 -263.874504) (xy 132.729869 -263.874012)
			(xy 132.680466 -263.866185) (xy 132.632897 -263.850727) (xy 132.58833 -263.828018) (xy 132.547864 -263.798619)
			(xy 132.512494 -263.763251) (xy 132.483092 -263.722787) (xy 132.460381 -263.678222) (xy 132.44492 -263.630653)
			(xy 132.43709 -263.581251) (xy 132.436616 -263.556242) (xy 132.436616 -263.555988) (xy 132.437017 -263.533515)
			(xy 132.443388 -263.489023) (xy 132.449316 -263.467342) (xy 132.452618 -263.455658) (xy 132.450586 -263.444482)
			(xy 132.4494 -263.438739) (xy 132.444789 -263.427961) (xy 132.441442 -263.423146) (xy 132.396992 -263.362948)
			(xy 132.39623 -263.361678) (xy 132.39242 -263.357106) (xy 132.392166 -263.356852) (xy 132.384608 -263.348648)
			(xy 132.364443 -263.339177) (xy 132.353304 -263.338564) (xy 132.216398 -263.338564) (xy 132.212588 -263.338818)
			(xy 132.202898 -263.34) (xy 132.185408 -263.348631) (xy 132.178552 -263.355582) (xy 132.174488 -263.360408)
			(xy 132.130546 -263.41959) (xy 132.125466 -263.427718) (xy 132.123823 -263.431228) (xy 132.121523 -263.438627)
			(xy 132.120894 -263.44245) (xy 132.120386 -263.45007) (xy 132.120386 -263.466834) (xy 132.122164 -263.473438)
			(xy 132.127234 -263.493635) (xy 132.132711 -263.534914) (xy 132.133086 -263.555734) (xy 132.133086 -263.556242)
			(xy 132.132595 -263.581251) (xy 132.124771 -263.630654) (xy 132.109314 -263.678224) (xy 132.086606 -263.722791)
			(xy 132.057206 -263.763256) (xy 132.021838 -263.798624) (xy 131.981373 -263.828024) (xy 131.936806 -263.850732)
			(xy 131.889236 -263.866189) (xy 131.839833 -263.874013) (xy 131.789815 -263.874013) (xy 131.740412 -263.866189)
			(xy 131.692842 -263.850732) (xy 131.648275 -263.828024) (xy 131.60781 -263.798624) (xy 131.572442 -263.763256)
			(xy 131.543042 -263.722791) (xy 131.520334 -263.678224) (xy 131.504877 -263.630654) (xy 131.497053 -263.581251)
			(xy 131.496562 -263.556242) (xy 131.496562 -263.555988) (xy 131.496963 -263.533515) (xy 131.503332 -263.489022)
			(xy 131.509262 -263.467342) (xy 131.512564 -263.455658) (xy 131.510532 -263.444482) (xy 131.509347 -263.438739)
			(xy 131.504739 -263.427958) (xy 131.501388 -263.423146) (xy 131.456938 -263.362948) (xy 131.456176 -263.361678)
			(xy 131.452366 -263.357106) (xy 131.452112 -263.356852) (xy 131.444557 -263.348641) (xy 131.424392 -263.339151)
			(xy 131.41325 -263.338564) (xy 130.33629 -263.338564) (xy 130.33248 -263.338818) (xy 130.322791 -263.340001)
			(xy 130.305303 -263.348634) (xy 130.298444 -263.355582) (xy 130.29438 -263.360408) (xy 130.24866 -263.421622)
			(xy 130.245179 -263.426596) (xy 130.240419 -263.437761) (xy 130.239262 -263.44372) (xy 130.237738 -263.451594)
			(xy 130.2385 -263.45642) (xy 130.239008 -263.459722) (xy 130.240024 -263.467088) (xy 130.24104 -263.470644)
			(xy 130.246489 -263.491559) (xy 130.252352 -263.534378) (xy 130.252724 -263.555988) (xy 130.252724 -263.556242)
			(xy 130.252234 -263.581231) (xy 130.244415 -263.630594) (xy 130.228971 -263.678126) (xy 130.206281 -263.722658)
			(xy 130.176905 -263.763091) (xy 130.141565 -263.798431) (xy 130.101132 -263.827807) (xy 130.0566 -263.850497)
			(xy 130.009068 -263.865941) (xy 129.959705 -263.87376) (xy 129.909727 -263.87376) (xy 129.860364 -263.865941)
			(xy 129.812832 -263.850497) (xy 129.7683 -263.827807) (xy 129.727867 -263.798431) (xy 129.692527 -263.763091)
			(xy 129.663151 -263.722658) (xy 129.640461 -263.678126) (xy 129.625017 -263.630594) (xy 129.617198 -263.581231)
			(xy 129.616708 -263.556242) (xy 129.616708 -263.555988) (xy 129.617124 -263.533579) (xy 129.623495 -263.489215)
			(xy 129.629408 -263.467596) (xy 129.629408 -263.466834) (xy 129.63201 -263.455469) (xy 129.627783 -263.432568)
			(xy 129.62128 -263.422892) (xy 129.603754 -263.399016) (xy 129.603246 -263.398508) (xy 129.573528 -263.359138)
			(xy 129.573528 -263.35863) (xy 129.573274 -263.358376) (xy 129.56966 -263.353916) (xy 129.560808 -263.346611)
			(xy 129.555748 -263.343898) (xy 129.550414 -263.341358) (xy 129.538984 -263.338564) (xy 129.396236 -263.338564)
			(xy 129.392426 -263.338818) (xy 129.382733 -263.339993) (xy 129.365232 -263.348616) (xy 129.35839 -263.355582)
			(xy 129.354326 -263.360408) (xy 129.308606 -263.421622) (xy 129.305128 -263.426597) (xy 129.300374 -263.437763)
			(xy 129.299208 -263.44372) (xy 129.297684 -263.451594) (xy 129.298446 -263.45642) (xy 129.298954 -263.459722)
			(xy 129.29997 -263.467088) (xy 129.300986 -263.470644) (xy 129.306423 -263.491496) (xy 129.312287 -263.534188)
			(xy 129.31267 -263.555734) (xy 129.31267 -263.55675) (xy 129.31267 -263.559036) (xy 129.311977 -263.583883)
			(xy 129.30382 -263.632915) (xy 129.288135 -263.680079) (xy 129.265301 -263.724229) (xy 129.235876 -263.764289)
			(xy 129.200577 -263.799282) (xy 129.160262 -263.828356) (xy 129.115915 -263.850803) (xy 129.068615 -263.866077)
			(xy 129.019514 -263.873805) (xy 128.994662 -263.87425) (xy 128.969674 -263.873757) (xy 128.920313 -263.865934)
			(xy 128.872783 -263.850487) (xy 128.828254 -263.827796) (xy 128.787822 -263.79842) (xy 128.752483 -263.763081)
			(xy 128.723106 -263.722649) (xy 128.700414 -263.678121) (xy 128.684967 -263.630591) (xy 128.677143 -263.58123)
			(xy 128.676654 -263.556242) (xy 128.676654 -263.555988) (xy 128.67706 -263.533516) (xy 128.683438 -263.489025)
			(xy 128.689354 -263.467342) (xy 128.689354 -263.466834) (xy 128.691806 -263.456248) (xy 128.688524 -263.43479)
			(xy 128.683004 -263.425432) (xy 128.6637 -263.399016) (xy 128.663192 -263.398508) (xy 128.633474 -263.359138)
			(xy 128.633474 -263.35863) (xy 128.63322 -263.358376) (xy 128.629608 -263.353913) (xy 128.620759 -263.346601)
			(xy 128.615694 -263.343898) (xy 128.61036 -263.341358) (xy 128.59893 -263.338564) (xy 128.456436 -263.338564)
			(xy 128.452626 -263.338818) (xy 128.442933 -263.339993) (xy 128.425432 -263.348616) (xy 128.41859 -263.355582)
			(xy 128.414526 -263.360408) (xy 128.368806 -263.421622) (xy 128.365328 -263.426597) (xy 128.360574 -263.437763)
			(xy 128.359408 -263.44372) (xy 128.357884 -263.451594) (xy 128.358646 -263.45642) (xy 128.359154 -263.459722)
			(xy 128.36017 -263.467088) (xy 128.361186 -263.470644) (xy 128.366636 -263.491558) (xy 128.3725 -263.534378)
			(xy 128.37287 -263.555988) (xy 128.37287 -263.556242) (xy 128.37238 -263.581231) (xy 128.364561 -263.630594)
			(xy 128.349117 -263.678126) (xy 128.326427 -263.722658) (xy 128.297051 -263.763091) (xy 128.261711 -263.798431)
			(xy 128.221278 -263.827807) (xy 128.176746 -263.850497) (xy 128.129214 -263.865941) (xy 128.079851 -263.87376)
			(xy 128.029873 -263.87376) (xy 127.98051 -263.865941) (xy 127.932978 -263.850497) (xy 127.888446 -263.827807)
			(xy 127.848013 -263.798431) (xy 127.812673 -263.763091) (xy 127.783297 -263.722658) (xy 127.760607 -263.678126)
			(xy 127.745163 -263.630594) (xy 127.737344 -263.581231) (xy 127.736854 -263.556242) (xy 127.736854 -263.555988)
			(xy 127.73727 -263.533579) (xy 127.74364 -263.489214) (xy 127.749554 -263.467596) (xy 127.749554 -263.466834)
			(xy 127.752155 -263.455469) (xy 127.747931 -263.432566) (xy 127.741426 -263.422892) (xy 127.7239 -263.399016)
			(xy 127.723392 -263.398508) (xy 127.693674 -263.359138) (xy 127.693674 -263.35863) (xy 127.69342 -263.358376)
			(xy 127.689808 -263.353913) (xy 127.680959 -263.346601) (xy 127.675894 -263.343898) (xy 127.67056 -263.341358)
			(xy 127.65913 -263.338564) (xy 127.516382 -263.338564) (xy 127.512572 -263.338818) (xy 127.502884 -263.340002)
			(xy 127.485397 -263.348637) (xy 127.478536 -263.355582) (xy 127.474472 -263.360408) (xy 127.428752 -263.421622)
			(xy 127.425271 -263.426596) (xy 127.420513 -263.437761) (xy 127.419354 -263.44372) (xy 127.41783 -263.451594)
			(xy 127.418592 -263.45642) (xy 127.4191 -263.459722) (xy 127.420116 -263.467088) (xy 127.421132 -263.470644)
			(xy 127.426568 -263.491496) (xy 127.432432 -263.534188) (xy 127.432816 -263.555734) (xy 127.432816 -263.55675)
			(xy 127.432816 -263.559036) (xy 127.432123 -263.583885) (xy 127.423967 -263.632919) (xy 127.408282 -263.680086)
			(xy 127.385449 -263.72424) (xy 127.356025 -263.764303) (xy 127.320726 -263.7993) (xy 127.280412 -263.82838)
			(xy 127.236064 -263.850833) (xy 127.188764 -263.866113) (xy 127.139662 -263.873848) (xy 127.114808 -263.87425)
			(xy 127.089817 -263.87376) (xy 127.040451 -263.865943) (xy 126.992915 -263.8505) (xy 126.94838 -263.827812)
			(xy 126.907942 -263.798436) (xy 126.872597 -263.763096) (xy 126.843214 -263.722663) (xy 126.820519 -263.678132)
			(xy 126.805068 -263.630598) (xy 126.797244 -263.581233) (xy 126.7968 -263.556242) (xy 126.7968 -263.555988)
			(xy 126.797207 -263.533516) (xy 126.803585 -263.489026) (xy 126.8095 -263.467342) (xy 126.8095 -263.466834)
			(xy 126.811953 -263.456249) (xy 126.808668 -263.434792) (xy 126.80315 -263.425432) (xy 126.783846 -263.399016)
			(xy 126.783338 -263.398508) (xy 126.75362 -263.359138) (xy 126.75362 -263.35863) (xy 126.753366 -263.358376)
			(xy 126.749751 -263.353916) (xy 126.740899 -263.346612) (xy 126.73584 -263.343898) (xy 126.730506 -263.341358)
			(xy 126.719076 -263.338564) (xy 125.636274 -263.338564) (xy 125.632464 -263.338818) (xy 125.622767 -263.339987)
			(xy 125.605257 -263.348601) (xy 125.598428 -263.355582) (xy 125.594364 -263.360408) (xy 125.548644 -263.421622)
			(xy 125.545164 -263.426596) (xy 125.540406 -263.437762) (xy 125.539246 -263.44372) (xy 125.537722 -263.451594)
			(xy 125.538484 -263.45642) (xy 125.538992 -263.459722) (xy 125.540008 -263.467088) (xy 125.541024 -263.470644)
			(xy 125.54646 -263.491496) (xy 125.552324 -263.534188) (xy 125.552708 -263.555734) (xy 125.552708 -263.55675)
			(xy 125.552708 -263.559036) (xy 125.552015 -263.583884) (xy 125.543859 -263.632918) (xy 125.528173 -263.680085)
			(xy 125.505341 -263.724238) (xy 125.475916 -263.7643) (xy 125.440617 -263.799297) (xy 125.400303 -263.828375)
			(xy 125.355956 -263.850828) (xy 125.308655 -263.866106) (xy 125.259554 -263.87384) (xy 125.2347 -263.87425)
			(xy 125.20971 -263.87376) (xy 125.160344 -263.865942) (xy 125.112809 -263.850498) (xy 125.068275 -263.827809)
			(xy 125.027838 -263.798433) (xy 124.992494 -263.763094) (xy 124.963113 -263.722661) (xy 124.940418 -263.67813)
			(xy 124.924968 -263.630597) (xy 124.917144 -263.581232) (xy 124.916692 -263.556242) (xy 124.916692 -263.555988)
			(xy 124.917099 -263.533516) (xy 124.923476 -263.489026) (xy 124.929392 -263.467342) (xy 124.929392 -263.466834)
			(xy 124.931845 -263.456249) (xy 124.92856 -263.434792) (xy 124.923042 -263.425432) (xy 124.903738 -263.399016)
			(xy 124.90323 -263.398508) (xy 124.873512 -263.359138) (xy 124.873512 -263.35863) (xy 124.873258 -263.358376)
			(xy 124.869643 -263.353917) (xy 124.86079 -263.346614) (xy 124.855732 -263.343898) (xy 124.850398 -263.341358)
			(xy 124.838968 -263.338564) (xy 123.75642 -263.338564) (xy 123.75261 -263.338818) (xy 123.742918 -263.339996)
			(xy 123.725422 -263.348622) (xy 123.718574 -263.355582) (xy 123.71451 -263.360408) (xy 123.66879 -263.421622)
			(xy 123.665307 -263.426595) (xy 123.660545 -263.43776) (xy 123.659392 -263.44372) (xy 123.657868 -263.451594)
			(xy 123.65863 -263.45642) (xy 123.659138 -263.459722) (xy 123.660154 -263.467088) (xy 123.66117 -263.470644)
			(xy 123.666607 -263.491496) (xy 123.672472 -263.534188) (xy 123.672854 -263.555734) (xy 123.672854 -263.55675)
			(xy 123.672854 -263.559036) (xy 123.67216 -263.583883) (xy 123.664004 -263.632913) (xy 123.648318 -263.680077)
			(xy 123.625485 -263.724226) (xy 123.596059 -263.764284) (xy 123.56076 -263.799275) (xy 123.520445 -263.828348)
			(xy 123.476098 -263.850793) (xy 123.428798 -263.866065) (xy 123.379698 -263.87379) (xy 123.354846 -263.87425)
			(xy 123.329851 -263.873789) (xy 123.280476 -263.865976) (xy 123.232931 -263.850535) (xy 123.188387 -263.827847)
			(xy 123.147941 -263.798469) (xy 123.112588 -263.763126) (xy 123.083199 -263.722688) (xy 123.060498 -263.67815)
			(xy 123.045045 -263.63061) (xy 123.037218 -263.581237) (xy 123.036838 -263.556242) (xy 123.036584 -263.556242)
			(xy 123.037034 -263.531812) (xy 123.044514 -263.483529) (xy 123.059288 -263.436956) (xy 123.08101 -263.393191)
			(xy 123.109167 -263.353261) (xy 123.143099 -263.318106) (xy 123.182008 -263.288553) (xy 123.224977 -263.265296)
			(xy 123.270998 -263.248883) (xy 123.294902 -263.243822) (xy 123.298204 -263.243314) (xy 123.306521 -263.240772)
			(xy 123.320894 -263.231001) (xy 123.331177 -263.21699) (xy 123.334018 -263.20877) (xy 123.359926 -263.124188)
			(xy 123.361678 -263.11779) (xy 123.362194 -263.10454) (xy 123.360942 -263.098026) (xy 123.358656 -263.08812)
			(xy 123.358148 -263.085834) (xy 123.357386 -263.077706) (xy 123.357386 -262.724646) (xy 123.357032 -262.715958)
			(xy 123.351176 -262.699598) (xy 123.345956 -262.692642) (xy 123.342654 -262.688832) (xy 123.30684 -262.653018)
			(xy 123.29877 -262.645722) (xy 123.278395 -262.638153) (xy 123.256714 -262.639688) (xy 123.246896 -262.644382)
			(xy 123.226322 -262.655558) (xy 123.218687 -262.660211) (xy 123.206934 -262.673664) (xy 123.200485 -262.690324)
			(xy 123.199906 -262.699246) (xy 123.199906 -262.702548) (xy 123.20016 -262.705088) (xy 123.200414 -262.70712)
			(xy 123.200414 -262.709152) (xy 123.200668 -262.709406) (xy 123.201639 -262.718582) (xy 123.202656 -262.737009)
			(xy 123.2027 -262.746236) (xy 123.2027 -262.75157) (xy 123.20182 -262.776285) (xy 123.193355 -262.825008)
			(xy 123.177447 -262.871833) (xy 123.154482 -262.91563) (xy 123.125013 -262.955343) (xy 123.08975 -262.990014)
			(xy 123.049544 -263.018808) (xy 123.005365 -263.041029) (xy 122.958278 -263.056142) (xy 122.909419 -263.063782)
			(xy 122.884692 -263.064244) (xy 122.8597 -263.063753) (xy 122.810333 -263.055933) (xy 122.762796 -263.040486)
			(xy 122.718261 -263.017793) (xy 122.677824 -262.988413) (xy 122.642481 -262.95307) (xy 122.613102 -262.912632)
			(xy 122.590411 -262.868096) (xy 122.574965 -262.820559) (xy 122.567146 -262.771192) (xy 122.567146 -262.721208)
			(xy 122.574965 -262.671841) (xy 122.590411 -262.624304) (xy 122.613102 -262.579768) (xy 122.642481 -262.53933)
			(xy 122.677824 -262.503987) (xy 122.718261 -262.474607) (xy 122.762796 -262.451914) (xy 122.810333 -262.436467)
			(xy 122.8597 -262.428647) (xy 122.884692 -262.428228) (xy 122.884946 -262.428228) (xy 122.901452 -262.428452)
			(xy 122.934284 -262.431888) (xy 122.950478 -262.435086) (xy 122.95759 -262.43661) (xy 122.957844 -262.43661)
			(xy 122.959368 -262.437118) (xy 122.968981 -262.438535) (xy 122.988051 -262.434885) (xy 123.004417 -262.424437)
			(xy 123.010422 -262.416798) (xy 123.011692 -262.41502) (xy 123.015248 -262.40867) (xy 123.018568 -262.400649)
			(xy 123.020181 -262.383376) (xy 123.015959 -262.36655) (xy 123.011438 -262.35914) (xy 123.00839 -262.354568)
			(xy 122.991118 -262.337296) (xy 122.988266 -262.334591) (xy 122.981888 -262.329999) (xy 122.978418 -262.328152)
			(xy 122.972991 -262.325571) (xy 122.961311 -262.322753) (xy 122.955304 -262.322564) (xy 119.05996 -262.322564)
			(xy 119.050119 -262.322035) (xy 119.031944 -262.314463) (xy 119.024654 -262.307832) (xy 118.993666 -262.276844)
			(xy 118.991126 -262.274558) (xy 118.743476 -262.026654) (xy 118.546118 -261.829296) (xy 118.543266 -261.826591)
			(xy 118.536888 -261.821999) (xy 118.533418 -261.820152) (xy 118.527991 -261.817571) (xy 118.516311 -261.814753)
			(xy 118.510304 -261.814564) (xy 117.934994 -261.814564) (xy 117.925817 -261.815028) (xy 117.908714 -261.8217)
			(xy 117.895128 -261.834047) (xy 117.886857 -261.850437) (xy 117.885464 -261.859522) (xy 117.885464 -262.459216)
			(xy 117.885041 -262.469233) (xy 117.877367 -262.487738) (xy 117.863194 -262.501896) (xy 117.844681 -262.509551)
			(xy 117.834664 -262.510016) (xy 117.670326 -262.510016) (xy 117.660533 -262.510537) (xy 117.642453 -262.518081)
			(xy 117.628596 -262.531931) (xy 117.621042 -262.550007) (xy 117.620542 -262.5598) (xy 117.620542 -262.56996)
			(xy 117.365526 -262.56996) (xy 117.345138 -262.569513) (xy 117.305099 -262.56179) (xy 117.267257 -262.546603)
			(xy 117.232988 -262.524503) (xy 117.203542 -262.496296) (xy 117.17999 -262.463009) (xy 117.16319 -262.425854)
			(xy 117.158008 -262.40613) (xy 117.157754 -262.404606) (xy 117.156738 -262.400796) (xy 117.150134 -262.386572)
			(xy 117.14734 -262.382508) (xy 117.132517 -262.360115) (xy 117.109058 -262.311808) (xy 117.093128 -262.260525)
			(xy 117.085088 -262.207429) (xy 117.084602 -262.180578) (xy 117.084602 -262.171688) (xy 117.085836 -262.143605)
			(xy 117.096056 -262.088331) (xy 117.114835 -262.03535) (xy 117.127782 -262.010398) (xy 117.141051 -261.986933)
			(xy 117.173578 -261.943948) (xy 117.192552 -261.9248) (xy 117.193314 -261.924038) (xy 117.193822 -261.92353)
			(xy 117.20576 -261.903972) (xy 117.208064 -261.895995) (xy 117.20793 -261.879402) (xy 117.205506 -261.87146)
			(xy 117.1956 -261.846822) (xy 117.195346 -261.84606) (xy 117.191133 -261.837045) (xy 117.177143 -261.822926)
			(xy 117.168168 -261.818628) (xy 117.159024 -261.814564) (xy 105.999534 -261.814564) (xy 105.990353 -261.815022)
			(xy 105.973237 -261.821686) (xy 105.959639 -261.834033) (xy 105.95136 -261.850429) (xy 105.950004 -261.859522)
			(xy 105.950004 -262.459216) (xy 105.949513 -262.469222) (xy 105.941851 -262.487709) (xy 105.927699 -262.501858)
			(xy 105.90921 -262.509515) (xy 105.899204 -262.510016) (xy 105.734866 -262.510016) (xy 105.725068 -262.51053)
			(xy 105.706974 -262.518067) (xy 105.693105 -262.531918) (xy 105.685543 -262.550002) (xy 105.685082 -262.5598)
			(xy 105.685082 -262.56996) (xy 105.430066 -262.56996) (xy 105.408514 -262.56939) (xy 105.366295 -262.560694)
			(xy 105.326672 -262.543722) (xy 105.291249 -262.51916) (xy 105.26146 -262.488003) (xy 105.238513 -262.451514)
			(xy 105.230422 -262.43153) (xy 105.228898 -262.42772) (xy 105.22331 -262.417814) (xy 105.22077 -262.41375)
			(xy 105.215436 -262.406384) (xy 105.21442 -262.405114) (xy 105.214166 -262.40486) (xy 105.200111 -262.387015)
			(xy 105.176162 -262.348416) (xy 105.166414 -262.327898) (xy 105.166414 -262.327644) (xy 105.16616 -262.32739)
			(xy 105.162969 -262.321061) (xy 105.15369 -262.310356) (xy 105.147872 -262.306308) (xy 105.141776 -262.302244)
			(xy 105.127806 -262.29818) (xy 105.120186 -262.29818) (xy 105.110179 -262.29867) (xy 105.091688 -262.306331)
			(xy 105.077535 -262.320483) (xy 105.069871 -262.338973) (xy 105.069386 -262.34898) (xy 105.069386 -262.746236)
			(xy 121.62663 -262.746236) (xy 121.62712 -262.721247) (xy 121.634939 -262.671884) (xy 121.650383 -262.624352)
			(xy 121.673073 -262.57982) (xy 121.702449 -262.539387) (xy 121.737789 -262.504047) (xy 121.778222 -262.474671)
			(xy 121.822754 -262.451981) (xy 121.870286 -262.436537) (xy 121.919649 -262.428718) (xy 121.969627 -262.428718)
			(xy 122.01899 -262.436537) (xy 122.066522 -262.451981) (xy 122.111054 -262.474671) (xy 122.151487 -262.504047)
			(xy 122.186827 -262.539387) (xy 122.216203 -262.57982) (xy 122.238893 -262.624352) (xy 122.254337 -262.671884)
			(xy 122.262156 -262.721247) (xy 122.262646 -262.746236) (xy 122.262052 -262.772041) (xy 122.253697 -262.822972)
			(xy 122.237229 -262.871886) (xy 122.213079 -262.917498) (xy 122.181882 -262.958614) (xy 122.144455 -262.994152)
			(xy 122.101782 -263.023182) (xy 122.054981 -263.044941) (xy 122.005282 -263.058858) (xy 121.97969 -263.062212)
			(xy 121.93524 -263.067292) (xy 121.93524 -263.067038) (xy 121.892822 -263.059926) (xy 121.868357 -263.055422)
			(xy 121.821133 -263.039787) (xy 121.776922 -263.016987) (xy 121.736802 -262.987579) (xy 121.701753 -262.95228)
			(xy 121.67263 -262.911952) (xy 121.650144 -262.86758) (xy 121.634845 -262.820247) (xy 121.627107 -262.771108)
			(xy 121.62663 -262.746236) (xy 105.069386 -262.746236) (xy 105.069386 -263.44499) (xy 105.068846 -263.454825)
			(xy 105.061252 -263.47298) (xy 105.054654 -263.480296) (xy 104.703118 -263.831832) (xy 104.695881 -263.838548)
			(xy 104.677676 -263.84615) (xy 104.667812 -263.846564) (xy 102.811326 -263.846564) (xy 102.811296 -263.846576)
			(xy 111.221526 -263.846576) (xy 111.225828 -263.791355) (xy 111.238623 -263.737464) (xy 111.259603 -263.686202)
			(xy 111.288263 -263.638804) (xy 111.323911 -263.596411) (xy 111.344456 -263.577832) (xy 111.352076 -263.56945)
			(xy 111.364271 -263.553508) (xy 111.393578 -263.526088) (xy 111.427486 -263.504618) (xy 111.464804 -263.489851)
			(xy 111.504222 -263.482305) (xy 111.524288 -263.48182) (xy 111.779304 -263.48182) (xy 111.779304 -263.490964)
			(xy 111.779749 -263.500983) (xy 111.787408 -263.5195) (xy 111.801573 -263.533674) (xy 111.820085 -263.541344)
			(xy 111.830104 -263.541764) (xy 111.993172 -263.541764) (xy 112.003173 -263.54231) (xy 112.021658 -263.549954)
			(xy 112.027954 -263.556242) (xy 121.15673 -263.556242) (xy 121.15673 -263.555734) (xy 121.157314 -263.529466)
			(xy 121.165989 -263.477651) (xy 121.183058 -263.427964) (xy 121.195084 -263.404604) (xy 121.198132 -263.399016)
			(xy 121.20118 -263.387078) (xy 121.20118 -263.31545) (xy 121.201488 -263.294399) (xy 121.209491 -263.253068)
			(xy 121.225432 -263.214104) (xy 121.248695 -263.179016) (xy 121.278378 -263.149164) (xy 121.313333 -263.125703)
			(xy 121.352206 -263.109541) (xy 121.393491 -263.101304) (xy 121.41454 -263.10082) (xy 121.669556 -263.10082)
			(xy 121.669556 -263.109964) (xy 121.670116 -263.119964) (xy 121.677756 -263.138447) (xy 121.691886 -263.152599)
			(xy 121.710357 -263.160268) (xy 121.720356 -263.160764) (xy 121.883424 -263.160764) (xy 121.893429 -263.161267)
			(xy 121.911914 -263.168928) (xy 121.926065 -263.183076) (xy 121.93373 -263.201559) (xy 121.934224 -263.211564)
			(xy 121.934224 -263.719564) (xy 121.933751 -263.72958) (xy 121.926098 -263.748092) (xy 121.911942 -263.762264)
			(xy 121.893439 -263.76994) (xy 121.883424 -263.770364) (xy 121.731532 -263.770364) (xy 121.721679 -263.770786)
			(xy 121.703382 -263.778083) (xy 121.695972 -263.784588) (xy 121.669556 -263.807702) (xy 121.669556 -263.830308)
			(xy 121.648982 -263.830308) (xy 121.642975 -263.830498) (xy 121.631295 -263.833316) (xy 121.625868 -263.835896)
			(xy 121.624852 -263.836404) (xy 121.601636 -263.848298) (xy 121.552273 -263.865155) (xy 121.500818 -263.87371)
			(xy 121.474738 -263.87425) (xy 121.449752 -263.873683) (xy 121.400394 -263.865871) (xy 121.352866 -263.850435)
			(xy 121.308338 -263.827754) (xy 121.267906 -263.798386) (xy 121.232566 -263.763055) (xy 121.203188 -263.72263)
			(xy 121.180496 -263.678108) (xy 121.165047 -263.630584) (xy 121.157223 -263.581228) (xy 121.15673 -263.556242)
			(xy 112.027954 -263.556242) (xy 112.035811 -263.564088) (xy 112.043477 -263.582563) (xy 112.043972 -263.592564)
			(xy 112.043972 -264.100564) (xy 112.04355 -264.110586) (xy 112.035887 -264.129108) (xy 112.021715 -264.143282)
			(xy 112.003194 -264.150949) (xy 111.993172 -264.151364) (xy 111.779304 -264.151364) (xy 111.779304 -264.160508)
			(xy 111.778818 -264.170516) (xy 111.771157 -264.189007) (xy 111.757003 -264.203159) (xy 111.738512 -264.210819)
			(xy 111.728504 -264.211308) (xy 111.524288 -264.211308) (xy 111.504219 -264.210825) (xy 111.464789 -264.203312)
			(xy 111.427462 -264.188555) (xy 111.393555 -264.167074) (xy 111.364266 -264.139628) (xy 111.352076 -264.123678)
			(xy 111.344456 -264.115296) (xy 111.323878 -264.096755) (xy 111.288235 -264.054358) (xy 111.259582 -264.006956)
			(xy 111.238609 -263.955691) (xy 111.225821 -263.901799) (xy 111.221526 -263.846576) (xy 102.811296 -263.846576)
			(xy 102.801928 -263.850374) (xy 102.778792 -263.859369) (xy 102.730509 -263.870878) (xy 102.681024 -263.874746)
			(xy 102.631539 -263.870878) (xy 102.583256 -263.859369) (xy 102.56012 -263.850374) (xy 102.550722 -263.846564)
			(xy 101.871272 -263.846564) (xy 101.861874 -263.850374) (xy 101.838738 -263.859369) (xy 101.790455 -263.870878)
			(xy 101.74097 -263.874746) (xy 101.691485 -263.870878) (xy 101.643202 -263.859369) (xy 101.620066 -263.850374)
			(xy 101.610668 -263.846564) (xy 101.40696 -263.846564) (xy 101.397119 -263.847094) (xy 101.378947 -263.854669)
			(xy 101.371654 -263.861296) (xy 101.25075 -263.9822) (xy 101.244677 -263.988852) (xy 101.237257 -264.005251)
			(xy 101.236272 -264.014204) (xy 101.236272 -264.057892) (xy 101.236018 -264.060178) (xy 101.236018 -264.366248)
			(xy 101.893116 -264.366248) (xy 101.893677 -264.339974) (xy 101.902357 -264.288147) (xy 101.910388 -264.263124)
			(xy 101.912928 -264.254996) (xy 101.912928 -264.20445) (xy 101.913288 -264.183402) (xy 101.921288 -264.142077)
			(xy 101.937224 -264.103118) (xy 101.96048 -264.068034) (xy 101.990156 -264.038183) (xy 102.025102 -264.014719)
			(xy 102.063965 -263.998553) (xy 102.105242 -263.990309) (xy 102.126288 -263.98982) (xy 102.381304 -263.98982)
			(xy 102.381304 -263.998964) (xy 102.381749 -264.008983) (xy 102.389408 -264.0275) (xy 102.403573 -264.041674)
			(xy 102.422085 -264.049344) (xy 102.432104 -264.049764) (xy 102.595172 -264.049764) (xy 102.605173 -264.05031)
			(xy 102.623658 -264.057954) (xy 102.637811 -264.072088) (xy 102.645477 -264.090563) (xy 102.645972 -264.100564)
			(xy 102.645972 -264.36828) (xy 103.769922 -264.36828) (xy 103.770541 -264.3407) (xy 103.780093 -264.286373)
			(xy 103.798874 -264.234509) (xy 103.812086 -264.210292) (xy 103.814784 -264.205272) (xy 103.818109 -264.194372)
			(xy 103.81869 -264.188702) (xy 103.820515 -264.168739) (xy 103.830638 -264.129956) (xy 103.847824 -264.093745)
			(xy 103.871467 -264.061379) (xy 103.900736 -264.033995) (xy 103.934604 -264.012557) (xy 103.971877 -263.997818)
			(xy 104.011247 -263.990296) (xy 104.031288 -263.98982) (xy 104.286304 -263.98982) (xy 104.286304 -263.998964)
			(xy 104.286749 -264.008983) (xy 104.294408 -264.0275) (xy 104.308573 -264.041674) (xy 104.327085 -264.049344)
			(xy 104.337104 -264.049764) (xy 104.500172 -264.049764) (xy 104.510173 -264.05031) (xy 104.528658 -264.057954)
			(xy 104.542811 -264.072088) (xy 104.550477 -264.090563) (xy 104.550972 -264.100564) (xy 104.550972 -264.36828)
			(xy 105.65003 -264.36828) (xy 105.650624 -264.341321) (xy 105.659724 -264.288178) (xy 105.67766 -264.237331)
			(xy 105.703918 -264.19024) (xy 105.720388 -264.16889) (xy 105.723671 -264.164619) (xy 105.72854 -264.155014)
			(xy 105.73004 -264.14984) (xy 105.735507 -264.130511) (xy 105.752625 -264.094176) (xy 105.776239 -264.061687)
			(xy 105.805517 -264.034192) (xy 105.839423 -264.012661) (xy 105.876759 -263.997857) (xy 105.916206 -263.990301)
			(xy 105.936288 -263.98982) (xy 106.191304 -263.98982) (xy 106.191304 -263.998964) (xy 106.191749 -264.008983)
			(xy 106.199408 -264.0275) (xy 106.213573 -264.041674) (xy 106.232085 -264.049344) (xy 106.242104 -264.049764)
			(xy 106.405172 -264.049764) (xy 106.415173 -264.05031) (xy 106.433658 -264.057954) (xy 106.447811 -264.072088)
			(xy 106.455477 -264.090563) (xy 106.455972 -264.100564) (xy 106.455972 -264.36828) (xy 107.529884 -264.36828)
			(xy 107.530403 -264.341669) (xy 107.53926 -264.289189) (xy 107.55674 -264.23892) (xy 107.582354 -264.192268)
			(xy 107.615386 -264.150537) (xy 107.634786 -264.132314) (xy 107.638562 -264.128702) (xy 107.644711 -264.120257)
			(xy 107.646978 -264.11555) (xy 107.65579 -264.097144) (xy 107.679316 -264.063807) (xy 107.708742 -264.035541)
			(xy 107.742997 -264.013373) (xy 107.780838 -263.998111) (xy 107.820887 -263.990308) (xy 107.841288 -263.98982)
			(xy 108.096304 -263.98982) (xy 108.096304 -263.998964) (xy 108.096749 -264.008983) (xy 108.104408 -264.0275)
			(xy 108.118573 -264.041674) (xy 108.137085 -264.049344) (xy 108.147104 -264.049764) (xy 108.310172 -264.049764)
			(xy 108.320173 -264.05031) (xy 108.338658 -264.057954) (xy 108.352811 -264.072088) (xy 108.360477 -264.090563)
			(xy 108.360972 -264.100564) (xy 108.360972 -264.36828) (xy 115.049808 -264.36828) (xy 115.05033 -264.341769)
			(xy 115.059138 -264.289484) (xy 115.07649 -264.239382) (xy 115.101907 -264.192849) (xy 115.11788 -264.171684)
			(xy 115.121095 -264.167329) (xy 115.125832 -264.157597) (xy 115.127278 -264.15238) (xy 115.13258 -264.132806)
			(xy 115.149506 -264.095962) (xy 115.173078 -264.062971) (xy 115.202451 -264.03502) (xy 115.23657 -264.013112)
			(xy 115.274208 -263.998034) (xy 115.314015 -263.990327) (xy 115.334288 -263.98982) (xy 115.589304 -263.98982)
			(xy 115.589304 -263.998964) (xy 115.589749 -264.008983) (xy 115.597408 -264.0275) (xy 115.611573 -264.041674)
			(xy 115.630085 -264.049344) (xy 115.640104 -264.049764) (xy 115.803172 -264.049764) (xy 115.813173 -264.05031)
			(xy 115.831658 -264.057954) (xy 115.845811 -264.072088) (xy 115.853477 -264.090563) (xy 115.853972 -264.100564)
			(xy 115.853972 -264.36828) (xy 116.929916 -264.36828) (xy 116.930458 -264.342086) (xy 116.939041 -264.290406)
			(xy 116.955986 -264.240834) (xy 116.980835 -264.194715) (xy 117.012914 -264.153297) (xy 117.03177 -264.135108)
			(xy 117.035552 -264.13143) (xy 117.041694 -264.122854) (xy 117.043962 -264.11809) (xy 117.052618 -264.099361)
			(xy 117.076016 -264.065382) (xy 117.105506 -264.036533) (xy 117.13999 -264.013887) (xy 117.178183 -263.99829)
			(xy 117.218661 -263.990323) (xy 117.239288 -263.98982) (xy 117.494304 -263.98982) (xy 117.494304 -263.998964)
			(xy 117.494749 -264.008983) (xy 117.502408 -264.0275) (xy 117.516573 -264.041674) (xy 117.535085 -264.049344)
			(xy 117.545104 -264.049764) (xy 117.708172 -264.049764) (xy 117.718173 -264.05031) (xy 117.736658 -264.057954)
			(xy 117.750811 -264.072088) (xy 117.758477 -264.090563) (xy 117.758972 -264.100564) (xy 117.758972 -264.36828)
			(xy 118.80977 -264.36828) (xy 118.810311 -264.342468) (xy 118.818632 -264.29152) (xy 118.835083 -264.242588)
			(xy 118.859232 -264.196961) (xy 118.890443 -264.155841) (xy 118.927894 -264.12031) (xy 118.948962 -264.10539)
			(xy 118.953253 -264.10228) (xy 118.960543 -264.094588) (xy 118.96344 -264.09015) (xy 118.975375 -264.072133)
			(xy 119.005188 -264.040858) (xy 119.040667 -264.016195) (xy 119.08037 -263.999145) (xy 119.122685 -263.990401)
			(xy 119.144288 -263.98982) (xy 119.399304 -263.98982) (xy 119.399304 -263.998964) (xy 119.399749 -264.008983)
			(xy 119.407408 -264.0275) (xy 119.421573 -264.041674) (xy 119.440085 -264.049344) (xy 119.450104 -264.049764)
			(xy 119.613172 -264.049764) (xy 119.623173 -264.05031) (xy 119.641658 -264.057954) (xy 119.655811 -264.072088)
			(xy 119.663477 -264.090563) (xy 119.663972 -264.100564) (xy 119.663972 -264.36828) (xy 120.687592 -264.36828)
			(xy 120.688164 -264.340996) (xy 120.69749 -264.287231) (xy 120.706134 -264.261346) (xy 120.708928 -264.253218)
			(xy 120.708928 -264.20445) (xy 120.709288 -264.183402) (xy 120.717288 -264.142077) (xy 120.733224 -264.103118)
			(xy 120.75648 -264.068034) (xy 120.786156 -264.038183) (xy 120.821102 -264.014719) (xy 120.859965 -263.998553)
			(xy 120.901242 -263.990309) (xy 120.922288 -263.98982) (xy 121.177304 -263.98982) (xy 121.177304 -263.998964)
			(xy 121.177749 -264.008983) (xy 121.185408 -264.0275) (xy 121.199573 -264.041674) (xy 121.218085 -264.049344)
			(xy 121.228104 -264.049764) (xy 121.391172 -264.049764) (xy 121.401173 -264.05031) (xy 121.419658 -264.057954)
			(xy 121.433811 -264.072088) (xy 121.441477 -264.090563) (xy 121.441972 -264.100564) (xy 121.441972 -264.366756)
			(xy 122.566684 -264.366756) (xy 122.566684 -264.366248) (xy 122.567214 -264.338867) (xy 122.576566 -264.28491)
			(xy 122.595053 -264.233363) (xy 122.608086 -264.209276) (xy 122.610761 -264.204245) (xy 122.614096 -264.193353)
			(xy 122.61469 -264.187686) (xy 122.616601 -264.167794) (xy 122.626881 -264.129183) (xy 122.644162 -264.093156)
			(xy 122.667839 -264.06097) (xy 122.697088 -264.033748) (xy 122.730888 -264.012438) (xy 122.768061 -263.997785)
			(xy 122.80731 -263.990298) (xy 122.827288 -263.98982) (xy 123.082304 -263.98982) (xy 123.082304 -263.998964)
			(xy 123.082749 -264.008983) (xy 123.090408 -264.0275) (xy 123.104573 -264.041674) (xy 123.123085 -264.049344)
			(xy 123.133104 -264.049764) (xy 123.296172 -264.049764) (xy 123.306173 -264.05031) (xy 123.324658 -264.057954)
			(xy 123.338811 -264.072088) (xy 123.346477 -264.090563) (xy 123.346972 -264.100564) (xy 123.346972 -264.504678)
			(xy 124.391928 -264.504678) (xy 124.391928 -264.50417) (xy 124.391928 -264.20445) (xy 124.392288 -264.183402)
			(xy 124.400288 -264.142077) (xy 124.416224 -264.103118) (xy 124.43948 -264.068034) (xy 124.469156 -264.038183)
			(xy 124.504102 -264.014719) (xy 124.542965 -263.998553) (xy 124.584242 -263.990309) (xy 124.605288 -263.98982)
			(xy 124.860304 -263.98982) (xy 124.860304 -263.998964) (xy 124.860749 -264.008983) (xy 124.868408 -264.0275)
			(xy 124.882573 -264.041674) (xy 124.901085 -264.049344) (xy 124.911104 -264.049764) (xy 125.074172 -264.049764)
			(xy 125.084173 -264.05031) (xy 125.102658 -264.057954) (xy 125.116811 -264.072088) (xy 125.124477 -264.090563)
			(xy 125.124972 -264.100564) (xy 125.124972 -264.391237) (xy 126.327136 -264.391237) (xy 126.327136 -264.341259)
			(xy 126.334955 -264.291896) (xy 126.350399 -264.244364) (xy 126.373089 -264.199832) (xy 126.402465 -264.159399)
			(xy 126.437805 -264.124059) (xy 126.478238 -264.094683) (xy 126.52277 -264.071993) (xy 126.570302 -264.056549)
			(xy 126.619665 -264.04873) (xy 126.669643 -264.04873) (xy 126.719006 -264.056549) (xy 126.766538 -264.071993)
			(xy 126.81107 -264.094683) (xy 126.851503 -264.124059) (xy 126.886843 -264.159399) (xy 126.916219 -264.199832)
			(xy 126.938909 -264.244364) (xy 126.954353 -264.291896) (xy 126.962172 -264.341259) (xy 126.962662 -264.366248)
			(xy 128.208527 -264.366248) (xy 128.212622 -264.31552) (xy 128.224801 -264.266106) (xy 128.244749 -264.219286)
			(xy 128.27195 -264.176272) (xy 128.305698 -264.138178) (xy 128.34512 -264.105991) (xy 128.389194 -264.080545)
			(xy 128.43678 -264.062498) (xy 128.486644 -264.052318) (xy 128.537496 -264.050269) (xy 128.588017 -264.056403)
			(xy 128.636901 -264.070563) (xy 128.68288 -264.09238) (xy 128.724764 -264.12129) (xy 128.761468 -264.156545)
			(xy 128.792041 -264.197231) (xy 128.815692 -264.242294) (xy 128.831808 -264.290568) (xy 128.839972 -264.340802)
			(xy 128.840484 -264.366248) (xy 129.148581 -264.366248) (xy 129.152676 -264.31552) (xy 129.164855 -264.266106)
			(xy 129.184803 -264.219286) (xy 129.212004 -264.176272) (xy 129.245752 -264.138178) (xy 129.285174 -264.105991)
			(xy 129.329248 -264.080545) (xy 129.376834 -264.062498) (xy 129.426698 -264.052318) (xy 129.47755 -264.050269)
			(xy 129.528071 -264.056403) (xy 129.576955 -264.070563) (xy 129.622934 -264.09238) (xy 129.664818 -264.12129)
			(xy 129.701522 -264.156545) (xy 129.732095 -264.197231) (xy 129.755746 -264.242294) (xy 129.771862 -264.290568)
			(xy 129.780026 -264.340802) (xy 129.780538 -264.366248) (xy 129.780035 -264.391237) (xy 130.087352 -264.391237)
			(xy 130.087352 -264.341259) (xy 130.095171 -264.291896) (xy 130.110615 -264.244364) (xy 130.133305 -264.199832)
			(xy 130.162681 -264.159399) (xy 130.198021 -264.124059) (xy 130.238454 -264.094683) (xy 130.282986 -264.071993)
			(xy 130.330518 -264.056549) (xy 130.379881 -264.04873) (xy 130.429859 -264.04873) (xy 130.479222 -264.056549)
			(xy 130.526754 -264.071993) (xy 130.571286 -264.094683) (xy 130.611719 -264.124059) (xy 130.647059 -264.159399)
			(xy 130.676435 -264.199832) (xy 130.699125 -264.244364) (xy 130.714569 -264.291896) (xy 130.722388 -264.341259)
			(xy 130.722878 -264.366248) (xy 131.028435 -264.366248) (xy 131.03253 -264.31552) (xy 131.044709 -264.266106)
			(xy 131.064657 -264.219286) (xy 131.091858 -264.176272) (xy 131.125606 -264.138178) (xy 131.165028 -264.105991)
			(xy 131.209102 -264.080545) (xy 131.256688 -264.062498) (xy 131.306552 -264.052318) (xy 131.357404 -264.050269)
			(xy 131.407925 -264.056403) (xy 131.456809 -264.070563) (xy 131.502788 -264.09238) (xy 131.544672 -264.12129)
			(xy 131.581376 -264.156545) (xy 131.611949 -264.197231) (xy 131.6356 -264.242294) (xy 131.651716 -264.290568)
			(xy 131.65988 -264.340802) (xy 131.660392 -264.366248) (xy 131.659889 -264.391237) (xy 131.967206 -264.391237)
			(xy 131.967206 -264.341259) (xy 131.975025 -264.291896) (xy 131.990469 -264.244364) (xy 132.013159 -264.199832)
			(xy 132.042535 -264.159399) (xy 132.077875 -264.124059) (xy 132.118308 -264.094683) (xy 132.16284 -264.071993)
			(xy 132.210372 -264.056549) (xy 132.259735 -264.04873) (xy 132.309713 -264.04873) (xy 132.359076 -264.056549)
			(xy 132.406608 -264.071993) (xy 132.45114 -264.094683) (xy 132.491573 -264.124059) (xy 132.526913 -264.159399)
			(xy 132.556289 -264.199832) (xy 132.578979 -264.244364) (xy 132.594423 -264.291896) (xy 132.602242 -264.341259)
			(xy 132.602732 -264.366248) (xy 132.602242 -264.391237) (xy 132.594423 -264.4406) (xy 132.578979 -264.488132)
			(xy 132.556289 -264.532664) (xy 132.526913 -264.573097) (xy 132.491573 -264.608437) (xy 132.45114 -264.637813)
			(xy 132.406608 -264.660503) (xy 132.359076 -264.675947) (xy 132.309713 -264.683766) (xy 132.259735 -264.683766)
			(xy 132.210372 -264.675947) (xy 132.16284 -264.660503) (xy 132.118308 -264.637813) (xy 132.077875 -264.608437)
			(xy 132.042535 -264.573097) (xy 132.013159 -264.532664) (xy 131.990469 -264.488132) (xy 131.975025 -264.4406)
			(xy 131.967206 -264.391237) (xy 131.659889 -264.391237) (xy 131.65988 -264.391694) (xy 131.651716 -264.441928)
			(xy 131.6356 -264.490202) (xy 131.611949 -264.535265) (xy 131.581376 -264.575951) (xy 131.544672 -264.611206)
			(xy 131.502788 -264.640116) (xy 131.456809 -264.661933) (xy 131.407925 -264.676093) (xy 131.357404 -264.682227)
			(xy 131.306552 -264.680178) (xy 131.256688 -264.669998) (xy 131.209102 -264.651951) (xy 131.165028 -264.626505)
			(xy 131.125606 -264.594318) (xy 131.091858 -264.556224) (xy 131.064657 -264.51321) (xy 131.044709 -264.46639)
			(xy 131.03253 -264.416976) (xy 131.028435 -264.366248) (xy 130.722878 -264.366248) (xy 130.722388 -264.391237)
			(xy 130.714569 -264.4406) (xy 130.699125 -264.488132) (xy 130.676435 -264.532664) (xy 130.647059 -264.573097)
			(xy 130.611719 -264.608437) (xy 130.571286 -264.637813) (xy 130.526754 -264.660503) (xy 130.479222 -264.675947)
			(xy 130.429859 -264.683766) (xy 130.379881 -264.683766) (xy 130.330518 -264.675947) (xy 130.282986 -264.660503)
			(xy 130.238454 -264.637813) (xy 130.198021 -264.608437) (xy 130.162681 -264.573097) (xy 130.133305 -264.532664)
			(xy 130.110615 -264.488132) (xy 130.095171 -264.4406) (xy 130.087352 -264.391237) (xy 129.780035 -264.391237)
			(xy 129.780026 -264.391694) (xy 129.771862 -264.441928) (xy 129.755746 -264.490202) (xy 129.732095 -264.535265)
			(xy 129.701522 -264.575951) (xy 129.664818 -264.611206) (xy 129.622934 -264.640116) (xy 129.576955 -264.661933)
			(xy 129.528071 -264.676093) (xy 129.47755 -264.682227) (xy 129.426698 -264.680178) (xy 129.376834 -264.669998)
			(xy 129.329248 -264.651951) (xy 129.285174 -264.626505) (xy 129.245752 -264.594318) (xy 129.212004 -264.556224)
			(xy 129.184803 -264.51321) (xy 129.164855 -264.46639) (xy 129.152676 -264.416976) (xy 129.148581 -264.366248)
			(xy 128.840484 -264.366248) (xy 128.839972 -264.391694) (xy 128.831808 -264.441928) (xy 128.815692 -264.490202)
			(xy 128.792041 -264.535265) (xy 128.761468 -264.575951) (xy 128.724764 -264.611206) (xy 128.68288 -264.640116)
			(xy 128.636901 -264.661933) (xy 128.588017 -264.676093) (xy 128.537496 -264.682227) (xy 128.486644 -264.680178)
			(xy 128.43678 -264.669998) (xy 128.389194 -264.651951) (xy 128.34512 -264.626505) (xy 128.305698 -264.594318)
			(xy 128.27195 -264.556224) (xy 128.244749 -264.51321) (xy 128.224801 -264.46639) (xy 128.212622 -264.416976)
			(xy 128.208527 -264.366248) (xy 126.962662 -264.366248) (xy 126.962172 -264.391237) (xy 126.954353 -264.4406)
			(xy 126.938909 -264.488132) (xy 126.916219 -264.532664) (xy 126.886843 -264.573097) (xy 126.851503 -264.608437)
			(xy 126.81107 -264.637813) (xy 126.766538 -264.660503) (xy 126.719006 -264.675947) (xy 126.669643 -264.683766)
			(xy 126.619665 -264.683766) (xy 126.570302 -264.675947) (xy 126.52277 -264.660503) (xy 126.478238 -264.637813)
			(xy 126.437805 -264.608437) (xy 126.402465 -264.573097) (xy 126.373089 -264.532664) (xy 126.350399 -264.488132)
			(xy 126.334955 -264.4406) (xy 126.327136 -264.391237) (xy 125.124972 -264.391237) (xy 125.124972 -264.608564)
			(xy 125.12455 -264.618586) (xy 125.116887 -264.637108) (xy 125.102715 -264.651282) (xy 125.084194 -264.658949)
			(xy 125.074172 -264.659364) (xy 124.89815 -264.659364) (xy 124.893538 -264.659462) (xy 124.884464 -264.661123)
			(xy 124.880116 -264.662666) (xy 124.860304 -264.669524) (xy 124.860304 -264.68959) (xy 124.830586 -264.719308)
			(xy 124.605288 -264.719308) (xy 124.584244 -264.718787) (xy 124.542972 -264.710544) (xy 124.504111 -264.694381)
			(xy 124.469168 -264.670922) (xy 124.439494 -264.641075) (xy 124.416237 -264.605997) (xy 124.400299 -264.567044)
			(xy 124.392295 -264.525724) (xy 124.391928 -264.504678) (xy 123.346972 -264.504678) (xy 123.346972 -264.608564)
			(xy 123.34655 -264.618586) (xy 123.338887 -264.637108) (xy 123.324715 -264.651282) (xy 123.306194 -264.658949)
			(xy 123.296172 -264.659364) (xy 123.082304 -264.659364) (xy 123.082304 -264.668508) (xy 123.081818 -264.678516)
			(xy 123.074157 -264.697007) (xy 123.060003 -264.711159) (xy 123.041512 -264.718819) (xy 123.031504 -264.719308)
			(xy 122.827288 -264.719308) (xy 122.806182 -264.718762) (xy 122.764791 -264.710482) (xy 122.725835 -264.694228)
			(xy 122.690834 -264.670633) (xy 122.661153 -264.640619) (xy 122.637951 -264.605356) (xy 122.622133 -264.566221)
			(xy 122.617738 -264.545572) (xy 122.616781 -264.541228) (xy 122.613595 -264.532924) (xy 122.611388 -264.529062)
			(xy 122.597406 -264.504315) (xy 122.577482 -264.45109) (xy 122.567335 -264.395172) (xy 122.566684 -264.366756)
			(xy 121.441972 -264.366756) (xy 121.441972 -264.608564) (xy 121.44155 -264.618586) (xy 121.433887 -264.637108)
			(xy 121.419715 -264.651282) (xy 121.401194 -264.658949) (xy 121.391172 -264.659364) (xy 121.177304 -264.659364)
			(xy 121.177304 -264.668508) (xy 121.176818 -264.678516) (xy 121.169157 -264.697007) (xy 121.155003 -264.711159)
			(xy 121.136512 -264.718819) (xy 121.126504 -264.719308) (xy 120.922288 -264.719308) (xy 120.901244 -264.718787)
			(xy 120.859972 -264.710544) (xy 120.821111 -264.694381) (xy 120.786168 -264.670922) (xy 120.756494 -264.641075)
			(xy 120.733237 -264.605997) (xy 120.717299 -264.567044) (xy 120.709295 -264.525724) (xy 120.708928 -264.504678)
			(xy 120.708928 -264.50417) (xy 120.708928 -264.483342) (xy 120.706134 -264.475214) (xy 120.697465 -264.449336)
			(xy 120.688149 -264.395566) (xy 120.687592 -264.36828) (xy 119.663972 -264.36828) (xy 119.663972 -264.608564)
			(xy 119.66355 -264.618586) (xy 119.655887 -264.637108) (xy 119.641715 -264.651282) (xy 119.623194 -264.658949)
			(xy 119.613172 -264.659364) (xy 119.399304 -264.659364) (xy 119.399304 -264.668508) (xy 119.398818 -264.678516)
			(xy 119.391157 -264.697007) (xy 119.377003 -264.711159) (xy 119.358512 -264.718819) (xy 119.348504 -264.719308)
			(xy 119.144288 -264.719308) (xy 119.12424 -264.718775) (xy 119.084859 -264.711224) (xy 119.047577 -264.696464)
			(xy 119.013699 -264.675013) (xy 118.998746 -264.66165) (xy 118.995988 -264.659161) (xy 118.989864 -264.654955)
			(xy 118.986554 -264.653268) (xy 118.964155 -264.641613) (xy 118.923038 -264.612312) (xy 118.887064 -264.576886)
			(xy 118.857135 -264.536224) (xy 118.834002 -264.491346) (xy 118.818245 -264.443378) (xy 118.81026 -264.393525)
			(xy 118.80977 -264.36828) (xy 117.758972 -264.36828) (xy 117.758972 -264.608564) (xy 117.75855 -264.618586)
			(xy 117.750887 -264.637108) (xy 117.736715 -264.651282) (xy 117.718194 -264.658949) (xy 117.708172 -264.659364)
			(xy 117.494304 -264.659364) (xy 117.494304 -264.668508) (xy 117.493818 -264.678516) (xy 117.486157 -264.697007)
			(xy 117.472003 -264.711159) (xy 117.453512 -264.718819) (xy 117.443504 -264.719308) (xy 117.239288 -264.719308)
			(xy 117.219515 -264.718804) (xy 117.180652 -264.711483) (xy 117.143801 -264.697131) (xy 117.110224 -264.676239)
			(xy 117.081068 -264.64952) (xy 117.068854 -264.633964) (xy 117.066582 -264.631105) (xy 117.061355 -264.626004)
			(xy 117.05844 -264.623804) (xy 117.03885 -264.608697) (xy 117.004177 -264.573412) (xy 116.975381 -264.533187)
			(xy 116.953155 -264.488991) (xy 116.938034 -264.441889) (xy 116.930384 -264.393015) (xy 116.929916 -264.36828)
			(xy 115.853972 -264.36828) (xy 115.853972 -264.608564) (xy 115.85355 -264.618586) (xy 115.845887 -264.637108)
			(xy 115.831715 -264.651282) (xy 115.813194 -264.658949) (xy 115.803172 -264.659364) (xy 115.589304 -264.659364)
			(xy 115.589304 -264.668508) (xy 115.588818 -264.678516) (xy 115.581157 -264.697007) (xy 115.567003 -264.711159)
			(xy 115.548512 -264.718819) (xy 115.538504 -264.719308) (xy 115.334288 -264.719308) (xy 115.313942 -264.718889)
			(xy 115.273989 -264.711172) (xy 115.236224 -264.696021) (xy 115.202016 -264.673985) (xy 115.172605 -264.645864)
			(xy 115.14906 -264.612676) (xy 115.140232 -264.59434) (xy 115.138593 -264.590828) (xy 115.134381 -264.584322)
			(xy 115.13185 -264.581386) (xy 115.116477 -264.56378) (xy 115.090553 -264.524889) (xy 115.070605 -264.48262)
			(xy 115.057063 -264.437885) (xy 115.05022 -264.39165) (xy 115.049808 -264.36828) (xy 108.360972 -264.36828)
			(xy 108.360972 -264.608564) (xy 108.36055 -264.618586) (xy 108.352887 -264.637108) (xy 108.338715 -264.651282)
			(xy 108.320194 -264.658949) (xy 108.310172 -264.659364) (xy 108.096304 -264.659364) (xy 108.096304 -264.668508)
			(xy 108.095818 -264.678516) (xy 108.088157 -264.697007) (xy 108.074003 -264.711159) (xy 108.055512 -264.718819)
			(xy 108.045504 -264.719308) (xy 107.841288 -264.719308) (xy 107.821852 -264.718901) (xy 107.783625 -264.71185)
			(xy 107.74731 -264.697985) (xy 107.714111 -264.677765) (xy 107.685128 -264.65186) (xy 107.672886 -264.636758)
			(xy 107.670611 -264.633901) (xy 107.665386 -264.628799) (xy 107.662472 -264.626598) (xy 107.642337 -264.611533)
			(xy 107.606599 -264.576161) (xy 107.576876 -264.535602) (xy 107.55391 -264.49087) (xy 107.538275 -264.443079)
			(xy 107.53036 -264.393422) (xy 107.529884 -264.36828) (xy 106.455972 -264.36828) (xy 106.455972 -264.608564)
			(xy 106.45555 -264.618586) (xy 106.447887 -264.637108) (xy 106.433715 -264.651282) (xy 106.415194 -264.658949)
			(xy 106.405172 -264.659364) (xy 106.191304 -264.659364) (xy 106.191304 -264.668508) (xy 106.190818 -264.678516)
			(xy 106.183157 -264.697007) (xy 106.169003 -264.711159) (xy 106.150512 -264.718819) (xy 106.140504 -264.719308)
			(xy 105.936288 -264.719308) (xy 105.91627 -264.71883) (xy 105.876945 -264.711319) (xy 105.839712 -264.696602)
			(xy 105.80588 -264.675195) (xy 105.776637 -264.64785) (xy 105.753011 -264.615528) (xy 105.74401 -264.597642)
			(xy 105.742244 -264.594113) (xy 105.737776 -264.587607) (xy 105.73512 -264.584688) (xy 105.719194 -264.566971)
			(xy 105.692322 -264.527633) (xy 105.671624 -264.484724) (xy 105.657562 -264.439207) (xy 105.650454 -264.3921)
			(xy 105.65003 -264.36828) (xy 104.550972 -264.36828) (xy 104.550972 -264.608564) (xy 104.55055 -264.618586)
			(xy 104.542887 -264.637108) (xy 104.528715 -264.651282) (xy 104.510194 -264.658949) (xy 104.500172 -264.659364)
			(xy 104.286304 -264.659364) (xy 104.286304 -264.668508) (xy 104.285818 -264.678516) (xy 104.278157 -264.697007)
			(xy 104.264003 -264.711159) (xy 104.245512 -264.718819) (xy 104.235504 -264.719308) (xy 104.031288 -264.719308)
			(xy 104.010463 -264.718748) (xy 103.969602 -264.710684) (xy 103.931081 -264.694847) (xy 103.896365 -264.671837)
			(xy 103.866773 -264.642529) (xy 103.843429 -264.608037) (xy 103.82722 -264.569671) (xy 103.8225 -264.549382)
			(xy 103.82151 -264.545169) (xy 103.818318 -264.537126) (xy 103.81615 -264.53338) (xy 103.801656 -264.508305)
			(xy 103.781038 -264.45419) (xy 103.770558 -264.397235) (xy 103.769922 -264.36828) (xy 102.645972 -264.36828)
			(xy 102.645972 -264.608564) (xy 102.64555 -264.618586) (xy 102.637887 -264.637108) (xy 102.623715 -264.651282)
			(xy 102.605194 -264.658949) (xy 102.595172 -264.659364) (xy 102.381304 -264.659364) (xy 102.381304 -264.668508)
			(xy 102.380818 -264.678516) (xy 102.373157 -264.697007) (xy 102.359003 -264.711159) (xy 102.340512 -264.718819)
			(xy 102.330504 -264.719308) (xy 102.126288 -264.719308) (xy 102.105244 -264.718787) (xy 102.063972 -264.710544)
			(xy 102.025111 -264.694381) (xy 101.990168 -264.670922) (xy 101.960494 -264.641075) (xy 101.937237 -264.605997)
			(xy 101.921299 -264.567044) (xy 101.913295 -264.525724) (xy 101.912928 -264.504678) (xy 101.912928 -264.50417)
			(xy 101.912928 -264.4775) (xy 101.910388 -264.469372) (xy 101.902357 -264.444349) (xy 101.893677 -264.392522)
			(xy 101.893116 -264.366248) (xy 101.236018 -264.366248) (xy 101.236018 -264.672318) (xy 101.236272 -264.674604)
			(xy 101.236272 -265.201243) (xy 101.423452 -265.201243) (xy 101.423452 -265.151265) (xy 101.431271 -265.101902)
			(xy 101.446715 -265.05437) (xy 101.469405 -265.009838) (xy 101.498781 -264.969405) (xy 101.534121 -264.934065)
			(xy 101.574554 -264.904689) (xy 101.619086 -264.881999) (xy 101.666618 -264.866555) (xy 101.715981 -264.858736)
			(xy 101.765959 -264.858736) (xy 101.790202 -264.862576) (xy 111.221526 -264.862576) (xy 111.225828 -264.807355)
			(xy 111.238623 -264.753464) (xy 111.259603 -264.702202) (xy 111.288263 -264.654804) (xy 111.323911 -264.612411)
			(xy 111.344456 -264.593832) (xy 111.352076 -264.58545) (xy 111.364271 -264.569508) (xy 111.393578 -264.542088)
			(xy 111.427486 -264.520618) (xy 111.464804 -264.505851) (xy 111.504222 -264.498305) (xy 111.524288 -264.49782)
			(xy 111.779304 -264.49782) (xy 111.779304 -264.506964) (xy 111.779749 -264.516983) (xy 111.787408 -264.5355)
			(xy 111.801573 -264.549674) (xy 111.820085 -264.557344) (xy 111.830104 -264.557764) (xy 111.993172 -264.557764)
			(xy 112.003173 -264.55831) (xy 112.021658 -264.565954) (xy 112.035811 -264.580088) (xy 112.043477 -264.598563)
			(xy 112.043972 -264.608564) (xy 112.043972 -265.116564) (xy 112.04355 -265.126586) (xy 112.035887 -265.145108)
			(xy 112.021715 -265.159282) (xy 112.003194 -265.166949) (xy 111.993172 -265.167364) (xy 111.779304 -265.167364)
			(xy 111.779304 -265.176508) (xy 111.778818 -265.186516) (xy 111.772716 -265.201243) (xy 121.15722 -265.201243)
			(xy 121.15722 -265.151265) (xy 121.165039 -265.101902) (xy 121.180483 -265.05437) (xy 121.203173 -265.009838)
			(xy 121.232549 -264.969405) (xy 121.267889 -264.934065) (xy 121.308322 -264.904689) (xy 121.352854 -264.881999)
			(xy 121.400386 -264.866555) (xy 121.449749 -264.858736) (xy 121.499727 -264.858736) (xy 121.54909 -264.866555)
			(xy 121.596622 -264.881999) (xy 121.641154 -264.904689) (xy 121.681587 -264.934065) (xy 121.716927 -264.969405)
			(xy 121.746303 -265.009838) (xy 121.768993 -265.05437) (xy 121.784437 -265.101902) (xy 121.792256 -265.151265)
			(xy 121.792746 -265.176254) (xy 121.792256 -265.201243) (xy 123.037328 -265.201243) (xy 123.037328 -265.151265)
			(xy 123.045147 -265.101902) (xy 123.060591 -265.05437) (xy 123.083281 -265.009838) (xy 123.112657 -264.969405)
			(xy 123.147997 -264.934065) (xy 123.18843 -264.904689) (xy 123.232962 -264.881999) (xy 123.280494 -264.866555)
			(xy 123.329857 -264.858736) (xy 123.379835 -264.858736) (xy 123.429198 -264.866555) (xy 123.47673 -264.881999)
			(xy 123.521262 -264.904689) (xy 123.561695 -264.934065) (xy 123.597035 -264.969405) (xy 123.626411 -265.009838)
			(xy 123.649101 -265.05437) (xy 123.664545 -265.101902) (xy 123.672364 -265.151265) (xy 123.672854 -265.176254)
			(xy 123.672364 -265.201243) (xy 124.917182 -265.201243) (xy 124.917182 -265.151265) (xy 124.925001 -265.101902)
			(xy 124.940445 -265.05437) (xy 124.963135 -265.009838) (xy 124.992511 -264.969405) (xy 125.027851 -264.934065)
			(xy 125.068284 -264.904689) (xy 125.112816 -264.881999) (xy 125.160348 -264.866555) (xy 125.209711 -264.858736)
			(xy 125.259689 -264.858736) (xy 125.309052 -264.866555) (xy 125.356584 -264.881999) (xy 125.401116 -264.904689)
			(xy 125.441549 -264.934065) (xy 125.476889 -264.969405) (xy 125.506265 -265.009838) (xy 125.528955 -265.05437)
			(xy 125.544399 -265.101902) (xy 125.552218 -265.151265) (xy 125.552708 -265.176254) (xy 125.552218 -265.201243)
			(xy 126.79729 -265.201243) (xy 126.79729 -265.151265) (xy 126.805109 -265.101902) (xy 126.820553 -265.05437)
			(xy 126.843243 -265.009838) (xy 126.872619 -264.969405) (xy 126.907959 -264.934065) (xy 126.948392 -264.904689)
			(xy 126.992924 -264.881999) (xy 127.040456 -264.866555) (xy 127.089819 -264.858736) (xy 127.139797 -264.858736)
			(xy 127.18916 -264.866555) (xy 127.236692 -264.881999) (xy 127.281224 -264.904689) (xy 127.321657 -264.934065)
			(xy 127.356997 -264.969405) (xy 127.386373 -265.009838) (xy 127.409063 -265.05437) (xy 127.424507 -265.101902)
			(xy 127.432326 -265.151265) (xy 127.432816 -265.176254) (xy 127.738627 -265.176254) (xy 127.742722 -265.125526)
			(xy 127.754901 -265.076112) (xy 127.774849 -265.029292) (xy 127.80205 -264.986278) (xy 127.835798 -264.948184)
			(xy 127.87522 -264.915997) (xy 127.919294 -264.890551) (xy 127.96688 -264.872504) (xy 128.016744 -264.862324)
			(xy 128.067596 -264.860275) (xy 128.118117 -264.866409) (xy 128.167001 -264.880569) (xy 128.21298 -264.902386)
			(xy 128.254864 -264.931296) (xy 128.291568 -264.966551) (xy 128.322141 -265.007237) (xy 128.345792 -265.0523)
			(xy 128.361908 -265.100574) (xy 128.370072 -265.150808) (xy 128.370584 -265.176254) (xy 128.370081 -265.201243)
			(xy 128.677144 -265.201243) (xy 128.677144 -265.151265) (xy 128.684963 -265.101902) (xy 128.700407 -265.05437)
			(xy 128.723097 -265.009838) (xy 128.752473 -264.969405) (xy 128.787813 -264.934065) (xy 128.828246 -264.904689)
			(xy 128.872778 -264.881999) (xy 128.92031 -264.866555) (xy 128.969673 -264.858736) (xy 129.019651 -264.858736)
			(xy 129.069014 -264.866555) (xy 129.116546 -264.881999) (xy 129.161078 -264.904689) (xy 129.201511 -264.934065)
			(xy 129.236851 -264.969405) (xy 129.266227 -265.009838) (xy 129.288917 -265.05437) (xy 129.304361 -265.101902)
			(xy 129.31218 -265.151265) (xy 129.31267 -265.176254) (xy 129.31218 -265.201243) (xy 129.617198 -265.201243)
			(xy 129.617198 -265.151265) (xy 129.625017 -265.101902) (xy 129.640461 -265.05437) (xy 129.663151 -265.009838)
			(xy 129.692527 -264.969405) (xy 129.727867 -264.934065) (xy 129.7683 -264.904689) (xy 129.812832 -264.881999)
			(xy 129.860364 -264.866555) (xy 129.909727 -264.858736) (xy 129.959705 -264.858736) (xy 130.009068 -264.866555)
			(xy 130.0566 -264.881999) (xy 130.101132 -264.904689) (xy 130.141565 -264.934065) (xy 130.176905 -264.969405)
			(xy 130.206281 -265.009838) (xy 130.228971 -265.05437) (xy 130.244415 -265.101902) (xy 130.252234 -265.151265)
			(xy 130.252724 -265.176254) (xy 130.252234 -265.201243) (xy 130.557252 -265.201243) (xy 130.557252 -265.151265)
			(xy 130.565071 -265.101902) (xy 130.580515 -265.05437) (xy 130.603205 -265.009838) (xy 130.632581 -264.969405)
			(xy 130.667921 -264.934065) (xy 130.708354 -264.904689) (xy 130.752886 -264.881999) (xy 130.800418 -264.866555)
			(xy 130.849781 -264.858736) (xy 130.899759 -264.858736) (xy 130.949122 -264.866555) (xy 130.996654 -264.881999)
			(xy 131.041186 -264.904689) (xy 131.081619 -264.934065) (xy 131.116959 -264.969405) (xy 131.146335 -265.009838)
			(xy 131.169025 -265.05437) (xy 131.184469 -265.101902) (xy 131.192288 -265.151265) (xy 131.192778 -265.176254)
			(xy 131.498589 -265.176254) (xy 131.502684 -265.125526) (xy 131.514863 -265.076112) (xy 131.534811 -265.029292)
			(xy 131.562012 -264.986278) (xy 131.59576 -264.948184) (xy 131.635182 -264.915997) (xy 131.679256 -264.890551)
			(xy 131.726842 -264.872504) (xy 131.776706 -264.862324) (xy 131.827558 -264.860275) (xy 131.878079 -264.866409)
			(xy 131.926963 -264.880569) (xy 131.972942 -264.902386) (xy 132.014826 -264.931296) (xy 132.05153 -264.966551)
			(xy 132.082103 -265.007237) (xy 132.105754 -265.0523) (xy 132.12187 -265.100574) (xy 132.130034 -265.150808)
			(xy 132.130546 -265.176254) (xy 132.130043 -265.201243) (xy 132.437106 -265.201243) (xy 132.437106 -265.151265)
			(xy 132.444925 -265.101902) (xy 132.460369 -265.05437) (xy 132.483059 -265.009838) (xy 132.512435 -264.969405)
			(xy 132.547775 -264.934065) (xy 132.588208 -264.904689) (xy 132.63274 -264.881999) (xy 132.680272 -264.866555)
			(xy 132.729635 -264.858736) (xy 132.779613 -264.858736) (xy 132.828976 -264.866555) (xy 132.876508 -264.881999)
			(xy 132.92104 -264.904689) (xy 132.961473 -264.934065) (xy 132.996813 -264.969405) (xy 133.026189 -265.009838)
			(xy 133.048879 -265.05437) (xy 133.064323 -265.101902) (xy 133.072142 -265.151265) (xy 133.072632 -265.176254)
			(xy 133.072142 -265.201243) (xy 133.064323 -265.250606) (xy 133.048879 -265.298138) (xy 133.026189 -265.34267)
			(xy 132.996813 -265.383103) (xy 132.961473 -265.418443) (xy 132.92104 -265.447819) (xy 132.876508 -265.470509)
			(xy 132.828976 -265.485953) (xy 132.779613 -265.493772) (xy 132.729635 -265.493772) (xy 132.680272 -265.485953)
			(xy 132.63274 -265.470509) (xy 132.588208 -265.447819) (xy 132.547775 -265.418443) (xy 132.512435 -265.383103)
			(xy 132.483059 -265.34267) (xy 132.460369 -265.298138) (xy 132.444925 -265.250606) (xy 132.437106 -265.201243)
			(xy 132.130043 -265.201243) (xy 132.130034 -265.2017) (xy 132.12187 -265.251934) (xy 132.105754 -265.300208)
			(xy 132.082103 -265.345271) (xy 132.05153 -265.385957) (xy 132.014826 -265.421212) (xy 131.972942 -265.450122)
			(xy 131.926963 -265.471939) (xy 131.878079 -265.486099) (xy 131.827558 -265.492233) (xy 131.776706 -265.490184)
			(xy 131.726842 -265.480004) (xy 131.679256 -265.461957) (xy 131.635182 -265.436511) (xy 131.59576 -265.404324)
			(xy 131.562012 -265.36623) (xy 131.534811 -265.323216) (xy 131.514863 -265.276396) (xy 131.502684 -265.226982)
			(xy 131.498589 -265.176254) (xy 131.192778 -265.176254) (xy 131.192288 -265.201243) (xy 131.184469 -265.250606)
			(xy 131.169025 -265.298138) (xy 131.146335 -265.34267) (xy 131.116959 -265.383103) (xy 131.081619 -265.418443)
			(xy 131.041186 -265.447819) (xy 130.996654 -265.470509) (xy 130.949122 -265.485953) (xy 130.899759 -265.493772)
			(xy 130.849781 -265.493772) (xy 130.800418 -265.485953) (xy 130.752886 -265.470509) (xy 130.708354 -265.447819)
			(xy 130.667921 -265.418443) (xy 130.632581 -265.383103) (xy 130.603205 -265.34267) (xy 130.580515 -265.298138)
			(xy 130.565071 -265.250606) (xy 130.557252 -265.201243) (xy 130.252234 -265.201243) (xy 130.244415 -265.250606)
			(xy 130.228971 -265.298138) (xy 130.206281 -265.34267) (xy 130.176905 -265.383103) (xy 130.141565 -265.418443)
			(xy 130.101132 -265.447819) (xy 130.0566 -265.470509) (xy 130.009068 -265.485953) (xy 129.959705 -265.493772)
			(xy 129.909727 -265.493772) (xy 129.860364 -265.485953) (xy 129.812832 -265.470509) (xy 129.7683 -265.447819)
			(xy 129.727867 -265.418443) (xy 129.692527 -265.383103) (xy 129.663151 -265.34267) (xy 129.640461 -265.298138)
			(xy 129.625017 -265.250606) (xy 129.617198 -265.201243) (xy 129.31218 -265.201243) (xy 129.304361 -265.250606)
			(xy 129.288917 -265.298138) (xy 129.266227 -265.34267) (xy 129.236851 -265.383103) (xy 129.201511 -265.418443)
			(xy 129.161078 -265.447819) (xy 129.116546 -265.470509) (xy 129.069014 -265.485953) (xy 129.019651 -265.493772)
			(xy 128.969673 -265.493772) (xy 128.92031 -265.485953) (xy 128.872778 -265.470509) (xy 128.828246 -265.447819)
			(xy 128.787813 -265.418443) (xy 128.752473 -265.383103) (xy 128.723097 -265.34267) (xy 128.700407 -265.298138)
			(xy 128.684963 -265.250606) (xy 128.677144 -265.201243) (xy 128.370081 -265.201243) (xy 128.370072 -265.2017)
			(xy 128.361908 -265.251934) (xy 128.345792 -265.300208) (xy 128.322141 -265.345271) (xy 128.291568 -265.385957)
			(xy 128.254864 -265.421212) (xy 128.21298 -265.450122) (xy 128.167001 -265.471939) (xy 128.118117 -265.486099)
			(xy 128.067596 -265.492233) (xy 128.016744 -265.490184) (xy 127.96688 -265.480004) (xy 127.919294 -265.461957)
			(xy 127.87522 -265.436511) (xy 127.835798 -265.404324) (xy 127.80205 -265.36623) (xy 127.774849 -265.323216)
			(xy 127.754901 -265.276396) (xy 127.742722 -265.226982) (xy 127.738627 -265.176254) (xy 127.432816 -265.176254)
			(xy 127.432326 -265.201243) (xy 127.424507 -265.250606) (xy 127.409063 -265.298138) (xy 127.386373 -265.34267)
			(xy 127.356997 -265.383103) (xy 127.321657 -265.418443) (xy 127.281224 -265.447819) (xy 127.236692 -265.470509)
			(xy 127.18916 -265.485953) (xy 127.139797 -265.493772) (xy 127.089819 -265.493772) (xy 127.040456 -265.485953)
			(xy 126.992924 -265.470509) (xy 126.948392 -265.447819) (xy 126.907959 -265.418443) (xy 126.872619 -265.383103)
			(xy 126.843243 -265.34267) (xy 126.820553 -265.298138) (xy 126.805109 -265.250606) (xy 126.79729 -265.201243)
			(xy 125.552218 -265.201243) (xy 125.544399 -265.250606) (xy 125.528955 -265.298138) (xy 125.506265 -265.34267)
			(xy 125.476889 -265.383103) (xy 125.441549 -265.418443) (xy 125.401116 -265.447819) (xy 125.356584 -265.470509)
			(xy 125.309052 -265.485953) (xy 125.259689 -265.493772) (xy 125.209711 -265.493772) (xy 125.160348 -265.485953)
			(xy 125.112816 -265.470509) (xy 125.068284 -265.447819) (xy 125.027851 -265.418443) (xy 124.992511 -265.383103)
			(xy 124.963135 -265.34267) (xy 124.940445 -265.298138) (xy 124.925001 -265.250606) (xy 124.917182 -265.201243)
			(xy 123.672364 -265.201243) (xy 123.664545 -265.250606) (xy 123.649101 -265.298138) (xy 123.626411 -265.34267)
			(xy 123.597035 -265.383103) (xy 123.561695 -265.418443) (xy 123.521262 -265.447819) (xy 123.47673 -265.470509)
			(xy 123.429198 -265.485953) (xy 123.379835 -265.493772) (xy 123.329857 -265.493772) (xy 123.280494 -265.485953)
			(xy 123.232962 -265.470509) (xy 123.18843 -265.447819) (xy 123.147997 -265.418443) (xy 123.112657 -265.383103)
			(xy 123.083281 -265.34267) (xy 123.060591 -265.298138) (xy 123.045147 -265.250606) (xy 123.037328 -265.201243)
			(xy 121.792256 -265.201243) (xy 121.784437 -265.250606) (xy 121.768993 -265.298138) (xy 121.746303 -265.34267)
			(xy 121.716927 -265.383103) (xy 121.681587 -265.418443) (xy 121.641154 -265.447819) (xy 121.596622 -265.470509)
			(xy 121.54909 -265.485953) (xy 121.499727 -265.493772) (xy 121.449749 -265.493772) (xy 121.400386 -265.485953)
			(xy 121.352854 -265.470509) (xy 121.308322 -265.447819) (xy 121.267889 -265.418443) (xy 121.232549 -265.383103)
			(xy 121.203173 -265.34267) (xy 121.180483 -265.298138) (xy 121.165039 -265.250606) (xy 121.15722 -265.201243)
			(xy 111.772716 -265.201243) (xy 111.771157 -265.205007) (xy 111.757003 -265.219159) (xy 111.738512 -265.226819)
			(xy 111.728504 -265.227308) (xy 111.524288 -265.227308) (xy 111.504219 -265.226825) (xy 111.464789 -265.219312)
			(xy 111.427462 -265.204555) (xy 111.393555 -265.183074) (xy 111.364266 -265.155628) (xy 111.352076 -265.139678)
			(xy 111.344456 -265.131296) (xy 111.323878 -265.112755) (xy 111.288235 -265.070358) (xy 111.259582 -265.022956)
			(xy 111.238609 -264.971691) (xy 111.225821 -264.917799) (xy 111.221526 -264.862576) (xy 101.790202 -264.862576)
			(xy 101.815322 -264.866555) (xy 101.862854 -264.881999) (xy 101.907386 -264.904689) (xy 101.947819 -264.934065)
			(xy 101.983159 -264.969405) (xy 102.012535 -265.009838) (xy 102.035225 -265.05437) (xy 102.050669 -265.101902)
			(xy 102.058488 -265.151265) (xy 102.058978 -265.176254) (xy 102.058488 -265.201243) (xy 102.050669 -265.250606)
			(xy 102.035225 -265.298138) (xy 102.012535 -265.34267) (xy 101.983159 -265.383103) (xy 101.947819 -265.418443)
			(xy 101.907386 -265.447819) (xy 101.862854 -265.470509) (xy 101.815322 -265.485953) (xy 101.765959 -265.493772)
			(xy 101.715981 -265.493772) (xy 101.666618 -265.485953) (xy 101.619086 -265.470509) (xy 101.574554 -265.447819)
			(xy 101.534121 -265.418443) (xy 101.498781 -265.383103) (xy 101.469405 -265.34267) (xy 101.446715 -265.298138)
			(xy 101.431271 -265.250606) (xy 101.423452 -265.201243) (xy 101.236272 -265.201243) (xy 101.236272 -265.350752)
			(xy 101.236018 -265.353038) (xy 101.236018 -265.39698) (xy 101.236018 -265.397234) (xy 101.23558 -265.407116)
			(xy 101.22813 -265.425418) (xy 101.22154 -265.432794) (xy 101.056694 -265.59764) (xy 101.052769 -265.601377)
			(xy 101.043671 -265.607259) (xy 101.03866 -265.609324) (xy 101.038406 -265.609324) (xy 101.031207 -265.6123)
			(xy 101.018928 -265.621871) (xy 101.014276 -265.62812) (xy 101.009958 -265.634216) (xy 101.005386 -265.648948)
			(xy 101.005386 -266.238482) (xy 101.006402 -266.248134) (xy 101.008026 -266.25538) (xy 101.014862 -266.268555)
			(xy 101.019864 -266.274042) (xy 101.117908 -266.372086) (xy 101.123406 -266.377077) (xy 101.136571 -266.383927)
			(xy 101.143816 -266.385548) (xy 101.153468 -266.386564) (xy 102.027482 -266.386564) (xy 102.032054 -266.38631)
			(xy 102.04071 -266.385214) (xy 102.056568 -266.377965) (xy 102.069047 -266.365789) (xy 102.073202 -266.358116)
			(xy 102.083616 -266.334494) (xy 102.083616 -266.333986) (xy 102.08387 -266.333478) (xy 102.086607 -266.326182)
			(xy 102.088019 -266.310672) (xy 102.086664 -266.302998) (xy 102.084378 -266.29487) (xy 102.081251 -266.286755)
			(xy 102.070463 -266.273129) (xy 102.063296 -266.2682) (xy 102.041621 -266.256272) (xy 102.001924 -266.226748)
			(xy 101.967271 -266.19144) (xy 101.938496 -266.151197) (xy 101.916292 -266.106988) (xy 101.901192 -266.059876)
			(xy 101.893562 -266.010996) (xy 101.893116 -265.98626) (xy 101.893116 -265.986006) (xy 101.893575 -265.961738)
			(xy 101.900955 -265.913765) (xy 101.915544 -265.867473) (xy 101.937003 -265.823937) (xy 101.964832 -265.784171)
			(xy 101.981254 -265.766296) (xy 101.997743 -265.749683) (xy 102.034723 -265.720988) (xy 102.054914 -265.709146)
			(xy 102.071276 -265.700225) (xy 102.105653 -265.685831) (xy 102.123494 -265.680444) (xy 102.127304 -265.679174)
			(xy 102.13213 -265.676888) (xy 102.150147 -265.665175) (xy 102.189706 -265.648408) (xy 102.231806 -265.639822)
			(xy 102.253288 -265.639296) (xy 102.48011 -265.639296) (xy 102.509828 -265.669014) (xy 102.509828 -265.680698)
			(xy 102.511098 -265.683492) (xy 102.522782 -265.691112) (xy 102.529063 -265.694902) (xy 102.543135 -265.699027)
			(xy 102.550468 -265.69924) (xy 102.723696 -265.69924) (xy 102.733715 -265.69966) (xy 102.752226 -265.70733)
			(xy 102.76639 -265.721504) (xy 102.774048 -265.740021) (xy 102.774496 -265.75004) (xy 102.774496 -266.311888)
			(xy 102.773988 -266.311888) (xy 102.773988 -266.335764) (xy 102.774401 -266.345791) (xy 102.782064 -266.364322)
			(xy 102.796237 -266.378509) (xy 102.814761 -266.386189) (xy 102.824788 -266.386564) (xy 103.745538 -266.386564)
			(xy 103.758203 -266.385812) (xy 103.780451 -266.373681) (xy 103.787956 -266.36345) (xy 103.81488 -266.322048)
			(xy 103.82885 -266.300458) (xy 103.832616 -266.294235) (xy 103.836749 -266.280296) (xy 103.836978 -266.273026)
			(xy 103.836978 -266.245086) (xy 103.833422 -266.236196) (xy 103.830094 -266.227648) (xy 103.824753 -266.210097)
			(xy 103.822754 -266.201144) (xy 103.822754 -266.200636) (xy 103.821006 -266.192155) (xy 103.818721 -266.174989)
			(xy 103.818182 -266.166346) (xy 103.817928 -266.161012) (xy 103.81234 -266.13993) (xy 103.809546 -266.134596)
			(xy 103.809292 -266.134342) (xy 103.800952 -266.117784) (xy 103.787713 -266.083152) (xy 103.782876 -266.065254)
			(xy 103.778261 -266.045961) (xy 103.773297 -266.006603) (xy 103.77297 -265.986768) (xy 103.77297 -265.977878)
			(xy 103.774171 -265.95211) (xy 103.783879 -265.901449) (xy 103.801639 -265.85302) (xy 103.813864 -265.830304)
			(xy 103.814118 -265.829796) (xy 103.816912 -265.824716) (xy 103.822246 -265.811254) (xy 103.823008 -265.808206)
			(xy 103.823262 -265.806936) (xy 103.828257 -265.78699) (xy 103.844834 -265.749368) (xy 103.868311 -265.715618)
			(xy 103.897819 -265.686991) (xy 103.932266 -265.664549) (xy 103.970374 -265.649121) (xy 104.010731 -265.64128)
			(xy 104.031288 -265.64082) (xy 104.256586 -265.64082) (xy 104.286304 -265.670538) (xy 104.286304 -265.680698)
			(xy 104.288082 -265.684508) (xy 104.300528 -265.692636) (xy 104.306808 -265.696432) (xy 104.320879 -265.70057)
			(xy 104.328214 -265.700764) (xy 104.521254 -265.700764) (xy 104.550972 -265.730482) (xy 104.550972 -265.745468)
			(xy 104.551226 -265.748008) (xy 104.551226 -266.336526) (xy 104.551704 -266.346351) (xy 104.559205 -266.364514)
			(xy 104.573064 -266.378446) (xy 104.591187 -266.386043) (xy 104.60101 -266.386564) (xy 105.650538 -266.386564)
			(xy 105.663203 -266.385812) (xy 105.685451 -266.373681) (xy 105.692956 -266.36345) (xy 105.71988 -266.322048)
			(xy 105.73385 -266.300458) (xy 105.737616 -266.294235) (xy 105.741749 -266.280296) (xy 105.741978 -266.273026)
			(xy 105.741978 -266.244832) (xy 105.737914 -266.235434) (xy 105.737152 -266.233402) (xy 105.735628 -266.229084)
			(xy 105.734358 -266.225528) (xy 105.73258 -266.220194) (xy 105.73258 -266.219686) (xy 105.728262 -266.203938)
			(xy 105.727246 -266.19835) (xy 105.718864 -266.18057) (xy 105.715816 -266.176506) (xy 105.701047 -266.155768)
			(xy 105.677598 -266.110581) (xy 105.661641 -266.062237) (xy 105.653583 -266.011969) (xy 105.653078 -265.986514)
			(xy 105.653078 -265.986006) (xy 105.653502 -265.962472) (xy 105.660436 -265.915919) (xy 105.674154 -265.870895)
			(xy 105.694356 -265.828384) (xy 105.720601 -265.789313) (xy 105.736136 -265.77163) (xy 105.738422 -265.76909)
			(xy 105.745026 -265.759692) (xy 105.747058 -265.755882) (xy 105.750106 -265.750294) (xy 105.761624 -265.730784)
			(xy 105.791499 -265.696735) (xy 105.827875 -265.669742) (xy 105.869121 -265.651016) (xy 105.913386 -265.641399)
			(xy 105.936034 -265.64082) (xy 106.161586 -265.64082) (xy 106.191304 -265.670538) (xy 106.191304 -265.680698)
			(xy 106.193082 -265.684508) (xy 106.205528 -265.692636) (xy 106.211808 -265.696432) (xy 106.225879 -265.70057)
			(xy 106.233214 -265.700764) (xy 106.426254 -265.700764) (xy 106.455972 -265.730482) (xy 106.455972 -265.745468)
			(xy 106.456226 -265.748008) (xy 106.456226 -266.336526) (xy 106.456704 -266.346351) (xy 106.464205 -266.364514)
			(xy 106.478064 -266.378446) (xy 106.496187 -266.386043) (xy 106.50601 -266.386564) (xy 107.54995 -266.386564)
			(xy 107.559856 -266.385548) (xy 107.56011 -266.385548) (xy 107.566714 -266.384278) (xy 107.575716 -266.381973)
			(xy 107.591334 -266.371933) (xy 107.597194 -266.36472) (xy 107.598718 -266.362434) (xy 107.62488 -266.322302)
			(xy 107.62488 -266.321794) (xy 107.643422 -266.292838) (xy 107.64674 -266.287385) (xy 107.650853 -266.275307)
			(xy 107.65155 -266.268962) (xy 107.652312 -266.256516) (xy 107.646724 -266.244324) (xy 107.645454 -266.24153)
			(xy 107.643676 -266.237466) (xy 107.641898 -266.233148) (xy 107.63123 -266.216384) (xy 107.626912 -266.21232)
			(xy 107.609381 -266.194275) (xy 107.579664 -266.153681) (xy 107.556705 -266.108917) (xy 107.541076 -266.061097)
			(xy 107.533167 -266.011414) (xy 107.532678 -265.98626) (xy 107.532678 -265.97991) (xy 107.53344 -265.966956)
			(xy 107.53598 -265.94181) (xy 107.538012 -265.928348) (xy 107.54296 -265.904172) (xy 107.559318 -265.857618)
			(xy 107.582656 -265.81414) (xy 107.612416 -265.774779) (xy 107.647887 -265.740475) (xy 107.667806 -265.72591)
			(xy 107.671108 -265.723624) (xy 107.677458 -265.717528) (xy 107.679998 -265.714734) (xy 107.680252 -265.71448)
			(xy 107.6833 -265.711178) (xy 107.684824 -265.7094) (xy 107.700099 -265.693655) (xy 107.735801 -265.668179)
			(xy 107.775948 -265.650517) (xy 107.818852 -265.64141) (xy 107.84078 -265.64082) (xy 108.066586 -265.64082)
			(xy 108.096304 -265.670538) (xy 108.096304 -265.680698) (xy 108.098082 -265.684508) (xy 108.110528 -265.692636)
			(xy 108.116808 -265.696432) (xy 108.130879 -265.70057) (xy 108.138214 -265.700764) (xy 108.331254 -265.700764)
			(xy 108.360972 -265.730482) (xy 108.360972 -265.745468) (xy 108.361226 -265.748008) (xy 108.361226 -266.336526)
			(xy 108.361704 -266.346351) (xy 108.369205 -266.364514) (xy 108.383064 -266.378446) (xy 108.401187 -266.386043)
			(xy 108.41101 -266.386564) (xy 109.333538 -266.386564) (xy 109.346203 -266.385812) (xy 109.368451 -266.373681)
			(xy 109.375956 -266.36345) (xy 109.40288 -266.322048) (xy 109.41685 -266.300458) (xy 109.420616 -266.294235)
			(xy 109.424749 -266.280296) (xy 109.424978 -266.273026) (xy 109.424978 -266.245086) (xy 109.421168 -266.235942)
			(xy 109.415326 -266.219178) (xy 109.410725 -266.203131) (xy 109.405999 -266.170086) (xy 109.405928 -266.153392)
			(xy 109.405928 -265.858244) (xy 109.405928 -265.857482) (xy 109.406103 -265.836306) (xy 109.413805 -265.794671)
			(xy 109.42956 -265.755369) (xy 109.45275 -265.719943) (xy 109.482465 -265.689779) (xy 109.517541 -265.666062)
			(xy 109.556602 -265.64972) (xy 109.598117 -265.641395) (xy 109.619288 -265.64082) (xy 109.844586 -265.64082)
			(xy 109.874304 -265.670538) (xy 109.874304 -265.680698) (xy 109.876082 -265.684508) (xy 109.888528 -265.692636)
			(xy 109.894808 -265.696432) (xy 109.908879 -265.70057) (xy 109.916214 -265.700764) (xy 110.109254 -265.700764)
			(xy 110.138972 -265.730482) (xy 110.138972 -265.745468) (xy 110.139226 -265.748008) (xy 110.139226 -266.336526)
			(xy 110.139704 -266.346351) (xy 110.147205 -266.364514) (xy 110.161064 -266.378446) (xy 110.179187 -266.386043)
			(xy 110.18901 -266.386564) (xy 113.143538 -266.386564) (xy 113.156203 -266.385812) (xy 113.178451 -266.373681)
			(xy 113.185956 -266.36345) (xy 113.21288 -266.322048) (xy 113.22685 -266.300458) (xy 113.230616 -266.294235)
			(xy 113.234749 -266.280296) (xy 113.234978 -266.273026) (xy 113.234978 -266.245086) (xy 113.231168 -266.235942)
			(xy 113.22558 -266.220194) (xy 113.221094 -266.204833) (xy 113.216254 -266.173201) (xy 113.215928 -266.157202)
			(xy 113.215928 -266.15644) (xy 113.204261 -266.137254) (xy 113.185843 -266.096301) (xy 113.173356 -266.053169)
			(xy 113.167045 -266.008712) (xy 113.166652 -265.98626) (xy 113.166652 -265.97991) (xy 113.167856 -265.95144)
			(xy 113.17912 -265.895589) (xy 113.200145 -265.842634) (xy 113.214658 -265.818112) (xy 113.21669 -265.81481)
			(xy 113.22177 -265.803634) (xy 113.222786 -265.79957) (xy 113.228359 -265.78035) (xy 113.245648 -265.744266)
			(xy 113.269352 -265.71203) (xy 113.29864 -265.684768) (xy 113.332491 -265.663434) (xy 113.36972 -265.648772)
			(xy 113.409028 -265.641295) (xy 113.429034 -265.64082) (xy 113.654586 -265.64082) (xy 113.684304 -265.670538)
			(xy 113.684304 -265.680698) (xy 113.686082 -265.684508) (xy 113.698528 -265.692636) (xy 113.704808 -265.696432)
			(xy 113.718879 -265.70057) (xy 113.726214 -265.700764) (xy 113.919254 -265.700764) (xy 113.948972 -265.730482)
			(xy 113.948972 -265.745468) (xy 113.949226 -265.748008) (xy 113.949226 -266.336526) (xy 113.949704 -266.346351)
			(xy 113.957205 -266.364514) (xy 113.971064 -266.378446) (xy 113.989187 -266.386043) (xy 113.99901 -266.386564)
			(xy 115.048538 -266.386564) (xy 115.061203 -266.385812) (xy 115.083451 -266.373681) (xy 115.090956 -266.36345)
			(xy 115.11788 -266.322048) (xy 115.13185 -266.300458) (xy 115.135616 -266.294235) (xy 115.139749 -266.280296)
			(xy 115.139978 -266.273026) (xy 115.139978 -266.245594) (xy 115.136422 -266.23645) (xy 115.135152 -266.232894)
			(xy 115.134898 -266.232386) (xy 115.127786 -266.210034) (xy 115.126516 -266.204954) (xy 115.11915 -266.190222)
			(xy 115.113816 -266.18184) (xy 115.112038 -266.179554) (xy 115.112038 -266.1793) (xy 115.096714 -266.158397)
			(xy 115.072349 -266.112653) (xy 115.055727 -266.063563) (xy 115.047287 -266.012427) (xy 115.04676 -265.986514)
			(xy 115.04676 -265.978386) (xy 115.047982 -265.951538) (xy 115.058322 -265.898803) (xy 115.067334 -265.873484)
			(xy 115.075404 -265.853262) (xy 115.096294 -265.815059) (xy 115.122211 -265.780072) (xy 115.137184 -265.764264)
			(xy 115.137692 -265.763756) (xy 115.140486 -265.760708) (xy 115.142518 -265.757914) (xy 115.147598 -265.750802)
			(xy 115.149122 -265.748516) (xy 115.14963 -265.7475) (xy 115.161268 -265.728403) (xy 115.191173 -265.69516)
			(xy 115.227342 -265.668869) (xy 115.268191 -265.650681) (xy 115.31193 -265.641393) (xy 115.334288 -265.64082)
			(xy 115.559586 -265.64082) (xy 115.589304 -265.670538) (xy 115.589304 -265.680698) (xy 115.591082 -265.684508)
			(xy 115.603528 -265.692636) (xy 115.609808 -265.696432) (xy 115.623879 -265.70057) (xy 115.631214 -265.700764)
			(xy 115.824254 -265.700764) (xy 115.853972 -265.730482) (xy 115.853972 -265.745468) (xy 115.854226 -265.748008)
			(xy 115.854226 -266.336526) (xy 115.854704 -266.346351) (xy 115.862205 -266.364514) (xy 115.876064 -266.378446)
			(xy 115.894187 -266.386043) (xy 115.90401 -266.386564) (xy 116.953538 -266.386564) (xy 116.966203 -266.385812)
			(xy 116.988451 -266.373681) (xy 116.995956 -266.36345) (xy 117.02288 -266.322048) (xy 117.03685 -266.300458)
			(xy 117.040616 -266.294235) (xy 117.044749 -266.280296) (xy 117.044978 -266.273026) (xy 117.044978 -266.258548)
			(xy 117.044674 -266.251057) (xy 117.040292 -266.236726) (xy 117.036342 -266.230354) (xy 117.029992 -266.22121)
			(xy 117.024404 -266.215622) (xy 117.02415 -266.215622) (xy 117.006062 -266.197501) (xy 116.975336 -266.156549)
			(xy 116.951561 -266.111207) (xy 116.935351 -266.062644) (xy 116.927122 -266.012112) (xy 116.926614 -265.986514)
			(xy 116.926614 -265.98626) (xy 116.927884 -265.956796) (xy 116.927884 -265.956288) (xy 116.930994 -265.929252)
			(xy 116.945258 -265.876737) (xy 116.96826 -265.827419) (xy 116.999329 -265.782743) (xy 117.018054 -265.762994)
			(xy 117.018562 -265.762486) (xy 117.018816 -265.762232) (xy 117.019578 -265.76147) (xy 117.020086 -265.760962)
			(xy 117.033294 -265.74877) (xy 117.033802 -265.748262) (xy 117.042494 -265.740645) (xy 117.060799 -265.726534)
			(xy 117.070378 -265.720068) (xy 117.073426 -265.718036) (xy 117.079776 -265.712194) (xy 117.095179 -265.695791)
			(xy 117.131496 -265.669238) (xy 117.172552 -265.650841) (xy 117.21654 -265.641406) (xy 117.239034 -265.64082)
			(xy 117.464586 -265.64082) (xy 117.494304 -265.670538) (xy 117.494304 -265.680698) (xy 117.496082 -265.684508)
			(xy 117.508528 -265.692636) (xy 117.514808 -265.696432) (xy 117.528879 -265.70057) (xy 117.536214 -265.700764)
			(xy 117.70868 -265.700764) (xy 117.718693 -265.701248) (xy 117.737198 -265.708903) (xy 117.751366 -265.723055)
			(xy 117.759041 -265.741552) (xy 117.75948 -265.751564) (xy 117.75948 -266.310364) (xy 117.759226 -266.310364)
			(xy 117.759226 -266.336526) (xy 117.759704 -266.346351) (xy 117.767205 -266.364514) (xy 117.781064 -266.378446)
			(xy 117.799187 -266.386043) (xy 117.80901 -266.386564) (xy 118.918482 -266.386564) (xy 118.927913 -266.38619)
			(xy 118.945501 -266.379374) (xy 118.959433 -266.366658) (xy 118.963948 -266.35837) (xy 118.974362 -266.334748)
			(xy 118.97628 -266.330339) (xy 118.978574 -266.321002) (xy 118.978934 -266.316206) (xy 118.979188 -266.306808)
			(xy 118.976394 -266.298426) (xy 118.971568 -266.282424) (xy 118.96725 -266.276074) (xy 118.962932 -266.269216)
			(xy 118.961408 -266.266422) (xy 118.960138 -266.264644) (xy 118.95328 -266.257024) (xy 118.946422 -266.249658)
			(xy 118.94185 -266.246356) (xy 118.921361 -266.231339) (xy 118.884983 -266.195886) (xy 118.8547 -266.155104)
			(xy 118.831281 -266.110028) (xy 118.815321 -266.061805) (xy 118.807226 -266.011658) (xy 118.806722 -265.98626)
			(xy 118.807253 -265.95967) (xy 118.816088 -265.907229) (xy 118.83352 -265.856987) (xy 118.859066 -265.810344)
			(xy 118.892013 -265.7686) (xy 118.931443 -265.732916) (xy 118.976259 -265.704286) (xy 119.000524 -265.693398)
			(xy 119.00154 -265.693144) (xy 119.011446 -265.687302) (xy 119.01424 -265.68527) (xy 119.014748 -265.684762)
			(xy 119.026587 -265.676001) (xy 119.052204 -265.661466) (xy 119.065802 -265.655806) (xy 119.084131 -265.649026)
			(xy 119.122471 -265.641484) (xy 119.142002 -265.64082) (xy 119.369586 -265.64082) (xy 119.399304 -265.670538)
			(xy 119.399304 -265.680698) (xy 119.401082 -265.684508) (xy 119.413528 -265.692636) (xy 119.419808 -265.696432)
			(xy 119.433879 -265.70057) (xy 119.441214 -265.700764) (xy 119.634254 -265.700764) (xy 119.663972 -265.730482)
			(xy 119.663972 -265.745468) (xy 119.664226 -265.748008) (xy 119.664226 -266.336526) (xy 119.664704 -266.346351)
			(xy 119.672205 -266.364514) (xy 119.686064 -266.378446) (xy 119.704187 -266.386043) (xy 119.71401 -266.386564)
			(xy 120.82399 -266.386564) (xy 120.8328 -266.386148) (xy 120.849357 -266.380107) (xy 120.862904 -266.368833)
			(xy 120.867678 -266.361418) (xy 120.86844 -266.360402) (xy 120.880378 -266.33297) (xy 120.884188 -266.324334)
			(xy 120.88368 -266.309094) (xy 120.881394 -266.296902) (xy 120.878092 -266.287758) (xy 120.865392 -266.272264)
			(xy 120.856502 -266.267438) (xy 120.834896 -266.255533) (xy 120.795329 -266.226077) (xy 120.76079 -266.190859)
			(xy 120.732112 -266.150725) (xy 120.709983 -266.106639) (xy 120.694935 -266.059662) (xy 120.687331 -266.010924)
			(xy 120.68683 -265.98626) (xy 120.68733 -265.960422) (xy 120.695676 -265.909425) (xy 120.712159 -265.860449)
			(xy 120.736345 -265.814783) (xy 120.767597 -265.773629) (xy 120.805092 -265.73807) (xy 120.847844 -265.709042)
			(xy 120.894727 -265.687309) (xy 120.919494 -265.679936) (xy 120.920256 -265.679682) (xy 120.923558 -265.678666)
			(xy 120.931178 -265.675364) (xy 120.934734 -265.673078) (xy 120.952009 -265.662665) (xy 120.989507 -265.647817)
			(xy 121.029123 -265.640258) (xy 121.049288 -265.639804) (xy 121.25452 -265.639804) (xy 121.26214 -265.640312)
			(xy 121.26595 -265.64082) (xy 121.274586 -265.64082) (xy 121.304304 -265.670538) (xy 121.304304 -265.677396)
			(xy 121.307098 -265.683492) (xy 121.319544 -265.69162) (xy 121.325824 -265.695414) (xy 121.339895 -265.699549)
			(xy 121.34723 -265.699748) (xy 121.519188 -265.699748) (xy 121.526808 -265.700256) (xy 121.530618 -265.700764)
			(xy 121.539254 -265.700764) (xy 121.568972 -265.730482) (xy 121.568972 -265.740642) (xy 121.569988 -265.750548)
			(xy 121.569988 -266.335764) (xy 121.570401 -266.345791) (xy 121.578064 -266.364322) (xy 121.592237 -266.378509)
			(xy 121.610761 -266.386189) (xy 121.620788 -266.386564) (xy 122.541538 -266.386564) (xy 122.554203 -266.385812)
			(xy 122.576451 -266.373681) (xy 122.583956 -266.36345) (xy 122.61088 -266.322048) (xy 122.62485 -266.300458)
			(xy 122.628616 -266.294235) (xy 122.632749 -266.280296) (xy 122.632978 -266.273026) (xy 122.632978 -266.245086)
			(xy 122.629422 -266.236196) (xy 122.62538 -266.225706) (xy 122.619269 -266.204071) (xy 122.61723 -266.193016)
			(xy 122.614436 -266.170156) (xy 122.614436 -266.169902) (xy 122.613928 -266.164314) (xy 122.607832 -266.143232)
			(xy 122.604784 -266.137136) (xy 122.602244 -266.13231) (xy 122.600974 -266.130024) (xy 122.590404 -266.108159)
			(xy 122.575296 -266.062007) (xy 122.567396 -266.014091) (xy 122.566684 -265.989816) (xy 122.566684 -265.987022)
			(xy 122.56643 -265.986006) (xy 122.567089 -265.957287) (xy 122.577482 -265.900796) (xy 122.597842 -265.847086)
			(xy 122.61215 -265.822176) (xy 122.614182 -265.81862) (xy 122.619516 -265.805412) (xy 122.62231 -265.795252)
			(xy 122.622818 -265.793474) (xy 122.623072 -265.792712) (xy 122.624342 -265.788902) (xy 122.625358 -265.7856)
			(xy 122.632974 -265.76484) (xy 122.655461 -265.726773) (xy 122.685301 -265.694149) (xy 122.721216 -265.668365)
			(xy 122.76167 -265.650525) (xy 122.804928 -265.641392) (xy 122.827034 -265.64082) (xy 123.052586 -265.64082)
			(xy 123.082304 -265.670538) (xy 123.082304 -265.680698) (xy 123.084082 -265.684508) (xy 123.096528 -265.692636)
			(xy 123.102808 -265.696432) (xy 123.116879 -265.70057) (xy 123.124214 -265.700764) (xy 123.317254 -265.700764)
			(xy 123.346972 -265.730482) (xy 123.346972 -265.745468) (xy 123.347226 -265.748008) (xy 123.347226 -266.336526)
			(xy 123.347704 -266.346351) (xy 123.355205 -266.364514) (xy 123.369064 -266.378446) (xy 123.387187 -266.386043)
			(xy 123.39701 -266.386564) (xy 124.446538 -266.386564) (xy 124.459203 -266.385812) (xy 124.481451 -266.373681)
			(xy 124.488956 -266.36345) (xy 124.51588 -266.322048) (xy 124.52985 -266.300458) (xy 124.533616 -266.294235)
			(xy 124.537749 -266.280296) (xy 124.537978 -266.273026) (xy 124.537978 -266.245086) (xy 124.534168 -266.235688)
			(xy 124.528072 -266.218416) (xy 124.52477 -266.206478) (xy 124.5235 -266.201398) (xy 124.51461 -266.182856)
			(xy 124.511308 -266.178284) (xy 124.496487 -266.15792) (xy 124.472783 -266.113481) (xy 124.456372 -266.065864)
			(xy 124.447664 -266.016258) (xy 124.446792 -265.991086) (xy 124.446792 -265.98626) (xy 124.447209 -265.962892)
			(xy 124.454059 -265.91666) (xy 124.467607 -265.87193) (xy 124.48756 -265.829667) (xy 124.513487 -265.790782)
			(xy 124.528834 -265.773154) (xy 124.535692 -265.765534) (xy 124.538994 -265.761216) (xy 124.544582 -265.752834)
			(xy 124.545598 -265.751056) (xy 124.555111 -265.734638) (xy 124.579005 -265.705168) (xy 124.60774 -265.680393)
			(xy 124.640407 -265.661097) (xy 124.675974 -265.64789) (xy 124.713318 -265.641188) (xy 124.732288 -265.64082)
			(xy 124.957586 -265.64082) (xy 124.987304 -265.670538) (xy 124.987304 -265.680698) (xy 124.989082 -265.684508)
			(xy 125.001528 -265.692636) (xy 125.007808 -265.696432) (xy 125.021879 -265.70057) (xy 125.029214 -265.700764)
			(xy 125.222254 -265.700764) (xy 125.251972 -265.730482) (xy 125.251972 -265.745468) (xy 125.252226 -265.748008)
			(xy 125.252226 -266.011249) (xy 126.327136 -266.011249) (xy 126.327136 -265.961271) (xy 126.334955 -265.911908)
			(xy 126.350399 -265.864376) (xy 126.373089 -265.819844) (xy 126.402465 -265.779411) (xy 126.437805 -265.744071)
			(xy 126.478238 -265.714695) (xy 126.52277 -265.692005) (xy 126.570302 -265.676561) (xy 126.619665 -265.668742)
			(xy 126.669643 -265.668742) (xy 126.719006 -265.676561) (xy 126.766538 -265.692005) (xy 126.81107 -265.714695)
			(xy 126.851503 -265.744071) (xy 126.886843 -265.779411) (xy 126.916219 -265.819844) (xy 126.938909 -265.864376)
			(xy 126.954353 -265.911908) (xy 126.962172 -265.961271) (xy 126.962662 -265.98626) (xy 128.208527 -265.98626)
			(xy 128.212622 -265.935532) (xy 128.224801 -265.886118) (xy 128.244749 -265.839298) (xy 128.27195 -265.796284)
			(xy 128.305698 -265.75819) (xy 128.34512 -265.726003) (xy 128.389194 -265.700557) (xy 128.43678 -265.68251)
			(xy 128.486644 -265.67233) (xy 128.537496 -265.670281) (xy 128.588017 -265.676415) (xy 128.636901 -265.690575)
			(xy 128.68288 -265.712392) (xy 128.724764 -265.741302) (xy 128.761468 -265.776557) (xy 128.792041 -265.817243)
			(xy 128.815692 -265.862306) (xy 128.831808 -265.91058) (xy 128.839972 -265.960814) (xy 128.840484 -265.98626)
			(xy 128.839981 -266.011249) (xy 129.147298 -266.011249) (xy 129.147298 -265.961271) (xy 129.155117 -265.911908)
			(xy 129.170561 -265.864376) (xy 129.193251 -265.819844) (xy 129.222627 -265.779411) (xy 129.257967 -265.744071)
			(xy 129.2984 -265.714695) (xy 129.342932 -265.692005) (xy 129.390464 -265.676561) (xy 129.439827 -265.668742)
			(xy 129.489805 -265.668742) (xy 129.539168 -265.676561) (xy 129.5867 -265.692005) (xy 129.631232 -265.714695)
			(xy 129.671665 -265.744071) (xy 129.707005 -265.779411) (xy 129.736381 -265.819844) (xy 129.759071 -265.864376)
			(xy 129.774515 -265.911908) (xy 129.782334 -265.961271) (xy 129.782824 -265.98626) (xy 131.028435 -265.98626)
			(xy 131.03253 -265.935532) (xy 131.044709 -265.886118) (xy 131.064657 -265.839298) (xy 131.091858 -265.796284)
			(xy 131.125606 -265.75819) (xy 131.165028 -265.726003) (xy 131.209102 -265.700557) (xy 131.256688 -265.68251)
			(xy 131.306552 -265.67233) (xy 131.357404 -265.670281) (xy 131.407925 -265.676415) (xy 131.456809 -265.690575)
			(xy 131.502788 -265.712392) (xy 131.544672 -265.741302) (xy 131.581376 -265.776557) (xy 131.611949 -265.817243)
			(xy 131.6356 -265.862306) (xy 131.651716 -265.91058) (xy 131.65988 -265.960814) (xy 131.660392 -265.98626)
			(xy 131.659889 -266.011249) (xy 131.967206 -266.011249) (xy 131.967206 -265.961271) (xy 131.975025 -265.911908)
			(xy 131.990469 -265.864376) (xy 132.013159 -265.819844) (xy 132.042535 -265.779411) (xy 132.077875 -265.744071)
			(xy 132.118308 -265.714695) (xy 132.16284 -265.692005) (xy 132.210372 -265.676561) (xy 132.259735 -265.668742)
			(xy 132.309713 -265.668742) (xy 132.359076 -265.676561) (xy 132.406608 -265.692005) (xy 132.45114 -265.714695)
			(xy 132.491573 -265.744071) (xy 132.526913 -265.779411) (xy 132.556289 -265.819844) (xy 132.578979 -265.864376)
			(xy 132.594423 -265.911908) (xy 132.602242 -265.961271) (xy 132.602732 -265.98626) (xy 132.602242 -266.011249)
			(xy 132.90726 -266.011249) (xy 132.90726 -265.961271) (xy 132.915079 -265.911908) (xy 132.930523 -265.864376)
			(xy 132.953213 -265.819844) (xy 132.982589 -265.779411) (xy 133.017929 -265.744071) (xy 133.058362 -265.714695)
			(xy 133.102894 -265.692005) (xy 133.150426 -265.676561) (xy 133.199789 -265.668742) (xy 133.249767 -265.668742)
			(xy 133.29913 -265.676561) (xy 133.346662 -265.692005) (xy 133.391194 -265.714695) (xy 133.431627 -265.744071)
			(xy 133.466967 -265.779411) (xy 133.496343 -265.819844) (xy 133.519033 -265.864376) (xy 133.534477 -265.911908)
			(xy 133.542296 -265.961271) (xy 133.542786 -265.98626) (xy 133.542296 -266.011249) (xy 133.534477 -266.060612)
			(xy 133.519033 -266.108144) (xy 133.496343 -266.152676) (xy 133.466967 -266.193109) (xy 133.431627 -266.228449)
			(xy 133.391194 -266.257825) (xy 133.346662 -266.280515) (xy 133.29913 -266.295959) (xy 133.249767 -266.303778)
			(xy 133.199789 -266.303778) (xy 133.150426 -266.295959) (xy 133.102894 -266.280515) (xy 133.058362 -266.257825)
			(xy 133.017929 -266.228449) (xy 132.982589 -266.193109) (xy 132.953213 -266.152676) (xy 132.930523 -266.108144)
			(xy 132.915079 -266.060612) (xy 132.90726 -266.011249) (xy 132.602242 -266.011249) (xy 132.594423 -266.060612)
			(xy 132.578979 -266.108144) (xy 132.556289 -266.152676) (xy 132.526913 -266.193109) (xy 132.491573 -266.228449)
			(xy 132.45114 -266.257825) (xy 132.406608 -266.280515) (xy 132.359076 -266.295959) (xy 132.309713 -266.303778)
			(xy 132.259735 -266.303778) (xy 132.210372 -266.295959) (xy 132.16284 -266.280515) (xy 132.118308 -266.257825)
			(xy 132.077875 -266.228449) (xy 132.042535 -266.193109) (xy 132.013159 -266.152676) (xy 131.990469 -266.108144)
			(xy 131.975025 -266.060612) (xy 131.967206 -266.011249) (xy 131.659889 -266.011249) (xy 131.65988 -266.011706)
			(xy 131.651716 -266.06194) (xy 131.6356 -266.110214) (xy 131.611949 -266.155277) (xy 131.581376 -266.195963)
			(xy 131.544672 -266.231218) (xy 131.502788 -266.260128) (xy 131.456809 -266.281945) (xy 131.407925 -266.296105)
			(xy 131.357404 -266.302239) (xy 131.306552 -266.30019) (xy 131.256688 -266.29001) (xy 131.209102 -266.271963)
			(xy 131.165028 -266.246517) (xy 131.125606 -266.21433) (xy 131.091858 -266.176236) (xy 131.064657 -266.133222)
			(xy 131.044709 -266.086402) (xy 131.03253 -266.036988) (xy 131.028435 -265.98626) (xy 129.782824 -265.98626)
			(xy 129.782334 -266.011249) (xy 129.774515 -266.060612) (xy 129.759071 -266.108144) (xy 129.736381 -266.152676)
			(xy 129.707005 -266.193109) (xy 129.671665 -266.228449) (xy 129.631232 -266.257825) (xy 129.5867 -266.280515)
			(xy 129.539168 -266.295959) (xy 129.489805 -266.303778) (xy 129.439827 -266.303778) (xy 129.390464 -266.295959)
			(xy 129.342932 -266.280515) (xy 129.2984 -266.257825) (xy 129.257967 -266.228449) (xy 129.222627 -266.193109)
			(xy 129.193251 -266.152676) (xy 129.170561 -266.108144) (xy 129.155117 -266.060612) (xy 129.147298 -266.011249)
			(xy 128.839981 -266.011249) (xy 128.839972 -266.011706) (xy 128.831808 -266.06194) (xy 128.815692 -266.110214)
			(xy 128.792041 -266.155277) (xy 128.761468 -266.195963) (xy 128.724764 -266.231218) (xy 128.68288 -266.260128)
			(xy 128.636901 -266.281945) (xy 128.588017 -266.296105) (xy 128.537496 -266.302239) (xy 128.486644 -266.30019)
			(xy 128.43678 -266.29001) (xy 128.389194 -266.271963) (xy 128.34512 -266.246517) (xy 128.305698 -266.21433)
			(xy 128.27195 -266.176236) (xy 128.244749 -266.133222) (xy 128.224801 -266.086402) (xy 128.212622 -266.036988)
			(xy 128.208527 -265.98626) (xy 126.962662 -265.98626) (xy 126.962172 -266.011249) (xy 126.954353 -266.060612)
			(xy 126.938909 -266.108144) (xy 126.916219 -266.152676) (xy 126.886843 -266.193109) (xy 126.851503 -266.228449)
			(xy 126.81107 -266.257825) (xy 126.766538 -266.280515) (xy 126.719006 -266.295959) (xy 126.669643 -266.303778)
			(xy 126.619665 -266.303778) (xy 126.570302 -266.295959) (xy 126.52277 -266.280515) (xy 126.478238 -266.257825)
			(xy 126.437805 -266.228449) (xy 126.402465 -266.193109) (xy 126.373089 -266.152676) (xy 126.350399 -266.108144)
			(xy 126.334955 -266.060612) (xy 126.327136 -266.011249) (xy 125.252226 -266.011249) (xy 125.252226 -266.336526)
			(xy 125.252704 -266.346351) (xy 125.260205 -266.364514) (xy 125.274064 -266.378446) (xy 125.292187 -266.386043)
			(xy 125.30201 -266.386564) (xy 126.384812 -266.386564) (xy 126.394655 -266.387089) (xy 126.412834 -266.394657)
			(xy 126.420118 -266.401296) (xy 126.67742 -266.658598) (xy 126.683169 -266.663798) (xy 126.697 -266.670781)
			(xy 126.704598 -266.672314) (xy 126.71298 -266.673076) (xy 126.73584 -266.673076) (xy 126.741428 -266.672822)
			(xy 126.800864 -266.664694) (xy 126.806693 -266.663721) (xy 126.817721 -266.659483) (xy 126.822708 -266.656312)
			(xy 126.827534 -266.65301) (xy 126.8349 -266.645136) (xy 126.838202 -266.639548) (xy 126.850388 -266.618887)
			(xy 126.880008 -266.581159) (xy 126.914963 -266.548313) (xy 126.95446 -266.521096) (xy 126.997599 -266.500127)
			(xy 127.043402 -266.485883) (xy 127.090825 -266.478687) (xy 127.114808 -266.478258) (xy 127.139798 -266.478749)
			(xy 127.189162 -266.486568) (xy 127.236695 -266.502012) (xy 127.281228 -266.524702) (xy 127.321663 -266.554078)
			(xy 127.357005 -266.589418) (xy 127.386384 -266.62985) (xy 127.409078 -266.674381) (xy 127.424526 -266.721913)
			(xy 127.432349 -266.771276) (xy 127.432816 -266.796266) (xy 127.738627 -266.796266) (xy 127.742722 -266.745538)
			(xy 127.754901 -266.696124) (xy 127.774849 -266.649304) (xy 127.80205 -266.60629) (xy 127.835798 -266.568196)
			(xy 127.87522 -266.536009) (xy 127.919294 -266.510563) (xy 127.96688 -266.492516) (xy 128.016744 -266.482336)
			(xy 128.067596 -266.480287) (xy 128.118117 -266.486421) (xy 128.167001 -266.500581) (xy 128.21298 -266.522398)
			(xy 128.254864 -266.551308) (xy 128.291568 -266.586563) (xy 128.322141 -266.627249) (xy 128.345792 -266.672312)
			(xy 128.361908 -266.720586) (xy 128.370072 -266.77082) (xy 128.370584 -266.796266) (xy 128.370081 -266.821255)
			(xy 128.677144 -266.821255) (xy 128.677144 -266.771277) (xy 128.684963 -266.721914) (xy 128.700407 -266.674382)
			(xy 128.723097 -266.62985) (xy 128.752473 -266.589417) (xy 128.787813 -266.554077) (xy 128.828246 -266.524701)
			(xy 128.872778 -266.502011) (xy 128.92031 -266.486567) (xy 128.969673 -266.478748) (xy 129.019651 -266.478748)
			(xy 129.069014 -266.486567) (xy 129.116546 -266.502011) (xy 129.161078 -266.524701) (xy 129.201511 -266.554077)
			(xy 129.236851 -266.589417) (xy 129.266227 -266.62985) (xy 129.288917 -266.674382) (xy 129.304361 -266.721914)
			(xy 129.31218 -266.771277) (xy 129.31267 -266.796266) (xy 129.618481 -266.796266) (xy 129.622576 -266.745538)
			(xy 129.634755 -266.696124) (xy 129.654703 -266.649304) (xy 129.681904 -266.60629) (xy 129.715652 -266.568196)
			(xy 129.755074 -266.536009) (xy 129.799148 -266.510563) (xy 129.846734 -266.492516) (xy 129.896598 -266.482336)
			(xy 129.94745 -266.480287) (xy 129.997971 -266.486421) (xy 130.046855 -266.500581) (xy 130.092834 -266.522398)
			(xy 130.134718 -266.551308) (xy 130.171422 -266.586563) (xy 130.201995 -266.627249) (xy 130.225646 -266.672312)
			(xy 130.241762 -266.720586) (xy 130.249926 -266.77082) (xy 130.250438 -266.796266) (xy 130.249935 -266.821255)
			(xy 130.557252 -266.821255) (xy 130.557252 -266.771277) (xy 130.565071 -266.721914) (xy 130.580515 -266.674382)
			(xy 130.603205 -266.62985) (xy 130.632581 -266.589417) (xy 130.667921 -266.554077) (xy 130.708354 -266.524701)
			(xy 130.752886 -266.502011) (xy 130.800418 -266.486567) (xy 130.849781 -266.478748) (xy 130.899759 -266.478748)
			(xy 130.949122 -266.486567) (xy 130.996654 -266.502011) (xy 131.041186 -266.524701) (xy 131.081619 -266.554077)
			(xy 131.116959 -266.589417) (xy 131.146335 -266.62985) (xy 131.169025 -266.674382) (xy 131.184469 -266.721914)
			(xy 131.192288 -266.771277) (xy 131.192778 -266.796266) (xy 131.498589 -266.796266) (xy 131.502684 -266.745538)
			(xy 131.514863 -266.696124) (xy 131.534811 -266.649304) (xy 131.562012 -266.60629) (xy 131.59576 -266.568196)
			(xy 131.635182 -266.536009) (xy 131.679256 -266.510563) (xy 131.726842 -266.492516) (xy 131.776706 -266.482336)
			(xy 131.827558 -266.480287) (xy 131.878079 -266.486421) (xy 131.926963 -266.500581) (xy 131.972942 -266.522398)
			(xy 132.014826 -266.551308) (xy 132.05153 -266.586563) (xy 132.082103 -266.627249) (xy 132.105754 -266.672312)
			(xy 132.12187 -266.720586) (xy 132.130034 -266.77082) (xy 132.130546 -266.796266) (xy 132.438643 -266.796266)
			(xy 132.442738 -266.745538) (xy 132.454917 -266.696124) (xy 132.474865 -266.649304) (xy 132.502066 -266.60629)
			(xy 132.535814 -266.568196) (xy 132.575236 -266.536009) (xy 132.61931 -266.510563) (xy 132.666896 -266.492516)
			(xy 132.71676 -266.482336) (xy 132.767612 -266.480287) (xy 132.818133 -266.486421) (xy 132.867017 -266.500581)
			(xy 132.912996 -266.522398) (xy 132.95488 -266.551308) (xy 132.991584 -266.586563) (xy 133.022157 -266.627249)
			(xy 133.045808 -266.672312) (xy 133.061924 -266.720586) (xy 133.070088 -266.77082) (xy 133.0706 -266.796266)
			(xy 133.070097 -266.821255) (xy 133.37716 -266.821255) (xy 133.37716 -266.771277) (xy 133.384979 -266.721914)
			(xy 133.400423 -266.674382) (xy 133.423113 -266.62985) (xy 133.452489 -266.589417) (xy 133.487829 -266.554077)
			(xy 133.528262 -266.524701) (xy 133.572794 -266.502011) (xy 133.620326 -266.486567) (xy 133.669689 -266.478748)
			(xy 133.719667 -266.478748) (xy 133.76903 -266.486567) (xy 133.816562 -266.502011) (xy 133.861094 -266.524701)
			(xy 133.901527 -266.554077) (xy 133.936867 -266.589417) (xy 133.966243 -266.62985) (xy 133.988933 -266.674382)
			(xy 134.004377 -266.721914) (xy 134.012196 -266.771277) (xy 134.012686 -266.796266) (xy 134.318497 -266.796266)
			(xy 134.322592 -266.745538) (xy 134.334771 -266.696124) (xy 134.354719 -266.649304) (xy 134.38192 -266.60629)
			(xy 134.415668 -266.568196) (xy 134.45509 -266.536009) (xy 134.499164 -266.510563) (xy 134.54675 -266.492516)
			(xy 134.596614 -266.482336) (xy 134.647466 -266.480287) (xy 134.697987 -266.486421) (xy 134.746871 -266.500581)
			(xy 134.79285 -266.522398) (xy 134.834734 -266.551308) (xy 134.871438 -266.586563) (xy 134.902011 -266.627249)
			(xy 134.925662 -266.672312) (xy 134.941778 -266.720586) (xy 134.949942 -266.77082) (xy 134.950454 -266.796266)
			(xy 134.949951 -266.821255) (xy 135.257268 -266.821255) (xy 135.257268 -266.771277) (xy 135.265087 -266.721914)
			(xy 135.280531 -266.674382) (xy 135.303221 -266.62985) (xy 135.332597 -266.589417) (xy 135.367937 -266.554077)
			(xy 135.40837 -266.524701) (xy 135.452902 -266.502011) (xy 135.500434 -266.486567) (xy 135.549797 -266.478748)
			(xy 135.599775 -266.478748) (xy 135.649138 -266.486567) (xy 135.69667 -266.502011) (xy 135.741202 -266.524701)
			(xy 135.781635 -266.554077) (xy 135.816975 -266.589417) (xy 135.846351 -266.62985) (xy 135.869041 -266.674382)
			(xy 135.884485 -266.721914) (xy 135.892304 -266.771277) (xy 135.892794 -266.796266) (xy 136.198605 -266.796266)
			(xy 136.2027 -266.745538) (xy 136.214879 -266.696124) (xy 136.234827 -266.649304) (xy 136.262028 -266.60629)
			(xy 136.295776 -266.568196) (xy 136.335198 -266.536009) (xy 136.379272 -266.510563) (xy 136.426858 -266.492516)
			(xy 136.476722 -266.482336) (xy 136.527574 -266.480287) (xy 136.578095 -266.486421) (xy 136.626979 -266.500581)
			(xy 136.672958 -266.522398) (xy 136.714842 -266.551308) (xy 136.751546 -266.586563) (xy 136.782119 -266.627249)
			(xy 136.80577 -266.672312) (xy 136.821886 -266.720586) (xy 136.83005 -266.77082) (xy 136.830562 -266.796266)
			(xy 136.830059 -266.821255) (xy 137.137122 -266.821255) (xy 137.137122 -266.771277) (xy 137.144941 -266.721914)
			(xy 137.160385 -266.674382) (xy 137.183075 -266.62985) (xy 137.212451 -266.589417) (xy 137.247791 -266.554077)
			(xy 137.288224 -266.524701) (xy 137.332756 -266.502011) (xy 137.380288 -266.486567) (xy 137.429651 -266.478748)
			(xy 137.479629 -266.478748) (xy 137.528992 -266.486567) (xy 137.576524 -266.502011) (xy 137.621056 -266.524701)
			(xy 137.661489 -266.554077) (xy 137.696829 -266.589417) (xy 137.726205 -266.62985) (xy 137.748895 -266.674382)
			(xy 137.764339 -266.721914) (xy 137.772158 -266.771277) (xy 137.772648 -266.796266) (xy 137.772158 -266.821255)
			(xy 137.764339 -266.870618) (xy 137.748895 -266.91815) (xy 137.726205 -266.962682) (xy 137.696829 -267.003115)
			(xy 137.661489 -267.038455) (xy 137.621056 -267.067831) (xy 137.576524 -267.090521) (xy 137.528992 -267.105965)
			(xy 137.479629 -267.113784) (xy 137.429651 -267.113784) (xy 137.380288 -267.105965) (xy 137.332756 -267.090521)
			(xy 137.288224 -267.067831) (xy 137.247791 -267.038455) (xy 137.212451 -267.003115) (xy 137.183075 -266.962682)
			(xy 137.160385 -266.91815) (xy 137.144941 -266.870618) (xy 137.137122 -266.821255) (xy 136.830059 -266.821255)
			(xy 136.83005 -266.821712) (xy 136.821886 -266.871946) (xy 136.80577 -266.92022) (xy 136.782119 -266.965283)
			(xy 136.751546 -267.005969) (xy 136.714842 -267.041224) (xy 136.672958 -267.070134) (xy 136.626979 -267.091951)
			(xy 136.578095 -267.106111) (xy 136.527574 -267.112245) (xy 136.476722 -267.110196) (xy 136.426858 -267.100016)
			(xy 136.379272 -267.081969) (xy 136.335198 -267.056523) (xy 136.295776 -267.024336) (xy 136.262028 -266.986242)
			(xy 136.234827 -266.943228) (xy 136.214879 -266.896408) (xy 136.2027 -266.846994) (xy 136.198605 -266.796266)
			(xy 135.892794 -266.796266) (xy 135.892304 -266.821255) (xy 135.884485 -266.870618) (xy 135.869041 -266.91815)
			(xy 135.846351 -266.962682) (xy 135.816975 -267.003115) (xy 135.781635 -267.038455) (xy 135.741202 -267.067831)
			(xy 135.69667 -267.090521) (xy 135.649138 -267.105965) (xy 135.599775 -267.113784) (xy 135.549797 -267.113784)
			(xy 135.500434 -267.105965) (xy 135.452902 -267.090521) (xy 135.40837 -267.067831) (xy 135.367937 -267.038455)
			(xy 135.332597 -267.003115) (xy 135.303221 -266.962682) (xy 135.280531 -266.91815) (xy 135.265087 -266.870618)
			(xy 135.257268 -266.821255) (xy 134.949951 -266.821255) (xy 134.949942 -266.821712) (xy 134.941778 -266.871946)
			(xy 134.925662 -266.92022) (xy 134.902011 -266.965283) (xy 134.871438 -267.005969) (xy 134.834734 -267.041224)
			(xy 134.79285 -267.070134) (xy 134.746871 -267.091951) (xy 134.697987 -267.106111) (xy 134.647466 -267.112245)
			(xy 134.596614 -267.110196) (xy 134.54675 -267.100016) (xy 134.499164 -267.081969) (xy 134.45509 -267.056523)
			(xy 134.415668 -267.024336) (xy 134.38192 -266.986242) (xy 134.354719 -266.943228) (xy 134.334771 -266.896408)
			(xy 134.322592 -266.846994) (xy 134.318497 -266.796266) (xy 134.012686 -266.796266) (xy 134.012196 -266.821255)
			(xy 134.004377 -266.870618) (xy 133.988933 -266.91815) (xy 133.966243 -266.962682) (xy 133.936867 -267.003115)
			(xy 133.901527 -267.038455) (xy 133.861094 -267.067831) (xy 133.816562 -267.090521) (xy 133.76903 -267.105965)
			(xy 133.719667 -267.113784) (xy 133.669689 -267.113784) (xy 133.620326 -267.105965) (xy 133.572794 -267.090521)
			(xy 133.528262 -267.067831) (xy 133.487829 -267.038455) (xy 133.452489 -267.003115) (xy 133.423113 -266.962682)
			(xy 133.400423 -266.91815) (xy 133.384979 -266.870618) (xy 133.37716 -266.821255) (xy 133.070097 -266.821255)
			(xy 133.070088 -266.821712) (xy 133.061924 -266.871946) (xy 133.045808 -266.92022) (xy 133.022157 -266.965283)
			(xy 132.991584 -267.005969) (xy 132.95488 -267.041224) (xy 132.912996 -267.070134) (xy 132.867017 -267.091951)
			(xy 132.818133 -267.106111) (xy 132.767612 -267.112245) (xy 132.71676 -267.110196) (xy 132.666896 -267.100016)
			(xy 132.61931 -267.081969) (xy 132.575236 -267.056523) (xy 132.535814 -267.024336) (xy 132.502066 -266.986242)
			(xy 132.474865 -266.943228) (xy 132.454917 -266.896408) (xy 132.442738 -266.846994) (xy 132.438643 -266.796266)
			(xy 132.130546 -266.796266) (xy 132.130034 -266.821712) (xy 132.12187 -266.871946) (xy 132.105754 -266.92022)
			(xy 132.082103 -266.965283) (xy 132.05153 -267.005969) (xy 132.014826 -267.041224) (xy 131.972942 -267.070134)
			(xy 131.926963 -267.091951) (xy 131.878079 -267.106111) (xy 131.827558 -267.112245) (xy 131.776706 -267.110196)
			(xy 131.726842 -267.100016) (xy 131.679256 -267.081969) (xy 131.635182 -267.056523) (xy 131.59576 -267.024336)
			(xy 131.562012 -266.986242) (xy 131.534811 -266.943228) (xy 131.514863 -266.896408) (xy 131.502684 -266.846994)
			(xy 131.498589 -266.796266) (xy 131.192778 -266.796266) (xy 131.192288 -266.821255) (xy 131.184469 -266.870618)
			(xy 131.169025 -266.91815) (xy 131.146335 -266.962682) (xy 131.116959 -267.003115) (xy 131.081619 -267.038455)
			(xy 131.041186 -267.067831) (xy 130.996654 -267.090521) (xy 130.949122 -267.105965) (xy 130.899759 -267.113784)
			(xy 130.849781 -267.113784) (xy 130.800418 -267.105965) (xy 130.752886 -267.090521) (xy 130.708354 -267.067831)
			(xy 130.667921 -267.038455) (xy 130.632581 -267.003115) (xy 130.603205 -266.962682) (xy 130.580515 -266.91815)
			(xy 130.565071 -266.870618) (xy 130.557252 -266.821255) (xy 130.249935 -266.821255) (xy 130.249926 -266.821712)
			(xy 130.241762 -266.871946) (xy 130.225646 -266.92022) (xy 130.201995 -266.965283) (xy 130.171422 -267.005969)
			(xy 130.134718 -267.041224) (xy 130.092834 -267.070134) (xy 130.046855 -267.091951) (xy 129.997971 -267.106111)
			(xy 129.94745 -267.112245) (xy 129.896598 -267.110196) (xy 129.846734 -267.100016) (xy 129.799148 -267.081969)
			(xy 129.755074 -267.056523) (xy 129.715652 -267.024336) (xy 129.681904 -266.986242) (xy 129.654703 -266.943228)
			(xy 129.634755 -266.896408) (xy 129.622576 -266.846994) (xy 129.618481 -266.796266) (xy 129.31267 -266.796266)
			(xy 129.31218 -266.821255) (xy 129.304361 -266.870618) (xy 129.288917 -266.91815) (xy 129.266227 -266.962682)
			(xy 129.236851 -267.003115) (xy 129.201511 -267.038455) (xy 129.161078 -267.067831) (xy 129.116546 -267.090521)
			(xy 129.069014 -267.105965) (xy 129.019651 -267.113784) (xy 128.969673 -267.113784) (xy 128.92031 -267.105965)
			(xy 128.872778 -267.090521) (xy 128.828246 -267.067831) (xy 128.787813 -267.038455) (xy 128.752473 -267.003115)
			(xy 128.723097 -266.962682) (xy 128.700407 -266.91815) (xy 128.684963 -266.870618) (xy 128.677144 -266.821255)
			(xy 128.370081 -266.821255) (xy 128.370072 -266.821712) (xy 128.361908 -266.871946) (xy 128.345792 -266.92022)
			(xy 128.322141 -266.965283) (xy 128.291568 -267.005969) (xy 128.254864 -267.041224) (xy 128.21298 -267.070134)
			(xy 128.167001 -267.091951) (xy 128.118117 -267.106111) (xy 128.067596 -267.112245) (xy 128.016744 -267.110196)
			(xy 127.96688 -267.100016) (xy 127.919294 -267.081969) (xy 127.87522 -267.056523) (xy 127.835798 -267.024336)
			(xy 127.80205 -266.986242) (xy 127.774849 -266.943228) (xy 127.754901 -266.896408) (xy 127.742722 -266.846994)
			(xy 127.738627 -266.796266) (xy 127.432816 -266.796266) (xy 127.432299 -266.821853) (xy 127.424097 -266.872364)
			(xy 127.407914 -266.920912) (xy 127.384168 -266.966242) (xy 127.353472 -267.007187) (xy 127.316617 -267.042689)
			(xy 127.274554 -267.071834) (xy 127.228367 -267.093869) (xy 127.203962 -267.101574) (xy 127.201422 -267.102336)
			(xy 127.19201 -267.106095) (xy 127.176963 -267.119648) (xy 127.168322 -267.137962) (xy 127.167386 -267.148056)
			(xy 127.167386 -267.631261) (xy 128.207244 -267.631261) (xy 128.207244 -267.581283) (xy 128.215063 -267.53192)
			(xy 128.230507 -267.484388) (xy 128.253197 -267.439856) (xy 128.282573 -267.399423) (xy 128.317913 -267.364083)
			(xy 128.358346 -267.334707) (xy 128.402878 -267.312017) (xy 128.45041 -267.296573) (xy 128.499773 -267.288754)
			(xy 128.549751 -267.288754) (xy 128.599114 -267.296573) (xy 128.646646 -267.312017) (xy 128.691178 -267.334707)
			(xy 128.731611 -267.364083) (xy 128.766951 -267.399423) (xy 128.796327 -267.439856) (xy 128.819017 -267.484388)
			(xy 128.834461 -267.53192) (xy 128.84228 -267.581283) (xy 128.84277 -267.606272) (xy 129.148581 -267.606272)
			(xy 129.152676 -267.555544) (xy 129.164855 -267.50613) (xy 129.184803 -267.45931) (xy 129.212004 -267.416296)
			(xy 129.245752 -267.378202) (xy 129.285174 -267.346015) (xy 129.329248 -267.320569) (xy 129.376834 -267.302522)
			(xy 129.426698 -267.292342) (xy 129.47755 -267.290293) (xy 129.528071 -267.296427) (xy 129.576955 -267.310587)
			(xy 129.622934 -267.332404) (xy 129.664818 -267.361314) (xy 129.701522 -267.396569) (xy 129.732095 -267.437255)
			(xy 129.755746 -267.482318) (xy 129.771862 -267.530592) (xy 129.780026 -267.580826) (xy 129.780538 -267.606272)
			(xy 129.780035 -267.631261) (xy 130.087352 -267.631261) (xy 130.087352 -267.581283) (xy 130.095171 -267.53192)
			(xy 130.110615 -267.484388) (xy 130.133305 -267.439856) (xy 130.162681 -267.399423) (xy 130.198021 -267.364083)
			(xy 130.238454 -267.334707) (xy 130.282986 -267.312017) (xy 130.330518 -267.296573) (xy 130.379881 -267.288754)
			(xy 130.429859 -267.288754) (xy 130.479222 -267.296573) (xy 130.526754 -267.312017) (xy 130.571286 -267.334707)
			(xy 130.611719 -267.364083) (xy 130.647059 -267.399423) (xy 130.676435 -267.439856) (xy 130.699125 -267.484388)
			(xy 130.714569 -267.53192) (xy 130.722388 -267.581283) (xy 130.722878 -267.606272) (xy 130.722388 -267.631261)
			(xy 131.027152 -267.631261) (xy 131.027152 -267.581283) (xy 131.034971 -267.53192) (xy 131.050415 -267.484388)
			(xy 131.073105 -267.439856) (xy 131.102481 -267.399423) (xy 131.137821 -267.364083) (xy 131.178254 -267.334707)
			(xy 131.222786 -267.312017) (xy 131.270318 -267.296573) (xy 131.319681 -267.288754) (xy 131.369659 -267.288754)
			(xy 131.419022 -267.296573) (xy 131.466554 -267.312017) (xy 131.511086 -267.334707) (xy 131.551519 -267.364083)
			(xy 131.586859 -267.399423) (xy 131.616235 -267.439856) (xy 131.638925 -267.484388) (xy 131.654369 -267.53192)
			(xy 131.662188 -267.581283) (xy 131.662678 -267.606272) (xy 131.662188 -267.631261) (xy 131.967206 -267.631261)
			(xy 131.967206 -267.581283) (xy 131.975025 -267.53192) (xy 131.990469 -267.484388) (xy 132.013159 -267.439856)
			(xy 132.042535 -267.399423) (xy 132.077875 -267.364083) (xy 132.118308 -267.334707) (xy 132.16284 -267.312017)
			(xy 132.210372 -267.296573) (xy 132.259735 -267.288754) (xy 132.309713 -267.288754) (xy 132.359076 -267.296573)
			(xy 132.406608 -267.312017) (xy 132.45114 -267.334707) (xy 132.491573 -267.364083) (xy 132.526913 -267.399423)
			(xy 132.556289 -267.439856) (xy 132.578979 -267.484388) (xy 132.594423 -267.53192) (xy 132.602242 -267.581283)
			(xy 132.602732 -267.606272) (xy 132.908543 -267.606272) (xy 132.912638 -267.555544) (xy 132.924817 -267.50613)
			(xy 132.944765 -267.45931) (xy 132.971966 -267.416296) (xy 133.005714 -267.378202) (xy 133.045136 -267.346015)
			(xy 133.08921 -267.320569) (xy 133.136796 -267.302522) (xy 133.18666 -267.292342) (xy 133.237512 -267.290293)
			(xy 133.288033 -267.296427) (xy 133.336917 -267.310587) (xy 133.382896 -267.332404) (xy 133.42478 -267.361314)
			(xy 133.461484 -267.396569) (xy 133.492057 -267.437255) (xy 133.515708 -267.482318) (xy 133.531824 -267.530592)
			(xy 133.539988 -267.580826) (xy 133.5405 -267.606272) (xy 133.539997 -267.631261) (xy 133.847314 -267.631261)
			(xy 133.847314 -267.581283) (xy 133.855133 -267.53192) (xy 133.870577 -267.484388) (xy 133.893267 -267.439856)
			(xy 133.922643 -267.399423) (xy 133.957983 -267.364083) (xy 133.998416 -267.334707) (xy 134.042948 -267.312017)
			(xy 134.09048 -267.296573) (xy 134.139843 -267.288754) (xy 134.189821 -267.288754) (xy 134.239184 -267.296573)
			(xy 134.286716 -267.312017) (xy 134.331248 -267.334707) (xy 134.371681 -267.364083) (xy 134.407021 -267.399423)
			(xy 134.436397 -267.439856) (xy 134.459087 -267.484388) (xy 134.474531 -267.53192) (xy 134.48235 -267.581283)
			(xy 134.48284 -267.606272) (xy 134.48235 -267.631261) (xy 134.787114 -267.631261) (xy 134.787114 -267.581283)
			(xy 134.794933 -267.53192) (xy 134.810377 -267.484388) (xy 134.833067 -267.439856) (xy 134.862443 -267.399423)
			(xy 134.897783 -267.364083) (xy 134.938216 -267.334707) (xy 134.982748 -267.312017) (xy 135.03028 -267.296573)
			(xy 135.079643 -267.288754) (xy 135.129621 -267.288754) (xy 135.178984 -267.296573) (xy 135.226516 -267.312017)
			(xy 135.271048 -267.334707) (xy 135.311481 -267.364083) (xy 135.346821 -267.399423) (xy 135.376197 -267.439856)
			(xy 135.398887 -267.484388) (xy 135.414331 -267.53192) (xy 135.42215 -267.581283) (xy 135.42264 -267.606272)
			(xy 135.728451 -267.606272) (xy 135.732546 -267.555544) (xy 135.744725 -267.50613) (xy 135.764673 -267.45931)
			(xy 135.791874 -267.416296) (xy 135.825622 -267.378202) (xy 135.865044 -267.346015) (xy 135.909118 -267.320569)
			(xy 135.956704 -267.302522) (xy 136.006568 -267.292342) (xy 136.05742 -267.290293) (xy 136.107941 -267.296427)
			(xy 136.156825 -267.310587) (xy 136.202804 -267.332404) (xy 136.244688 -267.361314) (xy 136.281392 -267.396569)
			(xy 136.311965 -267.437255) (xy 136.335616 -267.482318) (xy 136.351732 -267.530592) (xy 136.359896 -267.580826)
			(xy 136.360408 -267.606272) (xy 136.359905 -267.631261) (xy 136.667222 -267.631261) (xy 136.667222 -267.581283)
			(xy 136.675041 -267.53192) (xy 136.690485 -267.484388) (xy 136.713175 -267.439856) (xy 136.742551 -267.399423)
			(xy 136.777891 -267.364083) (xy 136.818324 -267.334707) (xy 136.862856 -267.312017) (xy 136.910388 -267.296573)
			(xy 136.959751 -267.288754) (xy 137.009729 -267.288754) (xy 137.059092 -267.296573) (xy 137.106624 -267.312017)
			(xy 137.151156 -267.334707) (xy 137.191589 -267.364083) (xy 137.226929 -267.399423) (xy 137.256305 -267.439856)
			(xy 137.278995 -267.484388) (xy 137.294439 -267.53192) (xy 137.302258 -267.581283) (xy 137.302748 -267.606272)
			(xy 137.302258 -267.631261) (xy 137.607276 -267.631261) (xy 137.607276 -267.581283) (xy 137.615095 -267.53192)
			(xy 137.630539 -267.484388) (xy 137.653229 -267.439856) (xy 137.682605 -267.399423) (xy 137.717945 -267.364083)
			(xy 137.758378 -267.334707) (xy 137.80291 -267.312017) (xy 137.850442 -267.296573) (xy 137.899805 -267.288754)
			(xy 137.949783 -267.288754) (xy 137.999146 -267.296573) (xy 138.046678 -267.312017) (xy 138.09121 -267.334707)
			(xy 138.131643 -267.364083) (xy 138.166983 -267.399423) (xy 138.196359 -267.439856) (xy 138.219049 -267.484388)
			(xy 138.234493 -267.53192) (xy 138.242312 -267.581283) (xy 138.242802 -267.606272) (xy 138.242312 -267.631261)
			(xy 138.54733 -267.631261) (xy 138.54733 -267.581283) (xy 138.555149 -267.53192) (xy 138.570593 -267.484388)
			(xy 138.593283 -267.439856) (xy 138.622659 -267.399423) (xy 138.657999 -267.364083) (xy 138.698432 -267.334707)
			(xy 138.742964 -267.312017) (xy 138.790496 -267.296573) (xy 138.839859 -267.288754) (xy 138.889837 -267.288754)
			(xy 138.9392 -267.296573) (xy 138.986732 -267.312017) (xy 139.031264 -267.334707) (xy 139.071697 -267.364083)
			(xy 139.107037 -267.399423) (xy 139.136413 -267.439856) (xy 139.159103 -267.484388) (xy 139.174547 -267.53192)
			(xy 139.182366 -267.581283) (xy 139.182856 -267.606272) (xy 139.488413 -267.606272) (xy 139.492508 -267.555544)
			(xy 139.504687 -267.50613) (xy 139.524635 -267.45931) (xy 139.551836 -267.416296) (xy 139.585584 -267.378202)
			(xy 139.625006 -267.346015) (xy 139.66908 -267.320569) (xy 139.716666 -267.302522) (xy 139.76653 -267.292342)
			(xy 139.817382 -267.290293) (xy 139.867903 -267.296427) (xy 139.916787 -267.310587) (xy 139.962766 -267.332404)
			(xy 140.00465 -267.361314) (xy 140.041354 -267.396569) (xy 140.071927 -267.437255) (xy 140.095578 -267.482318)
			(xy 140.111694 -267.530592) (xy 140.119858 -267.580826) (xy 140.12037 -267.606272) (xy 140.119867 -267.631261)
			(xy 140.427184 -267.631261) (xy 140.427184 -267.581283) (xy 140.435003 -267.53192) (xy 140.450447 -267.484388)
			(xy 140.473137 -267.439856) (xy 140.502513 -267.399423) (xy 140.537853 -267.364083) (xy 140.578286 -267.334707)
			(xy 140.622818 -267.312017) (xy 140.67035 -267.296573) (xy 140.719713 -267.288754) (xy 140.769691 -267.288754)
			(xy 140.819054 -267.296573) (xy 140.866586 -267.312017) (xy 140.911118 -267.334707) (xy 140.951551 -267.364083)
			(xy 140.986891 -267.399423) (xy 141.016267 -267.439856) (xy 141.038957 -267.484388) (xy 141.054401 -267.53192)
			(xy 141.06222 -267.581283) (xy 141.06271 -267.606272) (xy 141.06222 -267.631261) (xy 141.367238 -267.631261)
			(xy 141.367238 -267.581283) (xy 141.375057 -267.53192) (xy 141.390501 -267.484388) (xy 141.413191 -267.439856)
			(xy 141.442567 -267.399423) (xy 141.477907 -267.364083) (xy 141.51834 -267.334707) (xy 141.562872 -267.312017)
			(xy 141.610404 -267.296573) (xy 141.659767 -267.288754) (xy 141.709745 -267.288754) (xy 141.759108 -267.296573)
			(xy 141.80664 -267.312017) (xy 141.851172 -267.334707) (xy 141.891605 -267.364083) (xy 141.926945 -267.399423)
			(xy 141.956321 -267.439856) (xy 141.979011 -267.484388) (xy 141.994455 -267.53192) (xy 142.002274 -267.581283)
			(xy 142.002764 -267.606272) (xy 142.308575 -267.606272) (xy 142.31267 -267.555544) (xy 142.324849 -267.50613)
			(xy 142.344797 -267.45931) (xy 142.371998 -267.416296) (xy 142.405746 -267.378202) (xy 142.445168 -267.346015)
			(xy 142.489242 -267.320569) (xy 142.536828 -267.302522) (xy 142.586692 -267.292342) (xy 142.637544 -267.290293)
			(xy 142.688065 -267.296427) (xy 142.736949 -267.310587) (xy 142.782928 -267.332404) (xy 142.824812 -267.361314)
			(xy 142.861516 -267.396569) (xy 142.892089 -267.437255) (xy 142.91574 -267.482318) (xy 142.931856 -267.530592)
			(xy 142.94002 -267.580826) (xy 142.940532 -267.606272) (xy 142.940029 -267.631261) (xy 143.247092 -267.631261)
			(xy 143.247092 -267.581283) (xy 143.254911 -267.53192) (xy 143.270355 -267.484388) (xy 143.293045 -267.439856)
			(xy 143.322421 -267.399423) (xy 143.357761 -267.364083) (xy 143.398194 -267.334707) (xy 143.442726 -267.312017)
			(xy 143.490258 -267.296573) (xy 143.539621 -267.288754) (xy 143.589599 -267.288754) (xy 143.638962 -267.296573)
			(xy 143.686494 -267.312017) (xy 143.731026 -267.334707) (xy 143.771459 -267.364083) (xy 143.806799 -267.399423)
			(xy 143.836175 -267.439856) (xy 143.858865 -267.484388) (xy 143.874309 -267.53192) (xy 143.882128 -267.581283)
			(xy 143.882618 -267.606272) (xy 143.882128 -267.631261) (xy 143.874309 -267.680624) (xy 143.858865 -267.728156)
			(xy 143.836175 -267.772688) (xy 143.806799 -267.813121) (xy 143.771459 -267.848461) (xy 143.731026 -267.877837)
			(xy 143.686494 -267.900527) (xy 143.638962 -267.915971) (xy 143.589599 -267.92379) (xy 143.539621 -267.92379)
			(xy 143.490258 -267.915971) (xy 143.442726 -267.900527) (xy 143.398194 -267.877837) (xy 143.357761 -267.848461)
			(xy 143.322421 -267.813121) (xy 143.293045 -267.772688) (xy 143.270355 -267.728156) (xy 143.254911 -267.680624)
			(xy 143.247092 -267.631261) (xy 142.940029 -267.631261) (xy 142.94002 -267.631718) (xy 142.931856 -267.681952)
			(xy 142.91574 -267.730226) (xy 142.892089 -267.775289) (xy 142.861516 -267.815975) (xy 142.824812 -267.85123)
			(xy 142.782928 -267.88014) (xy 142.736949 -267.901957) (xy 142.688065 -267.916117) (xy 142.637544 -267.922251)
			(xy 142.586692 -267.920202) (xy 142.536828 -267.910022) (xy 142.489242 -267.891975) (xy 142.445168 -267.866529)
			(xy 142.405746 -267.834342) (xy 142.371998 -267.796248) (xy 142.344797 -267.753234) (xy 142.324849 -267.706414)
			(xy 142.31267 -267.657) (xy 142.308575 -267.606272) (xy 142.002764 -267.606272) (xy 142.002274 -267.631261)
			(xy 141.994455 -267.680624) (xy 141.979011 -267.728156) (xy 141.956321 -267.772688) (xy 141.926945 -267.813121)
			(xy 141.891605 -267.848461) (xy 141.851172 -267.877837) (xy 141.80664 -267.900527) (xy 141.759108 -267.915971)
			(xy 141.709745 -267.92379) (xy 141.659767 -267.92379) (xy 141.610404 -267.915971) (xy 141.562872 -267.900527)
			(xy 141.51834 -267.877837) (xy 141.477907 -267.848461) (xy 141.442567 -267.813121) (xy 141.413191 -267.772688)
			(xy 141.390501 -267.728156) (xy 141.375057 -267.680624) (xy 141.367238 -267.631261) (xy 141.06222 -267.631261)
			(xy 141.054401 -267.680624) (xy 141.038957 -267.728156) (xy 141.016267 -267.772688) (xy 140.986891 -267.813121)
			(xy 140.951551 -267.848461) (xy 140.911118 -267.877837) (xy 140.866586 -267.900527) (xy 140.819054 -267.915971)
			(xy 140.769691 -267.92379) (xy 140.719713 -267.92379) (xy 140.67035 -267.915971) (xy 140.622818 -267.900527)
			(xy 140.578286 -267.877837) (xy 140.537853 -267.848461) (xy 140.502513 -267.813121) (xy 140.473137 -267.772688)
			(xy 140.450447 -267.728156) (xy 140.435003 -267.680624) (xy 140.427184 -267.631261) (xy 140.119867 -267.631261)
			(xy 140.119858 -267.631718) (xy 140.111694 -267.681952) (xy 140.095578 -267.730226) (xy 140.071927 -267.775289)
			(xy 140.041354 -267.815975) (xy 140.00465 -267.85123) (xy 139.962766 -267.88014) (xy 139.916787 -267.901957)
			(xy 139.867903 -267.916117) (xy 139.817382 -267.922251) (xy 139.76653 -267.920202) (xy 139.716666 -267.910022)
			(xy 139.66908 -267.891975) (xy 139.625006 -267.866529) (xy 139.585584 -267.834342) (xy 139.551836 -267.796248)
			(xy 139.524635 -267.753234) (xy 139.504687 -267.706414) (xy 139.492508 -267.657) (xy 139.488413 -267.606272)
			(xy 139.182856 -267.606272) (xy 139.182366 -267.631261) (xy 139.174547 -267.680624) (xy 139.159103 -267.728156)
			(xy 139.136413 -267.772688) (xy 139.107037 -267.813121) (xy 139.071697 -267.848461) (xy 139.031264 -267.877837)
			(xy 138.986732 -267.900527) (xy 138.9392 -267.915971) (xy 138.889837 -267.92379) (xy 138.839859 -267.92379)
			(xy 138.790496 -267.915971) (xy 138.742964 -267.900527) (xy 138.698432 -267.877837) (xy 138.657999 -267.848461)
			(xy 138.622659 -267.813121) (xy 138.593283 -267.772688) (xy 138.570593 -267.728156) (xy 138.555149 -267.680624)
			(xy 138.54733 -267.631261) (xy 138.242312 -267.631261) (xy 138.234493 -267.680624) (xy 138.219049 -267.728156)
			(xy 138.196359 -267.772688) (xy 138.166983 -267.813121) (xy 138.131643 -267.848461) (xy 138.09121 -267.877837)
			(xy 138.046678 -267.900527) (xy 137.999146 -267.915971) (xy 137.949783 -267.92379) (xy 137.899805 -267.92379)
			(xy 137.850442 -267.915971) (xy 137.80291 -267.900527) (xy 137.758378 -267.877837) (xy 137.717945 -267.848461)
			(xy 137.682605 -267.813121) (xy 137.653229 -267.772688) (xy 137.630539 -267.728156) (xy 137.615095 -267.680624)
			(xy 137.607276 -267.631261) (xy 137.302258 -267.631261) (xy 137.294439 -267.680624) (xy 137.278995 -267.728156)
			(xy 137.256305 -267.772688) (xy 137.226929 -267.813121) (xy 137.191589 -267.848461) (xy 137.151156 -267.877837)
			(xy 137.106624 -267.900527) (xy 137.059092 -267.915971) (xy 137.009729 -267.92379) (xy 136.959751 -267.92379)
			(xy 136.910388 -267.915971) (xy 136.862856 -267.900527) (xy 136.818324 -267.877837) (xy 136.777891 -267.848461)
			(xy 136.742551 -267.813121) (xy 136.713175 -267.772688) (xy 136.690485 -267.728156) (xy 136.675041 -267.680624)
			(xy 136.667222 -267.631261) (xy 136.359905 -267.631261) (xy 136.359896 -267.631718) (xy 136.351732 -267.681952)
			(xy 136.335616 -267.730226) (xy 136.311965 -267.775289) (xy 136.281392 -267.815975) (xy 136.244688 -267.85123)
			(xy 136.202804 -267.88014) (xy 136.156825 -267.901957) (xy 136.107941 -267.916117) (xy 136.05742 -267.922251)
			(xy 136.006568 -267.920202) (xy 135.956704 -267.910022) (xy 135.909118 -267.891975) (xy 135.865044 -267.866529)
			(xy 135.825622 -267.834342) (xy 135.791874 -267.796248) (xy 135.764673 -267.753234) (xy 135.744725 -267.706414)
			(xy 135.732546 -267.657) (xy 135.728451 -267.606272) (xy 135.42264 -267.606272) (xy 135.42215 -267.631261)
			(xy 135.414331 -267.680624) (xy 135.398887 -267.728156) (xy 135.376197 -267.772688) (xy 135.346821 -267.813121)
			(xy 135.311481 -267.848461) (xy 135.271048 -267.877837) (xy 135.226516 -267.900527) (xy 135.178984 -267.915971)
			(xy 135.129621 -267.92379) (xy 135.079643 -267.92379) (xy 135.03028 -267.915971) (xy 134.982748 -267.900527)
			(xy 134.938216 -267.877837) (xy 134.897783 -267.848461) (xy 134.862443 -267.813121) (xy 134.833067 -267.772688)
			(xy 134.810377 -267.728156) (xy 134.794933 -267.680624) (xy 134.787114 -267.631261) (xy 134.48235 -267.631261)
			(xy 134.474531 -267.680624) (xy 134.459087 -267.728156) (xy 134.436397 -267.772688) (xy 134.407021 -267.813121)
			(xy 134.371681 -267.848461) (xy 134.331248 -267.877837) (xy 134.286716 -267.900527) (xy 134.239184 -267.915971)
			(xy 134.189821 -267.92379) (xy 134.139843 -267.92379) (xy 134.09048 -267.915971) (xy 134.042948 -267.900527)
			(xy 133.998416 -267.877837) (xy 133.957983 -267.848461) (xy 133.922643 -267.813121) (xy 133.893267 -267.772688)
			(xy 133.870577 -267.728156) (xy 133.855133 -267.680624) (xy 133.847314 -267.631261) (xy 133.539997 -267.631261)
			(xy 133.539988 -267.631718) (xy 133.531824 -267.681952) (xy 133.515708 -267.730226) (xy 133.492057 -267.775289)
			(xy 133.461484 -267.815975) (xy 133.42478 -267.85123) (xy 133.382896 -267.88014) (xy 133.336917 -267.901957)
			(xy 133.288033 -267.916117) (xy 133.237512 -267.922251) (xy 133.18666 -267.920202) (xy 133.136796 -267.910022)
			(xy 133.08921 -267.891975) (xy 133.045136 -267.866529) (xy 133.005714 -267.834342) (xy 132.971966 -267.796248)
			(xy 132.944765 -267.753234) (xy 132.924817 -267.706414) (xy 132.912638 -267.657) (xy 132.908543 -267.606272)
			(xy 132.602732 -267.606272) (xy 132.602242 -267.631261) (xy 132.594423 -267.680624) (xy 132.578979 -267.728156)
			(xy 132.556289 -267.772688) (xy 132.526913 -267.813121) (xy 132.491573 -267.848461) (xy 132.45114 -267.877837)
			(xy 132.406608 -267.900527) (xy 132.359076 -267.915971) (xy 132.309713 -267.92379) (xy 132.259735 -267.92379)
			(xy 132.210372 -267.915971) (xy 132.16284 -267.900527) (xy 132.118308 -267.877837) (xy 132.077875 -267.848461)
			(xy 132.042535 -267.813121) (xy 132.013159 -267.772688) (xy 131.990469 -267.728156) (xy 131.975025 -267.680624)
			(xy 131.967206 -267.631261) (xy 131.662188 -267.631261) (xy 131.654369 -267.680624) (xy 131.638925 -267.728156)
			(xy 131.616235 -267.772688) (xy 131.586859 -267.813121) (xy 131.551519 -267.848461) (xy 131.511086 -267.877837)
			(xy 131.466554 -267.900527) (xy 131.419022 -267.915971) (xy 131.369659 -267.92379) (xy 131.319681 -267.92379)
			(xy 131.270318 -267.915971) (xy 131.222786 -267.900527) (xy 131.178254 -267.877837) (xy 131.137821 -267.848461)
			(xy 131.102481 -267.813121) (xy 131.073105 -267.772688) (xy 131.050415 -267.728156) (xy 131.034971 -267.680624)
			(xy 131.027152 -267.631261) (xy 130.722388 -267.631261) (xy 130.714569 -267.680624) (xy 130.699125 -267.728156)
			(xy 130.676435 -267.772688) (xy 130.647059 -267.813121) (xy 130.611719 -267.848461) (xy 130.571286 -267.877837)
			(xy 130.526754 -267.900527) (xy 130.479222 -267.915971) (xy 130.429859 -267.92379) (xy 130.379881 -267.92379)
			(xy 130.330518 -267.915971) (xy 130.282986 -267.900527) (xy 130.238454 -267.877837) (xy 130.198021 -267.848461)
			(xy 130.162681 -267.813121) (xy 130.133305 -267.772688) (xy 130.110615 -267.728156) (xy 130.095171 -267.680624)
			(xy 130.087352 -267.631261) (xy 129.780035 -267.631261) (xy 129.780026 -267.631718) (xy 129.771862 -267.681952)
			(xy 129.755746 -267.730226) (xy 129.732095 -267.775289) (xy 129.701522 -267.815975) (xy 129.664818 -267.85123)
			(xy 129.622934 -267.88014) (xy 129.576955 -267.901957) (xy 129.528071 -267.916117) (xy 129.47755 -267.922251)
			(xy 129.426698 -267.920202) (xy 129.376834 -267.910022) (xy 129.329248 -267.891975) (xy 129.285174 -267.866529)
			(xy 129.245752 -267.834342) (xy 129.212004 -267.796248) (xy 129.184803 -267.753234) (xy 129.164855 -267.706414)
			(xy 129.152676 -267.657) (xy 129.148581 -267.606272) (xy 128.84277 -267.606272) (xy 128.84228 -267.631261)
			(xy 128.834461 -267.680624) (xy 128.819017 -267.728156) (xy 128.796327 -267.772688) (xy 128.766951 -267.813121)
			(xy 128.731611 -267.848461) (xy 128.691178 -267.877837) (xy 128.646646 -267.900527) (xy 128.599114 -267.915971)
			(xy 128.549751 -267.92379) (xy 128.499773 -267.92379) (xy 128.45041 -267.915971) (xy 128.402878 -267.900527)
			(xy 128.358346 -267.877837) (xy 128.317913 -267.848461) (xy 128.282573 -267.813121) (xy 128.253197 -267.772688)
			(xy 128.230507 -267.728156) (xy 128.215063 -267.680624) (xy 128.207244 -267.631261) (xy 127.167386 -267.631261)
			(xy 127.167386 -268.061948) (xy 127.168022 -268.073932) (xy 127.178889 -268.09529) (xy 127.188214 -268.102842)
			(xy 127.196342 -268.106906) (xy 127.204978 -268.110462) (xy 127.229389 -268.118188) (xy 127.275553 -268.140329)
			(xy 127.317583 -268.169566) (xy 127.354397 -268.205148) (xy 127.385047 -268.246159) (xy 127.408745 -268.291544)
			(xy 127.424881 -268.340133) (xy 127.43304 -268.390678) (xy 127.433578 -268.416278) (xy 127.433076 -268.441267)
			(xy 127.737344 -268.441267) (xy 127.737344 -268.391289) (xy 127.745163 -268.341926) (xy 127.760607 -268.294394)
			(xy 127.783297 -268.249862) (xy 127.812673 -268.209429) (xy 127.848013 -268.174089) (xy 127.888446 -268.144713)
			(xy 127.932978 -268.122023) (xy 127.98051 -268.106579) (xy 128.029873 -268.09876) (xy 128.079851 -268.09876)
			(xy 128.129214 -268.106579) (xy 128.176746 -268.122023) (xy 128.221278 -268.144713) (xy 128.261711 -268.174089)
			(xy 128.297051 -268.209429) (xy 128.326427 -268.249862) (xy 128.349117 -268.294394) (xy 128.364561 -268.341926)
			(xy 128.37238 -268.391289) (xy 128.37287 -268.416278) (xy 128.37238 -268.441267) (xy 128.677144 -268.441267)
			(xy 128.677144 -268.391289) (xy 128.684963 -268.341926) (xy 128.700407 -268.294394) (xy 128.723097 -268.249862)
			(xy 128.752473 -268.209429) (xy 128.787813 -268.174089) (xy 128.828246 -268.144713) (xy 128.872778 -268.122023)
			(xy 128.92031 -268.106579) (xy 128.969673 -268.09876) (xy 129.019651 -268.09876) (xy 129.069014 -268.106579)
			(xy 129.116546 -268.122023) (xy 129.161078 -268.144713) (xy 129.201511 -268.174089) (xy 129.236851 -268.209429)
			(xy 129.266227 -268.249862) (xy 129.288917 -268.294394) (xy 129.304361 -268.341926) (xy 129.31218 -268.391289)
			(xy 129.31267 -268.416278) (xy 129.31218 -268.441267) (xy 129.617198 -268.441267) (xy 129.617198 -268.391289)
			(xy 129.625017 -268.341926) (xy 129.640461 -268.294394) (xy 129.663151 -268.249862) (xy 129.692527 -268.209429)
			(xy 129.727867 -268.174089) (xy 129.7683 -268.144713) (xy 129.812832 -268.122023) (xy 129.860364 -268.106579)
			(xy 129.909727 -268.09876) (xy 129.959705 -268.09876) (xy 130.009068 -268.106579) (xy 130.0566 -268.122023)
			(xy 130.101132 -268.144713) (xy 130.141565 -268.174089) (xy 130.176905 -268.209429) (xy 130.206281 -268.249862)
			(xy 130.228971 -268.294394) (xy 130.244415 -268.341926) (xy 130.252234 -268.391289) (xy 130.252724 -268.416278)
			(xy 130.252234 -268.441267) (xy 131.497306 -268.441267) (xy 131.497306 -268.391289) (xy 131.505125 -268.341926)
			(xy 131.520569 -268.294394) (xy 131.543259 -268.249862) (xy 131.572635 -268.209429) (xy 131.607975 -268.174089)
			(xy 131.648408 -268.144713) (xy 131.69294 -268.122023) (xy 131.740472 -268.106579) (xy 131.789835 -268.09876)
			(xy 131.839813 -268.09876) (xy 131.889176 -268.106579) (xy 131.936708 -268.122023) (xy 131.98124 -268.144713)
			(xy 132.021673 -268.174089) (xy 132.057013 -268.209429) (xy 132.086389 -268.249862) (xy 132.109079 -268.294394)
			(xy 132.124523 -268.341926) (xy 132.132342 -268.391289) (xy 132.132832 -268.416278) (xy 132.132342 -268.441267)
			(xy 132.437106 -268.441267) (xy 132.437106 -268.391289) (xy 132.444925 -268.341926) (xy 132.460369 -268.294394)
			(xy 132.483059 -268.249862) (xy 132.512435 -268.209429) (xy 132.547775 -268.174089) (xy 132.588208 -268.144713)
			(xy 132.63274 -268.122023) (xy 132.680272 -268.106579) (xy 132.729635 -268.09876) (xy 132.779613 -268.09876)
			(xy 132.828976 -268.106579) (xy 132.876508 -268.122023) (xy 132.92104 -268.144713) (xy 132.961473 -268.174089)
			(xy 132.996813 -268.209429) (xy 133.026189 -268.249862) (xy 133.048879 -268.294394) (xy 133.064323 -268.341926)
			(xy 133.072142 -268.391289) (xy 133.072632 -268.416278) (xy 133.072142 -268.441267) (xy 133.37716 -268.441267)
			(xy 133.37716 -268.391289) (xy 133.384979 -268.341926) (xy 133.400423 -268.294394) (xy 133.423113 -268.249862)
			(xy 133.452489 -268.209429) (xy 133.487829 -268.174089) (xy 133.528262 -268.144713) (xy 133.572794 -268.122023)
			(xy 133.620326 -268.106579) (xy 133.669689 -268.09876) (xy 133.719667 -268.09876) (xy 133.76903 -268.106579)
			(xy 133.816562 -268.122023) (xy 133.861094 -268.144713) (xy 133.901527 -268.174089) (xy 133.936867 -268.209429)
			(xy 133.966243 -268.249862) (xy 133.988933 -268.294394) (xy 134.004377 -268.341926) (xy 134.012196 -268.391289)
			(xy 134.012686 -268.416278) (xy 134.012196 -268.441267) (xy 134.317214 -268.441267) (xy 134.317214 -268.391289)
			(xy 134.325033 -268.341926) (xy 134.340477 -268.294394) (xy 134.363167 -268.249862) (xy 134.392543 -268.209429)
			(xy 134.427883 -268.174089) (xy 134.468316 -268.144713) (xy 134.512848 -268.122023) (xy 134.56038 -268.106579)
			(xy 134.609743 -268.09876) (xy 134.659721 -268.09876) (xy 134.709084 -268.106579) (xy 134.756616 -268.122023)
			(xy 134.801148 -268.144713) (xy 134.841581 -268.174089) (xy 134.876921 -268.209429) (xy 134.906297 -268.249862)
			(xy 134.928987 -268.294394) (xy 134.944431 -268.341926) (xy 134.95225 -268.391289) (xy 134.95274 -268.416278)
			(xy 134.95225 -268.441267) (xy 135.257268 -268.441267) (xy 135.257268 -268.391289) (xy 135.265087 -268.341926)
			(xy 135.280531 -268.294394) (xy 135.303221 -268.249862) (xy 135.332597 -268.209429) (xy 135.367937 -268.174089)
			(xy 135.40837 -268.144713) (xy 135.452902 -268.122023) (xy 135.500434 -268.106579) (xy 135.549797 -268.09876)
			(xy 135.599775 -268.09876) (xy 135.649138 -268.106579) (xy 135.69667 -268.122023) (xy 135.741202 -268.144713)
			(xy 135.781635 -268.174089) (xy 135.816975 -268.209429) (xy 135.846351 -268.249862) (xy 135.869041 -268.294394)
			(xy 135.884485 -268.341926) (xy 135.892304 -268.391289) (xy 135.892794 -268.416278) (xy 135.892304 -268.441267)
			(xy 136.197322 -268.441267) (xy 136.197322 -268.391289) (xy 136.205141 -268.341926) (xy 136.220585 -268.294394)
			(xy 136.243275 -268.249862) (xy 136.272651 -268.209429) (xy 136.307991 -268.174089) (xy 136.348424 -268.144713)
			(xy 136.392956 -268.122023) (xy 136.440488 -268.106579) (xy 136.489851 -268.09876) (xy 136.539829 -268.09876)
			(xy 136.589192 -268.106579) (xy 136.636724 -268.122023) (xy 136.681256 -268.144713) (xy 136.721689 -268.174089)
			(xy 136.757029 -268.209429) (xy 136.786405 -268.249862) (xy 136.809095 -268.294394) (xy 136.824539 -268.341926)
			(xy 136.832358 -268.391289) (xy 136.832848 -268.416278) (xy 136.832358 -268.441267) (xy 138.077176 -268.441267)
			(xy 138.077176 -268.391289) (xy 138.084995 -268.341926) (xy 138.100439 -268.294394) (xy 138.123129 -268.249862)
			(xy 138.152505 -268.209429) (xy 138.187845 -268.174089) (xy 138.228278 -268.144713) (xy 138.27281 -268.122023)
			(xy 138.320342 -268.106579) (xy 138.369705 -268.09876) (xy 138.419683 -268.09876) (xy 138.469046 -268.106579)
			(xy 138.516578 -268.122023) (xy 138.56111 -268.144713) (xy 138.601543 -268.174089) (xy 138.636883 -268.209429)
			(xy 138.666259 -268.249862) (xy 138.688949 -268.294394) (xy 138.704393 -268.341926) (xy 138.712212 -268.391289)
			(xy 138.712702 -268.416278) (xy 138.712212 -268.441267) (xy 139.01723 -268.441267) (xy 139.01723 -268.391289)
			(xy 139.025049 -268.341926) (xy 139.040493 -268.294394) (xy 139.063183 -268.249862) (xy 139.092559 -268.209429)
			(xy 139.127899 -268.174089) (xy 139.168332 -268.144713) (xy 139.212864 -268.122023) (xy 139.260396 -268.106579)
			(xy 139.309759 -268.09876) (xy 139.359737 -268.09876) (xy 139.4091 -268.106579) (xy 139.456632 -268.122023)
			(xy 139.501164 -268.144713) (xy 139.541597 -268.174089) (xy 139.576937 -268.209429) (xy 139.606313 -268.249862)
			(xy 139.629003 -268.294394) (xy 139.644447 -268.341926) (xy 139.652266 -268.391289) (xy 139.652756 -268.416278)
			(xy 139.652266 -268.441267) (xy 139.957284 -268.441267) (xy 139.957284 -268.391289) (xy 139.965103 -268.341926)
			(xy 139.980547 -268.294394) (xy 140.003237 -268.249862) (xy 140.032613 -268.209429) (xy 140.067953 -268.174089)
			(xy 140.108386 -268.144713) (xy 140.152918 -268.122023) (xy 140.20045 -268.106579) (xy 140.249813 -268.09876)
			(xy 140.299791 -268.09876) (xy 140.349154 -268.106579) (xy 140.396686 -268.122023) (xy 140.441218 -268.144713)
			(xy 140.481651 -268.174089) (xy 140.516991 -268.209429) (xy 140.546367 -268.249862) (xy 140.569057 -268.294394)
			(xy 140.584501 -268.341926) (xy 140.59232 -268.391289) (xy 140.59281 -268.416278) (xy 140.59232 -268.441267)
			(xy 140.897338 -268.441267) (xy 140.897338 -268.391289) (xy 140.905157 -268.341926) (xy 140.920601 -268.294394)
			(xy 140.943291 -268.249862) (xy 140.972667 -268.209429) (xy 141.008007 -268.174089) (xy 141.04844 -268.144713)
			(xy 141.092972 -268.122023) (xy 141.140504 -268.106579) (xy 141.189867 -268.09876) (xy 141.239845 -268.09876)
			(xy 141.289208 -268.106579) (xy 141.33674 -268.122023) (xy 141.381272 -268.144713) (xy 141.421705 -268.174089)
			(xy 141.457045 -268.209429) (xy 141.486421 -268.249862) (xy 141.509111 -268.294394) (xy 141.524555 -268.341926)
			(xy 141.532374 -268.391289) (xy 141.532864 -268.416278) (xy 141.532374 -268.441267) (xy 141.837138 -268.441267)
			(xy 141.837138 -268.391289) (xy 141.844957 -268.341926) (xy 141.860401 -268.294394) (xy 141.883091 -268.249862)
			(xy 141.912467 -268.209429) (xy 141.947807 -268.174089) (xy 141.98824 -268.144713) (xy 142.032772 -268.122023)
			(xy 142.080304 -268.106579) (xy 142.129667 -268.09876) (xy 142.179645 -268.09876) (xy 142.229008 -268.106579)
			(xy 142.27654 -268.122023) (xy 142.321072 -268.144713) (xy 142.361505 -268.174089) (xy 142.396845 -268.209429)
			(xy 142.426221 -268.249862) (xy 142.448911 -268.294394) (xy 142.464355 -268.341926) (xy 142.472174 -268.391289)
			(xy 142.472664 -268.416278) (xy 142.472174 -268.441267) (xy 142.777192 -268.441267) (xy 142.777192 -268.391289)
			(xy 142.785011 -268.341926) (xy 142.800455 -268.294394) (xy 142.823145 -268.249862) (xy 142.852521 -268.209429)
			(xy 142.887861 -268.174089) (xy 142.928294 -268.144713) (xy 142.972826 -268.122023) (xy 143.020358 -268.106579)
			(xy 143.069721 -268.09876) (xy 143.119699 -268.09876) (xy 143.169062 -268.106579) (xy 143.216594 -268.122023)
			(xy 143.261126 -268.144713) (xy 143.301559 -268.174089) (xy 143.336899 -268.209429) (xy 143.366275 -268.249862)
			(xy 143.388965 -268.294394) (xy 143.404409 -268.341926) (xy 143.412228 -268.391289) (xy 143.412718 -268.416278)
			(xy 143.412228 -268.441267) (xy 143.404409 -268.49063) (xy 143.388965 -268.538162) (xy 143.366275 -268.582694)
			(xy 143.336899 -268.623127) (xy 143.301559 -268.658467) (xy 143.261126 -268.687843) (xy 143.216594 -268.710533)
			(xy 143.169062 -268.725977) (xy 143.119699 -268.733796) (xy 143.069721 -268.733796) (xy 143.020358 -268.725977)
			(xy 142.972826 -268.710533) (xy 142.928294 -268.687843) (xy 142.887861 -268.658467) (xy 142.852521 -268.623127)
			(xy 142.823145 -268.582694) (xy 142.800455 -268.538162) (xy 142.785011 -268.49063) (xy 142.777192 -268.441267)
			(xy 142.472174 -268.441267) (xy 142.464355 -268.49063) (xy 142.448911 -268.538162) (xy 142.426221 -268.582694)
			(xy 142.396845 -268.623127) (xy 142.361505 -268.658467) (xy 142.321072 -268.687843) (xy 142.27654 -268.710533)
			(xy 142.229008 -268.725977) (xy 142.179645 -268.733796) (xy 142.129667 -268.733796) (xy 142.080304 -268.725977)
			(xy 142.032772 -268.710533) (xy 141.98824 -268.687843) (xy 141.947807 -268.658467) (xy 141.912467 -268.623127)
			(xy 141.883091 -268.582694) (xy 141.860401 -268.538162) (xy 141.844957 -268.49063) (xy 141.837138 -268.441267)
			(xy 141.532374 -268.441267) (xy 141.524555 -268.49063) (xy 141.509111 -268.538162) (xy 141.486421 -268.582694)
			(xy 141.457045 -268.623127) (xy 141.421705 -268.658467) (xy 141.381272 -268.687843) (xy 141.33674 -268.710533)
			(xy 141.289208 -268.725977) (xy 141.239845 -268.733796) (xy 141.189867 -268.733796) (xy 141.140504 -268.725977)
			(xy 141.092972 -268.710533) (xy 141.04844 -268.687843) (xy 141.008007 -268.658467) (xy 140.972667 -268.623127)
			(xy 140.943291 -268.582694) (xy 140.920601 -268.538162) (xy 140.905157 -268.49063) (xy 140.897338 -268.441267)
			(xy 140.59232 -268.441267) (xy 140.584501 -268.49063) (xy 140.569057 -268.538162) (xy 140.546367 -268.582694)
			(xy 140.516991 -268.623127) (xy 140.481651 -268.658467) (xy 140.441218 -268.687843) (xy 140.396686 -268.710533)
			(xy 140.349154 -268.725977) (xy 140.299791 -268.733796) (xy 140.249813 -268.733796) (xy 140.20045 -268.725977)
			(xy 140.152918 -268.710533) (xy 140.108386 -268.687843) (xy 140.067953 -268.658467) (xy 140.032613 -268.623127)
			(xy 140.003237 -268.582694) (xy 139.980547 -268.538162) (xy 139.965103 -268.49063) (xy 139.957284 -268.441267)
			(xy 139.652266 -268.441267) (xy 139.644447 -268.49063) (xy 139.629003 -268.538162) (xy 139.606313 -268.582694)
			(xy 139.576937 -268.623127) (xy 139.541597 -268.658467) (xy 139.501164 -268.687843) (xy 139.456632 -268.710533)
			(xy 139.4091 -268.725977) (xy 139.359737 -268.733796) (xy 139.309759 -268.733796) (xy 139.260396 -268.725977)
			(xy 139.212864 -268.710533) (xy 139.168332 -268.687843) (xy 139.127899 -268.658467) (xy 139.092559 -268.623127)
			(xy 139.063183 -268.582694) (xy 139.040493 -268.538162) (xy 139.025049 -268.49063) (xy 139.01723 -268.441267)
			(xy 138.712212 -268.441267) (xy 138.704393 -268.49063) (xy 138.688949 -268.538162) (xy 138.666259 -268.582694)
			(xy 138.636883 -268.623127) (xy 138.601543 -268.658467) (xy 138.56111 -268.687843) (xy 138.516578 -268.710533)
			(xy 138.469046 -268.725977) (xy 138.419683 -268.733796) (xy 138.369705 -268.733796) (xy 138.320342 -268.725977)
			(xy 138.27281 -268.710533) (xy 138.228278 -268.687843) (xy 138.187845 -268.658467) (xy 138.152505 -268.623127)
			(xy 138.123129 -268.582694) (xy 138.100439 -268.538162) (xy 138.084995 -268.49063) (xy 138.077176 -268.441267)
			(xy 136.832358 -268.441267) (xy 136.824539 -268.49063) (xy 136.809095 -268.538162) (xy 136.786405 -268.582694)
			(xy 136.757029 -268.623127) (xy 136.721689 -268.658467) (xy 136.681256 -268.687843) (xy 136.636724 -268.710533)
			(xy 136.589192 -268.725977) (xy 136.539829 -268.733796) (xy 136.489851 -268.733796) (xy 136.440488 -268.725977)
			(xy 136.392956 -268.710533) (xy 136.348424 -268.687843) (xy 136.307991 -268.658467) (xy 136.272651 -268.623127)
			(xy 136.243275 -268.582694) (xy 136.220585 -268.538162) (xy 136.205141 -268.49063) (xy 136.197322 -268.441267)
			(xy 135.892304 -268.441267) (xy 135.884485 -268.49063) (xy 135.869041 -268.538162) (xy 135.846351 -268.582694)
			(xy 135.816975 -268.623127) (xy 135.781635 -268.658467) (xy 135.741202 -268.687843) (xy 135.69667 -268.710533)
			(xy 135.649138 -268.725977) (xy 135.599775 -268.733796) (xy 135.549797 -268.733796) (xy 135.500434 -268.725977)
			(xy 135.452902 -268.710533) (xy 135.40837 -268.687843) (xy 135.367937 -268.658467) (xy 135.332597 -268.623127)
			(xy 135.303221 -268.582694) (xy 135.280531 -268.538162) (xy 135.265087 -268.49063) (xy 135.257268 -268.441267)
			(xy 134.95225 -268.441267) (xy 134.944431 -268.49063) (xy 134.928987 -268.538162) (xy 134.906297 -268.582694)
			(xy 134.876921 -268.623127) (xy 134.841581 -268.658467) (xy 134.801148 -268.687843) (xy 134.756616 -268.710533)
			(xy 134.709084 -268.725977) (xy 134.659721 -268.733796) (xy 134.609743 -268.733796) (xy 134.56038 -268.725977)
			(xy 134.512848 -268.710533) (xy 134.468316 -268.687843) (xy 134.427883 -268.658467) (xy 134.392543 -268.623127)
			(xy 134.363167 -268.582694) (xy 134.340477 -268.538162) (xy 134.325033 -268.49063) (xy 134.317214 -268.441267)
			(xy 134.012196 -268.441267) (xy 134.004377 -268.49063) (xy 133.988933 -268.538162) (xy 133.966243 -268.582694)
			(xy 133.936867 -268.623127) (xy 133.901527 -268.658467) (xy 133.861094 -268.687843) (xy 133.816562 -268.710533)
			(xy 133.76903 -268.725977) (xy 133.719667 -268.733796) (xy 133.669689 -268.733796) (xy 133.620326 -268.725977)
			(xy 133.572794 -268.710533) (xy 133.528262 -268.687843) (xy 133.487829 -268.658467) (xy 133.452489 -268.623127)
			(xy 133.423113 -268.582694) (xy 133.400423 -268.538162) (xy 133.384979 -268.49063) (xy 133.37716 -268.441267)
			(xy 133.072142 -268.441267) (xy 133.064323 -268.49063) (xy 133.048879 -268.538162) (xy 133.026189 -268.582694)
			(xy 132.996813 -268.623127) (xy 132.961473 -268.658467) (xy 132.92104 -268.687843) (xy 132.876508 -268.710533)
			(xy 132.828976 -268.725977) (xy 132.779613 -268.733796) (xy 132.729635 -268.733796) (xy 132.680272 -268.725977)
			(xy 132.63274 -268.710533) (xy 132.588208 -268.687843) (xy 132.547775 -268.658467) (xy 132.512435 -268.623127)
			(xy 132.483059 -268.582694) (xy 132.460369 -268.538162) (xy 132.444925 -268.49063) (xy 132.437106 -268.441267)
			(xy 132.132342 -268.441267) (xy 132.124523 -268.49063) (xy 132.109079 -268.538162) (xy 132.086389 -268.582694)
			(xy 132.057013 -268.623127) (xy 132.021673 -268.658467) (xy 131.98124 -268.687843) (xy 131.936708 -268.710533)
			(xy 131.889176 -268.725977) (xy 131.839813 -268.733796) (xy 131.789835 -268.733796) (xy 131.740472 -268.725977)
			(xy 131.69294 -268.710533) (xy 131.648408 -268.687843) (xy 131.607975 -268.658467) (xy 131.572635 -268.623127)
			(xy 131.543259 -268.582694) (xy 131.520569 -268.538162) (xy 131.505125 -268.49063) (xy 131.497306 -268.441267)
			(xy 130.252234 -268.441267) (xy 130.244415 -268.49063) (xy 130.228971 -268.538162) (xy 130.206281 -268.582694)
			(xy 130.176905 -268.623127) (xy 130.141565 -268.658467) (xy 130.101132 -268.687843) (xy 130.0566 -268.710533)
			(xy 130.009068 -268.725977) (xy 129.959705 -268.733796) (xy 129.909727 -268.733796) (xy 129.860364 -268.725977)
			(xy 129.812832 -268.710533) (xy 129.7683 -268.687843) (xy 129.727867 -268.658467) (xy 129.692527 -268.623127)
			(xy 129.663151 -268.582694) (xy 129.640461 -268.538162) (xy 129.625017 -268.49063) (xy 129.617198 -268.441267)
			(xy 129.31218 -268.441267) (xy 129.304361 -268.49063) (xy 129.288917 -268.538162) (xy 129.266227 -268.582694)
			(xy 129.236851 -268.623127) (xy 129.201511 -268.658467) (xy 129.161078 -268.687843) (xy 129.116546 -268.710533)
			(xy 129.069014 -268.725977) (xy 129.019651 -268.733796) (xy 128.969673 -268.733796) (xy 128.92031 -268.725977)
			(xy 128.872778 -268.710533) (xy 128.828246 -268.687843) (xy 128.787813 -268.658467) (xy 128.752473 -268.623127)
			(xy 128.723097 -268.582694) (xy 128.700407 -268.538162) (xy 128.684963 -268.49063) (xy 128.677144 -268.441267)
			(xy 128.37238 -268.441267) (xy 128.364561 -268.49063) (xy 128.349117 -268.538162) (xy 128.326427 -268.582694)
			(xy 128.297051 -268.623127) (xy 128.261711 -268.658467) (xy 128.221278 -268.687843) (xy 128.176746 -268.710533)
			(xy 128.129214 -268.725977) (xy 128.079851 -268.733796) (xy 128.029873 -268.733796) (xy 127.98051 -268.725977)
			(xy 127.932978 -268.710533) (xy 127.888446 -268.687843) (xy 127.848013 -268.658467) (xy 127.812673 -268.623127)
			(xy 127.783297 -268.582694) (xy 127.760607 -268.538162) (xy 127.745163 -268.49063) (xy 127.737344 -268.441267)
			(xy 127.433076 -268.441267) (xy 127.433054 -268.442339) (xy 127.424567 -268.493766) (xy 127.407832 -268.54313)
			(xy 127.383294 -268.589115) (xy 127.351606 -268.630499) (xy 127.313611 -268.666181) (xy 127.270321 -268.695211)
			(xy 127.222887 -268.716816) (xy 127.197866 -268.724126) (xy 127.189035 -268.728484) (xy 127.175291 -268.742563)
			(xy 127.167837 -268.760772) (xy 127.167386 -268.770608) (xy 127.167386 -268.953488) (xy 127.167848 -268.963803)
			(xy 127.175949 -268.982774) (xy 127.190882 -268.997005) (xy 127.200406 -269.000986) (xy 127.28702 -269.033244)
			(xy 127.295734 -269.036086) (xy 127.314048 -269.036053) (xy 127.331184 -269.029588) (xy 127.338328 -269.023846)
			(xy 127.343662 -269.018512) (xy 127.344678 -269.017242) (xy 127.362964 -268.997083) (xy 127.40516 -268.962714)
			(xy 127.452588 -268.936024) (xy 127.503865 -268.917793) (xy 127.557497 -268.908552) (xy 127.584708 -268.908022)
			(xy 127.609718 -268.908513) (xy 127.659122 -268.916339) (xy 127.706694 -268.931797) (xy 127.751261 -268.954507)
			(xy 127.791728 -268.983908) (xy 127.827097 -269.019278) (xy 127.856498 -269.059746) (xy 127.879206 -269.104314)
			(xy 127.894663 -269.151886) (xy 127.902487 -269.20129) (xy 127.902487 -269.251273) (xy 128.207244 -269.251273)
			(xy 128.207244 -269.201295) (xy 128.215063 -269.151932) (xy 128.230507 -269.1044) (xy 128.253197 -269.059868)
			(xy 128.282573 -269.019435) (xy 128.317913 -268.984095) (xy 128.358346 -268.954719) (xy 128.402878 -268.932029)
			(xy 128.45041 -268.916585) (xy 128.499773 -268.908766) (xy 128.549751 -268.908766) (xy 128.599114 -268.916585)
			(xy 128.646646 -268.932029) (xy 128.691178 -268.954719) (xy 128.731611 -268.984095) (xy 128.766951 -269.019435)
			(xy 128.796327 -269.059868) (xy 128.819017 -269.1044) (xy 128.834461 -269.151932) (xy 128.84228 -269.201295)
			(xy 128.84277 -269.226284) (xy 129.148581 -269.226284) (xy 129.152676 -269.175556) (xy 129.164855 -269.126142)
			(xy 129.184803 -269.079322) (xy 129.212004 -269.036308) (xy 129.245752 -268.998214) (xy 129.285174 -268.966027)
			(xy 129.329248 -268.940581) (xy 129.376834 -268.922534) (xy 129.426698 -268.912354) (xy 129.47755 -268.910305)
			(xy 129.528071 -268.916439) (xy 129.576955 -268.930599) (xy 129.622934 -268.952416) (xy 129.664818 -268.981326)
			(xy 129.701522 -269.016581) (xy 129.732095 -269.057267) (xy 129.755746 -269.10233) (xy 129.771862 -269.150604)
			(xy 129.780026 -269.200838) (xy 129.780538 -269.226284) (xy 129.780035 -269.251273) (xy 130.087352 -269.251273)
			(xy 130.087352 -269.201295) (xy 130.095171 -269.151932) (xy 130.110615 -269.1044) (xy 130.133305 -269.059868)
			(xy 130.162681 -269.019435) (xy 130.198021 -268.984095) (xy 130.238454 -268.954719) (xy 130.282986 -268.932029)
			(xy 130.330518 -268.916585) (xy 130.379881 -268.908766) (xy 130.429859 -268.908766) (xy 130.479222 -268.916585)
			(xy 130.526754 -268.932029) (xy 130.571286 -268.954719) (xy 130.611719 -268.984095) (xy 130.647059 -269.019435)
			(xy 130.676435 -269.059868) (xy 130.699125 -269.1044) (xy 130.714569 -269.151932) (xy 130.722388 -269.201295)
			(xy 130.722878 -269.226284) (xy 130.722388 -269.251273) (xy 131.027152 -269.251273) (xy 131.027152 -269.201295)
			(xy 131.034971 -269.151932) (xy 131.050415 -269.1044) (xy 131.073105 -269.059868) (xy 131.102481 -269.019435)
			(xy 131.137821 -268.984095) (xy 131.178254 -268.954719) (xy 131.222786 -268.932029) (xy 131.270318 -268.916585)
			(xy 131.319681 -268.908766) (xy 131.369659 -268.908766) (xy 131.419022 -268.916585) (xy 131.466554 -268.932029)
			(xy 131.511086 -268.954719) (xy 131.551519 -268.984095) (xy 131.586859 -269.019435) (xy 131.616235 -269.059868)
			(xy 131.638925 -269.1044) (xy 131.654369 -269.151932) (xy 131.662188 -269.201295) (xy 131.662678 -269.226284)
			(xy 131.662188 -269.251273) (xy 131.967206 -269.251273) (xy 131.967206 -269.201295) (xy 131.975025 -269.151932)
			(xy 131.990469 -269.1044) (xy 132.013159 -269.059868) (xy 132.042535 -269.019435) (xy 132.077875 -268.984095)
			(xy 132.118308 -268.954719) (xy 132.16284 -268.932029) (xy 132.210372 -268.916585) (xy 132.259735 -268.908766)
			(xy 132.309713 -268.908766) (xy 132.359076 -268.916585) (xy 132.406608 -268.932029) (xy 132.45114 -268.954719)
			(xy 132.491573 -268.984095) (xy 132.526913 -269.019435) (xy 132.556289 -269.059868) (xy 132.578979 -269.1044)
			(xy 132.594423 -269.151932) (xy 132.602242 -269.201295) (xy 132.602732 -269.226284) (xy 132.908543 -269.226284)
			(xy 132.912638 -269.175556) (xy 132.924817 -269.126142) (xy 132.944765 -269.079322) (xy 132.971966 -269.036308)
			(xy 133.005714 -268.998214) (xy 133.045136 -268.966027) (xy 133.08921 -268.940581) (xy 133.136796 -268.922534)
			(xy 133.18666 -268.912354) (xy 133.237512 -268.910305) (xy 133.288033 -268.916439) (xy 133.336917 -268.930599)
			(xy 133.382896 -268.952416) (xy 133.42478 -268.981326) (xy 133.461484 -269.016581) (xy 133.492057 -269.057267)
			(xy 133.515708 -269.10233) (xy 133.531824 -269.150604) (xy 133.539988 -269.200838) (xy 133.5405 -269.226284)
			(xy 133.539997 -269.251273) (xy 133.847314 -269.251273) (xy 133.847314 -269.201295) (xy 133.855133 -269.151932)
			(xy 133.870577 -269.1044) (xy 133.893267 -269.059868) (xy 133.922643 -269.019435) (xy 133.957983 -268.984095)
			(xy 133.998416 -268.954719) (xy 134.042948 -268.932029) (xy 134.09048 -268.916585) (xy 134.139843 -268.908766)
			(xy 134.189821 -268.908766) (xy 134.239184 -268.916585) (xy 134.286716 -268.932029) (xy 134.331248 -268.954719)
			(xy 134.371681 -268.984095) (xy 134.407021 -269.019435) (xy 134.436397 -269.059868) (xy 134.459087 -269.1044)
			(xy 134.474531 -269.151932) (xy 134.48235 -269.201295) (xy 134.48284 -269.226284) (xy 134.48235 -269.251273)
			(xy 134.787114 -269.251273) (xy 134.787114 -269.201295) (xy 134.794933 -269.151932) (xy 134.810377 -269.1044)
			(xy 134.833067 -269.059868) (xy 134.862443 -269.019435) (xy 134.897783 -268.984095) (xy 134.938216 -268.954719)
			(xy 134.982748 -268.932029) (xy 135.03028 -268.916585) (xy 135.079643 -268.908766) (xy 135.129621 -268.908766)
			(xy 135.178984 -268.916585) (xy 135.226516 -268.932029) (xy 135.271048 -268.954719) (xy 135.311481 -268.984095)
			(xy 135.346821 -269.019435) (xy 135.376197 -269.059868) (xy 135.398887 -269.1044) (xy 135.414331 -269.151932)
			(xy 135.42215 -269.201295) (xy 135.42264 -269.226284) (xy 135.728451 -269.226284) (xy 135.732546 -269.175556)
			(xy 135.744725 -269.126142) (xy 135.764673 -269.079322) (xy 135.791874 -269.036308) (xy 135.825622 -268.998214)
			(xy 135.865044 -268.966027) (xy 135.909118 -268.940581) (xy 135.956704 -268.922534) (xy 136.006568 -268.912354)
			(xy 136.05742 -268.910305) (xy 136.107941 -268.916439) (xy 136.156825 -268.930599) (xy 136.202804 -268.952416)
			(xy 136.244688 -268.981326) (xy 136.281392 -269.016581) (xy 136.311965 -269.057267) (xy 136.335616 -269.10233)
			(xy 136.351732 -269.150604) (xy 136.359896 -269.200838) (xy 136.360408 -269.226284) (xy 136.359905 -269.251273)
			(xy 136.667222 -269.251273) (xy 136.667222 -269.201295) (xy 136.675041 -269.151932) (xy 136.690485 -269.1044)
			(xy 136.713175 -269.059868) (xy 136.742551 -269.019435) (xy 136.777891 -268.984095) (xy 136.818324 -268.954719)
			(xy 136.862856 -268.932029) (xy 136.910388 -268.916585) (xy 136.959751 -268.908766) (xy 137.009729 -268.908766)
			(xy 137.059092 -268.916585) (xy 137.106624 -268.932029) (xy 137.151156 -268.954719) (xy 137.191589 -268.984095)
			(xy 137.226929 -269.019435) (xy 137.256305 -269.059868) (xy 137.278995 -269.1044) (xy 137.294439 -269.151932)
			(xy 137.302258 -269.201295) (xy 137.302748 -269.226284) (xy 137.302258 -269.251273) (xy 137.607276 -269.251273)
			(xy 137.607276 -269.201295) (xy 137.615095 -269.151932) (xy 137.630539 -269.1044) (xy 137.653229 -269.059868)
			(xy 137.682605 -269.019435) (xy 137.717945 -268.984095) (xy 137.758378 -268.954719) (xy 137.80291 -268.932029)
			(xy 137.850442 -268.916585) (xy 137.899805 -268.908766) (xy 137.949783 -268.908766) (xy 137.999146 -268.916585)
			(xy 138.046678 -268.932029) (xy 138.09121 -268.954719) (xy 138.131643 -268.984095) (xy 138.166983 -269.019435)
			(xy 138.196359 -269.059868) (xy 138.219049 -269.1044) (xy 138.234493 -269.151932) (xy 138.242312 -269.201295)
			(xy 138.242802 -269.226284) (xy 138.242312 -269.251273) (xy 138.54733 -269.251273) (xy 138.54733 -269.201295)
			(xy 138.555149 -269.151932) (xy 138.570593 -269.1044) (xy 138.593283 -269.059868) (xy 138.622659 -269.019435)
			(xy 138.657999 -268.984095) (xy 138.698432 -268.954719) (xy 138.742964 -268.932029) (xy 138.790496 -268.916585)
			(xy 138.839859 -268.908766) (xy 138.889837 -268.908766) (xy 138.9392 -268.916585) (xy 138.986732 -268.932029)
			(xy 139.031264 -268.954719) (xy 139.071697 -268.984095) (xy 139.107037 -269.019435) (xy 139.136413 -269.059868)
			(xy 139.159103 -269.1044) (xy 139.174547 -269.151932) (xy 139.182366 -269.201295) (xy 139.182856 -269.226284)
			(xy 139.488413 -269.226284) (xy 139.492508 -269.175556) (xy 139.504687 -269.126142) (xy 139.524635 -269.079322)
			(xy 139.551836 -269.036308) (xy 139.585584 -268.998214) (xy 139.625006 -268.966027) (xy 139.66908 -268.940581)
			(xy 139.716666 -268.922534) (xy 139.76653 -268.912354) (xy 139.817382 -268.910305) (xy 139.867903 -268.916439)
			(xy 139.916787 -268.930599) (xy 139.962766 -268.952416) (xy 140.00465 -268.981326) (xy 140.041354 -269.016581)
			(xy 140.071927 -269.057267) (xy 140.095578 -269.10233) (xy 140.111694 -269.150604) (xy 140.119858 -269.200838)
			(xy 140.12037 -269.226284) (xy 140.119867 -269.251273) (xy 140.427184 -269.251273) (xy 140.427184 -269.201295)
			(xy 140.435003 -269.151932) (xy 140.450447 -269.1044) (xy 140.473137 -269.059868) (xy 140.502513 -269.019435)
			(xy 140.537853 -268.984095) (xy 140.578286 -268.954719) (xy 140.622818 -268.932029) (xy 140.67035 -268.916585)
			(xy 140.719713 -268.908766) (xy 140.769691 -268.908766) (xy 140.819054 -268.916585) (xy 140.866586 -268.932029)
			(xy 140.911118 -268.954719) (xy 140.951551 -268.984095) (xy 140.986891 -269.019435) (xy 141.016267 -269.059868)
			(xy 141.038957 -269.1044) (xy 141.054401 -269.151932) (xy 141.06222 -269.201295) (xy 141.06271 -269.226284)
			(xy 141.06222 -269.251273) (xy 141.367238 -269.251273) (xy 141.367238 -269.201295) (xy 141.375057 -269.151932)
			(xy 141.390501 -269.1044) (xy 141.413191 -269.059868) (xy 141.442567 -269.019435) (xy 141.477907 -268.984095)
			(xy 141.51834 -268.954719) (xy 141.562872 -268.932029) (xy 141.610404 -268.916585) (xy 141.659767 -268.908766)
			(xy 141.709745 -268.908766) (xy 141.759108 -268.916585) (xy 141.80664 -268.932029) (xy 141.851172 -268.954719)
			(xy 141.891605 -268.984095) (xy 141.926945 -269.019435) (xy 141.956321 -269.059868) (xy 141.979011 -269.1044)
			(xy 141.994455 -269.151932) (xy 142.002274 -269.201295) (xy 142.002764 -269.226284) (xy 142.308575 -269.226284)
			(xy 142.31267 -269.175556) (xy 142.324849 -269.126142) (xy 142.344797 -269.079322) (xy 142.371998 -269.036308)
			(xy 142.405746 -268.998214) (xy 142.445168 -268.966027) (xy 142.489242 -268.940581) (xy 142.536828 -268.922534)
			(xy 142.586692 -268.912354) (xy 142.637544 -268.910305) (xy 142.688065 -268.916439) (xy 142.736949 -268.930599)
			(xy 142.782928 -268.952416) (xy 142.824812 -268.981326) (xy 142.861516 -269.016581) (xy 142.892089 -269.057267)
			(xy 142.91574 -269.10233) (xy 142.931856 -269.150604) (xy 142.94002 -269.200838) (xy 142.940532 -269.226284)
			(xy 142.940029 -269.251273) (xy 143.247092 -269.251273) (xy 143.247092 -269.201295) (xy 143.254911 -269.151932)
			(xy 143.270355 -269.1044) (xy 143.293045 -269.059868) (xy 143.322421 -269.019435) (xy 143.357761 -268.984095)
			(xy 143.398194 -268.954719) (xy 143.442726 -268.932029) (xy 143.490258 -268.916585) (xy 143.539621 -268.908766)
			(xy 143.589599 -268.908766) (xy 143.638962 -268.916585) (xy 143.686494 -268.932029) (xy 143.731026 -268.954719)
			(xy 143.771459 -268.984095) (xy 143.806799 -269.019435) (xy 143.836175 -269.059868) (xy 143.858865 -269.1044)
			(xy 143.874309 -269.151932) (xy 143.882128 -269.201295) (xy 143.882618 -269.226284) (xy 143.882128 -269.251273)
			(xy 144.187146 -269.251273) (xy 144.187146 -269.201295) (xy 144.194965 -269.151932) (xy 144.210409 -269.1044)
			(xy 144.233099 -269.059868) (xy 144.262475 -269.019435) (xy 144.297815 -268.984095) (xy 144.338248 -268.954719)
			(xy 144.38278 -268.932029) (xy 144.430312 -268.916585) (xy 144.479675 -268.908766) (xy 144.529653 -268.908766)
			(xy 144.579016 -268.916585) (xy 144.626548 -268.932029) (xy 144.67108 -268.954719) (xy 144.711513 -268.984095)
			(xy 144.746853 -269.019435) (xy 144.776229 -269.059868) (xy 144.798919 -269.1044) (xy 144.814363 -269.151932)
			(xy 144.822182 -269.201295) (xy 144.822672 -269.226284) (xy 144.822182 -269.251273) (xy 144.814363 -269.300636)
			(xy 144.798919 -269.348168) (xy 144.776229 -269.3927) (xy 144.746853 -269.433133) (xy 144.711513 -269.468473)
			(xy 144.67108 -269.497849) (xy 144.626548 -269.520539) (xy 144.579016 -269.535983) (xy 144.529653 -269.543802)
			(xy 144.479675 -269.543802) (xy 144.430312 -269.535983) (xy 144.38278 -269.520539) (xy 144.338248 -269.497849)
			(xy 144.297815 -269.468473) (xy 144.262475 -269.433133) (xy 144.233099 -269.3927) (xy 144.210409 -269.348168)
			(xy 144.194965 -269.300636) (xy 144.187146 -269.251273) (xy 143.882128 -269.251273) (xy 143.874309 -269.300636)
			(xy 143.858865 -269.348168) (xy 143.836175 -269.3927) (xy 143.806799 -269.433133) (xy 143.771459 -269.468473)
			(xy 143.731026 -269.497849) (xy 143.686494 -269.520539) (xy 143.638962 -269.535983) (xy 143.589599 -269.543802)
			(xy 143.539621 -269.543802) (xy 143.490258 -269.535983) (xy 143.442726 -269.520539) (xy 143.398194 -269.497849)
			(xy 143.357761 -269.468473) (xy 143.322421 -269.433133) (xy 143.293045 -269.3927) (xy 143.270355 -269.348168)
			(xy 143.254911 -269.300636) (xy 143.247092 -269.251273) (xy 142.940029 -269.251273) (xy 142.94002 -269.25173)
			(xy 142.931856 -269.301964) (xy 142.91574 -269.350238) (xy 142.892089 -269.395301) (xy 142.861516 -269.435987)
			(xy 142.824812 -269.471242) (xy 142.782928 -269.500152) (xy 142.736949 -269.521969) (xy 142.688065 -269.536129)
			(xy 142.637544 -269.542263) (xy 142.586692 -269.540214) (xy 142.536828 -269.530034) (xy 142.489242 -269.511987)
			(xy 142.445168 -269.486541) (xy 142.405746 -269.454354) (xy 142.371998 -269.41626) (xy 142.344797 -269.373246)
			(xy 142.324849 -269.326426) (xy 142.31267 -269.277012) (xy 142.308575 -269.226284) (xy 142.002764 -269.226284)
			(xy 142.002274 -269.251273) (xy 141.994455 -269.300636) (xy 141.979011 -269.348168) (xy 141.956321 -269.3927)
			(xy 141.926945 -269.433133) (xy 141.891605 -269.468473) (xy 141.851172 -269.497849) (xy 141.80664 -269.520539)
			(xy 141.759108 -269.535983) (xy 141.709745 -269.543802) (xy 141.659767 -269.543802) (xy 141.610404 -269.535983)
			(xy 141.562872 -269.520539) (xy 141.51834 -269.497849) (xy 141.477907 -269.468473) (xy 141.442567 -269.433133)
			(xy 141.413191 -269.3927) (xy 141.390501 -269.348168) (xy 141.375057 -269.300636) (xy 141.367238 -269.251273)
			(xy 141.06222 -269.251273) (xy 141.054401 -269.300636) (xy 141.038957 -269.348168) (xy 141.016267 -269.3927)
			(xy 140.986891 -269.433133) (xy 140.951551 -269.468473) (xy 140.911118 -269.497849) (xy 140.866586 -269.520539)
			(xy 140.819054 -269.535983) (xy 140.769691 -269.543802) (xy 140.719713 -269.543802) (xy 140.67035 -269.535983)
			(xy 140.622818 -269.520539) (xy 140.578286 -269.497849) (xy 140.537853 -269.468473) (xy 140.502513 -269.433133)
			(xy 140.473137 -269.3927) (xy 140.450447 -269.348168) (xy 140.435003 -269.300636) (xy 140.427184 -269.251273)
			(xy 140.119867 -269.251273) (xy 140.119858 -269.25173) (xy 140.111694 -269.301964) (xy 140.095578 -269.350238)
			(xy 140.071927 -269.395301) (xy 140.041354 -269.435987) (xy 140.00465 -269.471242) (xy 139.962766 -269.500152)
			(xy 139.916787 -269.521969) (xy 139.867903 -269.536129) (xy 139.817382 -269.542263) (xy 139.76653 -269.540214)
			(xy 139.716666 -269.530034) (xy 139.66908 -269.511987) (xy 139.625006 -269.486541) (xy 139.585584 -269.454354)
			(xy 139.551836 -269.41626) (xy 139.524635 -269.373246) (xy 139.504687 -269.326426) (xy 139.492508 -269.277012)
			(xy 139.488413 -269.226284) (xy 139.182856 -269.226284) (xy 139.182366 -269.251273) (xy 139.174547 -269.300636)
			(xy 139.159103 -269.348168) (xy 139.136413 -269.3927) (xy 139.107037 -269.433133) (xy 139.071697 -269.468473)
			(xy 139.031264 -269.497849) (xy 138.986732 -269.520539) (xy 138.9392 -269.535983) (xy 138.889837 -269.543802)
			(xy 138.839859 -269.543802) (xy 138.790496 -269.535983) (xy 138.742964 -269.520539) (xy 138.698432 -269.497849)
			(xy 138.657999 -269.468473) (xy 138.622659 -269.433133) (xy 138.593283 -269.3927) (xy 138.570593 -269.348168)
			(xy 138.555149 -269.300636) (xy 138.54733 -269.251273) (xy 138.242312 -269.251273) (xy 138.234493 -269.300636)
			(xy 138.219049 -269.348168) (xy 138.196359 -269.3927) (xy 138.166983 -269.433133) (xy 138.131643 -269.468473)
			(xy 138.09121 -269.497849) (xy 138.046678 -269.520539) (xy 137.999146 -269.535983) (xy 137.949783 -269.543802)
			(xy 137.899805 -269.543802) (xy 137.850442 -269.535983) (xy 137.80291 -269.520539) (xy 137.758378 -269.497849)
			(xy 137.717945 -269.468473) (xy 137.682605 -269.433133) (xy 137.653229 -269.3927) (xy 137.630539 -269.348168)
			(xy 137.615095 -269.300636) (xy 137.607276 -269.251273) (xy 137.302258 -269.251273) (xy 137.294439 -269.300636)
			(xy 137.278995 -269.348168) (xy 137.256305 -269.3927) (xy 137.226929 -269.433133) (xy 137.191589 -269.468473)
			(xy 137.151156 -269.497849) (xy 137.106624 -269.520539) (xy 137.059092 -269.535983) (xy 137.009729 -269.543802)
			(xy 136.959751 -269.543802) (xy 136.910388 -269.535983) (xy 136.862856 -269.520539) (xy 136.818324 -269.497849)
			(xy 136.777891 -269.468473) (xy 136.742551 -269.433133) (xy 136.713175 -269.3927) (xy 136.690485 -269.348168)
			(xy 136.675041 -269.300636) (xy 136.667222 -269.251273) (xy 136.359905 -269.251273) (xy 136.359896 -269.25173)
			(xy 136.351732 -269.301964) (xy 136.335616 -269.350238) (xy 136.311965 -269.395301) (xy 136.281392 -269.435987)
			(xy 136.244688 -269.471242) (xy 136.202804 -269.500152) (xy 136.156825 -269.521969) (xy 136.107941 -269.536129)
			(xy 136.05742 -269.542263) (xy 136.006568 -269.540214) (xy 135.956704 -269.530034) (xy 135.909118 -269.511987)
			(xy 135.865044 -269.486541) (xy 135.825622 -269.454354) (xy 135.791874 -269.41626) (xy 135.764673 -269.373246)
			(xy 135.744725 -269.326426) (xy 135.732546 -269.277012) (xy 135.728451 -269.226284) (xy 135.42264 -269.226284)
			(xy 135.42215 -269.251273) (xy 135.414331 -269.300636) (xy 135.398887 -269.348168) (xy 135.376197 -269.3927)
			(xy 135.346821 -269.433133) (xy 135.311481 -269.468473) (xy 135.271048 -269.497849) (xy 135.226516 -269.520539)
			(xy 135.178984 -269.535983) (xy 135.129621 -269.543802) (xy 135.079643 -269.543802) (xy 135.03028 -269.535983)
			(xy 134.982748 -269.520539) (xy 134.938216 -269.497849) (xy 134.897783 -269.468473) (xy 134.862443 -269.433133)
			(xy 134.833067 -269.3927) (xy 134.810377 -269.348168) (xy 134.794933 -269.300636) (xy 134.787114 -269.251273)
			(xy 134.48235 -269.251273) (xy 134.474531 -269.300636) (xy 134.459087 -269.348168) (xy 134.436397 -269.3927)
			(xy 134.407021 -269.433133) (xy 134.371681 -269.468473) (xy 134.331248 -269.497849) (xy 134.286716 -269.520539)
			(xy 134.239184 -269.535983) (xy 134.189821 -269.543802) (xy 134.139843 -269.543802) (xy 134.09048 -269.535983)
			(xy 134.042948 -269.520539) (xy 133.998416 -269.497849) (xy 133.957983 -269.468473) (xy 133.922643 -269.433133)
			(xy 133.893267 -269.3927) (xy 133.870577 -269.348168) (xy 133.855133 -269.300636) (xy 133.847314 -269.251273)
			(xy 133.539997 -269.251273) (xy 133.539988 -269.25173) (xy 133.531824 -269.301964) (xy 133.515708 -269.350238)
			(xy 133.492057 -269.395301) (xy 133.461484 -269.435987) (xy 133.42478 -269.471242) (xy 133.382896 -269.500152)
			(xy 133.336917 -269.521969) (xy 133.288033 -269.536129) (xy 133.237512 -269.542263) (xy 133.18666 -269.540214)
			(xy 133.136796 -269.530034) (xy 133.08921 -269.511987) (xy 133.045136 -269.486541) (xy 133.005714 -269.454354)
			(xy 132.971966 -269.41626) (xy 132.944765 -269.373246) (xy 132.924817 -269.326426) (xy 132.912638 -269.277012)
			(xy 132.908543 -269.226284) (xy 132.602732 -269.226284) (xy 132.602242 -269.251273) (xy 132.594423 -269.300636)
			(xy 132.578979 -269.348168) (xy 132.556289 -269.3927) (xy 132.526913 -269.433133) (xy 132.491573 -269.468473)
			(xy 132.45114 -269.497849) (xy 132.406608 -269.520539) (xy 132.359076 -269.535983) (xy 132.309713 -269.543802)
			(xy 132.259735 -269.543802) (xy 132.210372 -269.535983) (xy 132.16284 -269.520539) (xy 132.118308 -269.497849)
			(xy 132.077875 -269.468473) (xy 132.042535 -269.433133) (xy 132.013159 -269.3927) (xy 131.990469 -269.348168)
			(xy 131.975025 -269.300636) (xy 131.967206 -269.251273) (xy 131.662188 -269.251273) (xy 131.654369 -269.300636)
			(xy 131.638925 -269.348168) (xy 131.616235 -269.3927) (xy 131.586859 -269.433133) (xy 131.551519 -269.468473)
			(xy 131.511086 -269.497849) (xy 131.466554 -269.520539) (xy 131.419022 -269.535983) (xy 131.369659 -269.543802)
			(xy 131.319681 -269.543802) (xy 131.270318 -269.535983) (xy 131.222786 -269.520539) (xy 131.178254 -269.497849)
			(xy 131.137821 -269.468473) (xy 131.102481 -269.433133) (xy 131.073105 -269.3927) (xy 131.050415 -269.348168)
			(xy 131.034971 -269.300636) (xy 131.027152 -269.251273) (xy 130.722388 -269.251273) (xy 130.714569 -269.300636)
			(xy 130.699125 -269.348168) (xy 130.676435 -269.3927) (xy 130.647059 -269.433133) (xy 130.611719 -269.468473)
			(xy 130.571286 -269.497849) (xy 130.526754 -269.520539) (xy 130.479222 -269.535983) (xy 130.429859 -269.543802)
			(xy 130.379881 -269.543802) (xy 130.330518 -269.535983) (xy 130.282986 -269.520539) (xy 130.238454 -269.497849)
			(xy 130.198021 -269.468473) (xy 130.162681 -269.433133) (xy 130.133305 -269.3927) (xy 130.110615 -269.348168)
			(xy 130.095171 -269.300636) (xy 130.087352 -269.251273) (xy 129.780035 -269.251273) (xy 129.780026 -269.25173)
			(xy 129.771862 -269.301964) (xy 129.755746 -269.350238) (xy 129.732095 -269.395301) (xy 129.701522 -269.435987)
			(xy 129.664818 -269.471242) (xy 129.622934 -269.500152) (xy 129.576955 -269.521969) (xy 129.528071 -269.536129)
			(xy 129.47755 -269.542263) (xy 129.426698 -269.540214) (xy 129.376834 -269.530034) (xy 129.329248 -269.511987)
			(xy 129.285174 -269.486541) (xy 129.245752 -269.454354) (xy 129.212004 -269.41626) (xy 129.184803 -269.373246)
			(xy 129.164855 -269.326426) (xy 129.152676 -269.277012) (xy 129.148581 -269.226284) (xy 128.84277 -269.226284)
			(xy 128.84228 -269.251273) (xy 128.834461 -269.300636) (xy 128.819017 -269.348168) (xy 128.796327 -269.3927)
			(xy 128.766951 -269.433133) (xy 128.731611 -269.468473) (xy 128.691178 -269.497849) (xy 128.646646 -269.520539)
			(xy 128.599114 -269.535983) (xy 128.549751 -269.543802) (xy 128.499773 -269.543802) (xy 128.45041 -269.535983)
			(xy 128.402878 -269.520539) (xy 128.358346 -269.497849) (xy 128.317913 -269.468473) (xy 128.282573 -269.433133)
			(xy 128.253197 -269.3927) (xy 128.230507 -269.348168) (xy 128.215063 -269.300636) (xy 128.207244 -269.251273)
			(xy 127.902487 -269.251273) (xy 127.902487 -269.25131) (xy 127.894663 -269.300714) (xy 127.879206 -269.348286)
			(xy 127.856498 -269.392854) (xy 127.827097 -269.433322) (xy 127.791728 -269.468692) (xy 127.751261 -269.498093)
			(xy 127.706694 -269.520803) (xy 127.659122 -269.536261) (xy 127.609718 -269.544087) (xy 127.584708 -269.544546)
			(xy 127.557339 -269.543977) (xy 127.503408 -269.534613) (xy 127.451874 -269.51616) (xy 127.404257 -269.489163)
			(xy 127.361961 -269.454416) (xy 127.343662 -269.434056) (xy 127.343154 -269.433548) (xy 127.343154 -269.433294)
			(xy 127.337862 -269.427808) (xy 127.324816 -269.419943) (xy 127.3175 -269.4178) (xy 127.310134 -269.415768)
			(xy 127.29464 -269.41653) (xy 127.20066 -269.451328) (xy 127.200406 -269.451328) (xy 127.193208 -269.454304)
			(xy 127.180928 -269.463876) (xy 127.176276 -269.470124) (xy 127.171958 -269.47622) (xy 127.167386 -269.490952)
			(xy 127.167386 -269.68196) (xy 127.168025 -269.693942) (xy 127.178895 -269.715296) (xy 127.188214 -269.722854)
			(xy 127.196342 -269.726918) (xy 127.204978 -269.730474) (xy 127.229392 -269.738199) (xy 127.275564 -269.760337)
			(xy 127.317602 -269.789573) (xy 127.354425 -269.825153) (xy 127.385086 -269.866163) (xy 127.408796 -269.911548)
			(xy 127.424945 -269.960139) (xy 127.433117 -270.010688) (xy 127.433578 -270.03629) (xy 127.738627 -270.03629)
			(xy 127.742722 -269.985562) (xy 127.754901 -269.936148) (xy 127.774849 -269.889328) (xy 127.80205 -269.846314)
			(xy 127.835798 -269.80822) (xy 127.87522 -269.776033) (xy 127.919294 -269.750587) (xy 127.96688 -269.73254)
			(xy 128.016744 -269.72236) (xy 128.067596 -269.720311) (xy 128.118117 -269.726445) (xy 128.167001 -269.740605)
			(xy 128.21298 -269.762422) (xy 128.254864 -269.791332) (xy 128.291568 -269.826587) (xy 128.322141 -269.867273)
			(xy 128.345792 -269.912336) (xy 128.361908 -269.96061) (xy 128.370072 -270.010844) (xy 128.370584 -270.03629)
			(xy 128.370081 -270.061279) (xy 128.677144 -270.061279) (xy 128.677144 -270.011301) (xy 128.684963 -269.961938)
			(xy 128.700407 -269.914406) (xy 128.723097 -269.869874) (xy 128.752473 -269.829441) (xy 128.787813 -269.794101)
			(xy 128.828246 -269.764725) (xy 128.872778 -269.742035) (xy 128.92031 -269.726591) (xy 128.969673 -269.718772)
			(xy 129.019651 -269.718772) (xy 129.069014 -269.726591) (xy 129.116546 -269.742035) (xy 129.161078 -269.764725)
			(xy 129.201511 -269.794101) (xy 129.236851 -269.829441) (xy 129.266227 -269.869874) (xy 129.288917 -269.914406)
			(xy 129.304361 -269.961938) (xy 129.31218 -270.011301) (xy 129.31267 -270.03629) (xy 129.618481 -270.03629)
			(xy 129.622576 -269.985562) (xy 129.634755 -269.936148) (xy 129.654703 -269.889328) (xy 129.681904 -269.846314)
			(xy 129.715652 -269.80822) (xy 129.755074 -269.776033) (xy 129.799148 -269.750587) (xy 129.846734 -269.73254)
			(xy 129.896598 -269.72236) (xy 129.94745 -269.720311) (xy 129.997971 -269.726445) (xy 130.046855 -269.740605)
			(xy 130.092834 -269.762422) (xy 130.134718 -269.791332) (xy 130.171422 -269.826587) (xy 130.201995 -269.867273)
			(xy 130.225646 -269.912336) (xy 130.241762 -269.96061) (xy 130.249926 -270.010844) (xy 130.250438 -270.03629)
			(xy 130.249935 -270.061279) (xy 130.557252 -270.061279) (xy 130.557252 -270.011301) (xy 130.565071 -269.961938)
			(xy 130.580515 -269.914406) (xy 130.603205 -269.869874) (xy 130.632581 -269.829441) (xy 130.667921 -269.794101)
			(xy 130.708354 -269.764725) (xy 130.752886 -269.742035) (xy 130.800418 -269.726591) (xy 130.849781 -269.718772)
			(xy 130.899759 -269.718772) (xy 130.949122 -269.726591) (xy 130.996654 -269.742035) (xy 131.041186 -269.764725)
			(xy 131.081619 -269.794101) (xy 131.116959 -269.829441) (xy 131.146335 -269.869874) (xy 131.169025 -269.914406)
			(xy 131.184469 -269.961938) (xy 131.192288 -270.011301) (xy 131.192778 -270.03629) (xy 131.498589 -270.03629)
			(xy 131.502684 -269.985562) (xy 131.514863 -269.936148) (xy 131.534811 -269.889328) (xy 131.562012 -269.846314)
			(xy 131.59576 -269.80822) (xy 131.635182 -269.776033) (xy 131.679256 -269.750587) (xy 131.726842 -269.73254)
			(xy 131.776706 -269.72236) (xy 131.827558 -269.720311) (xy 131.878079 -269.726445) (xy 131.926963 -269.740605)
			(xy 131.972942 -269.762422) (xy 132.014826 -269.791332) (xy 132.05153 -269.826587) (xy 132.082103 -269.867273)
			(xy 132.105754 -269.912336) (xy 132.12187 -269.96061) (xy 132.130034 -270.010844) (xy 132.130546 -270.03629)
			(xy 132.438643 -270.03629) (xy 132.442738 -269.985562) (xy 132.454917 -269.936148) (xy 132.474865 -269.889328)
			(xy 132.502066 -269.846314) (xy 132.535814 -269.80822) (xy 132.575236 -269.776033) (xy 132.61931 -269.750587)
			(xy 132.666896 -269.73254) (xy 132.71676 -269.72236) (xy 132.767612 -269.720311) (xy 132.818133 -269.726445)
			(xy 132.867017 -269.740605) (xy 132.912996 -269.762422) (xy 132.95488 -269.791332) (xy 132.991584 -269.826587)
			(xy 133.022157 -269.867273) (xy 133.045808 -269.912336) (xy 133.061924 -269.96061) (xy 133.070088 -270.010844)
			(xy 133.0706 -270.03629) (xy 133.070097 -270.061279) (xy 133.37716 -270.061279) (xy 133.37716 -270.011301)
			(xy 133.384979 -269.961938) (xy 133.400423 -269.914406) (xy 133.423113 -269.869874) (xy 133.452489 -269.829441)
			(xy 133.487829 -269.794101) (xy 133.528262 -269.764725) (xy 133.572794 -269.742035) (xy 133.620326 -269.726591)
			(xy 133.669689 -269.718772) (xy 133.719667 -269.718772) (xy 133.76903 -269.726591) (xy 133.816562 -269.742035)
			(xy 133.861094 -269.764725) (xy 133.901527 -269.794101) (xy 133.936867 -269.829441) (xy 133.966243 -269.869874)
			(xy 133.988933 -269.914406) (xy 134.004377 -269.961938) (xy 134.012196 -270.011301) (xy 134.012686 -270.03629)
			(xy 134.318497 -270.03629) (xy 134.322592 -269.985562) (xy 134.334771 -269.936148) (xy 134.354719 -269.889328)
			(xy 134.38192 -269.846314) (xy 134.415668 -269.80822) (xy 134.45509 -269.776033) (xy 134.499164 -269.750587)
			(xy 134.54675 -269.73254) (xy 134.596614 -269.72236) (xy 134.647466 -269.720311) (xy 134.697987 -269.726445)
			(xy 134.746871 -269.740605) (xy 134.79285 -269.762422) (xy 134.834734 -269.791332) (xy 134.871438 -269.826587)
			(xy 134.902011 -269.867273) (xy 134.925662 -269.912336) (xy 134.941778 -269.96061) (xy 134.949942 -270.010844)
			(xy 134.950454 -270.03629) (xy 134.949951 -270.061279) (xy 135.257268 -270.061279) (xy 135.257268 -270.011301)
			(xy 135.265087 -269.961938) (xy 135.280531 -269.914406) (xy 135.303221 -269.869874) (xy 135.332597 -269.829441)
			(xy 135.367937 -269.794101) (xy 135.40837 -269.764725) (xy 135.452902 -269.742035) (xy 135.500434 -269.726591)
			(xy 135.549797 -269.718772) (xy 135.599775 -269.718772) (xy 135.649138 -269.726591) (xy 135.69667 -269.742035)
			(xy 135.741202 -269.764725) (xy 135.781635 -269.794101) (xy 135.816975 -269.829441) (xy 135.846351 -269.869874)
			(xy 135.869041 -269.914406) (xy 135.884485 -269.961938) (xy 135.892304 -270.011301) (xy 135.892794 -270.03629)
			(xy 136.198605 -270.03629) (xy 136.2027 -269.985562) (xy 136.214879 -269.936148) (xy 136.234827 -269.889328)
			(xy 136.262028 -269.846314) (xy 136.295776 -269.80822) (xy 136.335198 -269.776033) (xy 136.379272 -269.750587)
			(xy 136.426858 -269.73254) (xy 136.476722 -269.72236) (xy 136.527574 -269.720311) (xy 136.578095 -269.726445)
			(xy 136.626979 -269.740605) (xy 136.672958 -269.762422) (xy 136.714842 -269.791332) (xy 136.751546 -269.826587)
			(xy 136.782119 -269.867273) (xy 136.80577 -269.912336) (xy 136.821886 -269.96061) (xy 136.83005 -270.010844)
			(xy 136.830562 -270.03629) (xy 136.830059 -270.061279) (xy 137.137122 -270.061279) (xy 137.137122 -270.011301)
			(xy 137.144941 -269.961938) (xy 137.160385 -269.914406) (xy 137.183075 -269.869874) (xy 137.212451 -269.829441)
			(xy 137.247791 -269.794101) (xy 137.288224 -269.764725) (xy 137.332756 -269.742035) (xy 137.380288 -269.726591)
			(xy 137.429651 -269.718772) (xy 137.479629 -269.718772) (xy 137.528992 -269.726591) (xy 137.576524 -269.742035)
			(xy 137.621056 -269.764725) (xy 137.661489 -269.794101) (xy 137.696829 -269.829441) (xy 137.726205 -269.869874)
			(xy 137.748895 -269.914406) (xy 137.764339 -269.961938) (xy 137.772158 -270.011301) (xy 137.772648 -270.03629)
			(xy 138.078459 -270.03629) (xy 138.082554 -269.985562) (xy 138.094733 -269.936148) (xy 138.114681 -269.889328)
			(xy 138.141882 -269.846314) (xy 138.17563 -269.80822) (xy 138.215052 -269.776033) (xy 138.259126 -269.750587)
			(xy 138.306712 -269.73254) (xy 138.356576 -269.72236) (xy 138.407428 -269.720311) (xy 138.457949 -269.726445)
			(xy 138.506833 -269.740605) (xy 138.552812 -269.762422) (xy 138.594696 -269.791332) (xy 138.6314 -269.826587)
			(xy 138.661973 -269.867273) (xy 138.685624 -269.912336) (xy 138.70174 -269.96061) (xy 138.709904 -270.010844)
			(xy 138.710416 -270.03629) (xy 139.018513 -270.03629) (xy 139.022608 -269.985562) (xy 139.034787 -269.936148)
			(xy 139.054735 -269.889328) (xy 139.081936 -269.846314) (xy 139.115684 -269.80822) (xy 139.155106 -269.776033)
			(xy 139.19918 -269.750587) (xy 139.246766 -269.73254) (xy 139.29663 -269.72236) (xy 139.347482 -269.720311)
			(xy 139.398003 -269.726445) (xy 139.446887 -269.740605) (xy 139.492866 -269.762422) (xy 139.53475 -269.791332)
			(xy 139.571454 -269.826587) (xy 139.602027 -269.867273) (xy 139.625678 -269.912336) (xy 139.641794 -269.96061)
			(xy 139.649958 -270.010844) (xy 139.65047 -270.03629) (xy 139.649967 -270.061279) (xy 139.957284 -270.061279)
			(xy 139.957284 -270.011301) (xy 139.965103 -269.961938) (xy 139.980547 -269.914406) (xy 140.003237 -269.869874)
			(xy 140.032613 -269.829441) (xy 140.067953 -269.794101) (xy 140.108386 -269.764725) (xy 140.152918 -269.742035)
			(xy 140.20045 -269.726591) (xy 140.249813 -269.718772) (xy 140.299791 -269.718772) (xy 140.349154 -269.726591)
			(xy 140.396686 -269.742035) (xy 140.441218 -269.764725) (xy 140.481651 -269.794101) (xy 140.516991 -269.829441)
			(xy 140.546367 -269.869874) (xy 140.569057 -269.914406) (xy 140.584501 -269.961938) (xy 140.59232 -270.011301)
			(xy 140.59281 -270.03629) (xy 140.898621 -270.03629) (xy 140.902716 -269.985562) (xy 140.914895 -269.936148)
			(xy 140.934843 -269.889328) (xy 140.962044 -269.846314) (xy 140.995792 -269.80822) (xy 141.035214 -269.776033)
			(xy 141.079288 -269.750587) (xy 141.126874 -269.73254) (xy 141.176738 -269.72236) (xy 141.22759 -269.720311)
			(xy 141.278111 -269.726445) (xy 141.326995 -269.740605) (xy 141.372974 -269.762422) (xy 141.414858 -269.791332)
			(xy 141.451562 -269.826587) (xy 141.482135 -269.867273) (xy 141.505786 -269.912336) (xy 141.521902 -269.96061)
			(xy 141.530066 -270.010844) (xy 141.530578 -270.03629) (xy 141.530075 -270.061279) (xy 141.837138 -270.061279)
			(xy 141.837138 -270.011301) (xy 141.844957 -269.961938) (xy 141.860401 -269.914406) (xy 141.883091 -269.869874)
			(xy 141.912467 -269.829441) (xy 141.947807 -269.794101) (xy 141.98824 -269.764725) (xy 142.032772 -269.742035)
			(xy 142.080304 -269.726591) (xy 142.129667 -269.718772) (xy 142.179645 -269.718772) (xy 142.229008 -269.726591)
			(xy 142.27654 -269.742035) (xy 142.321072 -269.764725) (xy 142.361505 -269.794101) (xy 142.396845 -269.829441)
			(xy 142.426221 -269.869874) (xy 142.448911 -269.914406) (xy 142.464355 -269.961938) (xy 142.472174 -270.011301)
			(xy 142.472664 -270.03629) (xy 142.778475 -270.03629) (xy 142.78257 -269.985562) (xy 142.794749 -269.936148)
			(xy 142.814697 -269.889328) (xy 142.841898 -269.846314) (xy 142.875646 -269.80822) (xy 142.915068 -269.776033)
			(xy 142.959142 -269.750587) (xy 143.006728 -269.73254) (xy 143.056592 -269.72236) (xy 143.107444 -269.720311)
			(xy 143.157965 -269.726445) (xy 143.206849 -269.740605) (xy 143.252828 -269.762422) (xy 143.294712 -269.791332)
			(xy 143.331416 -269.826587) (xy 143.361989 -269.867273) (xy 143.38564 -269.912336) (xy 143.401756 -269.96061)
			(xy 143.40992 -270.010844) (xy 143.410432 -270.03629) (xy 143.409929 -270.061279) (xy 143.717246 -270.061279)
			(xy 143.717246 -270.011301) (xy 143.725065 -269.961938) (xy 143.740509 -269.914406) (xy 143.763199 -269.869874)
			(xy 143.792575 -269.829441) (xy 143.827915 -269.794101) (xy 143.868348 -269.764725) (xy 143.91288 -269.742035)
			(xy 143.960412 -269.726591) (xy 144.009775 -269.718772) (xy 144.059753 -269.718772) (xy 144.109116 -269.726591)
			(xy 144.156648 -269.742035) (xy 144.20118 -269.764725) (xy 144.241613 -269.794101) (xy 144.276953 -269.829441)
			(xy 144.306329 -269.869874) (xy 144.329019 -269.914406) (xy 144.344463 -269.961938) (xy 144.352282 -270.011301)
			(xy 144.352772 -270.03629) (xy 144.352282 -270.061279) (xy 144.344463 -270.110642) (xy 144.329019 -270.158174)
			(xy 144.306329 -270.202706) (xy 144.276953 -270.243139) (xy 144.241613 -270.278479) (xy 144.20118 -270.307855)
			(xy 144.156648 -270.330545) (xy 144.109116 -270.345989) (xy 144.059753 -270.353808) (xy 144.009775 -270.353808)
			(xy 143.960412 -270.345989) (xy 143.91288 -270.330545) (xy 143.868348 -270.307855) (xy 143.827915 -270.278479)
			(xy 143.792575 -270.243139) (xy 143.763199 -270.202706) (xy 143.740509 -270.158174) (xy 143.725065 -270.110642)
			(xy 143.717246 -270.061279) (xy 143.409929 -270.061279) (xy 143.40992 -270.061736) (xy 143.401756 -270.11197)
			(xy 143.38564 -270.160244) (xy 143.361989 -270.205307) (xy 143.331416 -270.245993) (xy 143.294712 -270.281248)
			(xy 143.252828 -270.310158) (xy 143.206849 -270.331975) (xy 143.157965 -270.346135) (xy 143.107444 -270.352269)
			(xy 143.056592 -270.35022) (xy 143.006728 -270.34004) (xy 142.959142 -270.321993) (xy 142.915068 -270.296547)
			(xy 142.875646 -270.26436) (xy 142.841898 -270.226266) (xy 142.814697 -270.183252) (xy 142.794749 -270.136432)
			(xy 142.78257 -270.087018) (xy 142.778475 -270.03629) (xy 142.472664 -270.03629) (xy 142.472174 -270.061279)
			(xy 142.464355 -270.110642) (xy 142.448911 -270.158174) (xy 142.426221 -270.202706) (xy 142.396845 -270.243139)
			(xy 142.361505 -270.278479) (xy 142.321072 -270.307855) (xy 142.27654 -270.330545) (xy 142.229008 -270.345989)
			(xy 142.179645 -270.353808) (xy 142.129667 -270.353808) (xy 142.080304 -270.345989) (xy 142.032772 -270.330545)
			(xy 141.98824 -270.307855) (xy 141.947807 -270.278479) (xy 141.912467 -270.243139) (xy 141.883091 -270.202706)
			(xy 141.860401 -270.158174) (xy 141.844957 -270.110642) (xy 141.837138 -270.061279) (xy 141.530075 -270.061279)
			(xy 141.530066 -270.061736) (xy 141.521902 -270.11197) (xy 141.505786 -270.160244) (xy 141.482135 -270.205307)
			(xy 141.451562 -270.245993) (xy 141.414858 -270.281248) (xy 141.372974 -270.310158) (xy 141.326995 -270.331975)
			(xy 141.278111 -270.346135) (xy 141.22759 -270.352269) (xy 141.176738 -270.35022) (xy 141.126874 -270.34004)
			(xy 141.079288 -270.321993) (xy 141.035214 -270.296547) (xy 140.995792 -270.26436) (xy 140.962044 -270.226266)
			(xy 140.934843 -270.183252) (xy 140.914895 -270.136432) (xy 140.902716 -270.087018) (xy 140.898621 -270.03629)
			(xy 140.59281 -270.03629) (xy 140.59232 -270.061279) (xy 140.584501 -270.110642) (xy 140.569057 -270.158174)
			(xy 140.546367 -270.202706) (xy 140.516991 -270.243139) (xy 140.481651 -270.278479) (xy 140.441218 -270.307855)
			(xy 140.396686 -270.330545) (xy 140.349154 -270.345989) (xy 140.299791 -270.353808) (xy 140.249813 -270.353808)
			(xy 140.20045 -270.345989) (xy 140.152918 -270.330545) (xy 140.108386 -270.307855) (xy 140.067953 -270.278479)
			(xy 140.032613 -270.243139) (xy 140.003237 -270.202706) (xy 139.980547 -270.158174) (xy 139.965103 -270.110642)
			(xy 139.957284 -270.061279) (xy 139.649967 -270.061279) (xy 139.649958 -270.061736) (xy 139.641794 -270.11197)
			(xy 139.625678 -270.160244) (xy 139.602027 -270.205307) (xy 139.571454 -270.245993) (xy 139.53475 -270.281248)
			(xy 139.492866 -270.310158) (xy 139.446887 -270.331975) (xy 139.398003 -270.346135) (xy 139.347482 -270.352269)
			(xy 139.29663 -270.35022) (xy 139.246766 -270.34004) (xy 139.19918 -270.321993) (xy 139.155106 -270.296547)
			(xy 139.115684 -270.26436) (xy 139.081936 -270.226266) (xy 139.054735 -270.183252) (xy 139.034787 -270.136432)
			(xy 139.022608 -270.087018) (xy 139.018513 -270.03629) (xy 138.710416 -270.03629) (xy 138.709904 -270.061736)
			(xy 138.70174 -270.11197) (xy 138.685624 -270.160244) (xy 138.661973 -270.205307) (xy 138.6314 -270.245993)
			(xy 138.594696 -270.281248) (xy 138.552812 -270.310158) (xy 138.506833 -270.331975) (xy 138.457949 -270.346135)
			(xy 138.407428 -270.352269) (xy 138.356576 -270.35022) (xy 138.306712 -270.34004) (xy 138.259126 -270.321993)
			(xy 138.215052 -270.296547) (xy 138.17563 -270.26436) (xy 138.141882 -270.226266) (xy 138.114681 -270.183252)
			(xy 138.094733 -270.136432) (xy 138.082554 -270.087018) (xy 138.078459 -270.03629) (xy 137.772648 -270.03629)
			(xy 137.772158 -270.061279) (xy 137.764339 -270.110642) (xy 137.748895 -270.158174) (xy 137.726205 -270.202706)
			(xy 137.696829 -270.243139) (xy 137.661489 -270.278479) (xy 137.621056 -270.307855) (xy 137.576524 -270.330545)
			(xy 137.528992 -270.345989) (xy 137.479629 -270.353808) (xy 137.429651 -270.353808) (xy 137.380288 -270.345989)
			(xy 137.332756 -270.330545) (xy 137.288224 -270.307855) (xy 137.247791 -270.278479) (xy 137.212451 -270.243139)
			(xy 137.183075 -270.202706) (xy 137.160385 -270.158174) (xy 137.144941 -270.110642) (xy 137.137122 -270.061279)
			(xy 136.830059 -270.061279) (xy 136.83005 -270.061736) (xy 136.821886 -270.11197) (xy 136.80577 -270.160244)
			(xy 136.782119 -270.205307) (xy 136.751546 -270.245993) (xy 136.714842 -270.281248) (xy 136.672958 -270.310158)
			(xy 136.626979 -270.331975) (xy 136.578095 -270.346135) (xy 136.527574 -270.352269) (xy 136.476722 -270.35022)
			(xy 136.426858 -270.34004) (xy 136.379272 -270.321993) (xy 136.335198 -270.296547) (xy 136.295776 -270.26436)
			(xy 136.262028 -270.226266) (xy 136.234827 -270.183252) (xy 136.214879 -270.136432) (xy 136.2027 -270.087018)
			(xy 136.198605 -270.03629) (xy 135.892794 -270.03629) (xy 135.892304 -270.061279) (xy 135.884485 -270.110642)
			(xy 135.869041 -270.158174) (xy 135.846351 -270.202706) (xy 135.816975 -270.243139) (xy 135.781635 -270.278479)
			(xy 135.741202 -270.307855) (xy 135.69667 -270.330545) (xy 135.649138 -270.345989) (xy 135.599775 -270.353808)
			(xy 135.549797 -270.353808) (xy 135.500434 -270.345989) (xy 135.452902 -270.330545) (xy 135.40837 -270.307855)
			(xy 135.367937 -270.278479) (xy 135.332597 -270.243139) (xy 135.303221 -270.202706) (xy 135.280531 -270.158174)
			(xy 135.265087 -270.110642) (xy 135.257268 -270.061279) (xy 134.949951 -270.061279) (xy 134.949942 -270.061736)
			(xy 134.941778 -270.11197) (xy 134.925662 -270.160244) (xy 134.902011 -270.205307) (xy 134.871438 -270.245993)
			(xy 134.834734 -270.281248) (xy 134.79285 -270.310158) (xy 134.746871 -270.331975) (xy 134.697987 -270.346135)
			(xy 134.647466 -270.352269) (xy 134.596614 -270.35022) (xy 134.54675 -270.34004) (xy 134.499164 -270.321993)
			(xy 134.45509 -270.296547) (xy 134.415668 -270.26436) (xy 134.38192 -270.226266) (xy 134.354719 -270.183252)
			(xy 134.334771 -270.136432) (xy 134.322592 -270.087018) (xy 134.318497 -270.03629) (xy 134.012686 -270.03629)
			(xy 134.012196 -270.061279) (xy 134.004377 -270.110642) (xy 133.988933 -270.158174) (xy 133.966243 -270.202706)
			(xy 133.936867 -270.243139) (xy 133.901527 -270.278479) (xy 133.861094 -270.307855) (xy 133.816562 -270.330545)
			(xy 133.76903 -270.345989) (xy 133.719667 -270.353808) (xy 133.669689 -270.353808) (xy 133.620326 -270.345989)
			(xy 133.572794 -270.330545) (xy 133.528262 -270.307855) (xy 133.487829 -270.278479) (xy 133.452489 -270.243139)
			(xy 133.423113 -270.202706) (xy 133.400423 -270.158174) (xy 133.384979 -270.110642) (xy 133.37716 -270.061279)
			(xy 133.070097 -270.061279) (xy 133.070088 -270.061736) (xy 133.061924 -270.11197) (xy 133.045808 -270.160244)
			(xy 133.022157 -270.205307) (xy 132.991584 -270.245993) (xy 132.95488 -270.281248) (xy 132.912996 -270.310158)
			(xy 132.867017 -270.331975) (xy 132.818133 -270.346135) (xy 132.767612 -270.352269) (xy 132.71676 -270.35022)
			(xy 132.666896 -270.34004) (xy 132.61931 -270.321993) (xy 132.575236 -270.296547) (xy 132.535814 -270.26436)
			(xy 132.502066 -270.226266) (xy 132.474865 -270.183252) (xy 132.454917 -270.136432) (xy 132.442738 -270.087018)
			(xy 132.438643 -270.03629) (xy 132.130546 -270.03629) (xy 132.130034 -270.061736) (xy 132.12187 -270.11197)
			(xy 132.105754 -270.160244) (xy 132.082103 -270.205307) (xy 132.05153 -270.245993) (xy 132.014826 -270.281248)
			(xy 131.972942 -270.310158) (xy 131.926963 -270.331975) (xy 131.878079 -270.346135) (xy 131.827558 -270.352269)
			(xy 131.776706 -270.35022) (xy 131.726842 -270.34004) (xy 131.679256 -270.321993) (xy 131.635182 -270.296547)
			(xy 131.59576 -270.26436) (xy 131.562012 -270.226266) (xy 131.534811 -270.183252) (xy 131.514863 -270.136432)
			(xy 131.502684 -270.087018) (xy 131.498589 -270.03629) (xy 131.192778 -270.03629) (xy 131.192288 -270.061279)
			(xy 131.184469 -270.110642) (xy 131.169025 -270.158174) (xy 131.146335 -270.202706) (xy 131.116959 -270.243139)
			(xy 131.081619 -270.278479) (xy 131.041186 -270.307855) (xy 130.996654 -270.330545) (xy 130.949122 -270.345989)
			(xy 130.899759 -270.353808) (xy 130.849781 -270.353808) (xy 130.800418 -270.345989) (xy 130.752886 -270.330545)
			(xy 130.708354 -270.307855) (xy 130.667921 -270.278479) (xy 130.632581 -270.243139) (xy 130.603205 -270.202706)
			(xy 130.580515 -270.158174) (xy 130.565071 -270.110642) (xy 130.557252 -270.061279) (xy 130.249935 -270.061279)
			(xy 130.249926 -270.061736) (xy 130.241762 -270.11197) (xy 130.225646 -270.160244) (xy 130.201995 -270.205307)
			(xy 130.171422 -270.245993) (xy 130.134718 -270.281248) (xy 130.092834 -270.310158) (xy 130.046855 -270.331975)
			(xy 129.997971 -270.346135) (xy 129.94745 -270.352269) (xy 129.896598 -270.35022) (xy 129.846734 -270.34004)
			(xy 129.799148 -270.321993) (xy 129.755074 -270.296547) (xy 129.715652 -270.26436) (xy 129.681904 -270.226266)
			(xy 129.654703 -270.183252) (xy 129.634755 -270.136432) (xy 129.622576 -270.087018) (xy 129.618481 -270.03629)
			(xy 129.31267 -270.03629) (xy 129.31218 -270.061279) (xy 129.304361 -270.110642) (xy 129.288917 -270.158174)
			(xy 129.266227 -270.202706) (xy 129.236851 -270.243139) (xy 129.201511 -270.278479) (xy 129.161078 -270.307855)
			(xy 129.116546 -270.330545) (xy 129.069014 -270.345989) (xy 129.019651 -270.353808) (xy 128.969673 -270.353808)
			(xy 128.92031 -270.345989) (xy 128.872778 -270.330545) (xy 128.828246 -270.307855) (xy 128.787813 -270.278479)
			(xy 128.752473 -270.243139) (xy 128.723097 -270.202706) (xy 128.700407 -270.158174) (xy 128.684963 -270.110642)
			(xy 128.677144 -270.061279) (xy 128.370081 -270.061279) (xy 128.370072 -270.061736) (xy 128.361908 -270.11197)
			(xy 128.345792 -270.160244) (xy 128.322141 -270.205307) (xy 128.291568 -270.245993) (xy 128.254864 -270.281248)
			(xy 128.21298 -270.310158) (xy 128.167001 -270.331975) (xy 128.118117 -270.346135) (xy 128.067596 -270.352269)
			(xy 128.016744 -270.35022) (xy 127.96688 -270.34004) (xy 127.919294 -270.321993) (xy 127.87522 -270.296547)
			(xy 127.835798 -270.26436) (xy 127.80205 -270.226266) (xy 127.774849 -270.183252) (xy 127.754901 -270.136432)
			(xy 127.742722 -270.087018) (xy 127.738627 -270.03629) (xy 127.433578 -270.03629) (xy 127.433053 -270.062351)
			(xy 127.424564 -270.113776) (xy 127.407828 -270.163138) (xy 127.383289 -270.209122) (xy 127.351601 -270.250504)
			(xy 127.313606 -270.286185) (xy 127.270317 -270.315213) (xy 127.222883 -270.336817) (xy 127.197866 -270.344138)
			(xy 127.189036 -270.348496) (xy 127.175295 -270.362576) (xy 127.167845 -270.380785) (xy 127.167386 -270.39062)
			(xy 127.167386 -270.846296) (xy 128.208527 -270.846296) (xy 128.212622 -270.795568) (xy 128.224801 -270.746154)
			(xy 128.244749 -270.699334) (xy 128.27195 -270.65632) (xy 128.305698 -270.618226) (xy 128.34512 -270.586039)
			(xy 128.389194 -270.560593) (xy 128.43678 -270.542546) (xy 128.486644 -270.532366) (xy 128.537496 -270.530317)
			(xy 128.588017 -270.536451) (xy 128.636901 -270.550611) (xy 128.68288 -270.572428) (xy 128.724764 -270.601338)
			(xy 128.761468 -270.636593) (xy 128.792041 -270.677279) (xy 128.815692 -270.722342) (xy 128.831808 -270.770616)
			(xy 128.839972 -270.82085) (xy 128.840484 -270.846296) (xy 129.148581 -270.846296) (xy 129.152676 -270.795568)
			(xy 129.164855 -270.746154) (xy 129.184803 -270.699334) (xy 129.212004 -270.65632) (xy 129.245752 -270.618226)
			(xy 129.285174 -270.586039) (xy 129.329248 -270.560593) (xy 129.376834 -270.542546) (xy 129.426698 -270.532366)
			(xy 129.47755 -270.530317) (xy 129.528071 -270.536451) (xy 129.576955 -270.550611) (xy 129.622934 -270.572428)
			(xy 129.664818 -270.601338) (xy 129.701522 -270.636593) (xy 129.732095 -270.677279) (xy 129.755746 -270.722342)
			(xy 129.771862 -270.770616) (xy 129.780026 -270.82085) (xy 129.780538 -270.846296) (xy 131.028435 -270.846296)
			(xy 131.03253 -270.795568) (xy 131.044709 -270.746154) (xy 131.064657 -270.699334) (xy 131.091858 -270.65632)
			(xy 131.125606 -270.618226) (xy 131.165028 -270.586039) (xy 131.209102 -270.560593) (xy 131.256688 -270.542546)
			(xy 131.306552 -270.532366) (xy 131.357404 -270.530317) (xy 131.407925 -270.536451) (xy 131.456809 -270.550611)
			(xy 131.502788 -270.572428) (xy 131.544672 -270.601338) (xy 131.581376 -270.636593) (xy 131.611949 -270.677279)
			(xy 131.6356 -270.722342) (xy 131.651716 -270.770616) (xy 131.65988 -270.82085) (xy 131.660392 -270.846296)
			(xy 131.659889 -270.871285) (xy 131.967206 -270.871285) (xy 131.967206 -270.821307) (xy 131.975025 -270.771944)
			(xy 131.990469 -270.724412) (xy 132.013159 -270.67988) (xy 132.042535 -270.639447) (xy 132.077875 -270.604107)
			(xy 132.118308 -270.574731) (xy 132.16284 -270.552041) (xy 132.210372 -270.536597) (xy 132.259735 -270.528778)
			(xy 132.309713 -270.528778) (xy 132.359076 -270.536597) (xy 132.406608 -270.552041) (xy 132.45114 -270.574731)
			(xy 132.491573 -270.604107) (xy 132.526913 -270.639447) (xy 132.556289 -270.67988) (xy 132.578979 -270.724412)
			(xy 132.594423 -270.771944) (xy 132.602242 -270.821307) (xy 132.602732 -270.846296) (xy 132.908543 -270.846296)
			(xy 132.912638 -270.795568) (xy 132.924817 -270.746154) (xy 132.944765 -270.699334) (xy 132.971966 -270.65632)
			(xy 133.005714 -270.618226) (xy 133.045136 -270.586039) (xy 133.08921 -270.560593) (xy 133.136796 -270.542546)
			(xy 133.18666 -270.532366) (xy 133.237512 -270.530317) (xy 133.288033 -270.536451) (xy 133.336917 -270.550611)
			(xy 133.382896 -270.572428) (xy 133.42478 -270.601338) (xy 133.461484 -270.636593) (xy 133.492057 -270.677279)
			(xy 133.515708 -270.722342) (xy 133.531824 -270.770616) (xy 133.539988 -270.82085) (xy 133.5405 -270.846296)
			(xy 133.539997 -270.871285) (xy 133.847314 -270.871285) (xy 133.847314 -270.821307) (xy 133.855133 -270.771944)
			(xy 133.870577 -270.724412) (xy 133.893267 -270.67988) (xy 133.922643 -270.639447) (xy 133.957983 -270.604107)
			(xy 133.998416 -270.574731) (xy 134.042948 -270.552041) (xy 134.09048 -270.536597) (xy 134.139843 -270.528778)
			(xy 134.189821 -270.528778) (xy 134.239184 -270.536597) (xy 134.286716 -270.552041) (xy 134.331248 -270.574731)
			(xy 134.371681 -270.604107) (xy 134.407021 -270.639447) (xy 134.436397 -270.67988) (xy 134.459087 -270.724412)
			(xy 134.474531 -270.771944) (xy 134.48235 -270.821307) (xy 134.48284 -270.846296) (xy 134.788397 -270.846296)
			(xy 134.792492 -270.795568) (xy 134.804671 -270.746154) (xy 134.824619 -270.699334) (xy 134.85182 -270.65632)
			(xy 134.885568 -270.618226) (xy 134.92499 -270.586039) (xy 134.969064 -270.560593) (xy 135.01665 -270.542546)
			(xy 135.066514 -270.532366) (xy 135.117366 -270.530317) (xy 135.167887 -270.536451) (xy 135.216771 -270.550611)
			(xy 135.26275 -270.572428) (xy 135.304634 -270.601338) (xy 135.341338 -270.636593) (xy 135.371911 -270.677279)
			(xy 135.395562 -270.722342) (xy 135.411678 -270.770616) (xy 135.419842 -270.82085) (xy 135.420354 -270.846296)
			(xy 135.728451 -270.846296) (xy 135.732546 -270.795568) (xy 135.744725 -270.746154) (xy 135.764673 -270.699334)
			(xy 135.791874 -270.65632) (xy 135.825622 -270.618226) (xy 135.865044 -270.586039) (xy 135.909118 -270.560593)
			(xy 135.956704 -270.542546) (xy 136.006568 -270.532366) (xy 136.05742 -270.530317) (xy 136.107941 -270.536451)
			(xy 136.156825 -270.550611) (xy 136.202804 -270.572428) (xy 136.244688 -270.601338) (xy 136.281392 -270.636593)
			(xy 136.311965 -270.677279) (xy 136.335616 -270.722342) (xy 136.351732 -270.770616) (xy 136.359896 -270.82085)
			(xy 136.360408 -270.846296) (xy 137.608559 -270.846296) (xy 137.612654 -270.795568) (xy 137.624833 -270.746154)
			(xy 137.644781 -270.699334) (xy 137.671982 -270.65632) (xy 137.70573 -270.618226) (xy 137.745152 -270.586039)
			(xy 137.789226 -270.560593) (xy 137.836812 -270.542546) (xy 137.886676 -270.532366) (xy 137.937528 -270.530317)
			(xy 137.988049 -270.536451) (xy 138.036933 -270.550611) (xy 138.082912 -270.572428) (xy 138.124796 -270.601338)
			(xy 138.1615 -270.636593) (xy 138.192073 -270.677279) (xy 138.215724 -270.722342) (xy 138.23184 -270.770616)
			(xy 138.240004 -270.82085) (xy 138.240516 -270.846296) (xy 138.240013 -270.871285) (xy 138.54733 -270.871285)
			(xy 138.54733 -270.821307) (xy 138.555149 -270.771944) (xy 138.570593 -270.724412) (xy 138.593283 -270.67988)
			(xy 138.622659 -270.639447) (xy 138.657999 -270.604107) (xy 138.698432 -270.574731) (xy 138.742964 -270.552041)
			(xy 138.790496 -270.536597) (xy 138.839859 -270.528778) (xy 138.889837 -270.528778) (xy 138.9392 -270.536597)
			(xy 138.986732 -270.552041) (xy 139.031264 -270.574731) (xy 139.071697 -270.604107) (xy 139.107037 -270.639447)
			(xy 139.136413 -270.67988) (xy 139.159103 -270.724412) (xy 139.174547 -270.771944) (xy 139.182366 -270.821307)
			(xy 139.182856 -270.846296) (xy 139.488413 -270.846296) (xy 139.492508 -270.795568) (xy 139.504687 -270.746154)
			(xy 139.524635 -270.699334) (xy 139.551836 -270.65632) (xy 139.585584 -270.618226) (xy 139.625006 -270.586039)
			(xy 139.66908 -270.560593) (xy 139.716666 -270.542546) (xy 139.76653 -270.532366) (xy 139.817382 -270.530317)
			(xy 139.867903 -270.536451) (xy 139.916787 -270.550611) (xy 139.962766 -270.572428) (xy 140.00465 -270.601338)
			(xy 140.041354 -270.636593) (xy 140.071927 -270.677279) (xy 140.095578 -270.722342) (xy 140.111694 -270.770616)
			(xy 140.119858 -270.82085) (xy 140.12037 -270.846296) (xy 140.119867 -270.871285) (xy 140.427184 -270.871285)
			(xy 140.427184 -270.821307) (xy 140.435003 -270.771944) (xy 140.450447 -270.724412) (xy 140.473137 -270.67988)
			(xy 140.502513 -270.639447) (xy 140.537853 -270.604107) (xy 140.578286 -270.574731) (xy 140.622818 -270.552041)
			(xy 140.67035 -270.536597) (xy 140.719713 -270.528778) (xy 140.769691 -270.528778) (xy 140.819054 -270.536597)
			(xy 140.866586 -270.552041) (xy 140.911118 -270.574731) (xy 140.951551 -270.604107) (xy 140.986891 -270.639447)
			(xy 141.016267 -270.67988) (xy 141.038957 -270.724412) (xy 141.054401 -270.771944) (xy 141.06222 -270.821307)
			(xy 141.06271 -270.846296) (xy 141.368521 -270.846296) (xy 141.372616 -270.795568) (xy 141.384795 -270.746154)
			(xy 141.404743 -270.699334) (xy 141.431944 -270.65632) (xy 141.465692 -270.618226) (xy 141.505114 -270.586039)
			(xy 141.549188 -270.560593) (xy 141.596774 -270.542546) (xy 141.646638 -270.532366) (xy 141.69749 -270.530317)
			(xy 141.748011 -270.536451) (xy 141.796895 -270.550611) (xy 141.842874 -270.572428) (xy 141.884758 -270.601338)
			(xy 141.921462 -270.636593) (xy 141.952035 -270.677279) (xy 141.975686 -270.722342) (xy 141.991802 -270.770616)
			(xy 141.999966 -270.82085) (xy 142.000478 -270.846296) (xy 142.308575 -270.846296) (xy 142.31267 -270.795568)
			(xy 142.324849 -270.746154) (xy 142.344797 -270.699334) (xy 142.371998 -270.65632) (xy 142.405746 -270.618226)
			(xy 142.445168 -270.586039) (xy 142.489242 -270.560593) (xy 142.536828 -270.542546) (xy 142.586692 -270.532366)
			(xy 142.637544 -270.530317) (xy 142.688065 -270.536451) (xy 142.736949 -270.550611) (xy 142.782928 -270.572428)
			(xy 142.824812 -270.601338) (xy 142.861516 -270.636593) (xy 142.892089 -270.677279) (xy 142.91574 -270.722342)
			(xy 142.931856 -270.770616) (xy 142.94002 -270.82085) (xy 142.940532 -270.846296) (xy 142.94002 -270.871742)
			(xy 142.931856 -270.921976) (xy 142.91574 -270.97025) (xy 142.892089 -271.015313) (xy 142.861516 -271.055999)
			(xy 142.824812 -271.091254) (xy 142.782928 -271.120164) (xy 142.736949 -271.141981) (xy 142.688065 -271.156141)
			(xy 142.637544 -271.162275) (xy 142.586692 -271.160226) (xy 142.536828 -271.150046) (xy 142.489242 -271.131999)
			(xy 142.445168 -271.106553) (xy 142.405746 -271.074366) (xy 142.371998 -271.036272) (xy 142.344797 -270.993258)
			(xy 142.324849 -270.946438) (xy 142.31267 -270.897024) (xy 142.308575 -270.846296) (xy 142.000478 -270.846296)
			(xy 141.999966 -270.871742) (xy 141.991802 -270.921976) (xy 141.975686 -270.97025) (xy 141.952035 -271.015313)
			(xy 141.921462 -271.055999) (xy 141.884758 -271.091254) (xy 141.842874 -271.120164) (xy 141.796895 -271.141981)
			(xy 141.748011 -271.156141) (xy 141.69749 -271.162275) (xy 141.646638 -271.160226) (xy 141.596774 -271.150046)
			(xy 141.549188 -271.131999) (xy 141.505114 -271.106553) (xy 141.465692 -271.074366) (xy 141.431944 -271.036272)
			(xy 141.404743 -270.993258) (xy 141.384795 -270.946438) (xy 141.372616 -270.897024) (xy 141.368521 -270.846296)
			(xy 141.06271 -270.846296) (xy 141.06222 -270.871285) (xy 141.054401 -270.920648) (xy 141.038957 -270.96818)
			(xy 141.016267 -271.012712) (xy 140.986891 -271.053145) (xy 140.951551 -271.088485) (xy 140.911118 -271.117861)
			(xy 140.866586 -271.140551) (xy 140.819054 -271.155995) (xy 140.769691 -271.163814) (xy 140.719713 -271.163814)
			(xy 140.67035 -271.155995) (xy 140.622818 -271.140551) (xy 140.578286 -271.117861) (xy 140.537853 -271.088485)
			(xy 140.502513 -271.053145) (xy 140.473137 -271.012712) (xy 140.450447 -270.96818) (xy 140.435003 -270.920648)
			(xy 140.427184 -270.871285) (xy 140.119867 -270.871285) (xy 140.119858 -270.871742) (xy 140.111694 -270.921976)
			(xy 140.095578 -270.97025) (xy 140.071927 -271.015313) (xy 140.041354 -271.055999) (xy 140.00465 -271.091254)
			(xy 139.962766 -271.120164) (xy 139.916787 -271.141981) (xy 139.867903 -271.156141) (xy 139.817382 -271.162275)
			(xy 139.76653 -271.160226) (xy 139.716666 -271.150046) (xy 139.66908 -271.131999) (xy 139.625006 -271.106553)
			(xy 139.585584 -271.074366) (xy 139.551836 -271.036272) (xy 139.524635 -270.993258) (xy 139.504687 -270.946438)
			(xy 139.492508 -270.897024) (xy 139.488413 -270.846296) (xy 139.182856 -270.846296) (xy 139.182366 -270.871285)
			(xy 139.174547 -270.920648) (xy 139.159103 -270.96818) (xy 139.136413 -271.012712) (xy 139.107037 -271.053145)
			(xy 139.071697 -271.088485) (xy 139.031264 -271.117861) (xy 138.986732 -271.140551) (xy 138.9392 -271.155995)
			(xy 138.889837 -271.163814) (xy 138.839859 -271.163814) (xy 138.790496 -271.155995) (xy 138.742964 -271.140551)
			(xy 138.698432 -271.117861) (xy 138.657999 -271.088485) (xy 138.622659 -271.053145) (xy 138.593283 -271.012712)
			(xy 138.570593 -270.96818) (xy 138.555149 -270.920648) (xy 138.54733 -270.871285) (xy 138.240013 -270.871285)
			(xy 138.240004 -270.871742) (xy 138.23184 -270.921976) (xy 138.215724 -270.97025) (xy 138.192073 -271.015313)
			(xy 138.1615 -271.055999) (xy 138.124796 -271.091254) (xy 138.082912 -271.120164) (xy 138.036933 -271.141981)
			(xy 137.988049 -271.156141) (xy 137.937528 -271.162275) (xy 137.886676 -271.160226) (xy 137.836812 -271.150046)
			(xy 137.789226 -271.131999) (xy 137.745152 -271.106553) (xy 137.70573 -271.074366) (xy 137.671982 -271.036272)
			(xy 137.644781 -270.993258) (xy 137.624833 -270.946438) (xy 137.612654 -270.897024) (xy 137.608559 -270.846296)
			(xy 136.360408 -270.846296) (xy 136.359896 -270.871742) (xy 136.351732 -270.921976) (xy 136.335616 -270.97025)
			(xy 136.311965 -271.015313) (xy 136.281392 -271.055999) (xy 136.244688 -271.091254) (xy 136.202804 -271.120164)
			(xy 136.156825 -271.141981) (xy 136.107941 -271.156141) (xy 136.05742 -271.162275) (xy 136.006568 -271.160226)
			(xy 135.956704 -271.150046) (xy 135.909118 -271.131999) (xy 135.865044 -271.106553) (xy 135.825622 -271.074366)
			(xy 135.791874 -271.036272) (xy 135.764673 -270.993258) (xy 135.744725 -270.946438) (xy 135.732546 -270.897024)
			(xy 135.728451 -270.846296) (xy 135.420354 -270.846296) (xy 135.419842 -270.871742) (xy 135.411678 -270.921976)
			(xy 135.395562 -270.97025) (xy 135.371911 -271.015313) (xy 135.341338 -271.055999) (xy 135.304634 -271.091254)
			(xy 135.26275 -271.120164) (xy 135.216771 -271.141981) (xy 135.167887 -271.156141) (xy 135.117366 -271.162275)
			(xy 135.066514 -271.160226) (xy 135.01665 -271.150046) (xy 134.969064 -271.131999) (xy 134.92499 -271.106553)
			(xy 134.885568 -271.074366) (xy 134.85182 -271.036272) (xy 134.824619 -270.993258) (xy 134.804671 -270.946438)
			(xy 134.792492 -270.897024) (xy 134.788397 -270.846296) (xy 134.48284 -270.846296) (xy 134.48235 -270.871285)
			(xy 134.474531 -270.920648) (xy 134.459087 -270.96818) (xy 134.436397 -271.012712) (xy 134.407021 -271.053145)
			(xy 134.371681 -271.088485) (xy 134.331248 -271.117861) (xy 134.286716 -271.140551) (xy 134.239184 -271.155995)
			(xy 134.189821 -271.163814) (xy 134.139843 -271.163814) (xy 134.09048 -271.155995) (xy 134.042948 -271.140551)
			(xy 133.998416 -271.117861) (xy 133.957983 -271.088485) (xy 133.922643 -271.053145) (xy 133.893267 -271.012712)
			(xy 133.870577 -270.96818) (xy 133.855133 -270.920648) (xy 133.847314 -270.871285) (xy 133.539997 -270.871285)
			(xy 133.539988 -270.871742) (xy 133.531824 -270.921976) (xy 133.515708 -270.97025) (xy 133.492057 -271.015313)
			(xy 133.461484 -271.055999) (xy 133.42478 -271.091254) (xy 133.382896 -271.120164) (xy 133.336917 -271.141981)
			(xy 133.288033 -271.156141) (xy 133.237512 -271.162275) (xy 133.18666 -271.160226) (xy 133.136796 -271.150046)
			(xy 133.08921 -271.131999) (xy 133.045136 -271.106553) (xy 133.005714 -271.074366) (xy 132.971966 -271.036272)
			(xy 132.944765 -270.993258) (xy 132.924817 -270.946438) (xy 132.912638 -270.897024) (xy 132.908543 -270.846296)
			(xy 132.602732 -270.846296) (xy 132.602242 -270.871285) (xy 132.594423 -270.920648) (xy 132.578979 -270.96818)
			(xy 132.556289 -271.012712) (xy 132.526913 -271.053145) (xy 132.491573 -271.088485) (xy 132.45114 -271.117861)
			(xy 132.406608 -271.140551) (xy 132.359076 -271.155995) (xy 132.309713 -271.163814) (xy 132.259735 -271.163814)
			(xy 132.210372 -271.155995) (xy 132.16284 -271.140551) (xy 132.118308 -271.117861) (xy 132.077875 -271.088485)
			(xy 132.042535 -271.053145) (xy 132.013159 -271.012712) (xy 131.990469 -270.96818) (xy 131.975025 -270.920648)
			(xy 131.967206 -270.871285) (xy 131.659889 -270.871285) (xy 131.65988 -270.871742) (xy 131.651716 -270.921976)
			(xy 131.6356 -270.97025) (xy 131.611949 -271.015313) (xy 131.581376 -271.055999) (xy 131.544672 -271.091254)
			(xy 131.502788 -271.120164) (xy 131.456809 -271.141981) (xy 131.407925 -271.156141) (xy 131.357404 -271.162275)
			(xy 131.306552 -271.160226) (xy 131.256688 -271.150046) (xy 131.209102 -271.131999) (xy 131.165028 -271.106553)
			(xy 131.125606 -271.074366) (xy 131.091858 -271.036272) (xy 131.064657 -270.993258) (xy 131.044709 -270.946438)
			(xy 131.03253 -270.897024) (xy 131.028435 -270.846296) (xy 129.780538 -270.846296) (xy 129.780026 -270.871742)
			(xy 129.771862 -270.921976) (xy 129.755746 -270.97025) (xy 129.732095 -271.015313) (xy 129.701522 -271.055999)
			(xy 129.664818 -271.091254) (xy 129.622934 -271.120164) (xy 129.576955 -271.141981) (xy 129.528071 -271.156141)
			(xy 129.47755 -271.162275) (xy 129.426698 -271.160226) (xy 129.376834 -271.150046) (xy 129.329248 -271.131999)
			(xy 129.285174 -271.106553) (xy 129.245752 -271.074366) (xy 129.212004 -271.036272) (xy 129.184803 -270.993258)
			(xy 129.164855 -270.946438) (xy 129.152676 -270.897024) (xy 129.148581 -270.846296) (xy 128.840484 -270.846296)
			(xy 128.839972 -270.871742) (xy 128.831808 -270.921976) (xy 128.815692 -270.97025) (xy 128.792041 -271.015313)
			(xy 128.761468 -271.055999) (xy 128.724764 -271.091254) (xy 128.68288 -271.120164) (xy 128.636901 -271.141981)
			(xy 128.588017 -271.156141) (xy 128.537496 -271.162275) (xy 128.486644 -271.160226) (xy 128.43678 -271.150046)
			(xy 128.389194 -271.131999) (xy 128.34512 -271.106553) (xy 128.305698 -271.074366) (xy 128.27195 -271.036272)
			(xy 128.244749 -270.993258) (xy 128.224801 -270.946438) (xy 128.212622 -270.897024) (xy 128.208527 -270.846296)
			(xy 127.167386 -270.846296) (xy 127.167386 -271.301972) (xy 127.168027 -271.313953) (xy 127.1789 -271.335303)
			(xy 127.188214 -271.342866) (xy 127.196342 -271.34693) (xy 127.204978 -271.350486) (xy 127.229392 -271.358211)
			(xy 127.275563 -271.38035) (xy 127.3176 -271.409585) (xy 127.354422 -271.445166) (xy 127.385081 -271.486176)
			(xy 127.408789 -271.531561) (xy 127.424936 -271.580152) (xy 127.433107 -271.6307) (xy 127.433578 -271.656302)
			(xy 127.738627 -271.656302) (xy 127.742722 -271.605574) (xy 127.754901 -271.55616) (xy 127.774849 -271.50934)
			(xy 127.80205 -271.466326) (xy 127.835798 -271.428232) (xy 127.87522 -271.396045) (xy 127.919294 -271.370599)
			(xy 127.96688 -271.352552) (xy 128.016744 -271.342372) (xy 128.067596 -271.340323) (xy 128.118117 -271.346457)
			(xy 128.167001 -271.360617) (xy 128.21298 -271.382434) (xy 128.254864 -271.411344) (xy 128.291568 -271.446599)
			(xy 128.322141 -271.487285) (xy 128.345792 -271.532348) (xy 128.361908 -271.580622) (xy 128.370072 -271.630856)
			(xy 128.370584 -271.656302) (xy 128.370081 -271.681291) (xy 128.677144 -271.681291) (xy 128.677144 -271.631313)
			(xy 128.684963 -271.58195) (xy 128.700407 -271.534418) (xy 128.723097 -271.489886) (xy 128.752473 -271.449453)
			(xy 128.787813 -271.414113) (xy 128.828246 -271.384737) (xy 128.872778 -271.362047) (xy 128.92031 -271.346603)
			(xy 128.969673 -271.338784) (xy 129.019651 -271.338784) (xy 129.069014 -271.346603) (xy 129.116546 -271.362047)
			(xy 129.161078 -271.384737) (xy 129.201511 -271.414113) (xy 129.236851 -271.449453) (xy 129.266227 -271.489886)
			(xy 129.288917 -271.534418) (xy 129.304361 -271.58195) (xy 129.31218 -271.631313) (xy 129.31267 -271.656302)
			(xy 129.618481 -271.656302) (xy 129.622576 -271.605574) (xy 129.634755 -271.55616) (xy 129.654703 -271.50934)
			(xy 129.681904 -271.466326) (xy 129.715652 -271.428232) (xy 129.755074 -271.396045) (xy 129.799148 -271.370599)
			(xy 129.846734 -271.352552) (xy 129.896598 -271.342372) (xy 129.94745 -271.340323) (xy 129.997971 -271.346457)
			(xy 130.046855 -271.360617) (xy 130.092834 -271.382434) (xy 130.134718 -271.411344) (xy 130.171422 -271.446599)
			(xy 130.201995 -271.487285) (xy 130.225646 -271.532348) (xy 130.241762 -271.580622) (xy 130.249926 -271.630856)
			(xy 130.250438 -271.656302) (xy 130.249935 -271.681291) (xy 130.557252 -271.681291) (xy 130.557252 -271.631313)
			(xy 130.565071 -271.58195) (xy 130.580515 -271.534418) (xy 130.603205 -271.489886) (xy 130.632581 -271.449453)
			(xy 130.667921 -271.414113) (xy 130.708354 -271.384737) (xy 130.752886 -271.362047) (xy 130.800418 -271.346603)
			(xy 130.849781 -271.338784) (xy 130.899759 -271.338784) (xy 130.949122 -271.346603) (xy 130.996654 -271.362047)
			(xy 131.041186 -271.384737) (xy 131.081619 -271.414113) (xy 131.116959 -271.449453) (xy 131.146335 -271.489886)
			(xy 131.169025 -271.534418) (xy 131.184469 -271.58195) (xy 131.192288 -271.631313) (xy 131.192778 -271.656302)
			(xy 131.498589 -271.656302) (xy 131.502684 -271.605574) (xy 131.514863 -271.55616) (xy 131.534811 -271.50934)
			(xy 131.562012 -271.466326) (xy 131.59576 -271.428232) (xy 131.635182 -271.396045) (xy 131.679256 -271.370599)
			(xy 131.726842 -271.352552) (xy 131.776706 -271.342372) (xy 131.827558 -271.340323) (xy 131.878079 -271.346457)
			(xy 131.926963 -271.360617) (xy 131.972942 -271.382434) (xy 132.014826 -271.411344) (xy 132.05153 -271.446599)
			(xy 132.082103 -271.487285) (xy 132.105754 -271.532348) (xy 132.12187 -271.580622) (xy 132.130034 -271.630856)
			(xy 132.130546 -271.656302) (xy 132.438643 -271.656302) (xy 132.442738 -271.605574) (xy 132.454917 -271.55616)
			(xy 132.474865 -271.50934) (xy 132.502066 -271.466326) (xy 132.535814 -271.428232) (xy 132.575236 -271.396045)
			(xy 132.61931 -271.370599) (xy 132.666896 -271.352552) (xy 132.71676 -271.342372) (xy 132.767612 -271.340323)
			(xy 132.818133 -271.346457) (xy 132.867017 -271.360617) (xy 132.912996 -271.382434) (xy 132.95488 -271.411344)
			(xy 132.991584 -271.446599) (xy 133.022157 -271.487285) (xy 133.045808 -271.532348) (xy 133.061924 -271.580622)
			(xy 133.070088 -271.630856) (xy 133.0706 -271.656302) (xy 133.070097 -271.681291) (xy 133.37716 -271.681291)
			(xy 133.37716 -271.631313) (xy 133.384979 -271.58195) (xy 133.400423 -271.534418) (xy 133.423113 -271.489886)
			(xy 133.452489 -271.449453) (xy 133.487829 -271.414113) (xy 133.528262 -271.384737) (xy 133.572794 -271.362047)
			(xy 133.620326 -271.346603) (xy 133.669689 -271.338784) (xy 133.719667 -271.338784) (xy 133.76903 -271.346603)
			(xy 133.816562 -271.362047) (xy 133.861094 -271.384737) (xy 133.901527 -271.414113) (xy 133.936867 -271.449453)
			(xy 133.966243 -271.489886) (xy 133.988933 -271.534418) (xy 134.004377 -271.58195) (xy 134.012196 -271.631313)
			(xy 134.012686 -271.656302) (xy 134.318497 -271.656302) (xy 134.322592 -271.605574) (xy 134.334771 -271.55616)
			(xy 134.354719 -271.50934) (xy 134.38192 -271.466326) (xy 134.415668 -271.428232) (xy 134.45509 -271.396045)
			(xy 134.499164 -271.370599) (xy 134.54675 -271.352552) (xy 134.596614 -271.342372) (xy 134.647466 -271.340323)
			(xy 134.697987 -271.346457) (xy 134.746871 -271.360617) (xy 134.79285 -271.382434) (xy 134.834734 -271.411344)
			(xy 134.871438 -271.446599) (xy 134.902011 -271.487285) (xy 134.925662 -271.532348) (xy 134.941778 -271.580622)
			(xy 134.949942 -271.630856) (xy 134.950454 -271.656302) (xy 134.949951 -271.681291) (xy 135.257268 -271.681291)
			(xy 135.257268 -271.631313) (xy 135.265087 -271.58195) (xy 135.280531 -271.534418) (xy 135.303221 -271.489886)
			(xy 135.332597 -271.449453) (xy 135.367937 -271.414113) (xy 135.40837 -271.384737) (xy 135.452902 -271.362047)
			(xy 135.500434 -271.346603) (xy 135.549797 -271.338784) (xy 135.599775 -271.338784) (xy 135.649138 -271.346603)
			(xy 135.69667 -271.362047) (xy 135.741202 -271.384737) (xy 135.781635 -271.414113) (xy 135.816975 -271.449453)
			(xy 135.846351 -271.489886) (xy 135.869041 -271.534418) (xy 135.884485 -271.58195) (xy 135.892304 -271.631313)
			(xy 135.892794 -271.656302) (xy 136.198605 -271.656302) (xy 136.2027 -271.605574) (xy 136.214879 -271.55616)
			(xy 136.234827 -271.50934) (xy 136.262028 -271.466326) (xy 136.295776 -271.428232) (xy 136.335198 -271.396045)
			(xy 136.379272 -271.370599) (xy 136.426858 -271.352552) (xy 136.476722 -271.342372) (xy 136.527574 -271.340323)
			(xy 136.578095 -271.346457) (xy 136.626979 -271.360617) (xy 136.672958 -271.382434) (xy 136.714842 -271.411344)
			(xy 136.751546 -271.446599) (xy 136.782119 -271.487285) (xy 136.80577 -271.532348) (xy 136.821886 -271.580622)
			(xy 136.83005 -271.630856) (xy 136.830562 -271.656302) (xy 136.830059 -271.681291) (xy 137.137122 -271.681291)
			(xy 137.137122 -271.631313) (xy 137.144941 -271.58195) (xy 137.160385 -271.534418) (xy 137.183075 -271.489886)
			(xy 137.212451 -271.449453) (xy 137.247791 -271.414113) (xy 137.288224 -271.384737) (xy 137.332756 -271.362047)
			(xy 137.380288 -271.346603) (xy 137.429651 -271.338784) (xy 137.479629 -271.338784) (xy 137.528992 -271.346603)
			(xy 137.576524 -271.362047) (xy 137.621056 -271.384737) (xy 137.661489 -271.414113) (xy 137.696829 -271.449453)
			(xy 137.726205 -271.489886) (xy 137.748895 -271.534418) (xy 137.764339 -271.58195) (xy 137.772158 -271.631313)
			(xy 137.772648 -271.656302) (xy 138.078459 -271.656302) (xy 138.082554 -271.605574) (xy 138.094733 -271.55616)
			(xy 138.114681 -271.50934) (xy 138.141882 -271.466326) (xy 138.17563 -271.428232) (xy 138.215052 -271.396045)
			(xy 138.259126 -271.370599) (xy 138.306712 -271.352552) (xy 138.356576 -271.342372) (xy 138.407428 -271.340323)
			(xy 138.457949 -271.346457) (xy 138.506833 -271.360617) (xy 138.552812 -271.382434) (xy 138.594696 -271.411344)
			(xy 138.6314 -271.446599) (xy 138.661973 -271.487285) (xy 138.685624 -271.532348) (xy 138.70174 -271.580622)
			(xy 138.709904 -271.630856) (xy 138.710416 -271.656302) (xy 139.018513 -271.656302) (xy 139.022608 -271.605574)
			(xy 139.034787 -271.55616) (xy 139.054735 -271.50934) (xy 139.081936 -271.466326) (xy 139.115684 -271.428232)
			(xy 139.155106 -271.396045) (xy 139.19918 -271.370599) (xy 139.246766 -271.352552) (xy 139.29663 -271.342372)
			(xy 139.347482 -271.340323) (xy 139.398003 -271.346457) (xy 139.446887 -271.360617) (xy 139.492866 -271.382434)
			(xy 139.53475 -271.411344) (xy 139.571454 -271.446599) (xy 139.602027 -271.487285) (xy 139.625678 -271.532348)
			(xy 139.641794 -271.580622) (xy 139.649958 -271.630856) (xy 139.65047 -271.656302) (xy 139.649967 -271.681291)
			(xy 139.957284 -271.681291) (xy 139.957284 -271.631313) (xy 139.965103 -271.58195) (xy 139.980547 -271.534418)
			(xy 140.003237 -271.489886) (xy 140.032613 -271.449453) (xy 140.067953 -271.414113) (xy 140.108386 -271.384737)
			(xy 140.152918 -271.362047) (xy 140.20045 -271.346603) (xy 140.249813 -271.338784) (xy 140.299791 -271.338784)
			(xy 140.349154 -271.346603) (xy 140.396686 -271.362047) (xy 140.441218 -271.384737) (xy 140.481651 -271.414113)
			(xy 140.516991 -271.449453) (xy 140.546367 -271.489886) (xy 140.569057 -271.534418) (xy 140.584501 -271.58195)
			(xy 140.59232 -271.631313) (xy 140.59281 -271.656302) (xy 140.898621 -271.656302) (xy 140.902716 -271.605574)
			(xy 140.914895 -271.55616) (xy 140.934843 -271.50934) (xy 140.962044 -271.466326) (xy 140.995792 -271.428232)
			(xy 141.035214 -271.396045) (xy 141.079288 -271.370599) (xy 141.126874 -271.352552) (xy 141.176738 -271.342372)
			(xy 141.22759 -271.340323) (xy 141.278111 -271.346457) (xy 141.326995 -271.360617) (xy 141.372974 -271.382434)
			(xy 141.414858 -271.411344) (xy 141.451562 -271.446599) (xy 141.482135 -271.487285) (xy 141.505786 -271.532348)
			(xy 141.521902 -271.580622) (xy 141.530066 -271.630856) (xy 141.530578 -271.656302) (xy 141.530075 -271.681291)
			(xy 141.837138 -271.681291) (xy 141.837138 -271.631313) (xy 141.844957 -271.58195) (xy 141.860401 -271.534418)
			(xy 141.883091 -271.489886) (xy 141.912467 -271.449453) (xy 141.947807 -271.414113) (xy 141.98824 -271.384737)
			(xy 142.032772 -271.362047) (xy 142.080304 -271.346603) (xy 142.129667 -271.338784) (xy 142.179645 -271.338784)
			(xy 142.229008 -271.346603) (xy 142.27654 -271.362047) (xy 142.321072 -271.384737) (xy 142.361505 -271.414113)
			(xy 142.396845 -271.449453) (xy 142.426221 -271.489886) (xy 142.448911 -271.534418) (xy 142.464355 -271.58195)
			(xy 142.472174 -271.631313) (xy 142.472664 -271.656302) (xy 142.778475 -271.656302) (xy 142.78257 -271.605574)
			(xy 142.794749 -271.55616) (xy 142.814697 -271.50934) (xy 142.841898 -271.466326) (xy 142.875646 -271.428232)
			(xy 142.915068 -271.396045) (xy 142.959142 -271.370599) (xy 143.006728 -271.352552) (xy 143.056592 -271.342372)
			(xy 143.107444 -271.340323) (xy 143.157965 -271.346457) (xy 143.206849 -271.360617) (xy 143.252828 -271.382434)
			(xy 143.294712 -271.411344) (xy 143.331416 -271.446599) (xy 143.361989 -271.487285) (xy 143.38564 -271.532348)
			(xy 143.401756 -271.580622) (xy 143.40992 -271.630856) (xy 143.410432 -271.656302) (xy 143.409929 -271.681291)
			(xy 143.717246 -271.681291) (xy 143.717246 -271.631313) (xy 143.725065 -271.58195) (xy 143.740509 -271.534418)
			(xy 143.763199 -271.489886) (xy 143.792575 -271.449453) (xy 143.827915 -271.414113) (xy 143.868348 -271.384737)
			(xy 143.91288 -271.362047) (xy 143.960412 -271.346603) (xy 144.009775 -271.338784) (xy 144.059753 -271.338784)
			(xy 144.109116 -271.346603) (xy 144.156648 -271.362047) (xy 144.20118 -271.384737) (xy 144.241613 -271.414113)
			(xy 144.276953 -271.449453) (xy 144.306329 -271.489886) (xy 144.329019 -271.534418) (xy 144.344463 -271.58195)
			(xy 144.352282 -271.631313) (xy 144.352772 -271.656302) (xy 144.352282 -271.681291) (xy 144.344463 -271.730654)
			(xy 144.329019 -271.778186) (xy 144.306329 -271.822718) (xy 144.276953 -271.863151) (xy 144.241613 -271.898491)
			(xy 144.20118 -271.927867) (xy 144.156648 -271.950557) (xy 144.109116 -271.966001) (xy 144.059753 -271.97382)
			(xy 144.009775 -271.97382) (xy 143.960412 -271.966001) (xy 143.91288 -271.950557) (xy 143.868348 -271.927867)
			(xy 143.827915 -271.898491) (xy 143.792575 -271.863151) (xy 143.763199 -271.822718) (xy 143.740509 -271.778186)
			(xy 143.725065 -271.730654) (xy 143.717246 -271.681291) (xy 143.409929 -271.681291) (xy 143.40992 -271.681748)
			(xy 143.401756 -271.731982) (xy 143.38564 -271.780256) (xy 143.361989 -271.825319) (xy 143.331416 -271.866005)
			(xy 143.294712 -271.90126) (xy 143.252828 -271.93017) (xy 143.206849 -271.951987) (xy 143.157965 -271.966147)
			(xy 143.107444 -271.972281) (xy 143.056592 -271.970232) (xy 143.006728 -271.960052) (xy 142.959142 -271.942005)
			(xy 142.915068 -271.916559) (xy 142.875646 -271.884372) (xy 142.841898 -271.846278) (xy 142.814697 -271.803264)
			(xy 142.794749 -271.756444) (xy 142.78257 -271.70703) (xy 142.778475 -271.656302) (xy 142.472664 -271.656302)
			(xy 142.472174 -271.681291) (xy 142.464355 -271.730654) (xy 142.448911 -271.778186) (xy 142.426221 -271.822718)
			(xy 142.396845 -271.863151) (xy 142.361505 -271.898491) (xy 142.321072 -271.927867) (xy 142.27654 -271.950557)
			(xy 142.229008 -271.966001) (xy 142.179645 -271.97382) (xy 142.129667 -271.97382) (xy 142.080304 -271.966001)
			(xy 142.032772 -271.950557) (xy 141.98824 -271.927867) (xy 141.947807 -271.898491) (xy 141.912467 -271.863151)
			(xy 141.883091 -271.822718) (xy 141.860401 -271.778186) (xy 141.844957 -271.730654) (xy 141.837138 -271.681291)
			(xy 141.530075 -271.681291) (xy 141.530066 -271.681748) (xy 141.521902 -271.731982) (xy 141.505786 -271.780256)
			(xy 141.482135 -271.825319) (xy 141.451562 -271.866005) (xy 141.414858 -271.90126) (xy 141.372974 -271.93017)
			(xy 141.326995 -271.951987) (xy 141.278111 -271.966147) (xy 141.22759 -271.972281) (xy 141.176738 -271.970232)
			(xy 141.126874 -271.960052) (xy 141.079288 -271.942005) (xy 141.035214 -271.916559) (xy 140.995792 -271.884372)
			(xy 140.962044 -271.846278) (xy 140.934843 -271.803264) (xy 140.914895 -271.756444) (xy 140.902716 -271.70703)
			(xy 140.898621 -271.656302) (xy 140.59281 -271.656302) (xy 140.59232 -271.681291) (xy 140.584501 -271.730654)
			(xy 140.569057 -271.778186) (xy 140.546367 -271.822718) (xy 140.516991 -271.863151) (xy 140.481651 -271.898491)
			(xy 140.441218 -271.927867) (xy 140.396686 -271.950557) (xy 140.349154 -271.966001) (xy 140.299791 -271.97382)
			(xy 140.249813 -271.97382) (xy 140.20045 -271.966001) (xy 140.152918 -271.950557) (xy 140.108386 -271.927867)
			(xy 140.067953 -271.898491) (xy 140.032613 -271.863151) (xy 140.003237 -271.822718) (xy 139.980547 -271.778186)
			(xy 139.965103 -271.730654) (xy 139.957284 -271.681291) (xy 139.649967 -271.681291) (xy 139.649958 -271.681748)
			(xy 139.641794 -271.731982) (xy 139.625678 -271.780256) (xy 139.602027 -271.825319) (xy 139.571454 -271.866005)
			(xy 139.53475 -271.90126) (xy 139.492866 -271.93017) (xy 139.446887 -271.951987) (xy 139.398003 -271.966147)
			(xy 139.347482 -271.972281) (xy 139.29663 -271.970232) (xy 139.246766 -271.960052) (xy 139.19918 -271.942005)
			(xy 139.155106 -271.916559) (xy 139.115684 -271.884372) (xy 139.081936 -271.846278) (xy 139.054735 -271.803264)
			(xy 139.034787 -271.756444) (xy 139.022608 -271.70703) (xy 139.018513 -271.656302) (xy 138.710416 -271.656302)
			(xy 138.709904 -271.681748) (xy 138.70174 -271.731982) (xy 138.685624 -271.780256) (xy 138.661973 -271.825319)
			(xy 138.6314 -271.866005) (xy 138.594696 -271.90126) (xy 138.552812 -271.93017) (xy 138.506833 -271.951987)
			(xy 138.457949 -271.966147) (xy 138.407428 -271.972281) (xy 138.356576 -271.970232) (xy 138.306712 -271.960052)
			(xy 138.259126 -271.942005) (xy 138.215052 -271.916559) (xy 138.17563 -271.884372) (xy 138.141882 -271.846278)
			(xy 138.114681 -271.803264) (xy 138.094733 -271.756444) (xy 138.082554 -271.70703) (xy 138.078459 -271.656302)
			(xy 137.772648 -271.656302) (xy 137.772158 -271.681291) (xy 137.764339 -271.730654) (xy 137.748895 -271.778186)
			(xy 137.726205 -271.822718) (xy 137.696829 -271.863151) (xy 137.661489 -271.898491) (xy 137.621056 -271.927867)
			(xy 137.576524 -271.950557) (xy 137.528992 -271.966001) (xy 137.479629 -271.97382) (xy 137.429651 -271.97382)
			(xy 137.380288 -271.966001) (xy 137.332756 -271.950557) (xy 137.288224 -271.927867) (xy 137.247791 -271.898491)
			(xy 137.212451 -271.863151) (xy 137.183075 -271.822718) (xy 137.160385 -271.778186) (xy 137.144941 -271.730654)
			(xy 137.137122 -271.681291) (xy 136.830059 -271.681291) (xy 136.83005 -271.681748) (xy 136.821886 -271.731982)
			(xy 136.80577 -271.780256) (xy 136.782119 -271.825319) (xy 136.751546 -271.866005) (xy 136.714842 -271.90126)
			(xy 136.672958 -271.93017) (xy 136.626979 -271.951987) (xy 136.578095 -271.966147) (xy 136.527574 -271.972281)
			(xy 136.476722 -271.970232) (xy 136.426858 -271.960052) (xy 136.379272 -271.942005) (xy 136.335198 -271.916559)
			(xy 136.295776 -271.884372) (xy 136.262028 -271.846278) (xy 136.234827 -271.803264) (xy 136.214879 -271.756444)
			(xy 136.2027 -271.70703) (xy 136.198605 -271.656302) (xy 135.892794 -271.656302) (xy 135.892304 -271.681291)
			(xy 135.884485 -271.730654) (xy 135.869041 -271.778186) (xy 135.846351 -271.822718) (xy 135.816975 -271.863151)
			(xy 135.781635 -271.898491) (xy 135.741202 -271.927867) (xy 135.69667 -271.950557) (xy 135.649138 -271.966001)
			(xy 135.599775 -271.97382) (xy 135.549797 -271.97382) (xy 135.500434 -271.966001) (xy 135.452902 -271.950557)
			(xy 135.40837 -271.927867) (xy 135.367937 -271.898491) (xy 135.332597 -271.863151) (xy 135.303221 -271.822718)
			(xy 135.280531 -271.778186) (xy 135.265087 -271.730654) (xy 135.257268 -271.681291) (xy 134.949951 -271.681291)
			(xy 134.949942 -271.681748) (xy 134.941778 -271.731982) (xy 134.925662 -271.780256) (xy 134.902011 -271.825319)
			(xy 134.871438 -271.866005) (xy 134.834734 -271.90126) (xy 134.79285 -271.93017) (xy 134.746871 -271.951987)
			(xy 134.697987 -271.966147) (xy 134.647466 -271.972281) (xy 134.596614 -271.970232) (xy 134.54675 -271.960052)
			(xy 134.499164 -271.942005) (xy 134.45509 -271.916559) (xy 134.415668 -271.884372) (xy 134.38192 -271.846278)
			(xy 134.354719 -271.803264) (xy 134.334771 -271.756444) (xy 134.322592 -271.70703) (xy 134.318497 -271.656302)
			(xy 134.012686 -271.656302) (xy 134.012196 -271.681291) (xy 134.004377 -271.730654) (xy 133.988933 -271.778186)
			(xy 133.966243 -271.822718) (xy 133.936867 -271.863151) (xy 133.901527 -271.898491) (xy 133.861094 -271.927867)
			(xy 133.816562 -271.950557) (xy 133.76903 -271.966001) (xy 133.719667 -271.97382) (xy 133.669689 -271.97382)
			(xy 133.620326 -271.966001) (xy 133.572794 -271.950557) (xy 133.528262 -271.927867) (xy 133.487829 -271.898491)
			(xy 133.452489 -271.863151) (xy 133.423113 -271.822718) (xy 133.400423 -271.778186) (xy 133.384979 -271.730654)
			(xy 133.37716 -271.681291) (xy 133.070097 -271.681291) (xy 133.070088 -271.681748) (xy 133.061924 -271.731982)
			(xy 133.045808 -271.780256) (xy 133.022157 -271.825319) (xy 132.991584 -271.866005) (xy 132.95488 -271.90126)
			(xy 132.912996 -271.93017) (xy 132.867017 -271.951987) (xy 132.818133 -271.966147) (xy 132.767612 -271.972281)
			(xy 132.71676 -271.970232) (xy 132.666896 -271.960052) (xy 132.61931 -271.942005) (xy 132.575236 -271.916559)
			(xy 132.535814 -271.884372) (xy 132.502066 -271.846278) (xy 132.474865 -271.803264) (xy 132.454917 -271.756444)
			(xy 132.442738 -271.70703) (xy 132.438643 -271.656302) (xy 132.130546 -271.656302) (xy 132.130034 -271.681748)
			(xy 132.12187 -271.731982) (xy 132.105754 -271.780256) (xy 132.082103 -271.825319) (xy 132.05153 -271.866005)
			(xy 132.014826 -271.90126) (xy 131.972942 -271.93017) (xy 131.926963 -271.951987) (xy 131.878079 -271.966147)
			(xy 131.827558 -271.972281) (xy 131.776706 -271.970232) (xy 131.726842 -271.960052) (xy 131.679256 -271.942005)
			(xy 131.635182 -271.916559) (xy 131.59576 -271.884372) (xy 131.562012 -271.846278) (xy 131.534811 -271.803264)
			(xy 131.514863 -271.756444) (xy 131.502684 -271.70703) (xy 131.498589 -271.656302) (xy 131.192778 -271.656302)
			(xy 131.192288 -271.681291) (xy 131.184469 -271.730654) (xy 131.169025 -271.778186) (xy 131.146335 -271.822718)
			(xy 131.116959 -271.863151) (xy 131.081619 -271.898491) (xy 131.041186 -271.927867) (xy 130.996654 -271.950557)
			(xy 130.949122 -271.966001) (xy 130.899759 -271.97382) (xy 130.849781 -271.97382) (xy 130.800418 -271.966001)
			(xy 130.752886 -271.950557) (xy 130.708354 -271.927867) (xy 130.667921 -271.898491) (xy 130.632581 -271.863151)
			(xy 130.603205 -271.822718) (xy 130.580515 -271.778186) (xy 130.565071 -271.730654) (xy 130.557252 -271.681291)
			(xy 130.249935 -271.681291) (xy 130.249926 -271.681748) (xy 130.241762 -271.731982) (xy 130.225646 -271.780256)
			(xy 130.201995 -271.825319) (xy 130.171422 -271.866005) (xy 130.134718 -271.90126) (xy 130.092834 -271.93017)
			(xy 130.046855 -271.951987) (xy 129.997971 -271.966147) (xy 129.94745 -271.972281) (xy 129.896598 -271.970232)
			(xy 129.846734 -271.960052) (xy 129.799148 -271.942005) (xy 129.755074 -271.916559) (xy 129.715652 -271.884372)
			(xy 129.681904 -271.846278) (xy 129.654703 -271.803264) (xy 129.634755 -271.756444) (xy 129.622576 -271.70703)
			(xy 129.618481 -271.656302) (xy 129.31267 -271.656302) (xy 129.31218 -271.681291) (xy 129.304361 -271.730654)
			(xy 129.288917 -271.778186) (xy 129.266227 -271.822718) (xy 129.236851 -271.863151) (xy 129.201511 -271.898491)
			(xy 129.161078 -271.927867) (xy 129.116546 -271.950557) (xy 129.069014 -271.966001) (xy 129.019651 -271.97382)
			(xy 128.969673 -271.97382) (xy 128.92031 -271.966001) (xy 128.872778 -271.950557) (xy 128.828246 -271.927867)
			(xy 128.787813 -271.898491) (xy 128.752473 -271.863151) (xy 128.723097 -271.822718) (xy 128.700407 -271.778186)
			(xy 128.684963 -271.730654) (xy 128.677144 -271.681291) (xy 128.370081 -271.681291) (xy 128.370072 -271.681748)
			(xy 128.361908 -271.731982) (xy 128.345792 -271.780256) (xy 128.322141 -271.825319) (xy 128.291568 -271.866005)
			(xy 128.254864 -271.90126) (xy 128.21298 -271.93017) (xy 128.167001 -271.951987) (xy 128.118117 -271.966147)
			(xy 128.067596 -271.972281) (xy 128.016744 -271.970232) (xy 127.96688 -271.960052) (xy 127.919294 -271.942005)
			(xy 127.87522 -271.916559) (xy 127.835798 -271.884372) (xy 127.80205 -271.846278) (xy 127.774849 -271.803264)
			(xy 127.754901 -271.756444) (xy 127.742722 -271.70703) (xy 127.738627 -271.656302) (xy 127.433578 -271.656302)
			(xy 127.433052 -271.682362) (xy 127.424562 -271.733786) (xy 127.407824 -271.783146) (xy 127.383285 -271.829129)
			(xy 127.351596 -271.87051) (xy 127.313602 -271.906188) (xy 127.270312 -271.935215) (xy 127.22288 -271.956818)
			(xy 127.197866 -271.96415) (xy 127.189037 -271.968509) (xy 127.1753 -271.982589) (xy 127.167854 -272.000798)
			(xy 127.167386 -272.010632) (xy 127.167386 -272.193512) (xy 127.167852 -272.203824) (xy 127.175959 -272.222787)
			(xy 127.190892 -272.237011) (xy 127.200406 -272.24101) (xy 127.28702 -272.273268) (xy 127.295734 -272.276109)
			(xy 127.314049 -272.276076) (xy 127.331185 -272.269614) (xy 127.338328 -272.26387) (xy 127.343662 -272.258536)
			(xy 127.344678 -272.257266) (xy 127.362966 -272.237112) (xy 127.405165 -272.20275) (xy 127.452593 -272.176067)
			(xy 127.503869 -272.157841) (xy 127.557498 -272.148602) (xy 127.584708 -272.148046) (xy 127.609716 -272.148537)
			(xy 127.659116 -272.156363) (xy 127.706684 -272.171819) (xy 127.751249 -272.194527) (xy 127.791712 -272.223927)
			(xy 127.827079 -272.259294) (xy 127.856477 -272.299758) (xy 127.879184 -272.344323) (xy 127.894639 -272.391891)
			(xy 127.902463 -272.441292) (xy 127.902463 -272.466308) (xy 128.208527 -272.466308) (xy 128.212622 -272.41558)
			(xy 128.224801 -272.366166) (xy 128.244749 -272.319346) (xy 128.27195 -272.276332) (xy 128.305698 -272.238238)
			(xy 128.34512 -272.206051) (xy 128.389194 -272.180605) (xy 128.43678 -272.162558) (xy 128.486644 -272.152378)
			(xy 128.537496 -272.150329) (xy 128.588017 -272.156463) (xy 128.636901 -272.170623) (xy 128.68288 -272.19244)
			(xy 128.724764 -272.22135) (xy 128.761468 -272.256605) (xy 128.792041 -272.297291) (xy 128.815692 -272.342354)
			(xy 128.831808 -272.390628) (xy 128.839972 -272.440862) (xy 128.840484 -272.466308) (xy 129.148581 -272.466308)
			(xy 129.152676 -272.41558) (xy 129.164855 -272.366166) (xy 129.184803 -272.319346) (xy 129.212004 -272.276332)
			(xy 129.245752 -272.238238) (xy 129.285174 -272.206051) (xy 129.329248 -272.180605) (xy 129.376834 -272.162558)
			(xy 129.426698 -272.152378) (xy 129.47755 -272.150329) (xy 129.528071 -272.156463) (xy 129.576955 -272.170623)
			(xy 129.622934 -272.19244) (xy 129.664818 -272.22135) (xy 129.701522 -272.256605) (xy 129.732095 -272.297291)
			(xy 129.755746 -272.342354) (xy 129.771862 -272.390628) (xy 129.780026 -272.440862) (xy 129.780538 -272.466308)
			(xy 129.780035 -272.491297) (xy 130.087352 -272.491297) (xy 130.087352 -272.441319) (xy 130.095171 -272.391956)
			(xy 130.110615 -272.344424) (xy 130.133305 -272.299892) (xy 130.162681 -272.259459) (xy 130.198021 -272.224119)
			(xy 130.238454 -272.194743) (xy 130.282986 -272.172053) (xy 130.330518 -272.156609) (xy 130.379881 -272.14879)
			(xy 130.429859 -272.14879) (xy 130.479222 -272.156609) (xy 130.526754 -272.172053) (xy 130.571286 -272.194743)
			(xy 130.611719 -272.224119) (xy 130.647059 -272.259459) (xy 130.676435 -272.299892) (xy 130.699125 -272.344424)
			(xy 130.714569 -272.391956) (xy 130.722388 -272.441319) (xy 130.722878 -272.466308) (xy 131.028435 -272.466308)
			(xy 131.03253 -272.41558) (xy 131.044709 -272.366166) (xy 131.064657 -272.319346) (xy 131.091858 -272.276332)
			(xy 131.125606 -272.238238) (xy 131.165028 -272.206051) (xy 131.209102 -272.180605) (xy 131.256688 -272.162558)
			(xy 131.306552 -272.152378) (xy 131.357404 -272.150329) (xy 131.407925 -272.156463) (xy 131.456809 -272.170623)
			(xy 131.502788 -272.19244) (xy 131.544672 -272.22135) (xy 131.581376 -272.256605) (xy 131.611949 -272.297291)
			(xy 131.6356 -272.342354) (xy 131.651716 -272.390628) (xy 131.65988 -272.440862) (xy 131.660392 -272.466308)
			(xy 131.659889 -272.491297) (xy 131.967206 -272.491297) (xy 131.967206 -272.441319) (xy 131.975025 -272.391956)
			(xy 131.990469 -272.344424) (xy 132.013159 -272.299892) (xy 132.042535 -272.259459) (xy 132.077875 -272.224119)
			(xy 132.118308 -272.194743) (xy 132.16284 -272.172053) (xy 132.210372 -272.156609) (xy 132.259735 -272.14879)
			(xy 132.309713 -272.14879) (xy 132.359076 -272.156609) (xy 132.406608 -272.172053) (xy 132.45114 -272.194743)
			(xy 132.491573 -272.224119) (xy 132.526913 -272.259459) (xy 132.556289 -272.299892) (xy 132.578979 -272.344424)
			(xy 132.594423 -272.391956) (xy 132.602242 -272.441319) (xy 132.602732 -272.466308) (xy 132.908543 -272.466308)
			(xy 132.912638 -272.41558) (xy 132.924817 -272.366166) (xy 132.944765 -272.319346) (xy 132.971966 -272.276332)
			(xy 133.005714 -272.238238) (xy 133.045136 -272.206051) (xy 133.08921 -272.180605) (xy 133.136796 -272.162558)
			(xy 133.18666 -272.152378) (xy 133.237512 -272.150329) (xy 133.288033 -272.156463) (xy 133.336917 -272.170623)
			(xy 133.382896 -272.19244) (xy 133.42478 -272.22135) (xy 133.461484 -272.256605) (xy 133.492057 -272.297291)
			(xy 133.515708 -272.342354) (xy 133.531824 -272.390628) (xy 133.539988 -272.440862) (xy 133.5405 -272.466308)
			(xy 133.539997 -272.491297) (xy 133.847314 -272.491297) (xy 133.847314 -272.441319) (xy 133.855133 -272.391956)
			(xy 133.870577 -272.344424) (xy 133.893267 -272.299892) (xy 133.922643 -272.259459) (xy 133.957983 -272.224119)
			(xy 133.998416 -272.194743) (xy 134.042948 -272.172053) (xy 134.09048 -272.156609) (xy 134.139843 -272.14879)
			(xy 134.189821 -272.14879) (xy 134.239184 -272.156609) (xy 134.286716 -272.172053) (xy 134.331248 -272.194743)
			(xy 134.371681 -272.224119) (xy 134.407021 -272.259459) (xy 134.436397 -272.299892) (xy 134.459087 -272.344424)
			(xy 134.474531 -272.391956) (xy 134.48235 -272.441319) (xy 134.48284 -272.466308) (xy 134.788397 -272.466308)
			(xy 134.792492 -272.41558) (xy 134.804671 -272.366166) (xy 134.824619 -272.319346) (xy 134.85182 -272.276332)
			(xy 134.885568 -272.238238) (xy 134.92499 -272.206051) (xy 134.969064 -272.180605) (xy 135.01665 -272.162558)
			(xy 135.066514 -272.152378) (xy 135.117366 -272.150329) (xy 135.167887 -272.156463) (xy 135.216771 -272.170623)
			(xy 135.26275 -272.19244) (xy 135.304634 -272.22135) (xy 135.341338 -272.256605) (xy 135.371911 -272.297291)
			(xy 135.395562 -272.342354) (xy 135.411678 -272.390628) (xy 135.419842 -272.440862) (xy 135.420354 -272.466308)
			(xy 135.728451 -272.466308) (xy 135.732546 -272.41558) (xy 135.744725 -272.366166) (xy 135.764673 -272.319346)
			(xy 135.791874 -272.276332) (xy 135.825622 -272.238238) (xy 135.865044 -272.206051) (xy 135.909118 -272.180605)
			(xy 135.956704 -272.162558) (xy 136.006568 -272.152378) (xy 136.05742 -272.150329) (xy 136.107941 -272.156463)
			(xy 136.156825 -272.170623) (xy 136.202804 -272.19244) (xy 136.244688 -272.22135) (xy 136.281392 -272.256605)
			(xy 136.311965 -272.297291) (xy 136.335616 -272.342354) (xy 136.351732 -272.390628) (xy 136.359896 -272.440862)
			(xy 136.360408 -272.466308) (xy 136.359905 -272.491297) (xy 136.667222 -272.491297) (xy 136.667222 -272.441319)
			(xy 136.675041 -272.391956) (xy 136.690485 -272.344424) (xy 136.713175 -272.299892) (xy 136.742551 -272.259459)
			(xy 136.777891 -272.224119) (xy 136.818324 -272.194743) (xy 136.862856 -272.172053) (xy 136.910388 -272.156609)
			(xy 136.959751 -272.14879) (xy 137.009729 -272.14879) (xy 137.059092 -272.156609) (xy 137.106624 -272.172053)
			(xy 137.151156 -272.194743) (xy 137.191589 -272.224119) (xy 137.226929 -272.259459) (xy 137.256305 -272.299892)
			(xy 137.278995 -272.344424) (xy 137.294439 -272.391956) (xy 137.302258 -272.441319) (xy 137.302748 -272.466308)
			(xy 137.608559 -272.466308) (xy 137.612654 -272.41558) (xy 137.624833 -272.366166) (xy 137.644781 -272.319346)
			(xy 137.671982 -272.276332) (xy 137.70573 -272.238238) (xy 137.745152 -272.206051) (xy 137.789226 -272.180605)
			(xy 137.836812 -272.162558) (xy 137.886676 -272.152378) (xy 137.937528 -272.150329) (xy 137.988049 -272.156463)
			(xy 138.036933 -272.170623) (xy 138.082912 -272.19244) (xy 138.124796 -272.22135) (xy 138.1615 -272.256605)
			(xy 138.192073 -272.297291) (xy 138.215724 -272.342354) (xy 138.23184 -272.390628) (xy 138.240004 -272.440862)
			(xy 138.240516 -272.466308) (xy 138.240013 -272.491297) (xy 138.54733 -272.491297) (xy 138.54733 -272.441319)
			(xy 138.555149 -272.391956) (xy 138.570593 -272.344424) (xy 138.593283 -272.299892) (xy 138.622659 -272.259459)
			(xy 138.657999 -272.224119) (xy 138.698432 -272.194743) (xy 138.742964 -272.172053) (xy 138.790496 -272.156609)
			(xy 138.839859 -272.14879) (xy 138.889837 -272.14879) (xy 138.9392 -272.156609) (xy 138.986732 -272.172053)
			(xy 139.031264 -272.194743) (xy 139.071697 -272.224119) (xy 139.107037 -272.259459) (xy 139.136413 -272.299892)
			(xy 139.159103 -272.344424) (xy 139.174547 -272.391956) (xy 139.182366 -272.441319) (xy 139.182856 -272.466308)
			(xy 139.488413 -272.466308) (xy 139.492508 -272.41558) (xy 139.504687 -272.366166) (xy 139.524635 -272.319346)
			(xy 139.551836 -272.276332) (xy 139.585584 -272.238238) (xy 139.625006 -272.206051) (xy 139.66908 -272.180605)
			(xy 139.716666 -272.162558) (xy 139.76653 -272.152378) (xy 139.817382 -272.150329) (xy 139.867903 -272.156463)
			(xy 139.916787 -272.170623) (xy 139.962766 -272.19244) (xy 140.00465 -272.22135) (xy 140.041354 -272.256605)
			(xy 140.071927 -272.297291) (xy 140.095578 -272.342354) (xy 140.111694 -272.390628) (xy 140.119858 -272.440862)
			(xy 140.12037 -272.466308) (xy 140.119867 -272.491297) (xy 140.427184 -272.491297) (xy 140.427184 -272.441319)
			(xy 140.435003 -272.391956) (xy 140.450447 -272.344424) (xy 140.473137 -272.299892) (xy 140.502513 -272.259459)
			(xy 140.537853 -272.224119) (xy 140.578286 -272.194743) (xy 140.622818 -272.172053) (xy 140.67035 -272.156609)
			(xy 140.719713 -272.14879) (xy 140.769691 -272.14879) (xy 140.819054 -272.156609) (xy 140.866586 -272.172053)
			(xy 140.911118 -272.194743) (xy 140.951551 -272.224119) (xy 140.986891 -272.259459) (xy 141.016267 -272.299892)
			(xy 141.038957 -272.344424) (xy 141.054401 -272.391956) (xy 141.06222 -272.441319) (xy 141.06271 -272.466308)
			(xy 141.368521 -272.466308) (xy 141.372616 -272.41558) (xy 141.384795 -272.366166) (xy 141.404743 -272.319346)
			(xy 141.431944 -272.276332) (xy 141.465692 -272.238238) (xy 141.505114 -272.206051) (xy 141.549188 -272.180605)
			(xy 141.596774 -272.162558) (xy 141.646638 -272.152378) (xy 141.69749 -272.150329) (xy 141.748011 -272.156463)
			(xy 141.796895 -272.170623) (xy 141.842874 -272.19244) (xy 141.884758 -272.22135) (xy 141.921462 -272.256605)
			(xy 141.952035 -272.297291) (xy 141.975686 -272.342354) (xy 141.991802 -272.390628) (xy 141.999966 -272.440862)
			(xy 142.000478 -272.466308) (xy 142.308575 -272.466308) (xy 142.31267 -272.41558) (xy 142.324849 -272.366166)
			(xy 142.344797 -272.319346) (xy 142.371998 -272.276332) (xy 142.405746 -272.238238) (xy 142.445168 -272.206051)
			(xy 142.489242 -272.180605) (xy 142.536828 -272.162558) (xy 142.586692 -272.152378) (xy 142.637544 -272.150329)
			(xy 142.688065 -272.156463) (xy 142.736949 -272.170623) (xy 142.782928 -272.19244) (xy 142.824812 -272.22135)
			(xy 142.861516 -272.256605) (xy 142.892089 -272.297291) (xy 142.91574 -272.342354) (xy 142.931856 -272.390628)
			(xy 142.94002 -272.440862) (xy 142.940532 -272.466308) (xy 142.940029 -272.491297) (xy 143.247092 -272.491297)
			(xy 143.247092 -272.441319) (xy 143.254911 -272.391956) (xy 143.270355 -272.344424) (xy 143.293045 -272.299892)
			(xy 143.322421 -272.259459) (xy 143.357761 -272.224119) (xy 143.398194 -272.194743) (xy 143.442726 -272.172053)
			(xy 143.490258 -272.156609) (xy 143.539621 -272.14879) (xy 143.589599 -272.14879) (xy 143.638962 -272.156609)
			(xy 143.686494 -272.172053) (xy 143.731026 -272.194743) (xy 143.771459 -272.224119) (xy 143.806799 -272.259459)
			(xy 143.836175 -272.299892) (xy 143.858865 -272.344424) (xy 143.874309 -272.391956) (xy 143.882128 -272.441319)
			(xy 143.882618 -272.466308) (xy 143.882128 -272.491297) (xy 143.874309 -272.54066) (xy 143.858865 -272.588192)
			(xy 143.836175 -272.632724) (xy 143.806799 -272.673157) (xy 143.771459 -272.708497) (xy 143.731026 -272.737873)
			(xy 143.686494 -272.760563) (xy 143.638962 -272.776007) (xy 143.589599 -272.783826) (xy 143.539621 -272.783826)
			(xy 143.490258 -272.776007) (xy 143.442726 -272.760563) (xy 143.398194 -272.737873) (xy 143.357761 -272.708497)
			(xy 143.322421 -272.673157) (xy 143.293045 -272.632724) (xy 143.270355 -272.588192) (xy 143.254911 -272.54066)
			(xy 143.247092 -272.491297) (xy 142.940029 -272.491297) (xy 142.94002 -272.491754) (xy 142.931856 -272.541988)
			(xy 142.91574 -272.590262) (xy 142.892089 -272.635325) (xy 142.861516 -272.676011) (xy 142.824812 -272.711266)
			(xy 142.782928 -272.740176) (xy 142.736949 -272.761993) (xy 142.688065 -272.776153) (xy 142.637544 -272.782287)
			(xy 142.586692 -272.780238) (xy 142.536828 -272.770058) (xy 142.489242 -272.752011) (xy 142.445168 -272.726565)
			(xy 142.405746 -272.694378) (xy 142.371998 -272.656284) (xy 142.344797 -272.61327) (xy 142.324849 -272.56645)
			(xy 142.31267 -272.517036) (xy 142.308575 -272.466308) (xy 142.000478 -272.466308) (xy 141.999966 -272.491754)
			(xy 141.991802 -272.541988) (xy 141.975686 -272.590262) (xy 141.952035 -272.635325) (xy 141.921462 -272.676011)
			(xy 141.884758 -272.711266) (xy 141.842874 -272.740176) (xy 141.796895 -272.761993) (xy 141.748011 -272.776153)
			(xy 141.69749 -272.782287) (xy 141.646638 -272.780238) (xy 141.596774 -272.770058) (xy 141.549188 -272.752011)
			(xy 141.505114 -272.726565) (xy 141.465692 -272.694378) (xy 141.431944 -272.656284) (xy 141.404743 -272.61327)
			(xy 141.384795 -272.56645) (xy 141.372616 -272.517036) (xy 141.368521 -272.466308) (xy 141.06271 -272.466308)
			(xy 141.06222 -272.491297) (xy 141.054401 -272.54066) (xy 141.038957 -272.588192) (xy 141.016267 -272.632724)
			(xy 140.986891 -272.673157) (xy 140.951551 -272.708497) (xy 140.911118 -272.737873) (xy 140.866586 -272.760563)
			(xy 140.819054 -272.776007) (xy 140.769691 -272.783826) (xy 140.719713 -272.783826) (xy 140.67035 -272.776007)
			(xy 140.622818 -272.760563) (xy 140.578286 -272.737873) (xy 140.537853 -272.708497) (xy 140.502513 -272.673157)
			(xy 140.473137 -272.632724) (xy 140.450447 -272.588192) (xy 140.435003 -272.54066) (xy 140.427184 -272.491297)
			(xy 140.119867 -272.491297) (xy 140.119858 -272.491754) (xy 140.111694 -272.541988) (xy 140.095578 -272.590262)
			(xy 140.071927 -272.635325) (xy 140.041354 -272.676011) (xy 140.00465 -272.711266) (xy 139.962766 -272.740176)
			(xy 139.916787 -272.761993) (xy 139.867903 -272.776153) (xy 139.817382 -272.782287) (xy 139.76653 -272.780238)
			(xy 139.716666 -272.770058) (xy 139.66908 -272.752011) (xy 139.625006 -272.726565) (xy 139.585584 -272.694378)
			(xy 139.551836 -272.656284) (xy 139.524635 -272.61327) (xy 139.504687 -272.56645) (xy 139.492508 -272.517036)
			(xy 139.488413 -272.466308) (xy 139.182856 -272.466308) (xy 139.182366 -272.491297) (xy 139.174547 -272.54066)
			(xy 139.159103 -272.588192) (xy 139.136413 -272.632724) (xy 139.107037 -272.673157) (xy 139.071697 -272.708497)
			(xy 139.031264 -272.737873) (xy 138.986732 -272.760563) (xy 138.9392 -272.776007) (xy 138.889837 -272.783826)
			(xy 138.839859 -272.783826) (xy 138.790496 -272.776007) (xy 138.742964 -272.760563) (xy 138.698432 -272.737873)
			(xy 138.657999 -272.708497) (xy 138.622659 -272.673157) (xy 138.593283 -272.632724) (xy 138.570593 -272.588192)
			(xy 138.555149 -272.54066) (xy 138.54733 -272.491297) (xy 138.240013 -272.491297) (xy 138.240004 -272.491754)
			(xy 138.23184 -272.541988) (xy 138.215724 -272.590262) (xy 138.192073 -272.635325) (xy 138.1615 -272.676011)
			(xy 138.124796 -272.711266) (xy 138.082912 -272.740176) (xy 138.036933 -272.761993) (xy 137.988049 -272.776153)
			(xy 137.937528 -272.782287) (xy 137.886676 -272.780238) (xy 137.836812 -272.770058) (xy 137.789226 -272.752011)
			(xy 137.745152 -272.726565) (xy 137.70573 -272.694378) (xy 137.671982 -272.656284) (xy 137.644781 -272.61327)
			(xy 137.624833 -272.56645) (xy 137.612654 -272.517036) (xy 137.608559 -272.466308) (xy 137.302748 -272.466308)
			(xy 137.302258 -272.491297) (xy 137.294439 -272.54066) (xy 137.278995 -272.588192) (xy 137.256305 -272.632724)
			(xy 137.226929 -272.673157) (xy 137.191589 -272.708497) (xy 137.151156 -272.737873) (xy 137.106624 -272.760563)
			(xy 137.059092 -272.776007) (xy 137.009729 -272.783826) (xy 136.959751 -272.783826) (xy 136.910388 -272.776007)
			(xy 136.862856 -272.760563) (xy 136.818324 -272.737873) (xy 136.777891 -272.708497) (xy 136.742551 -272.673157)
			(xy 136.713175 -272.632724) (xy 136.690485 -272.588192) (xy 136.675041 -272.54066) (xy 136.667222 -272.491297)
			(xy 136.359905 -272.491297) (xy 136.359896 -272.491754) (xy 136.351732 -272.541988) (xy 136.335616 -272.590262)
			(xy 136.311965 -272.635325) (xy 136.281392 -272.676011) (xy 136.244688 -272.711266) (xy 136.202804 -272.740176)
			(xy 136.156825 -272.761993) (xy 136.107941 -272.776153) (xy 136.05742 -272.782287) (xy 136.006568 -272.780238)
			(xy 135.956704 -272.770058) (xy 135.909118 -272.752011) (xy 135.865044 -272.726565) (xy 135.825622 -272.694378)
			(xy 135.791874 -272.656284) (xy 135.764673 -272.61327) (xy 135.744725 -272.56645) (xy 135.732546 -272.517036)
			(xy 135.728451 -272.466308) (xy 135.420354 -272.466308) (xy 135.419842 -272.491754) (xy 135.411678 -272.541988)
			(xy 135.395562 -272.590262) (xy 135.371911 -272.635325) (xy 135.341338 -272.676011) (xy 135.304634 -272.711266)
			(xy 135.26275 -272.740176) (xy 135.216771 -272.761993) (xy 135.167887 -272.776153) (xy 135.117366 -272.782287)
			(xy 135.066514 -272.780238) (xy 135.01665 -272.770058) (xy 134.969064 -272.752011) (xy 134.92499 -272.726565)
			(xy 134.885568 -272.694378) (xy 134.85182 -272.656284) (xy 134.824619 -272.61327) (xy 134.804671 -272.56645)
			(xy 134.792492 -272.517036) (xy 134.788397 -272.466308) (xy 134.48284 -272.466308) (xy 134.48235 -272.491297)
			(xy 134.474531 -272.54066) (xy 134.459087 -272.588192) (xy 134.436397 -272.632724) (xy 134.407021 -272.673157)
			(xy 134.371681 -272.708497) (xy 134.331248 -272.737873) (xy 134.286716 -272.760563) (xy 134.239184 -272.776007)
			(xy 134.189821 -272.783826) (xy 134.139843 -272.783826) (xy 134.09048 -272.776007) (xy 134.042948 -272.760563)
			(xy 133.998416 -272.737873) (xy 133.957983 -272.708497) (xy 133.922643 -272.673157) (xy 133.893267 -272.632724)
			(xy 133.870577 -272.588192) (xy 133.855133 -272.54066) (xy 133.847314 -272.491297) (xy 133.539997 -272.491297)
			(xy 133.539988 -272.491754) (xy 133.531824 -272.541988) (xy 133.515708 -272.590262) (xy 133.492057 -272.635325)
			(xy 133.461484 -272.676011) (xy 133.42478 -272.711266) (xy 133.382896 -272.740176) (xy 133.336917 -272.761993)
			(xy 133.288033 -272.776153) (xy 133.237512 -272.782287) (xy 133.18666 -272.780238) (xy 133.136796 -272.770058)
			(xy 133.08921 -272.752011) (xy 133.045136 -272.726565) (xy 133.005714 -272.694378) (xy 132.971966 -272.656284)
			(xy 132.944765 -272.61327) (xy 132.924817 -272.56645) (xy 132.912638 -272.517036) (xy 132.908543 -272.466308)
			(xy 132.602732 -272.466308) (xy 132.602242 -272.491297) (xy 132.594423 -272.54066) (xy 132.578979 -272.588192)
			(xy 132.556289 -272.632724) (xy 132.526913 -272.673157) (xy 132.491573 -272.708497) (xy 132.45114 -272.737873)
			(xy 132.406608 -272.760563) (xy 132.359076 -272.776007) (xy 132.309713 -272.783826) (xy 132.259735 -272.783826)
			(xy 132.210372 -272.776007) (xy 132.16284 -272.760563) (xy 132.118308 -272.737873) (xy 132.077875 -272.708497)
			(xy 132.042535 -272.673157) (xy 132.013159 -272.632724) (xy 131.990469 -272.588192) (xy 131.975025 -272.54066)
			(xy 131.967206 -272.491297) (xy 131.659889 -272.491297) (xy 131.65988 -272.491754) (xy 131.651716 -272.541988)
			(xy 131.6356 -272.590262) (xy 131.611949 -272.635325) (xy 131.581376 -272.676011) (xy 131.544672 -272.711266)
			(xy 131.502788 -272.740176) (xy 131.456809 -272.761993) (xy 131.407925 -272.776153) (xy 131.357404 -272.782287)
			(xy 131.306552 -272.780238) (xy 131.256688 -272.770058) (xy 131.209102 -272.752011) (xy 131.165028 -272.726565)
			(xy 131.125606 -272.694378) (xy 131.091858 -272.656284) (xy 131.064657 -272.61327) (xy 131.044709 -272.56645)
			(xy 131.03253 -272.517036) (xy 131.028435 -272.466308) (xy 130.722878 -272.466308) (xy 130.722388 -272.491297)
			(xy 130.714569 -272.54066) (xy 130.699125 -272.588192) (xy 130.676435 -272.632724) (xy 130.647059 -272.673157)
			(xy 130.611719 -272.708497) (xy 130.571286 -272.737873) (xy 130.526754 -272.760563) (xy 130.479222 -272.776007)
			(xy 130.429859 -272.783826) (xy 130.379881 -272.783826) (xy 130.330518 -272.776007) (xy 130.282986 -272.760563)
			(xy 130.238454 -272.737873) (xy 130.198021 -272.708497) (xy 130.162681 -272.673157) (xy 130.133305 -272.632724)
			(xy 130.110615 -272.588192) (xy 130.095171 -272.54066) (xy 130.087352 -272.491297) (xy 129.780035 -272.491297)
			(xy 129.780026 -272.491754) (xy 129.771862 -272.541988) (xy 129.755746 -272.590262) (xy 129.732095 -272.635325)
			(xy 129.701522 -272.676011) (xy 129.664818 -272.711266) (xy 129.622934 -272.740176) (xy 129.576955 -272.761993)
			(xy 129.528071 -272.776153) (xy 129.47755 -272.782287) (xy 129.426698 -272.780238) (xy 129.376834 -272.770058)
			(xy 129.329248 -272.752011) (xy 129.285174 -272.726565) (xy 129.245752 -272.694378) (xy 129.212004 -272.656284)
			(xy 129.184803 -272.61327) (xy 129.164855 -272.56645) (xy 129.152676 -272.517036) (xy 129.148581 -272.466308)
			(xy 128.840484 -272.466308) (xy 128.839972 -272.491754) (xy 128.831808 -272.541988) (xy 128.815692 -272.590262)
			(xy 128.792041 -272.635325) (xy 128.761468 -272.676011) (xy 128.724764 -272.711266) (xy 128.68288 -272.740176)
			(xy 128.636901 -272.761993) (xy 128.588017 -272.776153) (xy 128.537496 -272.782287) (xy 128.486644 -272.780238)
			(xy 128.43678 -272.770058) (xy 128.389194 -272.752011) (xy 128.34512 -272.726565) (xy 128.305698 -272.694378)
			(xy 128.27195 -272.656284) (xy 128.244749 -272.61327) (xy 128.224801 -272.56645) (xy 128.212622 -272.517036)
			(xy 128.208527 -272.466308) (xy 127.902463 -272.466308) (xy 127.902463 -272.491308) (xy 127.894639 -272.540709)
			(xy 127.879184 -272.588277) (xy 127.856477 -272.632842) (xy 127.827079 -272.673306) (xy 127.791712 -272.708673)
			(xy 127.751249 -272.738073) (xy 127.706684 -272.760781) (xy 127.659116 -272.776237) (xy 127.609716 -272.784063)
			(xy 127.584708 -272.78457) (xy 127.55734 -272.784001) (xy 127.50341 -272.774635) (xy 127.451879 -272.756179)
			(xy 127.404267 -272.729177) (xy 127.361977 -272.694425) (xy 127.343662 -272.67408) (xy 127.343154 -272.673572)
			(xy 127.343154 -272.673318) (xy 127.337864 -272.66783) (xy 127.324818 -272.659961) (xy 127.3175 -272.657824)
			(xy 127.310134 -272.655792) (xy 127.29464 -272.656554) (xy 127.20066 -272.691352) (xy 127.200406 -272.691352)
			(xy 127.193204 -272.694324) (xy 127.180913 -272.703888) (xy 127.176276 -272.710148) (xy 127.171958 -272.716244)
			(xy 127.167386 -272.730976) (xy 127.167386 -272.921984) (xy 127.16803 -272.933964) (xy 127.178906 -272.955309)
			(xy 127.188214 -272.962878) (xy 127.196342 -272.966942) (xy 127.204978 -272.970498) (xy 127.229392 -272.978223)
			(xy 127.275561 -273.000362) (xy 127.317597 -273.029598) (xy 127.354418 -273.065179) (xy 127.385076 -273.106189)
			(xy 127.408782 -273.151574) (xy 127.424928 -273.200165) (xy 127.433096 -273.250712) (xy 127.433578 -273.276314)
			(xy 127.738627 -273.276314) (xy 127.742722 -273.225586) (xy 127.754901 -273.176172) (xy 127.774849 -273.129352)
			(xy 127.80205 -273.086338) (xy 127.835798 -273.048244) (xy 127.87522 -273.016057) (xy 127.919294 -272.990611)
			(xy 127.96688 -272.972564) (xy 128.016744 -272.962384) (xy 128.067596 -272.960335) (xy 128.118117 -272.966469)
			(xy 128.167001 -272.980629) (xy 128.21298 -273.002446) (xy 128.254864 -273.031356) (xy 128.291568 -273.066611)
			(xy 128.322141 -273.107297) (xy 128.345792 -273.15236) (xy 128.361908 -273.200634) (xy 128.370072 -273.250868)
			(xy 128.370584 -273.276314) (xy 128.370081 -273.301303) (xy 128.677144 -273.301303) (xy 128.677144 -273.251325)
			(xy 128.684963 -273.201962) (xy 128.700407 -273.15443) (xy 128.723097 -273.109898) (xy 128.752473 -273.069465)
			(xy 128.787813 -273.034125) (xy 128.828246 -273.004749) (xy 128.872778 -272.982059) (xy 128.92031 -272.966615)
			(xy 128.969673 -272.958796) (xy 129.019651 -272.958796) (xy 129.069014 -272.966615) (xy 129.116546 -272.982059)
			(xy 129.161078 -273.004749) (xy 129.201511 -273.034125) (xy 129.236851 -273.069465) (xy 129.266227 -273.109898)
			(xy 129.288917 -273.15443) (xy 129.304361 -273.201962) (xy 129.31218 -273.251325) (xy 129.31267 -273.276314)
			(xy 129.618481 -273.276314) (xy 129.622576 -273.225586) (xy 129.634755 -273.176172) (xy 129.654703 -273.129352)
			(xy 129.681904 -273.086338) (xy 129.715652 -273.048244) (xy 129.755074 -273.016057) (xy 129.799148 -272.990611)
			(xy 129.846734 -272.972564) (xy 129.896598 -272.962384) (xy 129.94745 -272.960335) (xy 129.997971 -272.966469)
			(xy 130.046855 -272.980629) (xy 130.092834 -273.002446) (xy 130.134718 -273.031356) (xy 130.171422 -273.066611)
			(xy 130.201995 -273.107297) (xy 130.225646 -273.15236) (xy 130.241762 -273.200634) (xy 130.249926 -273.250868)
			(xy 130.250438 -273.276314) (xy 131.498589 -273.276314) (xy 131.502684 -273.225586) (xy 131.514863 -273.176172)
			(xy 131.534811 -273.129352) (xy 131.562012 -273.086338) (xy 131.59576 -273.048244) (xy 131.635182 -273.016057)
			(xy 131.679256 -272.990611) (xy 131.726842 -272.972564) (xy 131.776706 -272.962384) (xy 131.827558 -272.960335)
			(xy 131.878079 -272.966469) (xy 131.926963 -272.980629) (xy 131.972942 -273.002446) (xy 132.014826 -273.031356)
			(xy 132.05153 -273.066611) (xy 132.082103 -273.107297) (xy 132.105754 -273.15236) (xy 132.12187 -273.200634)
			(xy 132.130034 -273.250868) (xy 132.130546 -273.276314) (xy 132.438643 -273.276314) (xy 132.442738 -273.225586)
			(xy 132.454917 -273.176172) (xy 132.474865 -273.129352) (xy 132.502066 -273.086338) (xy 132.535814 -273.048244)
			(xy 132.575236 -273.016057) (xy 132.61931 -272.990611) (xy 132.666896 -272.972564) (xy 132.71676 -272.962384)
			(xy 132.767612 -272.960335) (xy 132.818133 -272.966469) (xy 132.867017 -272.980629) (xy 132.912996 -273.002446)
			(xy 132.95488 -273.031356) (xy 132.991584 -273.066611) (xy 133.022157 -273.107297) (xy 133.045808 -273.15236)
			(xy 133.061924 -273.200634) (xy 133.070088 -273.250868) (xy 133.0706 -273.276314) (xy 133.070097 -273.301303)
			(xy 133.37716 -273.301303) (xy 133.37716 -273.251325) (xy 133.384979 -273.201962) (xy 133.400423 -273.15443)
			(xy 133.423113 -273.109898) (xy 133.452489 -273.069465) (xy 133.487829 -273.034125) (xy 133.528262 -273.004749)
			(xy 133.572794 -272.982059) (xy 133.620326 -272.966615) (xy 133.669689 -272.958796) (xy 133.719667 -272.958796)
			(xy 133.76903 -272.966615) (xy 133.816562 -272.982059) (xy 133.861094 -273.004749) (xy 133.901527 -273.034125)
			(xy 133.936867 -273.069465) (xy 133.966243 -273.109898) (xy 133.988933 -273.15443) (xy 134.004377 -273.201962)
			(xy 134.012196 -273.251325) (xy 134.012686 -273.276314) (xy 134.318497 -273.276314) (xy 134.322592 -273.225586)
			(xy 134.334771 -273.176172) (xy 134.354719 -273.129352) (xy 134.38192 -273.086338) (xy 134.415668 -273.048244)
			(xy 134.45509 -273.016057) (xy 134.499164 -272.990611) (xy 134.54675 -272.972564) (xy 134.596614 -272.962384)
			(xy 134.647466 -272.960335) (xy 134.697987 -272.966469) (xy 134.746871 -272.980629) (xy 134.79285 -273.002446)
			(xy 134.834734 -273.031356) (xy 134.871438 -273.066611) (xy 134.902011 -273.107297) (xy 134.925662 -273.15236)
			(xy 134.941778 -273.200634) (xy 134.949942 -273.250868) (xy 134.950454 -273.276314) (xy 134.949951 -273.301303)
			(xy 135.257268 -273.301303) (xy 135.257268 -273.251325) (xy 135.265087 -273.201962) (xy 135.280531 -273.15443)
			(xy 135.303221 -273.109898) (xy 135.332597 -273.069465) (xy 135.367937 -273.034125) (xy 135.40837 -273.004749)
			(xy 135.452902 -272.982059) (xy 135.500434 -272.966615) (xy 135.549797 -272.958796) (xy 135.599775 -272.958796)
			(xy 135.649138 -272.966615) (xy 135.69667 -272.982059) (xy 135.741202 -273.004749) (xy 135.781635 -273.034125)
			(xy 135.816975 -273.069465) (xy 135.846351 -273.109898) (xy 135.869041 -273.15443) (xy 135.884485 -273.201962)
			(xy 135.892304 -273.251325) (xy 135.892794 -273.276314) (xy 136.198605 -273.276314) (xy 136.2027 -273.225586)
			(xy 136.214879 -273.176172) (xy 136.234827 -273.129352) (xy 136.262028 -273.086338) (xy 136.295776 -273.048244)
			(xy 136.335198 -273.016057) (xy 136.379272 -272.990611) (xy 136.426858 -272.972564) (xy 136.476722 -272.962384)
			(xy 136.527574 -272.960335) (xy 136.578095 -272.966469) (xy 136.626979 -272.980629) (xy 136.672958 -273.002446)
			(xy 136.714842 -273.031356) (xy 136.751546 -273.066611) (xy 136.782119 -273.107297) (xy 136.80577 -273.15236)
			(xy 136.821886 -273.200634) (xy 136.83005 -273.250868) (xy 136.830562 -273.276314) (xy 138.078459 -273.276314)
			(xy 138.082554 -273.225586) (xy 138.094733 -273.176172) (xy 138.114681 -273.129352) (xy 138.141882 -273.086338)
			(xy 138.17563 -273.048244) (xy 138.215052 -273.016057) (xy 138.259126 -272.990611) (xy 138.306712 -272.972564)
			(xy 138.356576 -272.962384) (xy 138.407428 -272.960335) (xy 138.457949 -272.966469) (xy 138.506833 -272.980629)
			(xy 138.552812 -273.002446) (xy 138.594696 -273.031356) (xy 138.6314 -273.066611) (xy 138.661973 -273.107297)
			(xy 138.685624 -273.15236) (xy 138.70174 -273.200634) (xy 138.709904 -273.250868) (xy 138.710416 -273.276314)
			(xy 139.018513 -273.276314) (xy 139.022608 -273.225586) (xy 139.034787 -273.176172) (xy 139.054735 -273.129352)
			(xy 139.081936 -273.086338) (xy 139.115684 -273.048244) (xy 139.155106 -273.016057) (xy 139.19918 -272.990611)
			(xy 139.246766 -272.972564) (xy 139.29663 -272.962384) (xy 139.347482 -272.960335) (xy 139.398003 -272.966469)
			(xy 139.446887 -272.980629) (xy 139.492866 -273.002446) (xy 139.53475 -273.031356) (xy 139.571454 -273.066611)
			(xy 139.602027 -273.107297) (xy 139.625678 -273.15236) (xy 139.641794 -273.200634) (xy 139.649958 -273.250868)
			(xy 139.65047 -273.276314) (xy 139.649967 -273.301303) (xy 139.957284 -273.301303) (xy 139.957284 -273.251325)
			(xy 139.965103 -273.201962) (xy 139.980547 -273.15443) (xy 140.003237 -273.109898) (xy 140.032613 -273.069465)
			(xy 140.067953 -273.034125) (xy 140.108386 -273.004749) (xy 140.152918 -272.982059) (xy 140.20045 -272.966615)
			(xy 140.249813 -272.958796) (xy 140.299791 -272.958796) (xy 140.349154 -272.966615) (xy 140.396686 -272.982059)
			(xy 140.441218 -273.004749) (xy 140.481651 -273.034125) (xy 140.516991 -273.069465) (xy 140.546367 -273.109898)
			(xy 140.569057 -273.15443) (xy 140.584501 -273.201962) (xy 140.59232 -273.251325) (xy 140.59281 -273.276314)
			(xy 140.898621 -273.276314) (xy 140.902716 -273.225586) (xy 140.914895 -273.176172) (xy 140.934843 -273.129352)
			(xy 140.962044 -273.086338) (xy 140.995792 -273.048244) (xy 141.035214 -273.016057) (xy 141.079288 -272.990611)
			(xy 141.126874 -272.972564) (xy 141.176738 -272.962384) (xy 141.22759 -272.960335) (xy 141.278111 -272.966469)
			(xy 141.326995 -272.980629) (xy 141.372974 -273.002446) (xy 141.414858 -273.031356) (xy 141.451562 -273.066611)
			(xy 141.482135 -273.107297) (xy 141.505786 -273.15236) (xy 141.521902 -273.200634) (xy 141.530066 -273.250868)
			(xy 141.530578 -273.276314) (xy 141.530075 -273.301303) (xy 141.837138 -273.301303) (xy 141.837138 -273.251325)
			(xy 141.844957 -273.201962) (xy 141.860401 -273.15443) (xy 141.883091 -273.109898) (xy 141.912467 -273.069465)
			(xy 141.947807 -273.034125) (xy 141.98824 -273.004749) (xy 142.032772 -272.982059) (xy 142.080304 -272.966615)
			(xy 142.129667 -272.958796) (xy 142.179645 -272.958796) (xy 142.229008 -272.966615) (xy 142.27654 -272.982059)
			(xy 142.321072 -273.004749) (xy 142.361505 -273.034125) (xy 142.396845 -273.069465) (xy 142.426221 -273.109898)
			(xy 142.448911 -273.15443) (xy 142.464355 -273.201962) (xy 142.472174 -273.251325) (xy 142.472664 -273.276314)
			(xy 142.778475 -273.276314) (xy 142.78257 -273.225586) (xy 142.794749 -273.176172) (xy 142.814697 -273.129352)
			(xy 142.841898 -273.086338) (xy 142.875646 -273.048244) (xy 142.915068 -273.016057) (xy 142.959142 -272.990611)
			(xy 143.006728 -272.972564) (xy 143.056592 -272.962384) (xy 143.107444 -272.960335) (xy 143.157965 -272.966469)
			(xy 143.206849 -272.980629) (xy 143.252828 -273.002446) (xy 143.294712 -273.031356) (xy 143.331416 -273.066611)
			(xy 143.361989 -273.107297) (xy 143.38564 -273.15236) (xy 143.401756 -273.200634) (xy 143.40992 -273.250868)
			(xy 143.410432 -273.276314) (xy 143.40992 -273.30176) (xy 143.401756 -273.351994) (xy 143.38564 -273.400268)
			(xy 143.361989 -273.445331) (xy 143.331416 -273.486017) (xy 143.294712 -273.521272) (xy 143.252828 -273.550182)
			(xy 143.206849 -273.571999) (xy 143.157965 -273.586159) (xy 143.107444 -273.592293) (xy 143.056592 -273.590244)
			(xy 143.006728 -273.580064) (xy 142.959142 -273.562017) (xy 142.915068 -273.536571) (xy 142.875646 -273.504384)
			(xy 142.841898 -273.46629) (xy 142.814697 -273.423276) (xy 142.794749 -273.376456) (xy 142.78257 -273.327042)
			(xy 142.778475 -273.276314) (xy 142.472664 -273.276314) (xy 142.472174 -273.301303) (xy 142.464355 -273.350666)
			(xy 142.448911 -273.398198) (xy 142.426221 -273.44273) (xy 142.396845 -273.483163) (xy 142.361505 -273.518503)
			(xy 142.321072 -273.547879) (xy 142.27654 -273.570569) (xy 142.229008 -273.586013) (xy 142.179645 -273.593832)
			(xy 142.129667 -273.593832) (xy 142.080304 -273.586013) (xy 142.032772 -273.570569) (xy 141.98824 -273.547879)
			(xy 141.947807 -273.518503) (xy 141.912467 -273.483163) (xy 141.883091 -273.44273) (xy 141.860401 -273.398198)
			(xy 141.844957 -273.350666) (xy 141.837138 -273.301303) (xy 141.530075 -273.301303) (xy 141.530066 -273.30176)
			(xy 141.521902 -273.351994) (xy 141.505786 -273.400268) (xy 141.482135 -273.445331) (xy 141.451562 -273.486017)
			(xy 141.414858 -273.521272) (xy 141.372974 -273.550182) (xy 141.326995 -273.571999) (xy 141.278111 -273.586159)
			(xy 141.22759 -273.592293) (xy 141.176738 -273.590244) (xy 141.126874 -273.580064) (xy 141.079288 -273.562017)
			(xy 141.035214 -273.536571) (xy 140.995792 -273.504384) (xy 140.962044 -273.46629) (xy 140.934843 -273.423276)
			(xy 140.914895 -273.376456) (xy 140.902716 -273.327042) (xy 140.898621 -273.276314) (xy 140.59281 -273.276314)
			(xy 140.59232 -273.301303) (xy 140.584501 -273.350666) (xy 140.569057 -273.398198) (xy 140.546367 -273.44273)
			(xy 140.516991 -273.483163) (xy 140.481651 -273.518503) (xy 140.441218 -273.547879) (xy 140.396686 -273.570569)
			(xy 140.349154 -273.586013) (xy 140.299791 -273.593832) (xy 140.249813 -273.593832) (xy 140.20045 -273.586013)
			(xy 140.152918 -273.570569) (xy 140.108386 -273.547879) (xy 140.067953 -273.518503) (xy 140.032613 -273.483163)
			(xy 140.003237 -273.44273) (xy 139.980547 -273.398198) (xy 139.965103 -273.350666) (xy 139.957284 -273.301303)
			(xy 139.649967 -273.301303) (xy 139.649958 -273.30176) (xy 139.641794 -273.351994) (xy 139.625678 -273.400268)
			(xy 139.602027 -273.445331) (xy 139.571454 -273.486017) (xy 139.53475 -273.521272) (xy 139.492866 -273.550182)
			(xy 139.446887 -273.571999) (xy 139.398003 -273.586159) (xy 139.347482 -273.592293) (xy 139.29663 -273.590244)
			(xy 139.246766 -273.580064) (xy 139.19918 -273.562017) (xy 139.155106 -273.536571) (xy 139.115684 -273.504384)
			(xy 139.081936 -273.46629) (xy 139.054735 -273.423276) (xy 139.034787 -273.376456) (xy 139.022608 -273.327042)
			(xy 139.018513 -273.276314) (xy 138.710416 -273.276314) (xy 138.709904 -273.30176) (xy 138.70174 -273.351994)
			(xy 138.685624 -273.400268) (xy 138.661973 -273.445331) (xy 138.6314 -273.486017) (xy 138.594696 -273.521272)
			(xy 138.552812 -273.550182) (xy 138.506833 -273.571999) (xy 138.457949 -273.586159) (xy 138.407428 -273.592293)
			(xy 138.356576 -273.590244) (xy 138.306712 -273.580064) (xy 138.259126 -273.562017) (xy 138.215052 -273.536571)
			(xy 138.17563 -273.504384) (xy 138.141882 -273.46629) (xy 138.114681 -273.423276) (xy 138.094733 -273.376456)
			(xy 138.082554 -273.327042) (xy 138.078459 -273.276314) (xy 136.830562 -273.276314) (xy 136.83005 -273.30176)
			(xy 136.821886 -273.351994) (xy 136.80577 -273.400268) (xy 136.782119 -273.445331) (xy 136.751546 -273.486017)
			(xy 136.714842 -273.521272) (xy 136.672958 -273.550182) (xy 136.626979 -273.571999) (xy 136.578095 -273.586159)
			(xy 136.527574 -273.592293) (xy 136.476722 -273.590244) (xy 136.426858 -273.580064) (xy 136.379272 -273.562017)
			(xy 136.335198 -273.536571) (xy 136.295776 -273.504384) (xy 136.262028 -273.46629) (xy 136.234827 -273.423276)
			(xy 136.214879 -273.376456) (xy 136.2027 -273.327042) (xy 136.198605 -273.276314) (xy 135.892794 -273.276314)
			(xy 135.892304 -273.301303) (xy 135.884485 -273.350666) (xy 135.869041 -273.398198) (xy 135.846351 -273.44273)
			(xy 135.816975 -273.483163) (xy 135.781635 -273.518503) (xy 135.741202 -273.547879) (xy 135.69667 -273.570569)
			(xy 135.649138 -273.586013) (xy 135.599775 -273.593832) (xy 135.549797 -273.593832) (xy 135.500434 -273.586013)
			(xy 135.452902 -273.570569) (xy 135.40837 -273.547879) (xy 135.367937 -273.518503) (xy 135.332597 -273.483163)
			(xy 135.303221 -273.44273) (xy 135.280531 -273.398198) (xy 135.265087 -273.350666) (xy 135.257268 -273.301303)
			(xy 134.949951 -273.301303) (xy 134.949942 -273.30176) (xy 134.941778 -273.351994) (xy 134.925662 -273.400268)
			(xy 134.902011 -273.445331) (xy 134.871438 -273.486017) (xy 134.834734 -273.521272) (xy 134.79285 -273.550182)
			(xy 134.746871 -273.571999) (xy 134.697987 -273.586159) (xy 134.647466 -273.592293) (xy 134.596614 -273.590244)
			(xy 134.54675 -273.580064) (xy 134.499164 -273.562017) (xy 134.45509 -273.536571) (xy 134.415668 -273.504384)
			(xy 134.38192 -273.46629) (xy 134.354719 -273.423276) (xy 134.334771 -273.376456) (xy 134.322592 -273.327042)
			(xy 134.318497 -273.276314) (xy 134.012686 -273.276314) (xy 134.012196 -273.301303) (xy 134.004377 -273.350666)
			(xy 133.988933 -273.398198) (xy 133.966243 -273.44273) (xy 133.936867 -273.483163) (xy 133.901527 -273.518503)
			(xy 133.861094 -273.547879) (xy 133.816562 -273.570569) (xy 133.76903 -273.586013) (xy 133.719667 -273.593832)
			(xy 133.669689 -273.593832) (xy 133.620326 -273.586013) (xy 133.572794 -273.570569) (xy 133.528262 -273.547879)
			(xy 133.487829 -273.518503) (xy 133.452489 -273.483163) (xy 133.423113 -273.44273) (xy 133.400423 -273.398198)
			(xy 133.384979 -273.350666) (xy 133.37716 -273.301303) (xy 133.070097 -273.301303) (xy 133.070088 -273.30176)
			(xy 133.061924 -273.351994) (xy 133.045808 -273.400268) (xy 133.022157 -273.445331) (xy 132.991584 -273.486017)
			(xy 132.95488 -273.521272) (xy 132.912996 -273.550182) (xy 132.867017 -273.571999) (xy 132.818133 -273.586159)
			(xy 132.767612 -273.592293) (xy 132.71676 -273.590244) (xy 132.666896 -273.580064) (xy 132.61931 -273.562017)
			(xy 132.575236 -273.536571) (xy 132.535814 -273.504384) (xy 132.502066 -273.46629) (xy 132.474865 -273.423276)
			(xy 132.454917 -273.376456) (xy 132.442738 -273.327042) (xy 132.438643 -273.276314) (xy 132.130546 -273.276314)
			(xy 132.130034 -273.30176) (xy 132.12187 -273.351994) (xy 132.105754 -273.400268) (xy 132.082103 -273.445331)
			(xy 132.05153 -273.486017) (xy 132.014826 -273.521272) (xy 131.972942 -273.550182) (xy 131.926963 -273.571999)
			(xy 131.878079 -273.586159) (xy 131.827558 -273.592293) (xy 131.776706 -273.590244) (xy 131.726842 -273.580064)
			(xy 131.679256 -273.562017) (xy 131.635182 -273.536571) (xy 131.59576 -273.504384) (xy 131.562012 -273.46629)
			(xy 131.534811 -273.423276) (xy 131.514863 -273.376456) (xy 131.502684 -273.327042) (xy 131.498589 -273.276314)
			(xy 130.250438 -273.276314) (xy 130.249926 -273.30176) (xy 130.241762 -273.351994) (xy 130.225646 -273.400268)
			(xy 130.201995 -273.445331) (xy 130.171422 -273.486017) (xy 130.134718 -273.521272) (xy 130.092834 -273.550182)
			(xy 130.046855 -273.571999) (xy 129.997971 -273.586159) (xy 129.94745 -273.592293) (xy 129.896598 -273.590244)
			(xy 129.846734 -273.580064) (xy 129.799148 -273.562017) (xy 129.755074 -273.536571) (xy 129.715652 -273.504384)
			(xy 129.681904 -273.46629) (xy 129.654703 -273.423276) (xy 129.634755 -273.376456) (xy 129.622576 -273.327042)
			(xy 129.618481 -273.276314) (xy 129.31267 -273.276314) (xy 129.31218 -273.301303) (xy 129.304361 -273.350666)
			(xy 129.288917 -273.398198) (xy 129.266227 -273.44273) (xy 129.236851 -273.483163) (xy 129.201511 -273.518503)
			(xy 129.161078 -273.547879) (xy 129.116546 -273.570569) (xy 129.069014 -273.586013) (xy 129.019651 -273.593832)
			(xy 128.969673 -273.593832) (xy 128.92031 -273.586013) (xy 128.872778 -273.570569) (xy 128.828246 -273.547879)
			(xy 128.787813 -273.518503) (xy 128.752473 -273.483163) (xy 128.723097 -273.44273) (xy 128.700407 -273.398198)
			(xy 128.684963 -273.350666) (xy 128.677144 -273.301303) (xy 128.370081 -273.301303) (xy 128.370072 -273.30176)
			(xy 128.361908 -273.351994) (xy 128.345792 -273.400268) (xy 128.322141 -273.445331) (xy 128.291568 -273.486017)
			(xy 128.254864 -273.521272) (xy 128.21298 -273.550182) (xy 128.167001 -273.571999) (xy 128.118117 -273.586159)
			(xy 128.067596 -273.592293) (xy 128.016744 -273.590244) (xy 127.96688 -273.580064) (xy 127.919294 -273.562017)
			(xy 127.87522 -273.536571) (xy 127.835798 -273.504384) (xy 127.80205 -273.46629) (xy 127.774849 -273.423276)
			(xy 127.754901 -273.376456) (xy 127.742722 -273.327042) (xy 127.738627 -273.276314) (xy 127.433578 -273.276314)
			(xy 127.433051 -273.302374) (xy 127.424559 -273.353797) (xy 127.407821 -273.403155) (xy 127.383281 -273.449136)
			(xy 127.351592 -273.490515) (xy 127.313597 -273.526192) (xy 127.270308 -273.555218) (xy 127.222876 -273.57682)
			(xy 127.197866 -273.584162) (xy 127.189038 -273.588521) (xy 127.175304 -273.602603) (xy 127.167863 -273.62081)
			(xy 127.167386 -273.630644) (xy 127.167386 -274.08632) (xy 128.208527 -274.08632) (xy 128.212622 -274.035592)
			(xy 128.224801 -273.986178) (xy 128.244749 -273.939358) (xy 128.27195 -273.896344) (xy 128.305698 -273.85825)
			(xy 128.34512 -273.826063) (xy 128.389194 -273.800617) (xy 128.43678 -273.78257) (xy 128.486644 -273.77239)
			(xy 128.537496 -273.770341) (xy 128.588017 -273.776475) (xy 128.636901 -273.790635) (xy 128.68288 -273.812452)
			(xy 128.724764 -273.841362) (xy 128.761468 -273.876617) (xy 128.792041 -273.917303) (xy 128.815692 -273.962366)
			(xy 128.831808 -274.01064) (xy 128.839972 -274.060874) (xy 128.840484 -274.08632) (xy 129.148581 -274.08632)
			(xy 129.152676 -274.035592) (xy 129.164855 -273.986178) (xy 129.184803 -273.939358) (xy 129.212004 -273.896344)
			(xy 129.245752 -273.85825) (xy 129.285174 -273.826063) (xy 129.329248 -273.800617) (xy 129.376834 -273.78257)
			(xy 129.426698 -273.77239) (xy 129.47755 -273.770341) (xy 129.528071 -273.776475) (xy 129.576955 -273.790635)
			(xy 129.622934 -273.812452) (xy 129.664818 -273.841362) (xy 129.701522 -273.876617) (xy 129.732095 -273.917303)
			(xy 129.755746 -273.962366) (xy 129.771862 -274.01064) (xy 129.780026 -274.060874) (xy 129.780538 -274.08632)
			(xy 129.780035 -274.111309) (xy 130.087352 -274.111309) (xy 130.087352 -274.061331) (xy 130.095171 -274.011968)
			(xy 130.110615 -273.964436) (xy 130.133305 -273.919904) (xy 130.162681 -273.879471) (xy 130.198021 -273.844131)
			(xy 130.238454 -273.814755) (xy 130.282986 -273.792065) (xy 130.330518 -273.776621) (xy 130.379881 -273.768802)
			(xy 130.429859 -273.768802) (xy 130.479222 -273.776621) (xy 130.526754 -273.792065) (xy 130.571286 -273.814755)
			(xy 130.611719 -273.844131) (xy 130.647059 -273.879471) (xy 130.676435 -273.919904) (xy 130.699125 -273.964436)
			(xy 130.714569 -274.011968) (xy 130.722388 -274.061331) (xy 130.722878 -274.08632) (xy 131.028435 -274.08632)
			(xy 131.03253 -274.035592) (xy 131.044709 -273.986178) (xy 131.064657 -273.939358) (xy 131.091858 -273.896344)
			(xy 131.125606 -273.85825) (xy 131.165028 -273.826063) (xy 131.209102 -273.800617) (xy 131.256688 -273.78257)
			(xy 131.306552 -273.77239) (xy 131.357404 -273.770341) (xy 131.407925 -273.776475) (xy 131.456809 -273.790635)
			(xy 131.502788 -273.812452) (xy 131.544672 -273.841362) (xy 131.581376 -273.876617) (xy 131.611949 -273.917303)
			(xy 131.6356 -273.962366) (xy 131.651716 -274.01064) (xy 131.65988 -274.060874) (xy 131.660392 -274.08632)
			(xy 131.659889 -274.111309) (xy 131.967206 -274.111309) (xy 131.967206 -274.061331) (xy 131.975025 -274.011968)
			(xy 131.990469 -273.964436) (xy 132.013159 -273.919904) (xy 132.042535 -273.879471) (xy 132.077875 -273.844131)
			(xy 132.118308 -273.814755) (xy 132.16284 -273.792065) (xy 132.210372 -273.776621) (xy 132.259735 -273.768802)
			(xy 132.309713 -273.768802) (xy 132.359076 -273.776621) (xy 132.406608 -273.792065) (xy 132.45114 -273.814755)
			(xy 132.491573 -273.844131) (xy 132.526913 -273.879471) (xy 132.556289 -273.919904) (xy 132.578979 -273.964436)
			(xy 132.594423 -274.011968) (xy 132.602242 -274.061331) (xy 132.602732 -274.08632) (xy 132.908543 -274.08632)
			(xy 132.912638 -274.035592) (xy 132.924817 -273.986178) (xy 132.944765 -273.939358) (xy 132.971966 -273.896344)
			(xy 133.005714 -273.85825) (xy 133.045136 -273.826063) (xy 133.08921 -273.800617) (xy 133.136796 -273.78257)
			(xy 133.18666 -273.77239) (xy 133.237512 -273.770341) (xy 133.288033 -273.776475) (xy 133.336917 -273.790635)
			(xy 133.382896 -273.812452) (xy 133.42478 -273.841362) (xy 133.461484 -273.876617) (xy 133.492057 -273.917303)
			(xy 133.515708 -273.962366) (xy 133.531824 -274.01064) (xy 133.539988 -274.060874) (xy 133.5405 -274.08632)
			(xy 133.539997 -274.111309) (xy 133.847314 -274.111309) (xy 133.847314 -274.061331) (xy 133.855133 -274.011968)
			(xy 133.870577 -273.964436) (xy 133.893267 -273.919904) (xy 133.922643 -273.879471) (xy 133.957983 -273.844131)
			(xy 133.998416 -273.814755) (xy 134.042948 -273.792065) (xy 134.09048 -273.776621) (xy 134.139843 -273.768802)
			(xy 134.189821 -273.768802) (xy 134.239184 -273.776621) (xy 134.286716 -273.792065) (xy 134.331248 -273.814755)
			(xy 134.371681 -273.844131) (xy 134.407021 -273.879471) (xy 134.436397 -273.919904) (xy 134.459087 -273.964436)
			(xy 134.474531 -274.011968) (xy 134.48235 -274.061331) (xy 134.48284 -274.08632) (xy 134.788397 -274.08632)
			(xy 134.792492 -274.035592) (xy 134.804671 -273.986178) (xy 134.824619 -273.939358) (xy 134.85182 -273.896344)
			(xy 134.885568 -273.85825) (xy 134.92499 -273.826063) (xy 134.969064 -273.800617) (xy 135.01665 -273.78257)
			(xy 135.066514 -273.77239) (xy 135.117366 -273.770341) (xy 135.167887 -273.776475) (xy 135.216771 -273.790635)
			(xy 135.26275 -273.812452) (xy 135.304634 -273.841362) (xy 135.341338 -273.876617) (xy 135.371911 -273.917303)
			(xy 135.395562 -273.962366) (xy 135.411678 -274.01064) (xy 135.419842 -274.060874) (xy 135.420354 -274.08632)
			(xy 135.728451 -274.08632) (xy 135.732546 -274.035592) (xy 135.744725 -273.986178) (xy 135.764673 -273.939358)
			(xy 135.791874 -273.896344) (xy 135.825622 -273.85825) (xy 135.865044 -273.826063) (xy 135.909118 -273.800617)
			(xy 135.956704 -273.78257) (xy 136.006568 -273.77239) (xy 136.05742 -273.770341) (xy 136.107941 -273.776475)
			(xy 136.156825 -273.790635) (xy 136.202804 -273.812452) (xy 136.244688 -273.841362) (xy 136.281392 -273.876617)
			(xy 136.311965 -273.917303) (xy 136.335616 -273.962366) (xy 136.351732 -274.01064) (xy 136.359896 -274.060874)
			(xy 136.360408 -274.08632) (xy 136.359905 -274.111309) (xy 136.667222 -274.111309) (xy 136.667222 -274.061331)
			(xy 136.675041 -274.011968) (xy 136.690485 -273.964436) (xy 136.713175 -273.919904) (xy 136.742551 -273.879471)
			(xy 136.777891 -273.844131) (xy 136.818324 -273.814755) (xy 136.862856 -273.792065) (xy 136.910388 -273.776621)
			(xy 136.959751 -273.768802) (xy 137.009729 -273.768802) (xy 137.059092 -273.776621) (xy 137.106624 -273.792065)
			(xy 137.151156 -273.814755) (xy 137.191589 -273.844131) (xy 137.226929 -273.879471) (xy 137.256305 -273.919904)
			(xy 137.278995 -273.964436) (xy 137.294439 -274.011968) (xy 137.302258 -274.061331) (xy 137.302748 -274.08632)
			(xy 137.608559 -274.08632) (xy 137.612654 -274.035592) (xy 137.624833 -273.986178) (xy 137.644781 -273.939358)
			(xy 137.671982 -273.896344) (xy 137.70573 -273.85825) (xy 137.745152 -273.826063) (xy 137.789226 -273.800617)
			(xy 137.836812 -273.78257) (xy 137.886676 -273.77239) (xy 137.937528 -273.770341) (xy 137.988049 -273.776475)
			(xy 138.036933 -273.790635) (xy 138.082912 -273.812452) (xy 138.124796 -273.841362) (xy 138.1615 -273.876617)
			(xy 138.192073 -273.917303) (xy 138.215724 -273.962366) (xy 138.23184 -274.01064) (xy 138.240004 -274.060874)
			(xy 138.240516 -274.08632) (xy 138.240013 -274.111309) (xy 138.54733 -274.111309) (xy 138.54733 -274.061331)
			(xy 138.555149 -274.011968) (xy 138.570593 -273.964436) (xy 138.593283 -273.919904) (xy 138.622659 -273.879471)
			(xy 138.657999 -273.844131) (xy 138.698432 -273.814755) (xy 138.742964 -273.792065) (xy 138.790496 -273.776621)
			(xy 138.839859 -273.768802) (xy 138.889837 -273.768802) (xy 138.9392 -273.776621) (xy 138.986732 -273.792065)
			(xy 139.031264 -273.814755) (xy 139.071697 -273.844131) (xy 139.107037 -273.879471) (xy 139.136413 -273.919904)
			(xy 139.159103 -273.964436) (xy 139.174547 -274.011968) (xy 139.182366 -274.061331) (xy 139.182856 -274.08632)
			(xy 139.488413 -274.08632) (xy 139.492508 -274.035592) (xy 139.504687 -273.986178) (xy 139.524635 -273.939358)
			(xy 139.551836 -273.896344) (xy 139.585584 -273.85825) (xy 139.625006 -273.826063) (xy 139.66908 -273.800617)
			(xy 139.716666 -273.78257) (xy 139.76653 -273.77239) (xy 139.817382 -273.770341) (xy 139.867903 -273.776475)
			(xy 139.916787 -273.790635) (xy 139.962766 -273.812452) (xy 140.00465 -273.841362) (xy 140.041354 -273.876617)
			(xy 140.071927 -273.917303) (xy 140.095578 -273.962366) (xy 140.111694 -274.01064) (xy 140.119858 -274.060874)
			(xy 140.12037 -274.08632) (xy 140.119867 -274.111309) (xy 140.427184 -274.111309) (xy 140.427184 -274.061331)
			(xy 140.435003 -274.011968) (xy 140.450447 -273.964436) (xy 140.473137 -273.919904) (xy 140.502513 -273.879471)
			(xy 140.537853 -273.844131) (xy 140.578286 -273.814755) (xy 140.622818 -273.792065) (xy 140.67035 -273.776621)
			(xy 140.719713 -273.768802) (xy 140.769691 -273.768802) (xy 140.819054 -273.776621) (xy 140.866586 -273.792065)
			(xy 140.911118 -273.814755) (xy 140.951551 -273.844131) (xy 140.986891 -273.879471) (xy 141.016267 -273.919904)
			(xy 141.038957 -273.964436) (xy 141.054401 -274.011968) (xy 141.06222 -274.061331) (xy 141.06271 -274.08632)
			(xy 141.368521 -274.08632) (xy 141.372616 -274.035592) (xy 141.384795 -273.986178) (xy 141.404743 -273.939358)
			(xy 141.431944 -273.896344) (xy 141.465692 -273.85825) (xy 141.505114 -273.826063) (xy 141.549188 -273.800617)
			(xy 141.596774 -273.78257) (xy 141.646638 -273.77239) (xy 141.69749 -273.770341) (xy 141.748011 -273.776475)
			(xy 141.796895 -273.790635) (xy 141.842874 -273.812452) (xy 141.884758 -273.841362) (xy 141.921462 -273.876617)
			(xy 141.952035 -273.917303) (xy 141.975686 -273.962366) (xy 141.991802 -274.01064) (xy 141.999966 -274.060874)
			(xy 142.000478 -274.08632) (xy 142.308575 -274.08632) (xy 142.31267 -274.035592) (xy 142.324849 -273.986178)
			(xy 142.344797 -273.939358) (xy 142.371998 -273.896344) (xy 142.405746 -273.85825) (xy 142.445168 -273.826063)
			(xy 142.489242 -273.800617) (xy 142.536828 -273.78257) (xy 142.586692 -273.77239) (xy 142.637544 -273.770341)
			(xy 142.688065 -273.776475) (xy 142.736949 -273.790635) (xy 142.782928 -273.812452) (xy 142.824812 -273.841362)
			(xy 142.861516 -273.876617) (xy 142.892089 -273.917303) (xy 142.91574 -273.962366) (xy 142.931856 -274.01064)
			(xy 142.94002 -274.060874) (xy 142.940532 -274.08632) (xy 142.940029 -274.111309) (xy 143.247092 -274.111309)
			(xy 143.247092 -274.061331) (xy 143.254911 -274.011968) (xy 143.270355 -273.964436) (xy 143.293045 -273.919904)
			(xy 143.322421 -273.879471) (xy 143.357761 -273.844131) (xy 143.398194 -273.814755) (xy 143.442726 -273.792065)
			(xy 143.490258 -273.776621) (xy 143.539621 -273.768802) (xy 143.589599 -273.768802) (xy 143.638962 -273.776621)
			(xy 143.686494 -273.792065) (xy 143.731026 -273.814755) (xy 143.771459 -273.844131) (xy 143.806799 -273.879471)
			(xy 143.836175 -273.919904) (xy 143.858865 -273.964436) (xy 143.874309 -274.011968) (xy 143.882128 -274.061331)
			(xy 143.882618 -274.08632) (xy 143.882128 -274.111309) (xy 143.874309 -274.160672) (xy 143.858865 -274.208204)
			(xy 143.836175 -274.252736) (xy 143.806799 -274.293169) (xy 143.771459 -274.328509) (xy 143.731026 -274.357885)
			(xy 143.686494 -274.380575) (xy 143.638962 -274.396019) (xy 143.589599 -274.403838) (xy 143.539621 -274.403838)
			(xy 143.490258 -274.396019) (xy 143.442726 -274.380575) (xy 143.398194 -274.357885) (xy 143.357761 -274.328509)
			(xy 143.322421 -274.293169) (xy 143.293045 -274.252736) (xy 143.270355 -274.208204) (xy 143.254911 -274.160672)
			(xy 143.247092 -274.111309) (xy 142.940029 -274.111309) (xy 142.94002 -274.111766) (xy 142.931856 -274.162)
			(xy 142.91574 -274.210274) (xy 142.892089 -274.255337) (xy 142.861516 -274.296023) (xy 142.824812 -274.331278)
			(xy 142.782928 -274.360188) (xy 142.736949 -274.382005) (xy 142.688065 -274.396165) (xy 142.637544 -274.402299)
			(xy 142.586692 -274.40025) (xy 142.536828 -274.39007) (xy 142.489242 -274.372023) (xy 142.445168 -274.346577)
			(xy 142.405746 -274.31439) (xy 142.371998 -274.276296) (xy 142.344797 -274.233282) (xy 142.324849 -274.186462)
			(xy 142.31267 -274.137048) (xy 142.308575 -274.08632) (xy 142.000478 -274.08632) (xy 141.999966 -274.111766)
			(xy 141.991802 -274.162) (xy 141.975686 -274.210274) (xy 141.952035 -274.255337) (xy 141.921462 -274.296023)
			(xy 141.884758 -274.331278) (xy 141.842874 -274.360188) (xy 141.796895 -274.382005) (xy 141.748011 -274.396165)
			(xy 141.69749 -274.402299) (xy 141.646638 -274.40025) (xy 141.596774 -274.39007) (xy 141.549188 -274.372023)
			(xy 141.505114 -274.346577) (xy 141.465692 -274.31439) (xy 141.431944 -274.276296) (xy 141.404743 -274.233282)
			(xy 141.384795 -274.186462) (xy 141.372616 -274.137048) (xy 141.368521 -274.08632) (xy 141.06271 -274.08632)
			(xy 141.06222 -274.111309) (xy 141.054401 -274.160672) (xy 141.038957 -274.208204) (xy 141.016267 -274.252736)
			(xy 140.986891 -274.293169) (xy 140.951551 -274.328509) (xy 140.911118 -274.357885) (xy 140.866586 -274.380575)
			(xy 140.819054 -274.396019) (xy 140.769691 -274.403838) (xy 140.719713 -274.403838) (xy 140.67035 -274.396019)
			(xy 140.622818 -274.380575) (xy 140.578286 -274.357885) (xy 140.537853 -274.328509) (xy 140.502513 -274.293169)
			(xy 140.473137 -274.252736) (xy 140.450447 -274.208204) (xy 140.435003 -274.160672) (xy 140.427184 -274.111309)
			(xy 140.119867 -274.111309) (xy 140.119858 -274.111766) (xy 140.111694 -274.162) (xy 140.095578 -274.210274)
			(xy 140.071927 -274.255337) (xy 140.041354 -274.296023) (xy 140.00465 -274.331278) (xy 139.962766 -274.360188)
			(xy 139.916787 -274.382005) (xy 139.867903 -274.396165) (xy 139.817382 -274.402299) (xy 139.76653 -274.40025)
			(xy 139.716666 -274.39007) (xy 139.66908 -274.372023) (xy 139.625006 -274.346577) (xy 139.585584 -274.31439)
			(xy 139.551836 -274.276296) (xy 139.524635 -274.233282) (xy 139.504687 -274.186462) (xy 139.492508 -274.137048)
			(xy 139.488413 -274.08632) (xy 139.182856 -274.08632) (xy 139.182366 -274.111309) (xy 139.174547 -274.160672)
			(xy 139.159103 -274.208204) (xy 139.136413 -274.252736) (xy 139.107037 -274.293169) (xy 139.071697 -274.328509)
			(xy 139.031264 -274.357885) (xy 138.986732 -274.380575) (xy 138.9392 -274.396019) (xy 138.889837 -274.403838)
			(xy 138.839859 -274.403838) (xy 138.790496 -274.396019) (xy 138.742964 -274.380575) (xy 138.698432 -274.357885)
			(xy 138.657999 -274.328509) (xy 138.622659 -274.293169) (xy 138.593283 -274.252736) (xy 138.570593 -274.208204)
			(xy 138.555149 -274.160672) (xy 138.54733 -274.111309) (xy 138.240013 -274.111309) (xy 138.240004 -274.111766)
			(xy 138.23184 -274.162) (xy 138.215724 -274.210274) (xy 138.192073 -274.255337) (xy 138.1615 -274.296023)
			(xy 138.124796 -274.331278) (xy 138.082912 -274.360188) (xy 138.036933 -274.382005) (xy 137.988049 -274.396165)
			(xy 137.937528 -274.402299) (xy 137.886676 -274.40025) (xy 137.836812 -274.39007) (xy 137.789226 -274.372023)
			(xy 137.745152 -274.346577) (xy 137.70573 -274.31439) (xy 137.671982 -274.276296) (xy 137.644781 -274.233282)
			(xy 137.624833 -274.186462) (xy 137.612654 -274.137048) (xy 137.608559 -274.08632) (xy 137.302748 -274.08632)
			(xy 137.302258 -274.111309) (xy 137.294439 -274.160672) (xy 137.278995 -274.208204) (xy 137.256305 -274.252736)
			(xy 137.226929 -274.293169) (xy 137.191589 -274.328509) (xy 137.151156 -274.357885) (xy 137.106624 -274.380575)
			(xy 137.059092 -274.396019) (xy 137.009729 -274.403838) (xy 136.959751 -274.403838) (xy 136.910388 -274.396019)
			(xy 136.862856 -274.380575) (xy 136.818324 -274.357885) (xy 136.777891 -274.328509) (xy 136.742551 -274.293169)
			(xy 136.713175 -274.252736) (xy 136.690485 -274.208204) (xy 136.675041 -274.160672) (xy 136.667222 -274.111309)
			(xy 136.359905 -274.111309) (xy 136.359896 -274.111766) (xy 136.351732 -274.162) (xy 136.335616 -274.210274)
			(xy 136.311965 -274.255337) (xy 136.281392 -274.296023) (xy 136.244688 -274.331278) (xy 136.202804 -274.360188)
			(xy 136.156825 -274.382005) (xy 136.107941 -274.396165) (xy 136.05742 -274.402299) (xy 136.006568 -274.40025)
			(xy 135.956704 -274.39007) (xy 135.909118 -274.372023) (xy 135.865044 -274.346577) (xy 135.825622 -274.31439)
			(xy 135.791874 -274.276296) (xy 135.764673 -274.233282) (xy 135.744725 -274.186462) (xy 135.732546 -274.137048)
			(xy 135.728451 -274.08632) (xy 135.420354 -274.08632) (xy 135.419842 -274.111766) (xy 135.411678 -274.162)
			(xy 135.395562 -274.210274) (xy 135.371911 -274.255337) (xy 135.341338 -274.296023) (xy 135.304634 -274.331278)
			(xy 135.26275 -274.360188) (xy 135.216771 -274.382005) (xy 135.167887 -274.396165) (xy 135.117366 -274.402299)
			(xy 135.066514 -274.40025) (xy 135.01665 -274.39007) (xy 134.969064 -274.372023) (xy 134.92499 -274.346577)
			(xy 134.885568 -274.31439) (xy 134.85182 -274.276296) (xy 134.824619 -274.233282) (xy 134.804671 -274.186462)
			(xy 134.792492 -274.137048) (xy 134.788397 -274.08632) (xy 134.48284 -274.08632) (xy 134.48235 -274.111309)
			(xy 134.474531 -274.160672) (xy 134.459087 -274.208204) (xy 134.436397 -274.252736) (xy 134.407021 -274.293169)
			(xy 134.371681 -274.328509) (xy 134.331248 -274.357885) (xy 134.286716 -274.380575) (xy 134.239184 -274.396019)
			(xy 134.189821 -274.403838) (xy 134.139843 -274.403838) (xy 134.09048 -274.396019) (xy 134.042948 -274.380575)
			(xy 133.998416 -274.357885) (xy 133.957983 -274.328509) (xy 133.922643 -274.293169) (xy 133.893267 -274.252736)
			(xy 133.870577 -274.208204) (xy 133.855133 -274.160672) (xy 133.847314 -274.111309) (xy 133.539997 -274.111309)
			(xy 133.539988 -274.111766) (xy 133.531824 -274.162) (xy 133.515708 -274.210274) (xy 133.492057 -274.255337)
			(xy 133.461484 -274.296023) (xy 133.42478 -274.331278) (xy 133.382896 -274.360188) (xy 133.336917 -274.382005)
			(xy 133.288033 -274.396165) (xy 133.237512 -274.402299) (xy 133.18666 -274.40025) (xy 133.136796 -274.39007)
			(xy 133.08921 -274.372023) (xy 133.045136 -274.346577) (xy 133.005714 -274.31439) (xy 132.971966 -274.276296)
			(xy 132.944765 -274.233282) (xy 132.924817 -274.186462) (xy 132.912638 -274.137048) (xy 132.908543 -274.08632)
			(xy 132.602732 -274.08632) (xy 132.602242 -274.111309) (xy 132.594423 -274.160672) (xy 132.578979 -274.208204)
			(xy 132.556289 -274.252736) (xy 132.526913 -274.293169) (xy 132.491573 -274.328509) (xy 132.45114 -274.357885)
			(xy 132.406608 -274.380575) (xy 132.359076 -274.396019) (xy 132.309713 -274.403838) (xy 132.259735 -274.403838)
			(xy 132.210372 -274.396019) (xy 132.16284 -274.380575) (xy 132.118308 -274.357885) (xy 132.077875 -274.328509)
			(xy 132.042535 -274.293169) (xy 132.013159 -274.252736) (xy 131.990469 -274.208204) (xy 131.975025 -274.160672)
			(xy 131.967206 -274.111309) (xy 131.659889 -274.111309) (xy 131.65988 -274.111766) (xy 131.651716 -274.162)
			(xy 131.6356 -274.210274) (xy 131.611949 -274.255337) (xy 131.581376 -274.296023) (xy 131.544672 -274.331278)
			(xy 131.502788 -274.360188) (xy 131.456809 -274.382005) (xy 131.407925 -274.396165) (xy 131.357404 -274.402299)
			(xy 131.306552 -274.40025) (xy 131.256688 -274.39007) (xy 131.209102 -274.372023) (xy 131.165028 -274.346577)
			(xy 131.125606 -274.31439) (xy 131.091858 -274.276296) (xy 131.064657 -274.233282) (xy 131.044709 -274.186462)
			(xy 131.03253 -274.137048) (xy 131.028435 -274.08632) (xy 130.722878 -274.08632) (xy 130.722388 -274.111309)
			(xy 130.714569 -274.160672) (xy 130.699125 -274.208204) (xy 130.676435 -274.252736) (xy 130.647059 -274.293169)
			(xy 130.611719 -274.328509) (xy 130.571286 -274.357885) (xy 130.526754 -274.380575) (xy 130.479222 -274.396019)
			(xy 130.429859 -274.403838) (xy 130.379881 -274.403838) (xy 130.330518 -274.396019) (xy 130.282986 -274.380575)
			(xy 130.238454 -274.357885) (xy 130.198021 -274.328509) (xy 130.162681 -274.293169) (xy 130.133305 -274.252736)
			(xy 130.110615 -274.208204) (xy 130.095171 -274.160672) (xy 130.087352 -274.111309) (xy 129.780035 -274.111309)
			(xy 129.780026 -274.111766) (xy 129.771862 -274.162) (xy 129.755746 -274.210274) (xy 129.732095 -274.255337)
			(xy 129.701522 -274.296023) (xy 129.664818 -274.331278) (xy 129.622934 -274.360188) (xy 129.576955 -274.382005)
			(xy 129.528071 -274.396165) (xy 129.47755 -274.402299) (xy 129.426698 -274.40025) (xy 129.376834 -274.39007)
			(xy 129.329248 -274.372023) (xy 129.285174 -274.346577) (xy 129.245752 -274.31439) (xy 129.212004 -274.276296)
			(xy 129.184803 -274.233282) (xy 129.164855 -274.186462) (xy 129.152676 -274.137048) (xy 129.148581 -274.08632)
			(xy 128.840484 -274.08632) (xy 128.839972 -274.111766) (xy 128.831808 -274.162) (xy 128.815692 -274.210274)
			(xy 128.792041 -274.255337) (xy 128.761468 -274.296023) (xy 128.724764 -274.331278) (xy 128.68288 -274.360188)
			(xy 128.636901 -274.382005) (xy 128.588017 -274.396165) (xy 128.537496 -274.402299) (xy 128.486644 -274.40025)
			(xy 128.43678 -274.39007) (xy 128.389194 -274.372023) (xy 128.34512 -274.346577) (xy 128.305698 -274.31439)
			(xy 128.27195 -274.276296) (xy 128.244749 -274.233282) (xy 128.224801 -274.186462) (xy 128.212622 -274.137048)
			(xy 128.208527 -274.08632) (xy 127.167386 -274.08632) (xy 127.167386 -274.541996) (xy 127.168033 -274.553974)
			(xy 127.178911 -274.575315) (xy 127.188214 -274.58289) (xy 127.196342 -274.586954) (xy 127.204978 -274.59051)
			(xy 127.229391 -274.598235) (xy 127.27556 -274.620375) (xy 127.317594 -274.649611) (xy 127.354414 -274.685192)
			(xy 127.38507 -274.726202) (xy 127.408775 -274.771587) (xy 127.424919 -274.820178) (xy 127.433086 -274.870725)
			(xy 127.433578 -274.896326) (xy 127.738627 -274.896326) (xy 127.742722 -274.845598) (xy 127.754901 -274.796184)
			(xy 127.774849 -274.749364) (xy 127.80205 -274.70635) (xy 127.835798 -274.668256) (xy 127.87522 -274.636069)
			(xy 127.919294 -274.610623) (xy 127.96688 -274.592576) (xy 128.016744 -274.582396) (xy 128.067596 -274.580347)
			(xy 128.118117 -274.586481) (xy 128.167001 -274.600641) (xy 128.21298 -274.622458) (xy 128.254864 -274.651368)
			(xy 128.291568 -274.686623) (xy 128.322141 -274.727309) (xy 128.345792 -274.772372) (xy 128.361908 -274.820646)
			(xy 128.370072 -274.87088) (xy 128.370584 -274.896326) (xy 128.370081 -274.921315) (xy 128.677144 -274.921315)
			(xy 128.677144 -274.871337) (xy 128.684963 -274.821974) (xy 128.700407 -274.774442) (xy 128.723097 -274.72991)
			(xy 128.752473 -274.689477) (xy 128.787813 -274.654137) (xy 128.828246 -274.624761) (xy 128.872778 -274.602071)
			(xy 128.92031 -274.586627) (xy 128.969673 -274.578808) (xy 129.019651 -274.578808) (xy 129.069014 -274.586627)
			(xy 129.116546 -274.602071) (xy 129.161078 -274.624761) (xy 129.201511 -274.654137) (xy 129.236851 -274.689477)
			(xy 129.266227 -274.72991) (xy 129.288917 -274.774442) (xy 129.304361 -274.821974) (xy 129.31218 -274.871337)
			(xy 129.31267 -274.896326) (xy 129.618481 -274.896326) (xy 129.622576 -274.845598) (xy 129.634755 -274.796184)
			(xy 129.654703 -274.749364) (xy 129.681904 -274.70635) (xy 129.715652 -274.668256) (xy 129.755074 -274.636069)
			(xy 129.799148 -274.610623) (xy 129.846734 -274.592576) (xy 129.896598 -274.582396) (xy 129.94745 -274.580347)
			(xy 129.997971 -274.586481) (xy 130.046855 -274.600641) (xy 130.092834 -274.622458) (xy 130.134718 -274.651368)
			(xy 130.171422 -274.686623) (xy 130.201995 -274.727309) (xy 130.225646 -274.772372) (xy 130.241762 -274.820646)
			(xy 130.249926 -274.87088) (xy 130.250438 -274.896326) (xy 130.249935 -274.921315) (xy 130.557252 -274.921315)
			(xy 130.557252 -274.871337) (xy 130.565071 -274.821974) (xy 130.580515 -274.774442) (xy 130.603205 -274.72991)
			(xy 130.632581 -274.689477) (xy 130.667921 -274.654137) (xy 130.708354 -274.624761) (xy 130.752886 -274.602071)
			(xy 130.800418 -274.586627) (xy 130.849781 -274.578808) (xy 130.899759 -274.578808) (xy 130.949122 -274.586627)
			(xy 130.996654 -274.602071) (xy 131.041186 -274.624761) (xy 131.081619 -274.654137) (xy 131.116959 -274.689477)
			(xy 131.146335 -274.72991) (xy 131.169025 -274.774442) (xy 131.184469 -274.821974) (xy 131.192288 -274.871337)
			(xy 131.192778 -274.896326) (xy 131.498589 -274.896326) (xy 131.502684 -274.845598) (xy 131.514863 -274.796184)
			(xy 131.534811 -274.749364) (xy 131.562012 -274.70635) (xy 131.59576 -274.668256) (xy 131.635182 -274.636069)
			(xy 131.679256 -274.610623) (xy 131.726842 -274.592576) (xy 131.776706 -274.582396) (xy 131.827558 -274.580347)
			(xy 131.878079 -274.586481) (xy 131.926963 -274.600641) (xy 131.972942 -274.622458) (xy 132.014826 -274.651368)
			(xy 132.05153 -274.686623) (xy 132.082103 -274.727309) (xy 132.105754 -274.772372) (xy 132.12187 -274.820646)
			(xy 132.130034 -274.87088) (xy 132.130546 -274.896326) (xy 132.438643 -274.896326) (xy 132.442738 -274.845598)
			(xy 132.454917 -274.796184) (xy 132.474865 -274.749364) (xy 132.502066 -274.70635) (xy 132.535814 -274.668256)
			(xy 132.575236 -274.636069) (xy 132.61931 -274.610623) (xy 132.666896 -274.592576) (xy 132.71676 -274.582396)
			(xy 132.767612 -274.580347) (xy 132.818133 -274.586481) (xy 132.867017 -274.600641) (xy 132.912996 -274.622458)
			(xy 132.95488 -274.651368) (xy 132.991584 -274.686623) (xy 133.022157 -274.727309) (xy 133.045808 -274.772372)
			(xy 133.061924 -274.820646) (xy 133.070088 -274.87088) (xy 133.0706 -274.896326) (xy 133.070097 -274.921315)
			(xy 133.37716 -274.921315) (xy 133.37716 -274.871337) (xy 133.384979 -274.821974) (xy 133.400423 -274.774442)
			(xy 133.423113 -274.72991) (xy 133.452489 -274.689477) (xy 133.487829 -274.654137) (xy 133.528262 -274.624761)
			(xy 133.572794 -274.602071) (xy 133.620326 -274.586627) (xy 133.669689 -274.578808) (xy 133.719667 -274.578808)
			(xy 133.76903 -274.586627) (xy 133.816562 -274.602071) (xy 133.861094 -274.624761) (xy 133.901527 -274.654137)
			(xy 133.936867 -274.689477) (xy 133.966243 -274.72991) (xy 133.988933 -274.774442) (xy 134.004377 -274.821974)
			(xy 134.012196 -274.871337) (xy 134.012686 -274.896326) (xy 134.318497 -274.896326) (xy 134.322592 -274.845598)
			(xy 134.334771 -274.796184) (xy 134.354719 -274.749364) (xy 134.38192 -274.70635) (xy 134.415668 -274.668256)
			(xy 134.45509 -274.636069) (xy 134.499164 -274.610623) (xy 134.54675 -274.592576) (xy 134.596614 -274.582396)
			(xy 134.647466 -274.580347) (xy 134.697987 -274.586481) (xy 134.746871 -274.600641) (xy 134.79285 -274.622458)
			(xy 134.834734 -274.651368) (xy 134.871438 -274.686623) (xy 134.902011 -274.727309) (xy 134.925662 -274.772372)
			(xy 134.941778 -274.820646) (xy 134.949942 -274.87088) (xy 134.950454 -274.896326) (xy 134.949951 -274.921315)
			(xy 135.257268 -274.921315) (xy 135.257268 -274.871337) (xy 135.265087 -274.821974) (xy 135.280531 -274.774442)
			(xy 135.303221 -274.72991) (xy 135.332597 -274.689477) (xy 135.367937 -274.654137) (xy 135.40837 -274.624761)
			(xy 135.452902 -274.602071) (xy 135.500434 -274.586627) (xy 135.549797 -274.578808) (xy 135.599775 -274.578808)
			(xy 135.649138 -274.586627) (xy 135.69667 -274.602071) (xy 135.741202 -274.624761) (xy 135.781635 -274.654137)
			(xy 135.816975 -274.689477) (xy 135.846351 -274.72991) (xy 135.869041 -274.774442) (xy 135.884485 -274.821974)
			(xy 135.892304 -274.871337) (xy 135.892794 -274.896326) (xy 136.198605 -274.896326) (xy 136.2027 -274.845598)
			(xy 136.214879 -274.796184) (xy 136.234827 -274.749364) (xy 136.262028 -274.70635) (xy 136.295776 -274.668256)
			(xy 136.335198 -274.636069) (xy 136.379272 -274.610623) (xy 136.426858 -274.592576) (xy 136.476722 -274.582396)
			(xy 136.527574 -274.580347) (xy 136.578095 -274.586481) (xy 136.626979 -274.600641) (xy 136.672958 -274.622458)
			(xy 136.714842 -274.651368) (xy 136.751546 -274.686623) (xy 136.782119 -274.727309) (xy 136.80577 -274.772372)
			(xy 136.821886 -274.820646) (xy 136.83005 -274.87088) (xy 136.830562 -274.896326) (xy 136.830059 -274.921315)
			(xy 137.137122 -274.921315) (xy 137.137122 -274.871337) (xy 137.144941 -274.821974) (xy 137.160385 -274.774442)
			(xy 137.183075 -274.72991) (xy 137.212451 -274.689477) (xy 137.247791 -274.654137) (xy 137.288224 -274.624761)
			(xy 137.332756 -274.602071) (xy 137.380288 -274.586627) (xy 137.429651 -274.578808) (xy 137.479629 -274.578808)
			(xy 137.528992 -274.586627) (xy 137.576524 -274.602071) (xy 137.621056 -274.624761) (xy 137.661489 -274.654137)
			(xy 137.696829 -274.689477) (xy 137.726205 -274.72991) (xy 137.748895 -274.774442) (xy 137.764339 -274.821974)
			(xy 137.772158 -274.871337) (xy 137.772648 -274.896326) (xy 138.078459 -274.896326) (xy 138.082554 -274.845598)
			(xy 138.094733 -274.796184) (xy 138.114681 -274.749364) (xy 138.141882 -274.70635) (xy 138.17563 -274.668256)
			(xy 138.215052 -274.636069) (xy 138.259126 -274.610623) (xy 138.306712 -274.592576) (xy 138.356576 -274.582396)
			(xy 138.407428 -274.580347) (xy 138.457949 -274.586481) (xy 138.506833 -274.600641) (xy 138.552812 -274.622458)
			(xy 138.594696 -274.651368) (xy 138.6314 -274.686623) (xy 138.661973 -274.727309) (xy 138.685624 -274.772372)
			(xy 138.70174 -274.820646) (xy 138.709904 -274.87088) (xy 138.710416 -274.896326) (xy 139.018513 -274.896326)
			(xy 139.022608 -274.845598) (xy 139.034787 -274.796184) (xy 139.054735 -274.749364) (xy 139.081936 -274.70635)
			(xy 139.115684 -274.668256) (xy 139.155106 -274.636069) (xy 139.19918 -274.610623) (xy 139.246766 -274.592576)
			(xy 139.29663 -274.582396) (xy 139.347482 -274.580347) (xy 139.398003 -274.586481) (xy 139.446887 -274.600641)
			(xy 139.492866 -274.622458) (xy 139.53475 -274.651368) (xy 139.571454 -274.686623) (xy 139.602027 -274.727309)
			(xy 139.625678 -274.772372) (xy 139.641794 -274.820646) (xy 139.649958 -274.87088) (xy 139.65047 -274.896326)
			(xy 139.649967 -274.921315) (xy 139.957284 -274.921315) (xy 139.957284 -274.871337) (xy 139.965103 -274.821974)
			(xy 139.980547 -274.774442) (xy 140.003237 -274.72991) (xy 140.032613 -274.689477) (xy 140.067953 -274.654137)
			(xy 140.108386 -274.624761) (xy 140.152918 -274.602071) (xy 140.20045 -274.586627) (xy 140.249813 -274.578808)
			(xy 140.299791 -274.578808) (xy 140.349154 -274.586627) (xy 140.396686 -274.602071) (xy 140.441218 -274.624761)
			(xy 140.481651 -274.654137) (xy 140.516991 -274.689477) (xy 140.546367 -274.72991) (xy 140.569057 -274.774442)
			(xy 140.584501 -274.821974) (xy 140.59232 -274.871337) (xy 140.59281 -274.896326) (xy 140.898621 -274.896326)
			(xy 140.902716 -274.845598) (xy 140.914895 -274.796184) (xy 140.934843 -274.749364) (xy 140.962044 -274.70635)
			(xy 140.995792 -274.668256) (xy 141.035214 -274.636069) (xy 141.079288 -274.610623) (xy 141.126874 -274.592576)
			(xy 141.176738 -274.582396) (xy 141.22759 -274.580347) (xy 141.278111 -274.586481) (xy 141.326995 -274.600641)
			(xy 141.372974 -274.622458) (xy 141.414858 -274.651368) (xy 141.451562 -274.686623) (xy 141.482135 -274.727309)
			(xy 141.505786 -274.772372) (xy 141.521902 -274.820646) (xy 141.530066 -274.87088) (xy 141.530578 -274.896326)
			(xy 141.530075 -274.921315) (xy 141.837138 -274.921315) (xy 141.837138 -274.871337) (xy 141.844957 -274.821974)
			(xy 141.860401 -274.774442) (xy 141.883091 -274.72991) (xy 141.912467 -274.689477) (xy 141.947807 -274.654137)
			(xy 141.98824 -274.624761) (xy 142.032772 -274.602071) (xy 142.080304 -274.586627) (xy 142.129667 -274.578808)
			(xy 142.179645 -274.578808) (xy 142.229008 -274.586627) (xy 142.27654 -274.602071) (xy 142.321072 -274.624761)
			(xy 142.361505 -274.654137) (xy 142.396845 -274.689477) (xy 142.426221 -274.72991) (xy 142.448911 -274.774442)
			(xy 142.464355 -274.821974) (xy 142.472174 -274.871337) (xy 142.472664 -274.896326) (xy 142.778475 -274.896326)
			(xy 142.78257 -274.845598) (xy 142.794749 -274.796184) (xy 142.814697 -274.749364) (xy 142.841898 -274.70635)
			(xy 142.875646 -274.668256) (xy 142.915068 -274.636069) (xy 142.959142 -274.610623) (xy 143.006728 -274.592576)
			(xy 143.056592 -274.582396) (xy 143.107444 -274.580347) (xy 143.157965 -274.586481) (xy 143.206849 -274.600641)
			(xy 143.252828 -274.622458) (xy 143.294712 -274.651368) (xy 143.331416 -274.686623) (xy 143.361989 -274.727309)
			(xy 143.38564 -274.772372) (xy 143.401756 -274.820646) (xy 143.40992 -274.87088) (xy 143.410432 -274.896326)
			(xy 143.409929 -274.921315) (xy 143.717246 -274.921315) (xy 143.717246 -274.871337) (xy 143.725065 -274.821974)
			(xy 143.740509 -274.774442) (xy 143.763199 -274.72991) (xy 143.792575 -274.689477) (xy 143.827915 -274.654137)
			(xy 143.868348 -274.624761) (xy 143.91288 -274.602071) (xy 143.960412 -274.586627) (xy 144.009775 -274.578808)
			(xy 144.059753 -274.578808) (xy 144.109116 -274.586627) (xy 144.156648 -274.602071) (xy 144.20118 -274.624761)
			(xy 144.241613 -274.654137) (xy 144.276953 -274.689477) (xy 144.306329 -274.72991) (xy 144.329019 -274.774442)
			(xy 144.344463 -274.821974) (xy 144.352282 -274.871337) (xy 144.352772 -274.896326) (xy 144.352282 -274.921315)
			(xy 144.344463 -274.970678) (xy 144.329019 -275.01821) (xy 144.306329 -275.062742) (xy 144.276953 -275.103175)
			(xy 144.241613 -275.138515) (xy 144.20118 -275.167891) (xy 144.156648 -275.190581) (xy 144.109116 -275.206025)
			(xy 144.059753 -275.213844) (xy 144.009775 -275.213844) (xy 143.960412 -275.206025) (xy 143.91288 -275.190581)
			(xy 143.868348 -275.167891) (xy 143.827915 -275.138515) (xy 143.792575 -275.103175) (xy 143.763199 -275.062742)
			(xy 143.740509 -275.01821) (xy 143.725065 -274.970678) (xy 143.717246 -274.921315) (xy 143.409929 -274.921315)
			(xy 143.40992 -274.921772) (xy 143.401756 -274.972006) (xy 143.38564 -275.02028) (xy 143.361989 -275.065343)
			(xy 143.331416 -275.106029) (xy 143.294712 -275.141284) (xy 143.252828 -275.170194) (xy 143.206849 -275.192011)
			(xy 143.157965 -275.206171) (xy 143.107444 -275.212305) (xy 143.056592 -275.210256) (xy 143.006728 -275.200076)
			(xy 142.959142 -275.182029) (xy 142.915068 -275.156583) (xy 142.875646 -275.124396) (xy 142.841898 -275.086302)
			(xy 142.814697 -275.043288) (xy 142.794749 -274.996468) (xy 142.78257 -274.947054) (xy 142.778475 -274.896326)
			(xy 142.472664 -274.896326) (xy 142.472174 -274.921315) (xy 142.464355 -274.970678) (xy 142.448911 -275.01821)
			(xy 142.426221 -275.062742) (xy 142.396845 -275.103175) (xy 142.361505 -275.138515) (xy 142.321072 -275.167891)
			(xy 142.27654 -275.190581) (xy 142.229008 -275.206025) (xy 142.179645 -275.213844) (xy 142.129667 -275.213844)
			(xy 142.080304 -275.206025) (xy 142.032772 -275.190581) (xy 141.98824 -275.167891) (xy 141.947807 -275.138515)
			(xy 141.912467 -275.103175) (xy 141.883091 -275.062742) (xy 141.860401 -275.01821) (xy 141.844957 -274.970678)
			(xy 141.837138 -274.921315) (xy 141.530075 -274.921315) (xy 141.530066 -274.921772) (xy 141.521902 -274.972006)
			(xy 141.505786 -275.02028) (xy 141.482135 -275.065343) (xy 141.451562 -275.106029) (xy 141.414858 -275.141284)
			(xy 141.372974 -275.170194) (xy 141.326995 -275.192011) (xy 141.278111 -275.206171) (xy 141.22759 -275.212305)
			(xy 141.176738 -275.210256) (xy 141.126874 -275.200076) (xy 141.079288 -275.182029) (xy 141.035214 -275.156583)
			(xy 140.995792 -275.124396) (xy 140.962044 -275.086302) (xy 140.934843 -275.043288) (xy 140.914895 -274.996468)
			(xy 140.902716 -274.947054) (xy 140.898621 -274.896326) (xy 140.59281 -274.896326) (xy 140.59232 -274.921315)
			(xy 140.584501 -274.970678) (xy 140.569057 -275.01821) (xy 140.546367 -275.062742) (xy 140.516991 -275.103175)
			(xy 140.481651 -275.138515) (xy 140.441218 -275.167891) (xy 140.396686 -275.190581) (xy 140.349154 -275.206025)
			(xy 140.299791 -275.213844) (xy 140.249813 -275.213844) (xy 140.20045 -275.206025) (xy 140.152918 -275.190581)
			(xy 140.108386 -275.167891) (xy 140.067953 -275.138515) (xy 140.032613 -275.103175) (xy 140.003237 -275.062742)
			(xy 139.980547 -275.01821) (xy 139.965103 -274.970678) (xy 139.957284 -274.921315) (xy 139.649967 -274.921315)
			(xy 139.649958 -274.921772) (xy 139.641794 -274.972006) (xy 139.625678 -275.02028) (xy 139.602027 -275.065343)
			(xy 139.571454 -275.106029) (xy 139.53475 -275.141284) (xy 139.492866 -275.170194) (xy 139.446887 -275.192011)
			(xy 139.398003 -275.206171) (xy 139.347482 -275.212305) (xy 139.29663 -275.210256) (xy 139.246766 -275.200076)
			(xy 139.19918 -275.182029) (xy 139.155106 -275.156583) (xy 139.115684 -275.124396) (xy 139.081936 -275.086302)
			(xy 139.054735 -275.043288) (xy 139.034787 -274.996468) (xy 139.022608 -274.947054) (xy 139.018513 -274.896326)
			(xy 138.710416 -274.896326) (xy 138.709904 -274.921772) (xy 138.70174 -274.972006) (xy 138.685624 -275.02028)
			(xy 138.661973 -275.065343) (xy 138.6314 -275.106029) (xy 138.594696 -275.141284) (xy 138.552812 -275.170194)
			(xy 138.506833 -275.192011) (xy 138.457949 -275.206171) (xy 138.407428 -275.212305) (xy 138.356576 -275.210256)
			(xy 138.306712 -275.200076) (xy 138.259126 -275.182029) (xy 138.215052 -275.156583) (xy 138.17563 -275.124396)
			(xy 138.141882 -275.086302) (xy 138.114681 -275.043288) (xy 138.094733 -274.996468) (xy 138.082554 -274.947054)
			(xy 138.078459 -274.896326) (xy 137.772648 -274.896326) (xy 137.772158 -274.921315) (xy 137.764339 -274.970678)
			(xy 137.748895 -275.01821) (xy 137.726205 -275.062742) (xy 137.696829 -275.103175) (xy 137.661489 -275.138515)
			(xy 137.621056 -275.167891) (xy 137.576524 -275.190581) (xy 137.528992 -275.206025) (xy 137.479629 -275.213844)
			(xy 137.429651 -275.213844) (xy 137.380288 -275.206025) (xy 137.332756 -275.190581) (xy 137.288224 -275.167891)
			(xy 137.247791 -275.138515) (xy 137.212451 -275.103175) (xy 137.183075 -275.062742) (xy 137.160385 -275.01821)
			(xy 137.144941 -274.970678) (xy 137.137122 -274.921315) (xy 136.830059 -274.921315) (xy 136.83005 -274.921772)
			(xy 136.821886 -274.972006) (xy 136.80577 -275.02028) (xy 136.782119 -275.065343) (xy 136.751546 -275.106029)
			(xy 136.714842 -275.141284) (xy 136.672958 -275.170194) (xy 136.626979 -275.192011) (xy 136.578095 -275.206171)
			(xy 136.527574 -275.212305) (xy 136.476722 -275.210256) (xy 136.426858 -275.200076) (xy 136.379272 -275.182029)
			(xy 136.335198 -275.156583) (xy 136.295776 -275.124396) (xy 136.262028 -275.086302) (xy 136.234827 -275.043288)
			(xy 136.214879 -274.996468) (xy 136.2027 -274.947054) (xy 136.198605 -274.896326) (xy 135.892794 -274.896326)
			(xy 135.892304 -274.921315) (xy 135.884485 -274.970678) (xy 135.869041 -275.01821) (xy 135.846351 -275.062742)
			(xy 135.816975 -275.103175) (xy 135.781635 -275.138515) (xy 135.741202 -275.167891) (xy 135.69667 -275.190581)
			(xy 135.649138 -275.206025) (xy 135.599775 -275.213844) (xy 135.549797 -275.213844) (xy 135.500434 -275.206025)
			(xy 135.452902 -275.190581) (xy 135.40837 -275.167891) (xy 135.367937 -275.138515) (xy 135.332597 -275.103175)
			(xy 135.303221 -275.062742) (xy 135.280531 -275.01821) (xy 135.265087 -274.970678) (xy 135.257268 -274.921315)
			(xy 134.949951 -274.921315) (xy 134.949942 -274.921772) (xy 134.941778 -274.972006) (xy 134.925662 -275.02028)
			(xy 134.902011 -275.065343) (xy 134.871438 -275.106029) (xy 134.834734 -275.141284) (xy 134.79285 -275.170194)
			(xy 134.746871 -275.192011) (xy 134.697987 -275.206171) (xy 134.647466 -275.212305) (xy 134.596614 -275.210256)
			(xy 134.54675 -275.200076) (xy 134.499164 -275.182029) (xy 134.45509 -275.156583) (xy 134.415668 -275.124396)
			(xy 134.38192 -275.086302) (xy 134.354719 -275.043288) (xy 134.334771 -274.996468) (xy 134.322592 -274.947054)
			(xy 134.318497 -274.896326) (xy 134.012686 -274.896326) (xy 134.012196 -274.921315) (xy 134.004377 -274.970678)
			(xy 133.988933 -275.01821) (xy 133.966243 -275.062742) (xy 133.936867 -275.103175) (xy 133.901527 -275.138515)
			(xy 133.861094 -275.167891) (xy 133.816562 -275.190581) (xy 133.76903 -275.206025) (xy 133.719667 -275.213844)
			(xy 133.669689 -275.213844) (xy 133.620326 -275.206025) (xy 133.572794 -275.190581) (xy 133.528262 -275.167891)
			(xy 133.487829 -275.138515) (xy 133.452489 -275.103175) (xy 133.423113 -275.062742) (xy 133.400423 -275.01821)
			(xy 133.384979 -274.970678) (xy 133.37716 -274.921315) (xy 133.070097 -274.921315) (xy 133.070088 -274.921772)
			(xy 133.061924 -274.972006) (xy 133.045808 -275.02028) (xy 133.022157 -275.065343) (xy 132.991584 -275.106029)
			(xy 132.95488 -275.141284) (xy 132.912996 -275.170194) (xy 132.867017 -275.192011) (xy 132.818133 -275.206171)
			(xy 132.767612 -275.212305) (xy 132.71676 -275.210256) (xy 132.666896 -275.200076) (xy 132.61931 -275.182029)
			(xy 132.575236 -275.156583) (xy 132.535814 -275.124396) (xy 132.502066 -275.086302) (xy 132.474865 -275.043288)
			(xy 132.454917 -274.996468) (xy 132.442738 -274.947054) (xy 132.438643 -274.896326) (xy 132.130546 -274.896326)
			(xy 132.130034 -274.921772) (xy 132.12187 -274.972006) (xy 132.105754 -275.02028) (xy 132.082103 -275.065343)
			(xy 132.05153 -275.106029) (xy 132.014826 -275.141284) (xy 131.972942 -275.170194) (xy 131.926963 -275.192011)
			(xy 131.878079 -275.206171) (xy 131.827558 -275.212305) (xy 131.776706 -275.210256) (xy 131.726842 -275.200076)
			(xy 131.679256 -275.182029) (xy 131.635182 -275.156583) (xy 131.59576 -275.124396) (xy 131.562012 -275.086302)
			(xy 131.534811 -275.043288) (xy 131.514863 -274.996468) (xy 131.502684 -274.947054) (xy 131.498589 -274.896326)
			(xy 131.192778 -274.896326) (xy 131.192288 -274.921315) (xy 131.184469 -274.970678) (xy 131.169025 -275.01821)
			(xy 131.146335 -275.062742) (xy 131.116959 -275.103175) (xy 131.081619 -275.138515) (xy 131.041186 -275.167891)
			(xy 130.996654 -275.190581) (xy 130.949122 -275.206025) (xy 130.899759 -275.213844) (xy 130.849781 -275.213844)
			(xy 130.800418 -275.206025) (xy 130.752886 -275.190581) (xy 130.708354 -275.167891) (xy 130.667921 -275.138515)
			(xy 130.632581 -275.103175) (xy 130.603205 -275.062742) (xy 130.580515 -275.01821) (xy 130.565071 -274.970678)
			(xy 130.557252 -274.921315) (xy 130.249935 -274.921315) (xy 130.249926 -274.921772) (xy 130.241762 -274.972006)
			(xy 130.225646 -275.02028) (xy 130.201995 -275.065343) (xy 130.171422 -275.106029) (xy 130.134718 -275.141284)
			(xy 130.092834 -275.170194) (xy 130.046855 -275.192011) (xy 129.997971 -275.206171) (xy 129.94745 -275.212305)
			(xy 129.896598 -275.210256) (xy 129.846734 -275.200076) (xy 129.799148 -275.182029) (xy 129.755074 -275.156583)
			(xy 129.715652 -275.124396) (xy 129.681904 -275.086302) (xy 129.654703 -275.043288) (xy 129.634755 -274.996468)
			(xy 129.622576 -274.947054) (xy 129.618481 -274.896326) (xy 129.31267 -274.896326) (xy 129.31218 -274.921315)
			(xy 129.304361 -274.970678) (xy 129.288917 -275.01821) (xy 129.266227 -275.062742) (xy 129.236851 -275.103175)
			(xy 129.201511 -275.138515) (xy 129.161078 -275.167891) (xy 129.116546 -275.190581) (xy 129.069014 -275.206025)
			(xy 129.019651 -275.213844) (xy 128.969673 -275.213844) (xy 128.92031 -275.206025) (xy 128.872778 -275.190581)
			(xy 128.828246 -275.167891) (xy 128.787813 -275.138515) (xy 128.752473 -275.103175) (xy 128.723097 -275.062742)
			(xy 128.700407 -275.01821) (xy 128.684963 -274.970678) (xy 128.677144 -274.921315) (xy 128.370081 -274.921315)
			(xy 128.370072 -274.921772) (xy 128.361908 -274.972006) (xy 128.345792 -275.02028) (xy 128.322141 -275.065343)
			(xy 128.291568 -275.106029) (xy 128.254864 -275.141284) (xy 128.21298 -275.170194) (xy 128.167001 -275.192011)
			(xy 128.118117 -275.206171) (xy 128.067596 -275.212305) (xy 128.016744 -275.210256) (xy 127.96688 -275.200076)
			(xy 127.919294 -275.182029) (xy 127.87522 -275.156583) (xy 127.835798 -275.124396) (xy 127.80205 -275.086302)
			(xy 127.774849 -275.043288) (xy 127.754901 -274.996468) (xy 127.742722 -274.947054) (xy 127.738627 -274.896326)
			(xy 127.433578 -274.896326) (xy 127.433058 -274.92239) (xy 127.424578 -274.973823) (xy 127.407848 -275.023193)
			(xy 127.383313 -275.069185) (xy 127.351626 -275.110577) (xy 127.313631 -275.146265) (xy 127.270339 -275.175301)
			(xy 127.222902 -275.19691) (xy 127.197866 -275.204174) (xy 127.18904 -275.208534) (xy 127.175309 -275.222616)
			(xy 127.167872 -275.240823) (xy 127.167386 -275.250656) (xy 127.167386 -275.433536) (xy 127.167856 -275.443845)
			(xy 127.175968 -275.4628) (xy 127.190901 -275.477016) (xy 127.200406 -275.481034) (xy 127.28702 -275.513292)
			(xy 127.295733 -275.516136) (xy 127.314047 -275.516104) (xy 127.331181 -275.509633) (xy 127.338328 -275.503894)
			(xy 127.343662 -275.49856) (xy 127.344678 -275.49729) (xy 127.362966 -275.477134) (xy 127.405163 -275.44277)
			(xy 127.452592 -275.416085) (xy 127.503868 -275.397857) (xy 127.557498 -275.388618) (xy 127.584708 -275.38807)
			(xy 127.609714 -275.388561) (xy 127.659111 -275.396386) (xy 127.706675 -275.411842) (xy 127.751236 -275.434548)
			(xy 127.791697 -275.463945) (xy 127.82706 -275.499309) (xy 127.856457 -275.539771) (xy 127.879161 -275.584332)
			(xy 127.894616 -275.631897) (xy 127.90244 -275.681294) (xy 127.90244 -275.706332) (xy 128.208527 -275.706332)
			(xy 128.212622 -275.655604) (xy 128.224801 -275.60619) (xy 128.244749 -275.55937) (xy 128.27195 -275.516356)
			(xy 128.305698 -275.478262) (xy 128.34512 -275.446075) (xy 128.389194 -275.420629) (xy 128.43678 -275.402582)
			(xy 128.486644 -275.392402) (xy 128.537496 -275.390353) (xy 128.588017 -275.396487) (xy 128.636901 -275.410647)
			(xy 128.68288 -275.432464) (xy 128.724764 -275.461374) (xy 128.761468 -275.496629) (xy 128.792041 -275.537315)
			(xy 128.815692 -275.582378) (xy 128.831808 -275.630652) (xy 128.839972 -275.680886) (xy 128.840484 -275.706332)
			(xy 129.148581 -275.706332) (xy 129.152676 -275.655604) (xy 129.164855 -275.60619) (xy 129.184803 -275.55937)
			(xy 129.212004 -275.516356) (xy 129.245752 -275.478262) (xy 129.285174 -275.446075) (xy 129.329248 -275.420629)
			(xy 129.376834 -275.402582) (xy 129.426698 -275.392402) (xy 129.47755 -275.390353) (xy 129.528071 -275.396487)
			(xy 129.576955 -275.410647) (xy 129.622934 -275.432464) (xy 129.664818 -275.461374) (xy 129.701522 -275.496629)
			(xy 129.732095 -275.537315) (xy 129.755746 -275.582378) (xy 129.771862 -275.630652) (xy 129.780026 -275.680886)
			(xy 129.780538 -275.706332) (xy 131.028435 -275.706332) (xy 131.03253 -275.655604) (xy 131.044709 -275.60619)
			(xy 131.064657 -275.55937) (xy 131.091858 -275.516356) (xy 131.125606 -275.478262) (xy 131.165028 -275.446075)
			(xy 131.209102 -275.420629) (xy 131.256688 -275.402582) (xy 131.306552 -275.392402) (xy 131.357404 -275.390353)
			(xy 131.407925 -275.396487) (xy 131.456809 -275.410647) (xy 131.502788 -275.432464) (xy 131.544672 -275.461374)
			(xy 131.581376 -275.496629) (xy 131.611949 -275.537315) (xy 131.6356 -275.582378) (xy 131.651716 -275.630652)
			(xy 131.65988 -275.680886) (xy 131.660392 -275.706332) (xy 131.659889 -275.731321) (xy 131.967206 -275.731321)
			(xy 131.967206 -275.681343) (xy 131.975025 -275.63198) (xy 131.990469 -275.584448) (xy 132.013159 -275.539916)
			(xy 132.042535 -275.499483) (xy 132.077875 -275.464143) (xy 132.118308 -275.434767) (xy 132.16284 -275.412077)
			(xy 132.210372 -275.396633) (xy 132.259735 -275.388814) (xy 132.309713 -275.388814) (xy 132.359076 -275.396633)
			(xy 132.406608 -275.412077) (xy 132.45114 -275.434767) (xy 132.491573 -275.464143) (xy 132.526913 -275.499483)
			(xy 132.556289 -275.539916) (xy 132.578979 -275.584448) (xy 132.594423 -275.63198) (xy 132.602242 -275.681343)
			(xy 132.602732 -275.706332) (xy 132.908543 -275.706332) (xy 132.912638 -275.655604) (xy 132.924817 -275.60619)
			(xy 132.944765 -275.55937) (xy 132.971966 -275.516356) (xy 133.005714 -275.478262) (xy 133.045136 -275.446075)
			(xy 133.08921 -275.420629) (xy 133.136796 -275.402582) (xy 133.18666 -275.392402) (xy 133.237512 -275.390353)
			(xy 133.288033 -275.396487) (xy 133.336917 -275.410647) (xy 133.382896 -275.432464) (xy 133.42478 -275.461374)
			(xy 133.461484 -275.496629) (xy 133.492057 -275.537315) (xy 133.515708 -275.582378) (xy 133.531824 -275.630652)
			(xy 133.539988 -275.680886) (xy 133.5405 -275.706332) (xy 133.539997 -275.731321) (xy 133.847314 -275.731321)
			(xy 133.847314 -275.681343) (xy 133.855133 -275.63198) (xy 133.870577 -275.584448) (xy 133.893267 -275.539916)
			(xy 133.922643 -275.499483) (xy 133.957983 -275.464143) (xy 133.998416 -275.434767) (xy 134.042948 -275.412077)
			(xy 134.09048 -275.396633) (xy 134.139843 -275.388814) (xy 134.189821 -275.388814) (xy 134.239184 -275.396633)
			(xy 134.286716 -275.412077) (xy 134.331248 -275.434767) (xy 134.371681 -275.464143) (xy 134.407021 -275.499483)
			(xy 134.436397 -275.539916) (xy 134.459087 -275.584448) (xy 134.474531 -275.63198) (xy 134.48235 -275.681343)
			(xy 134.48284 -275.706332) (xy 134.788397 -275.706332) (xy 134.792492 -275.655604) (xy 134.804671 -275.60619)
			(xy 134.824619 -275.55937) (xy 134.85182 -275.516356) (xy 134.885568 -275.478262) (xy 134.92499 -275.446075)
			(xy 134.969064 -275.420629) (xy 135.01665 -275.402582) (xy 135.066514 -275.392402) (xy 135.117366 -275.390353)
			(xy 135.167887 -275.396487) (xy 135.216771 -275.410647) (xy 135.26275 -275.432464) (xy 135.304634 -275.461374)
			(xy 135.341338 -275.496629) (xy 135.371911 -275.537315) (xy 135.395562 -275.582378) (xy 135.411678 -275.630652)
			(xy 135.419842 -275.680886) (xy 135.420354 -275.706332) (xy 135.728451 -275.706332) (xy 135.732546 -275.655604)
			(xy 135.744725 -275.60619) (xy 135.764673 -275.55937) (xy 135.791874 -275.516356) (xy 135.825622 -275.478262)
			(xy 135.865044 -275.446075) (xy 135.909118 -275.420629) (xy 135.956704 -275.402582) (xy 136.006568 -275.392402)
			(xy 136.05742 -275.390353) (xy 136.107941 -275.396487) (xy 136.156825 -275.410647) (xy 136.202804 -275.432464)
			(xy 136.244688 -275.461374) (xy 136.281392 -275.496629) (xy 136.311965 -275.537315) (xy 136.335616 -275.582378)
			(xy 136.351732 -275.630652) (xy 136.359896 -275.680886) (xy 136.360408 -275.706332) (xy 137.608559 -275.706332)
			(xy 137.612654 -275.655604) (xy 137.624833 -275.60619) (xy 137.644781 -275.55937) (xy 137.671982 -275.516356)
			(xy 137.70573 -275.478262) (xy 137.745152 -275.446075) (xy 137.789226 -275.420629) (xy 137.836812 -275.402582)
			(xy 137.886676 -275.392402) (xy 137.937528 -275.390353) (xy 137.988049 -275.396487) (xy 138.036933 -275.410647)
			(xy 138.082912 -275.432464) (xy 138.124796 -275.461374) (xy 138.1615 -275.496629) (xy 138.192073 -275.537315)
			(xy 138.215724 -275.582378) (xy 138.23184 -275.630652) (xy 138.240004 -275.680886) (xy 138.240516 -275.706332)
			(xy 138.240013 -275.731321) (xy 138.54733 -275.731321) (xy 138.54733 -275.681343) (xy 138.555149 -275.63198)
			(xy 138.570593 -275.584448) (xy 138.593283 -275.539916) (xy 138.622659 -275.499483) (xy 138.657999 -275.464143)
			(xy 138.698432 -275.434767) (xy 138.742964 -275.412077) (xy 138.790496 -275.396633) (xy 138.839859 -275.388814)
			(xy 138.889837 -275.388814) (xy 138.9392 -275.396633) (xy 138.986732 -275.412077) (xy 139.031264 -275.434767)
			(xy 139.071697 -275.464143) (xy 139.107037 -275.499483) (xy 139.136413 -275.539916) (xy 139.159103 -275.584448)
			(xy 139.174547 -275.63198) (xy 139.182366 -275.681343) (xy 139.182856 -275.706332) (xy 139.488413 -275.706332)
			(xy 139.492508 -275.655604) (xy 139.504687 -275.60619) (xy 139.524635 -275.55937) (xy 139.551836 -275.516356)
			(xy 139.585584 -275.478262) (xy 139.625006 -275.446075) (xy 139.66908 -275.420629) (xy 139.716666 -275.402582)
			(xy 139.76653 -275.392402) (xy 139.817382 -275.390353) (xy 139.867903 -275.396487) (xy 139.916787 -275.410647)
			(xy 139.962766 -275.432464) (xy 140.00465 -275.461374) (xy 140.041354 -275.496629) (xy 140.071927 -275.537315)
			(xy 140.095578 -275.582378) (xy 140.111694 -275.630652) (xy 140.119858 -275.680886) (xy 140.12037 -275.706332)
			(xy 140.119867 -275.731321) (xy 140.427184 -275.731321) (xy 140.427184 -275.681343) (xy 140.435003 -275.63198)
			(xy 140.450447 -275.584448) (xy 140.473137 -275.539916) (xy 140.502513 -275.499483) (xy 140.537853 -275.464143)
			(xy 140.578286 -275.434767) (xy 140.622818 -275.412077) (xy 140.67035 -275.396633) (xy 140.719713 -275.388814)
			(xy 140.769691 -275.388814) (xy 140.819054 -275.396633) (xy 140.866586 -275.412077) (xy 140.911118 -275.434767)
			(xy 140.951551 -275.464143) (xy 140.986891 -275.499483) (xy 141.016267 -275.539916) (xy 141.038957 -275.584448)
			(xy 141.054401 -275.63198) (xy 141.06222 -275.681343) (xy 141.06271 -275.706332) (xy 141.368521 -275.706332)
			(xy 141.372616 -275.655604) (xy 141.384795 -275.60619) (xy 141.404743 -275.55937) (xy 141.431944 -275.516356)
			(xy 141.465692 -275.478262) (xy 141.505114 -275.446075) (xy 141.549188 -275.420629) (xy 141.596774 -275.402582)
			(xy 141.646638 -275.392402) (xy 141.69749 -275.390353) (xy 141.748011 -275.396487) (xy 141.796895 -275.410647)
			(xy 141.842874 -275.432464) (xy 141.884758 -275.461374) (xy 141.921462 -275.496629) (xy 141.952035 -275.537315)
			(xy 141.975686 -275.582378) (xy 141.991802 -275.630652) (xy 141.999966 -275.680886) (xy 142.000478 -275.706332)
			(xy 142.308575 -275.706332) (xy 142.31267 -275.655604) (xy 142.324849 -275.60619) (xy 142.344797 -275.55937)
			(xy 142.371998 -275.516356) (xy 142.405746 -275.478262) (xy 142.445168 -275.446075) (xy 142.489242 -275.420629)
			(xy 142.536828 -275.402582) (xy 142.586692 -275.392402) (xy 142.637544 -275.390353) (xy 142.688065 -275.396487)
			(xy 142.736949 -275.410647) (xy 142.782928 -275.432464) (xy 142.824812 -275.461374) (xy 142.861516 -275.496629)
			(xy 142.892089 -275.537315) (xy 142.91574 -275.582378) (xy 142.931856 -275.630652) (xy 142.94002 -275.680886)
			(xy 142.940532 -275.706332) (xy 142.94002 -275.731778) (xy 142.931856 -275.782012) (xy 142.91574 -275.830286)
			(xy 142.892089 -275.875349) (xy 142.861516 -275.916035) (xy 142.824812 -275.95129) (xy 142.782928 -275.9802)
			(xy 142.736949 -276.002017) (xy 142.688065 -276.016177) (xy 142.637544 -276.022311) (xy 142.586692 -276.020262)
			(xy 142.536828 -276.010082) (xy 142.489242 -275.992035) (xy 142.445168 -275.966589) (xy 142.405746 -275.934402)
			(xy 142.371998 -275.896308) (xy 142.344797 -275.853294) (xy 142.324849 -275.806474) (xy 142.31267 -275.75706)
			(xy 142.308575 -275.706332) (xy 142.000478 -275.706332) (xy 141.999966 -275.731778) (xy 141.991802 -275.782012)
			(xy 141.975686 -275.830286) (xy 141.952035 -275.875349) (xy 141.921462 -275.916035) (xy 141.884758 -275.95129)
			(xy 141.842874 -275.9802) (xy 141.796895 -276.002017) (xy 141.748011 -276.016177) (xy 141.69749 -276.022311)
			(xy 141.646638 -276.020262) (xy 141.596774 -276.010082) (xy 141.549188 -275.992035) (xy 141.505114 -275.966589)
			(xy 141.465692 -275.934402) (xy 141.431944 -275.896308) (xy 141.404743 -275.853294) (xy 141.384795 -275.806474)
			(xy 141.372616 -275.75706) (xy 141.368521 -275.706332) (xy 141.06271 -275.706332) (xy 141.06222 -275.731321)
			(xy 141.054401 -275.780684) (xy 141.038957 -275.828216) (xy 141.016267 -275.872748) (xy 140.986891 -275.913181)
			(xy 140.951551 -275.948521) (xy 140.911118 -275.977897) (xy 140.866586 -276.000587) (xy 140.819054 -276.016031)
			(xy 140.769691 -276.02385) (xy 140.719713 -276.02385) (xy 140.67035 -276.016031) (xy 140.622818 -276.000587)
			(xy 140.578286 -275.977897) (xy 140.537853 -275.948521) (xy 140.502513 -275.913181) (xy 140.473137 -275.872748)
			(xy 140.450447 -275.828216) (xy 140.435003 -275.780684) (xy 140.427184 -275.731321) (xy 140.119867 -275.731321)
			(xy 140.119858 -275.731778) (xy 140.111694 -275.782012) (xy 140.095578 -275.830286) (xy 140.071927 -275.875349)
			(xy 140.041354 -275.916035) (xy 140.00465 -275.95129) (xy 139.962766 -275.9802) (xy 139.916787 -276.002017)
			(xy 139.867903 -276.016177) (xy 139.817382 -276.022311) (xy 139.76653 -276.020262) (xy 139.716666 -276.010082)
			(xy 139.66908 -275.992035) (xy 139.625006 -275.966589) (xy 139.585584 -275.934402) (xy 139.551836 -275.896308)
			(xy 139.524635 -275.853294) (xy 139.504687 -275.806474) (xy 139.492508 -275.75706) (xy 139.488413 -275.706332)
			(xy 139.182856 -275.706332) (xy 139.182366 -275.731321) (xy 139.174547 -275.780684) (xy 139.159103 -275.828216)
			(xy 139.136413 -275.872748) (xy 139.107037 -275.913181) (xy 139.071697 -275.948521) (xy 139.031264 -275.977897)
			(xy 138.986732 -276.000587) (xy 138.9392 -276.016031) (xy 138.889837 -276.02385) (xy 138.839859 -276.02385)
			(xy 138.790496 -276.016031) (xy 138.742964 -276.000587) (xy 138.698432 -275.977897) (xy 138.657999 -275.948521)
			(xy 138.622659 -275.913181) (xy 138.593283 -275.872748) (xy 138.570593 -275.828216) (xy 138.555149 -275.780684)
			(xy 138.54733 -275.731321) (xy 138.240013 -275.731321) (xy 138.240004 -275.731778) (xy 138.23184 -275.782012)
			(xy 138.215724 -275.830286) (xy 138.192073 -275.875349) (xy 138.1615 -275.916035) (xy 138.124796 -275.95129)
			(xy 138.082912 -275.9802) (xy 138.036933 -276.002017) (xy 137.988049 -276.016177) (xy 137.937528 -276.022311)
			(xy 137.886676 -276.020262) (xy 137.836812 -276.010082) (xy 137.789226 -275.992035) (xy 137.745152 -275.966589)
			(xy 137.70573 -275.934402) (xy 137.671982 -275.896308) (xy 137.644781 -275.853294) (xy 137.624833 -275.806474)
			(xy 137.612654 -275.75706) (xy 137.608559 -275.706332) (xy 136.360408 -275.706332) (xy 136.359896 -275.731778)
			(xy 136.351732 -275.782012) (xy 136.335616 -275.830286) (xy 136.311965 -275.875349) (xy 136.281392 -275.916035)
			(xy 136.244688 -275.95129) (xy 136.202804 -275.9802) (xy 136.156825 -276.002017) (xy 136.107941 -276.016177)
			(xy 136.05742 -276.022311) (xy 136.006568 -276.020262) (xy 135.956704 -276.010082) (xy 135.909118 -275.992035)
			(xy 135.865044 -275.966589) (xy 135.825622 -275.934402) (xy 135.791874 -275.896308) (xy 135.764673 -275.853294)
			(xy 135.744725 -275.806474) (xy 135.732546 -275.75706) (xy 135.728451 -275.706332) (xy 135.420354 -275.706332)
			(xy 135.419842 -275.731778) (xy 135.411678 -275.782012) (xy 135.395562 -275.830286) (xy 135.371911 -275.875349)
			(xy 135.341338 -275.916035) (xy 135.304634 -275.95129) (xy 135.26275 -275.9802) (xy 135.216771 -276.002017)
			(xy 135.167887 -276.016177) (xy 135.117366 -276.022311) (xy 135.066514 -276.020262) (xy 135.01665 -276.010082)
			(xy 134.969064 -275.992035) (xy 134.92499 -275.966589) (xy 134.885568 -275.934402) (xy 134.85182 -275.896308)
			(xy 134.824619 -275.853294) (xy 134.804671 -275.806474) (xy 134.792492 -275.75706) (xy 134.788397 -275.706332)
			(xy 134.48284 -275.706332) (xy 134.48235 -275.731321) (xy 134.474531 -275.780684) (xy 134.459087 -275.828216)
			(xy 134.436397 -275.872748) (xy 134.407021 -275.913181) (xy 134.371681 -275.948521) (xy 134.331248 -275.977897)
			(xy 134.286716 -276.000587) (xy 134.239184 -276.016031) (xy 134.189821 -276.02385) (xy 134.139843 -276.02385)
			(xy 134.09048 -276.016031) (xy 134.042948 -276.000587) (xy 133.998416 -275.977897) (xy 133.957983 -275.948521)
			(xy 133.922643 -275.913181) (xy 133.893267 -275.872748) (xy 133.870577 -275.828216) (xy 133.855133 -275.780684)
			(xy 133.847314 -275.731321) (xy 133.539997 -275.731321) (xy 133.539988 -275.731778) (xy 133.531824 -275.782012)
			(xy 133.515708 -275.830286) (xy 133.492057 -275.875349) (xy 133.461484 -275.916035) (xy 133.42478 -275.95129)
			(xy 133.382896 -275.9802) (xy 133.336917 -276.002017) (xy 133.288033 -276.016177) (xy 133.237512 -276.022311)
			(xy 133.18666 -276.020262) (xy 133.136796 -276.010082) (xy 133.08921 -275.992035) (xy 133.045136 -275.966589)
			(xy 133.005714 -275.934402) (xy 132.971966 -275.896308) (xy 132.944765 -275.853294) (xy 132.924817 -275.806474)
			(xy 132.912638 -275.75706) (xy 132.908543 -275.706332) (xy 132.602732 -275.706332) (xy 132.602242 -275.731321)
			(xy 132.594423 -275.780684) (xy 132.578979 -275.828216) (xy 132.556289 -275.872748) (xy 132.526913 -275.913181)
			(xy 132.491573 -275.948521) (xy 132.45114 -275.977897) (xy 132.406608 -276.000587) (xy 132.359076 -276.016031)
			(xy 132.309713 -276.02385) (xy 132.259735 -276.02385) (xy 132.210372 -276.016031) (xy 132.16284 -276.000587)
			(xy 132.118308 -275.977897) (xy 132.077875 -275.948521) (xy 132.042535 -275.913181) (xy 132.013159 -275.872748)
			(xy 131.990469 -275.828216) (xy 131.975025 -275.780684) (xy 131.967206 -275.731321) (xy 131.659889 -275.731321)
			(xy 131.65988 -275.731778) (xy 131.651716 -275.782012) (xy 131.6356 -275.830286) (xy 131.611949 -275.875349)
			(xy 131.581376 -275.916035) (xy 131.544672 -275.95129) (xy 131.502788 -275.9802) (xy 131.456809 -276.002017)
			(xy 131.407925 -276.016177) (xy 131.357404 -276.022311) (xy 131.306552 -276.020262) (xy 131.256688 -276.010082)
			(xy 131.209102 -275.992035) (xy 131.165028 -275.966589) (xy 131.125606 -275.934402) (xy 131.091858 -275.896308)
			(xy 131.064657 -275.853294) (xy 131.044709 -275.806474) (xy 131.03253 -275.75706) (xy 131.028435 -275.706332)
			(xy 129.780538 -275.706332) (xy 129.780026 -275.731778) (xy 129.771862 -275.782012) (xy 129.755746 -275.830286)
			(xy 129.732095 -275.875349) (xy 129.701522 -275.916035) (xy 129.664818 -275.95129) (xy 129.622934 -275.9802)
			(xy 129.576955 -276.002017) (xy 129.528071 -276.016177) (xy 129.47755 -276.022311) (xy 129.426698 -276.020262)
			(xy 129.376834 -276.010082) (xy 129.329248 -275.992035) (xy 129.285174 -275.966589) (xy 129.245752 -275.934402)
			(xy 129.212004 -275.896308) (xy 129.184803 -275.853294) (xy 129.164855 -275.806474) (xy 129.152676 -275.75706)
			(xy 129.148581 -275.706332) (xy 128.840484 -275.706332) (xy 128.839972 -275.731778) (xy 128.831808 -275.782012)
			(xy 128.815692 -275.830286) (xy 128.792041 -275.875349) (xy 128.761468 -275.916035) (xy 128.724764 -275.95129)
			(xy 128.68288 -275.9802) (xy 128.636901 -276.002017) (xy 128.588017 -276.016177) (xy 128.537496 -276.022311)
			(xy 128.486644 -276.020262) (xy 128.43678 -276.010082) (xy 128.389194 -275.992035) (xy 128.34512 -275.966589)
			(xy 128.305698 -275.934402) (xy 128.27195 -275.896308) (xy 128.244749 -275.853294) (xy 128.224801 -275.806474)
			(xy 128.212622 -275.75706) (xy 128.208527 -275.706332) (xy 127.90244 -275.706332) (xy 127.90244 -275.731306)
			(xy 127.894616 -275.780703) (xy 127.879161 -275.828268) (xy 127.856457 -275.872829) (xy 127.82706 -275.913291)
			(xy 127.791697 -275.948655) (xy 127.751236 -275.978052) (xy 127.706675 -276.000758) (xy 127.659111 -276.016214)
			(xy 127.609714 -276.024039) (xy 127.584708 -276.024594) (xy 127.55734 -276.024025) (xy 127.50341 -276.01466)
			(xy 127.451878 -275.996205) (xy 127.404264 -275.969204) (xy 127.361972 -275.934454) (xy 127.343662 -275.914104)
			(xy 127.343154 -275.913596) (xy 127.343154 -275.913342) (xy 127.337865 -275.907852) (xy 127.32482 -275.899979)
			(xy 127.3175 -275.897848) (xy 127.310134 -275.895816) (xy 127.29464 -275.896578) (xy 127.20066 -275.931376)
			(xy 127.200406 -275.931376) (xy 127.193205 -275.93435) (xy 127.180918 -275.943916) (xy 127.176276 -275.950172)
			(xy 127.171958 -275.956268) (xy 127.167386 -275.971) (xy 127.167386 -276.162008) (xy 127.168035 -276.173985)
			(xy 127.178916 -276.195322) (xy 127.188214 -276.202902) (xy 127.196342 -276.206966) (xy 127.204978 -276.210522)
			(xy 127.229391 -276.218247) (xy 127.275558 -276.240387) (xy 127.317592 -276.269624) (xy 127.35441 -276.305205)
			(xy 127.385065 -276.346216) (xy 127.408768 -276.3916) (xy 127.42491 -276.440191) (xy 127.433075 -276.490737)
			(xy 127.433578 -276.516338) (xy 127.738627 -276.516338) (xy 127.742722 -276.46561) (xy 127.754901 -276.416196)
			(xy 127.774849 -276.369376) (xy 127.80205 -276.326362) (xy 127.835798 -276.288268) (xy 127.87522 -276.256081)
			(xy 127.919294 -276.230635) (xy 127.96688 -276.212588) (xy 128.016744 -276.202408) (xy 128.067596 -276.200359)
			(xy 128.118117 -276.206493) (xy 128.167001 -276.220653) (xy 128.21298 -276.24247) (xy 128.254864 -276.27138)
			(xy 128.291568 -276.306635) (xy 128.322141 -276.347321) (xy 128.345792 -276.392384) (xy 128.361908 -276.440658)
			(xy 128.370072 -276.490892) (xy 128.370584 -276.516338) (xy 128.370081 -276.541327) (xy 128.677144 -276.541327)
			(xy 128.677144 -276.491349) (xy 128.684963 -276.441986) (xy 128.700407 -276.394454) (xy 128.723097 -276.349922)
			(xy 128.752473 -276.309489) (xy 128.787813 -276.274149) (xy 128.828246 -276.244773) (xy 128.872778 -276.222083)
			(xy 128.92031 -276.206639) (xy 128.969673 -276.19882) (xy 129.019651 -276.19882) (xy 129.069014 -276.206639)
			(xy 129.116546 -276.222083) (xy 129.161078 -276.244773) (xy 129.201511 -276.274149) (xy 129.236851 -276.309489)
			(xy 129.266227 -276.349922) (xy 129.288917 -276.394454) (xy 129.304361 -276.441986) (xy 129.31218 -276.491349)
			(xy 129.31267 -276.516338) (xy 129.618481 -276.516338) (xy 129.622576 -276.46561) (xy 129.634755 -276.416196)
			(xy 129.654703 -276.369376) (xy 129.681904 -276.326362) (xy 129.715652 -276.288268) (xy 129.755074 -276.256081)
			(xy 129.799148 -276.230635) (xy 129.846734 -276.212588) (xy 129.896598 -276.202408) (xy 129.94745 -276.200359)
			(xy 129.997971 -276.206493) (xy 130.046855 -276.220653) (xy 130.092834 -276.24247) (xy 130.134718 -276.27138)
			(xy 130.171422 -276.306635) (xy 130.201995 -276.347321) (xy 130.225646 -276.392384) (xy 130.241762 -276.440658)
			(xy 130.249926 -276.490892) (xy 130.250438 -276.516338) (xy 130.249935 -276.541327) (xy 130.557252 -276.541327)
			(xy 130.557252 -276.491349) (xy 130.565071 -276.441986) (xy 130.580515 -276.394454) (xy 130.603205 -276.349922)
			(xy 130.632581 -276.309489) (xy 130.667921 -276.274149) (xy 130.708354 -276.244773) (xy 130.752886 -276.222083)
			(xy 130.800418 -276.206639) (xy 130.849781 -276.19882) (xy 130.899759 -276.19882) (xy 130.949122 -276.206639)
			(xy 130.996654 -276.222083) (xy 131.041186 -276.244773) (xy 131.081619 -276.274149) (xy 131.116959 -276.309489)
			(xy 131.146335 -276.349922) (xy 131.169025 -276.394454) (xy 131.184469 -276.441986) (xy 131.192288 -276.491349)
			(xy 131.192778 -276.516338) (xy 131.498589 -276.516338) (xy 131.502684 -276.46561) (xy 131.514863 -276.416196)
			(xy 131.534811 -276.369376) (xy 131.562012 -276.326362) (xy 131.59576 -276.288268) (xy 131.635182 -276.256081)
			(xy 131.679256 -276.230635) (xy 131.726842 -276.212588) (xy 131.776706 -276.202408) (xy 131.827558 -276.200359)
			(xy 131.878079 -276.206493) (xy 131.926963 -276.220653) (xy 131.972942 -276.24247) (xy 132.014826 -276.27138)
			(xy 132.05153 -276.306635) (xy 132.082103 -276.347321) (xy 132.105754 -276.392384) (xy 132.12187 -276.440658)
			(xy 132.130034 -276.490892) (xy 132.130546 -276.516338) (xy 132.438643 -276.516338) (xy 132.442738 -276.46561)
			(xy 132.454917 -276.416196) (xy 132.474865 -276.369376) (xy 132.502066 -276.326362) (xy 132.535814 -276.288268)
			(xy 132.575236 -276.256081) (xy 132.61931 -276.230635) (xy 132.666896 -276.212588) (xy 132.71676 -276.202408)
			(xy 132.767612 -276.200359) (xy 132.818133 -276.206493) (xy 132.867017 -276.220653) (xy 132.912996 -276.24247)
			(xy 132.95488 -276.27138) (xy 132.991584 -276.306635) (xy 133.022157 -276.347321) (xy 133.045808 -276.392384)
			(xy 133.061924 -276.440658) (xy 133.070088 -276.490892) (xy 133.0706 -276.516338) (xy 133.070097 -276.541327)
			(xy 133.37716 -276.541327) (xy 133.37716 -276.491349) (xy 133.384979 -276.441986) (xy 133.400423 -276.394454)
			(xy 133.423113 -276.349922) (xy 133.452489 -276.309489) (xy 133.487829 -276.274149) (xy 133.528262 -276.244773)
			(xy 133.572794 -276.222083) (xy 133.620326 -276.206639) (xy 133.669689 -276.19882) (xy 133.719667 -276.19882)
			(xy 133.76903 -276.206639) (xy 133.816562 -276.222083) (xy 133.861094 -276.244773) (xy 133.901527 -276.274149)
			(xy 133.936867 -276.309489) (xy 133.966243 -276.349922) (xy 133.988933 -276.394454) (xy 134.004377 -276.441986)
			(xy 134.012196 -276.491349) (xy 134.012686 -276.516338) (xy 134.318497 -276.516338) (xy 134.322592 -276.46561)
			(xy 134.334771 -276.416196) (xy 134.354719 -276.369376) (xy 134.38192 -276.326362) (xy 134.415668 -276.288268)
			(xy 134.45509 -276.256081) (xy 134.499164 -276.230635) (xy 134.54675 -276.212588) (xy 134.596614 -276.202408)
			(xy 134.647466 -276.200359) (xy 134.697987 -276.206493) (xy 134.746871 -276.220653) (xy 134.79285 -276.24247)
			(xy 134.834734 -276.27138) (xy 134.871438 -276.306635) (xy 134.902011 -276.347321) (xy 134.925662 -276.392384)
			(xy 134.941778 -276.440658) (xy 134.949942 -276.490892) (xy 134.950454 -276.516338) (xy 134.949951 -276.541327)
			(xy 135.257268 -276.541327) (xy 135.257268 -276.491349) (xy 135.265087 -276.441986) (xy 135.280531 -276.394454)
			(xy 135.303221 -276.349922) (xy 135.332597 -276.309489) (xy 135.367937 -276.274149) (xy 135.40837 -276.244773)
			(xy 135.452902 -276.222083) (xy 135.500434 -276.206639) (xy 135.549797 -276.19882) (xy 135.599775 -276.19882)
			(xy 135.649138 -276.206639) (xy 135.69667 -276.222083) (xy 135.741202 -276.244773) (xy 135.781635 -276.274149)
			(xy 135.816975 -276.309489) (xy 135.846351 -276.349922) (xy 135.869041 -276.394454) (xy 135.884485 -276.441986)
			(xy 135.892304 -276.491349) (xy 135.892794 -276.516338) (xy 136.198605 -276.516338) (xy 136.2027 -276.46561)
			(xy 136.214879 -276.416196) (xy 136.234827 -276.369376) (xy 136.262028 -276.326362) (xy 136.295776 -276.288268)
			(xy 136.335198 -276.256081) (xy 136.379272 -276.230635) (xy 136.426858 -276.212588) (xy 136.476722 -276.202408)
			(xy 136.527574 -276.200359) (xy 136.578095 -276.206493) (xy 136.626979 -276.220653) (xy 136.672958 -276.24247)
			(xy 136.714842 -276.27138) (xy 136.751546 -276.306635) (xy 136.782119 -276.347321) (xy 136.80577 -276.392384)
			(xy 136.821886 -276.440658) (xy 136.83005 -276.490892) (xy 136.830562 -276.516338) (xy 136.830059 -276.541327)
			(xy 137.137122 -276.541327) (xy 137.137122 -276.491349) (xy 137.144941 -276.441986) (xy 137.160385 -276.394454)
			(xy 137.183075 -276.349922) (xy 137.212451 -276.309489) (xy 137.247791 -276.274149) (xy 137.288224 -276.244773)
			(xy 137.332756 -276.222083) (xy 137.380288 -276.206639) (xy 137.429651 -276.19882) (xy 137.479629 -276.19882)
			(xy 137.528992 -276.206639) (xy 137.576524 -276.222083) (xy 137.621056 -276.244773) (xy 137.661489 -276.274149)
			(xy 137.696829 -276.309489) (xy 137.726205 -276.349922) (xy 137.748895 -276.394454) (xy 137.764339 -276.441986)
			(xy 137.772158 -276.491349) (xy 137.772648 -276.516338) (xy 138.078459 -276.516338) (xy 138.082554 -276.46561)
			(xy 138.094733 -276.416196) (xy 138.114681 -276.369376) (xy 138.141882 -276.326362) (xy 138.17563 -276.288268)
			(xy 138.215052 -276.256081) (xy 138.259126 -276.230635) (xy 138.306712 -276.212588) (xy 138.356576 -276.202408)
			(xy 138.407428 -276.200359) (xy 138.457949 -276.206493) (xy 138.506833 -276.220653) (xy 138.552812 -276.24247)
			(xy 138.594696 -276.27138) (xy 138.6314 -276.306635) (xy 138.661973 -276.347321) (xy 138.685624 -276.392384)
			(xy 138.70174 -276.440658) (xy 138.709904 -276.490892) (xy 138.710416 -276.516338) (xy 139.018513 -276.516338)
			(xy 139.022608 -276.46561) (xy 139.034787 -276.416196) (xy 139.054735 -276.369376) (xy 139.081936 -276.326362)
			(xy 139.115684 -276.288268) (xy 139.155106 -276.256081) (xy 139.19918 -276.230635) (xy 139.246766 -276.212588)
			(xy 139.29663 -276.202408) (xy 139.347482 -276.200359) (xy 139.398003 -276.206493) (xy 139.446887 -276.220653)
			(xy 139.492866 -276.24247) (xy 139.53475 -276.27138) (xy 139.571454 -276.306635) (xy 139.602027 -276.347321)
			(xy 139.625678 -276.392384) (xy 139.641794 -276.440658) (xy 139.649958 -276.490892) (xy 139.65047 -276.516338)
			(xy 139.649967 -276.541327) (xy 139.957284 -276.541327) (xy 139.957284 -276.491349) (xy 139.965103 -276.441986)
			(xy 139.980547 -276.394454) (xy 140.003237 -276.349922) (xy 140.032613 -276.309489) (xy 140.067953 -276.274149)
			(xy 140.108386 -276.244773) (xy 140.152918 -276.222083) (xy 140.20045 -276.206639) (xy 140.249813 -276.19882)
			(xy 140.299791 -276.19882) (xy 140.349154 -276.206639) (xy 140.396686 -276.222083) (xy 140.441218 -276.244773)
			(xy 140.481651 -276.274149) (xy 140.516991 -276.309489) (xy 140.546367 -276.349922) (xy 140.569057 -276.394454)
			(xy 140.584501 -276.441986) (xy 140.59232 -276.491349) (xy 140.59281 -276.516338) (xy 140.898621 -276.516338)
			(xy 140.902716 -276.46561) (xy 140.914895 -276.416196) (xy 140.934843 -276.369376) (xy 140.962044 -276.326362)
			(xy 140.995792 -276.288268) (xy 141.035214 -276.256081) (xy 141.079288 -276.230635) (xy 141.126874 -276.212588)
			(xy 141.176738 -276.202408) (xy 141.22759 -276.200359) (xy 141.278111 -276.206493) (xy 141.326995 -276.220653)
			(xy 141.372974 -276.24247) (xy 141.414858 -276.27138) (xy 141.451562 -276.306635) (xy 141.482135 -276.347321)
			(xy 141.505786 -276.392384) (xy 141.521902 -276.440658) (xy 141.530066 -276.490892) (xy 141.530578 -276.516338)
			(xy 141.530075 -276.541327) (xy 141.837138 -276.541327) (xy 141.837138 -276.491349) (xy 141.844957 -276.441986)
			(xy 141.860401 -276.394454) (xy 141.883091 -276.349922) (xy 141.912467 -276.309489) (xy 141.947807 -276.274149)
			(xy 141.98824 -276.244773) (xy 142.032772 -276.222083) (xy 142.080304 -276.206639) (xy 142.129667 -276.19882)
			(xy 142.179645 -276.19882) (xy 142.229008 -276.206639) (xy 142.27654 -276.222083) (xy 142.321072 -276.244773)
			(xy 142.361505 -276.274149) (xy 142.396845 -276.309489) (xy 142.426221 -276.349922) (xy 142.448911 -276.394454)
			(xy 142.464355 -276.441986) (xy 142.472174 -276.491349) (xy 142.472664 -276.516338) (xy 142.778475 -276.516338)
			(xy 142.78257 -276.46561) (xy 142.794749 -276.416196) (xy 142.814697 -276.369376) (xy 142.841898 -276.326362)
			(xy 142.875646 -276.288268) (xy 142.915068 -276.256081) (xy 142.959142 -276.230635) (xy 143.006728 -276.212588)
			(xy 143.056592 -276.202408) (xy 143.107444 -276.200359) (xy 143.157965 -276.206493) (xy 143.206849 -276.220653)
			(xy 143.252828 -276.24247) (xy 143.294712 -276.27138) (xy 143.331416 -276.306635) (xy 143.361989 -276.347321)
			(xy 143.38564 -276.392384) (xy 143.401756 -276.440658) (xy 143.40992 -276.490892) (xy 143.410432 -276.516338)
			(xy 143.409929 -276.541327) (xy 143.717246 -276.541327) (xy 143.717246 -276.491349) (xy 143.725065 -276.441986)
			(xy 143.740509 -276.394454) (xy 143.763199 -276.349922) (xy 143.792575 -276.309489) (xy 143.827915 -276.274149)
			(xy 143.868348 -276.244773) (xy 143.91288 -276.222083) (xy 143.960412 -276.206639) (xy 144.009775 -276.19882)
			(xy 144.059753 -276.19882) (xy 144.109116 -276.206639) (xy 144.156648 -276.222083) (xy 144.20118 -276.244773)
			(xy 144.241613 -276.274149) (xy 144.276953 -276.309489) (xy 144.306329 -276.349922) (xy 144.329019 -276.394454)
			(xy 144.344463 -276.441986) (xy 144.352282 -276.491349) (xy 144.352772 -276.516338) (xy 144.352282 -276.541327)
			(xy 144.344463 -276.59069) (xy 144.329019 -276.638222) (xy 144.306329 -276.682754) (xy 144.276953 -276.723187)
			(xy 144.241613 -276.758527) (xy 144.20118 -276.787903) (xy 144.156648 -276.810593) (xy 144.109116 -276.826037)
			(xy 144.059753 -276.833856) (xy 144.009775 -276.833856) (xy 143.960412 -276.826037) (xy 143.91288 -276.810593)
			(xy 143.868348 -276.787903) (xy 143.827915 -276.758527) (xy 143.792575 -276.723187) (xy 143.763199 -276.682754)
			(xy 143.740509 -276.638222) (xy 143.725065 -276.59069) (xy 143.717246 -276.541327) (xy 143.409929 -276.541327)
			(xy 143.40992 -276.541784) (xy 143.401756 -276.592018) (xy 143.38564 -276.640292) (xy 143.361989 -276.685355)
			(xy 143.331416 -276.726041) (xy 143.294712 -276.761296) (xy 143.252828 -276.790206) (xy 143.206849 -276.812023)
			(xy 143.157965 -276.826183) (xy 143.107444 -276.832317) (xy 143.056592 -276.830268) (xy 143.006728 -276.820088)
			(xy 142.959142 -276.802041) (xy 142.915068 -276.776595) (xy 142.875646 -276.744408) (xy 142.841898 -276.706314)
			(xy 142.814697 -276.6633) (xy 142.794749 -276.61648) (xy 142.78257 -276.567066) (xy 142.778475 -276.516338)
			(xy 142.472664 -276.516338) (xy 142.472174 -276.541327) (xy 142.464355 -276.59069) (xy 142.448911 -276.638222)
			(xy 142.426221 -276.682754) (xy 142.396845 -276.723187) (xy 142.361505 -276.758527) (xy 142.321072 -276.787903)
			(xy 142.27654 -276.810593) (xy 142.229008 -276.826037) (xy 142.179645 -276.833856) (xy 142.129667 -276.833856)
			(xy 142.080304 -276.826037) (xy 142.032772 -276.810593) (xy 141.98824 -276.787903) (xy 141.947807 -276.758527)
			(xy 141.912467 -276.723187) (xy 141.883091 -276.682754) (xy 141.860401 -276.638222) (xy 141.844957 -276.59069)
			(xy 141.837138 -276.541327) (xy 141.530075 -276.541327) (xy 141.530066 -276.541784) (xy 141.521902 -276.592018)
			(xy 141.505786 -276.640292) (xy 141.482135 -276.685355) (xy 141.451562 -276.726041) (xy 141.414858 -276.761296)
			(xy 141.372974 -276.790206) (xy 141.326995 -276.812023) (xy 141.278111 -276.826183) (xy 141.22759 -276.832317)
			(xy 141.176738 -276.830268) (xy 141.126874 -276.820088) (xy 141.079288 -276.802041) (xy 141.035214 -276.776595)
			(xy 140.995792 -276.744408) (xy 140.962044 -276.706314) (xy 140.934843 -276.6633) (xy 140.914895 -276.61648)
			(xy 140.902716 -276.567066) (xy 140.898621 -276.516338) (xy 140.59281 -276.516338) (xy 140.59232 -276.541327)
			(xy 140.584501 -276.59069) (xy 140.569057 -276.638222) (xy 140.546367 -276.682754) (xy 140.516991 -276.723187)
			(xy 140.481651 -276.758527) (xy 140.441218 -276.787903) (xy 140.396686 -276.810593) (xy 140.349154 -276.826037)
			(xy 140.299791 -276.833856) (xy 140.249813 -276.833856) (xy 140.20045 -276.826037) (xy 140.152918 -276.810593)
			(xy 140.108386 -276.787903) (xy 140.067953 -276.758527) (xy 140.032613 -276.723187) (xy 140.003237 -276.682754)
			(xy 139.980547 -276.638222) (xy 139.965103 -276.59069) (xy 139.957284 -276.541327) (xy 139.649967 -276.541327)
			(xy 139.649958 -276.541784) (xy 139.641794 -276.592018) (xy 139.625678 -276.640292) (xy 139.602027 -276.685355)
			(xy 139.571454 -276.726041) (xy 139.53475 -276.761296) (xy 139.492866 -276.790206) (xy 139.446887 -276.812023)
			(xy 139.398003 -276.826183) (xy 139.347482 -276.832317) (xy 139.29663 -276.830268) (xy 139.246766 -276.820088)
			(xy 139.19918 -276.802041) (xy 139.155106 -276.776595) (xy 139.115684 -276.744408) (xy 139.081936 -276.706314)
			(xy 139.054735 -276.6633) (xy 139.034787 -276.61648) (xy 139.022608 -276.567066) (xy 139.018513 -276.516338)
			(xy 138.710416 -276.516338) (xy 138.709904 -276.541784) (xy 138.70174 -276.592018) (xy 138.685624 -276.640292)
			(xy 138.661973 -276.685355) (xy 138.6314 -276.726041) (xy 138.594696 -276.761296) (xy 138.552812 -276.790206)
			(xy 138.506833 -276.812023) (xy 138.457949 -276.826183) (xy 138.407428 -276.832317) (xy 138.356576 -276.830268)
			(xy 138.306712 -276.820088) (xy 138.259126 -276.802041) (xy 138.215052 -276.776595) (xy 138.17563 -276.744408)
			(xy 138.141882 -276.706314) (xy 138.114681 -276.6633) (xy 138.094733 -276.61648) (xy 138.082554 -276.567066)
			(xy 138.078459 -276.516338) (xy 137.772648 -276.516338) (xy 137.772158 -276.541327) (xy 137.764339 -276.59069)
			(xy 137.748895 -276.638222) (xy 137.726205 -276.682754) (xy 137.696829 -276.723187) (xy 137.661489 -276.758527)
			(xy 137.621056 -276.787903) (xy 137.576524 -276.810593) (xy 137.528992 -276.826037) (xy 137.479629 -276.833856)
			(xy 137.429651 -276.833856) (xy 137.380288 -276.826037) (xy 137.332756 -276.810593) (xy 137.288224 -276.787903)
			(xy 137.247791 -276.758527) (xy 137.212451 -276.723187) (xy 137.183075 -276.682754) (xy 137.160385 -276.638222)
			(xy 137.144941 -276.59069) (xy 137.137122 -276.541327) (xy 136.830059 -276.541327) (xy 136.83005 -276.541784)
			(xy 136.821886 -276.592018) (xy 136.80577 -276.640292) (xy 136.782119 -276.685355) (xy 136.751546 -276.726041)
			(xy 136.714842 -276.761296) (xy 136.672958 -276.790206) (xy 136.626979 -276.812023) (xy 136.578095 -276.826183)
			(xy 136.527574 -276.832317) (xy 136.476722 -276.830268) (xy 136.426858 -276.820088) (xy 136.379272 -276.802041)
			(xy 136.335198 -276.776595) (xy 136.295776 -276.744408) (xy 136.262028 -276.706314) (xy 136.234827 -276.6633)
			(xy 136.214879 -276.61648) (xy 136.2027 -276.567066) (xy 136.198605 -276.516338) (xy 135.892794 -276.516338)
			(xy 135.892304 -276.541327) (xy 135.884485 -276.59069) (xy 135.869041 -276.638222) (xy 135.846351 -276.682754)
			(xy 135.816975 -276.723187) (xy 135.781635 -276.758527) (xy 135.741202 -276.787903) (xy 135.69667 -276.810593)
			(xy 135.649138 -276.826037) (xy 135.599775 -276.833856) (xy 135.549797 -276.833856) (xy 135.500434 -276.826037)
			(xy 135.452902 -276.810593) (xy 135.40837 -276.787903) (xy 135.367937 -276.758527) (xy 135.332597 -276.723187)
			(xy 135.303221 -276.682754) (xy 135.280531 -276.638222) (xy 135.265087 -276.59069) (xy 135.257268 -276.541327)
			(xy 134.949951 -276.541327) (xy 134.949942 -276.541784) (xy 134.941778 -276.592018) (xy 134.925662 -276.640292)
			(xy 134.902011 -276.685355) (xy 134.871438 -276.726041) (xy 134.834734 -276.761296) (xy 134.79285 -276.790206)
			(xy 134.746871 -276.812023) (xy 134.697987 -276.826183) (xy 134.647466 -276.832317) (xy 134.596614 -276.830268)
			(xy 134.54675 -276.820088) (xy 134.499164 -276.802041) (xy 134.45509 -276.776595) (xy 134.415668 -276.744408)
			(xy 134.38192 -276.706314) (xy 134.354719 -276.6633) (xy 134.334771 -276.61648) (xy 134.322592 -276.567066)
			(xy 134.318497 -276.516338) (xy 134.012686 -276.516338) (xy 134.012196 -276.541327) (xy 134.004377 -276.59069)
			(xy 133.988933 -276.638222) (xy 133.966243 -276.682754) (xy 133.936867 -276.723187) (xy 133.901527 -276.758527)
			(xy 133.861094 -276.787903) (xy 133.816562 -276.810593) (xy 133.76903 -276.826037) (xy 133.719667 -276.833856)
			(xy 133.669689 -276.833856) (xy 133.620326 -276.826037) (xy 133.572794 -276.810593) (xy 133.528262 -276.787903)
			(xy 133.487829 -276.758527) (xy 133.452489 -276.723187) (xy 133.423113 -276.682754) (xy 133.400423 -276.638222)
			(xy 133.384979 -276.59069) (xy 133.37716 -276.541327) (xy 133.070097 -276.541327) (xy 133.070088 -276.541784)
			(xy 133.061924 -276.592018) (xy 133.045808 -276.640292) (xy 133.022157 -276.685355) (xy 132.991584 -276.726041)
			(xy 132.95488 -276.761296) (xy 132.912996 -276.790206) (xy 132.867017 -276.812023) (xy 132.818133 -276.826183)
			(xy 132.767612 -276.832317) (xy 132.71676 -276.830268) (xy 132.666896 -276.820088) (xy 132.61931 -276.802041)
			(xy 132.575236 -276.776595) (xy 132.535814 -276.744408) (xy 132.502066 -276.706314) (xy 132.474865 -276.6633)
			(xy 132.454917 -276.61648) (xy 132.442738 -276.567066) (xy 132.438643 -276.516338) (xy 132.130546 -276.516338)
			(xy 132.130034 -276.541784) (xy 132.12187 -276.592018) (xy 132.105754 -276.640292) (xy 132.082103 -276.685355)
			(xy 132.05153 -276.726041) (xy 132.014826 -276.761296) (xy 131.972942 -276.790206) (xy 131.926963 -276.812023)
			(xy 131.878079 -276.826183) (xy 131.827558 -276.832317) (xy 131.776706 -276.830268) (xy 131.726842 -276.820088)
			(xy 131.679256 -276.802041) (xy 131.635182 -276.776595) (xy 131.59576 -276.744408) (xy 131.562012 -276.706314)
			(xy 131.534811 -276.6633) (xy 131.514863 -276.61648) (xy 131.502684 -276.567066) (xy 131.498589 -276.516338)
			(xy 131.192778 -276.516338) (xy 131.192288 -276.541327) (xy 131.184469 -276.59069) (xy 131.169025 -276.638222)
			(xy 131.146335 -276.682754) (xy 131.116959 -276.723187) (xy 131.081619 -276.758527) (xy 131.041186 -276.787903)
			(xy 130.996654 -276.810593) (xy 130.949122 -276.826037) (xy 130.899759 -276.833856) (xy 130.849781 -276.833856)
			(xy 130.800418 -276.826037) (xy 130.752886 -276.810593) (xy 130.708354 -276.787903) (xy 130.667921 -276.758527)
			(xy 130.632581 -276.723187) (xy 130.603205 -276.682754) (xy 130.580515 -276.638222) (xy 130.565071 -276.59069)
			(xy 130.557252 -276.541327) (xy 130.249935 -276.541327) (xy 130.249926 -276.541784) (xy 130.241762 -276.592018)
			(xy 130.225646 -276.640292) (xy 130.201995 -276.685355) (xy 130.171422 -276.726041) (xy 130.134718 -276.761296)
			(xy 130.092834 -276.790206) (xy 130.046855 -276.812023) (xy 129.997971 -276.826183) (xy 129.94745 -276.832317)
			(xy 129.896598 -276.830268) (xy 129.846734 -276.820088) (xy 129.799148 -276.802041) (xy 129.755074 -276.776595)
			(xy 129.715652 -276.744408) (xy 129.681904 -276.706314) (xy 129.654703 -276.6633) (xy 129.634755 -276.61648)
			(xy 129.622576 -276.567066) (xy 129.618481 -276.516338) (xy 129.31267 -276.516338) (xy 129.31218 -276.541327)
			(xy 129.304361 -276.59069) (xy 129.288917 -276.638222) (xy 129.266227 -276.682754) (xy 129.236851 -276.723187)
			(xy 129.201511 -276.758527) (xy 129.161078 -276.787903) (xy 129.116546 -276.810593) (xy 129.069014 -276.826037)
			(xy 129.019651 -276.833856) (xy 128.969673 -276.833856) (xy 128.92031 -276.826037) (xy 128.872778 -276.810593)
			(xy 128.828246 -276.787903) (xy 128.787813 -276.758527) (xy 128.752473 -276.723187) (xy 128.723097 -276.682754)
			(xy 128.700407 -276.638222) (xy 128.684963 -276.59069) (xy 128.677144 -276.541327) (xy 128.370081 -276.541327)
			(xy 128.370072 -276.541784) (xy 128.361908 -276.592018) (xy 128.345792 -276.640292) (xy 128.322141 -276.685355)
			(xy 128.291568 -276.726041) (xy 128.254864 -276.761296) (xy 128.21298 -276.790206) (xy 128.167001 -276.812023)
			(xy 128.118117 -276.826183) (xy 128.067596 -276.832317) (xy 128.016744 -276.830268) (xy 127.96688 -276.820088)
			(xy 127.919294 -276.802041) (xy 127.87522 -276.776595) (xy 127.835798 -276.744408) (xy 127.80205 -276.706314)
			(xy 127.774849 -276.6633) (xy 127.754901 -276.61648) (xy 127.742722 -276.567066) (xy 127.738627 -276.516338)
			(xy 127.433578 -276.516338) (xy 127.433057 -276.542401) (xy 127.424575 -276.593833) (xy 127.407844 -276.643201)
			(xy 127.383308 -276.689192) (xy 127.351621 -276.730582) (xy 127.313627 -276.766269) (xy 127.270335 -276.795303)
			(xy 127.222898 -276.816912) (xy 127.197866 -276.824186) (xy 127.189041 -276.828547) (xy 127.175314 -276.842629)
			(xy 127.16788 -276.860836) (xy 127.167386 -276.870668) (xy 127.167386 -277.326344) (xy 128.208527 -277.326344)
			(xy 128.212622 -277.275616) (xy 128.224801 -277.226202) (xy 128.244749 -277.179382) (xy 128.27195 -277.136368)
			(xy 128.305698 -277.098274) (xy 128.34512 -277.066087) (xy 128.389194 -277.040641) (xy 128.43678 -277.022594)
			(xy 128.486644 -277.012414) (xy 128.537496 -277.010365) (xy 128.588017 -277.016499) (xy 128.636901 -277.030659)
			(xy 128.68288 -277.052476) (xy 128.724764 -277.081386) (xy 128.761468 -277.116641) (xy 128.792041 -277.157327)
			(xy 128.815692 -277.20239) (xy 128.831808 -277.250664) (xy 128.839972 -277.300898) (xy 128.840484 -277.326344)
			(xy 129.148581 -277.326344) (xy 129.152676 -277.275616) (xy 129.164855 -277.226202) (xy 129.184803 -277.179382)
			(xy 129.212004 -277.136368) (xy 129.245752 -277.098274) (xy 129.285174 -277.066087) (xy 129.329248 -277.040641)
			(xy 129.376834 -277.022594) (xy 129.426698 -277.012414) (xy 129.47755 -277.010365) (xy 129.528071 -277.016499)
			(xy 129.576955 -277.030659) (xy 129.622934 -277.052476) (xy 129.664818 -277.081386) (xy 129.701522 -277.116641)
			(xy 129.732095 -277.157327) (xy 129.755746 -277.20239) (xy 129.771862 -277.250664) (xy 129.780026 -277.300898)
			(xy 129.780538 -277.326344) (xy 129.780035 -277.351333) (xy 130.087352 -277.351333) (xy 130.087352 -277.301355)
			(xy 130.095171 -277.251992) (xy 130.110615 -277.20446) (xy 130.133305 -277.159928) (xy 130.162681 -277.119495)
			(xy 130.198021 -277.084155) (xy 130.238454 -277.054779) (xy 130.282986 -277.032089) (xy 130.330518 -277.016645)
			(xy 130.379881 -277.008826) (xy 130.429859 -277.008826) (xy 130.479222 -277.016645) (xy 130.526754 -277.032089)
			(xy 130.571286 -277.054779) (xy 130.611719 -277.084155) (xy 130.647059 -277.119495) (xy 130.676435 -277.159928)
			(xy 130.699125 -277.20446) (xy 130.714569 -277.251992) (xy 130.722388 -277.301355) (xy 130.722878 -277.326344)
			(xy 131.028435 -277.326344) (xy 131.03253 -277.275616) (xy 131.044709 -277.226202) (xy 131.064657 -277.179382)
			(xy 131.091858 -277.136368) (xy 131.125606 -277.098274) (xy 131.165028 -277.066087) (xy 131.209102 -277.040641)
			(xy 131.256688 -277.022594) (xy 131.306552 -277.012414) (xy 131.357404 -277.010365) (xy 131.407925 -277.016499)
			(xy 131.456809 -277.030659) (xy 131.502788 -277.052476) (xy 131.544672 -277.081386) (xy 131.581376 -277.116641)
			(xy 131.611949 -277.157327) (xy 131.6356 -277.20239) (xy 131.651716 -277.250664) (xy 131.65988 -277.300898)
			(xy 131.660392 -277.326344) (xy 131.659889 -277.351333) (xy 131.967206 -277.351333) (xy 131.967206 -277.301355)
			(xy 131.975025 -277.251992) (xy 131.990469 -277.20446) (xy 132.013159 -277.159928) (xy 132.042535 -277.119495)
			(xy 132.077875 -277.084155) (xy 132.118308 -277.054779) (xy 132.16284 -277.032089) (xy 132.210372 -277.016645)
			(xy 132.259735 -277.008826) (xy 132.309713 -277.008826) (xy 132.359076 -277.016645) (xy 132.406608 -277.032089)
			(xy 132.45114 -277.054779) (xy 132.491573 -277.084155) (xy 132.526913 -277.119495) (xy 132.556289 -277.159928)
			(xy 132.578979 -277.20446) (xy 132.594423 -277.251992) (xy 132.602242 -277.301355) (xy 132.602732 -277.326344)
			(xy 132.908543 -277.326344) (xy 132.912638 -277.275616) (xy 132.924817 -277.226202) (xy 132.944765 -277.179382)
			(xy 132.971966 -277.136368) (xy 133.005714 -277.098274) (xy 133.045136 -277.066087) (xy 133.08921 -277.040641)
			(xy 133.136796 -277.022594) (xy 133.18666 -277.012414) (xy 133.237512 -277.010365) (xy 133.288033 -277.016499)
			(xy 133.336917 -277.030659) (xy 133.382896 -277.052476) (xy 133.42478 -277.081386) (xy 133.461484 -277.116641)
			(xy 133.492057 -277.157327) (xy 133.515708 -277.20239) (xy 133.531824 -277.250664) (xy 133.539988 -277.300898)
			(xy 133.5405 -277.326344) (xy 133.539997 -277.351333) (xy 133.847314 -277.351333) (xy 133.847314 -277.301355)
			(xy 133.855133 -277.251992) (xy 133.870577 -277.20446) (xy 133.893267 -277.159928) (xy 133.922643 -277.119495)
			(xy 133.957983 -277.084155) (xy 133.998416 -277.054779) (xy 134.042948 -277.032089) (xy 134.09048 -277.016645)
			(xy 134.139843 -277.008826) (xy 134.189821 -277.008826) (xy 134.239184 -277.016645) (xy 134.286716 -277.032089)
			(xy 134.331248 -277.054779) (xy 134.371681 -277.084155) (xy 134.407021 -277.119495) (xy 134.436397 -277.159928)
			(xy 134.459087 -277.20446) (xy 134.474531 -277.251992) (xy 134.48235 -277.301355) (xy 134.48284 -277.326344)
			(xy 134.788397 -277.326344) (xy 134.792492 -277.275616) (xy 134.804671 -277.226202) (xy 134.824619 -277.179382)
			(xy 134.85182 -277.136368) (xy 134.885568 -277.098274) (xy 134.92499 -277.066087) (xy 134.969064 -277.040641)
			(xy 135.01665 -277.022594) (xy 135.066514 -277.012414) (xy 135.117366 -277.010365) (xy 135.167887 -277.016499)
			(xy 135.216771 -277.030659) (xy 135.26275 -277.052476) (xy 135.304634 -277.081386) (xy 135.341338 -277.116641)
			(xy 135.371911 -277.157327) (xy 135.395562 -277.20239) (xy 135.411678 -277.250664) (xy 135.419842 -277.300898)
			(xy 135.420354 -277.326344) (xy 135.728451 -277.326344) (xy 135.732546 -277.275616) (xy 135.744725 -277.226202)
			(xy 135.764673 -277.179382) (xy 135.791874 -277.136368) (xy 135.825622 -277.098274) (xy 135.865044 -277.066087)
			(xy 135.909118 -277.040641) (xy 135.956704 -277.022594) (xy 136.006568 -277.012414) (xy 136.05742 -277.010365)
			(xy 136.107941 -277.016499) (xy 136.156825 -277.030659) (xy 136.202804 -277.052476) (xy 136.244688 -277.081386)
			(xy 136.281392 -277.116641) (xy 136.311965 -277.157327) (xy 136.335616 -277.20239) (xy 136.351732 -277.250664)
			(xy 136.359896 -277.300898) (xy 136.360408 -277.326344) (xy 136.359905 -277.351333) (xy 136.667222 -277.351333)
			(xy 136.667222 -277.301355) (xy 136.675041 -277.251992) (xy 136.690485 -277.20446) (xy 136.713175 -277.159928)
			(xy 136.742551 -277.119495) (xy 136.777891 -277.084155) (xy 136.818324 -277.054779) (xy 136.862856 -277.032089)
			(xy 136.910388 -277.016645) (xy 136.959751 -277.008826) (xy 137.009729 -277.008826) (xy 137.059092 -277.016645)
			(xy 137.106624 -277.032089) (xy 137.151156 -277.054779) (xy 137.191589 -277.084155) (xy 137.226929 -277.119495)
			(xy 137.256305 -277.159928) (xy 137.278995 -277.20446) (xy 137.294439 -277.251992) (xy 137.302258 -277.301355)
			(xy 137.302748 -277.326344) (xy 137.608559 -277.326344) (xy 137.612654 -277.275616) (xy 137.624833 -277.226202)
			(xy 137.644781 -277.179382) (xy 137.671982 -277.136368) (xy 137.70573 -277.098274) (xy 137.745152 -277.066087)
			(xy 137.789226 -277.040641) (xy 137.836812 -277.022594) (xy 137.886676 -277.012414) (xy 137.937528 -277.010365)
			(xy 137.988049 -277.016499) (xy 138.036933 -277.030659) (xy 138.082912 -277.052476) (xy 138.124796 -277.081386)
			(xy 138.1615 -277.116641) (xy 138.192073 -277.157327) (xy 138.215724 -277.20239) (xy 138.23184 -277.250664)
			(xy 138.240004 -277.300898) (xy 138.240516 -277.326344) (xy 138.240013 -277.351333) (xy 138.54733 -277.351333)
			(xy 138.54733 -277.301355) (xy 138.555149 -277.251992) (xy 138.570593 -277.20446) (xy 138.593283 -277.159928)
			(xy 138.622659 -277.119495) (xy 138.657999 -277.084155) (xy 138.698432 -277.054779) (xy 138.742964 -277.032089)
			(xy 138.790496 -277.016645) (xy 138.839859 -277.008826) (xy 138.889837 -277.008826) (xy 138.9392 -277.016645)
			(xy 138.986732 -277.032089) (xy 139.031264 -277.054779) (xy 139.071697 -277.084155) (xy 139.107037 -277.119495)
			(xy 139.136413 -277.159928) (xy 139.159103 -277.20446) (xy 139.174547 -277.251992) (xy 139.182366 -277.301355)
			(xy 139.182856 -277.326344) (xy 139.488413 -277.326344) (xy 139.492508 -277.275616) (xy 139.504687 -277.226202)
			(xy 139.524635 -277.179382) (xy 139.551836 -277.136368) (xy 139.585584 -277.098274) (xy 139.625006 -277.066087)
			(xy 139.66908 -277.040641) (xy 139.716666 -277.022594) (xy 139.76653 -277.012414) (xy 139.817382 -277.010365)
			(xy 139.867903 -277.016499) (xy 139.916787 -277.030659) (xy 139.962766 -277.052476) (xy 140.00465 -277.081386)
			(xy 140.041354 -277.116641) (xy 140.071927 -277.157327) (xy 140.095578 -277.20239) (xy 140.111694 -277.250664)
			(xy 140.119858 -277.300898) (xy 140.12037 -277.326344) (xy 140.119867 -277.351333) (xy 140.427184 -277.351333)
			(xy 140.427184 -277.301355) (xy 140.435003 -277.251992) (xy 140.450447 -277.20446) (xy 140.473137 -277.159928)
			(xy 140.502513 -277.119495) (xy 140.537853 -277.084155) (xy 140.578286 -277.054779) (xy 140.622818 -277.032089)
			(xy 140.67035 -277.016645) (xy 140.719713 -277.008826) (xy 140.769691 -277.008826) (xy 140.819054 -277.016645)
			(xy 140.866586 -277.032089) (xy 140.911118 -277.054779) (xy 140.951551 -277.084155) (xy 140.986891 -277.119495)
			(xy 141.016267 -277.159928) (xy 141.038957 -277.20446) (xy 141.054401 -277.251992) (xy 141.06222 -277.301355)
			(xy 141.06271 -277.326344) (xy 141.368521 -277.326344) (xy 141.372616 -277.275616) (xy 141.384795 -277.226202)
			(xy 141.404743 -277.179382) (xy 141.431944 -277.136368) (xy 141.465692 -277.098274) (xy 141.505114 -277.066087)
			(xy 141.549188 -277.040641) (xy 141.596774 -277.022594) (xy 141.646638 -277.012414) (xy 141.69749 -277.010365)
			(xy 141.748011 -277.016499) (xy 141.796895 -277.030659) (xy 141.842874 -277.052476) (xy 141.884758 -277.081386)
			(xy 141.921462 -277.116641) (xy 141.952035 -277.157327) (xy 141.975686 -277.20239) (xy 141.991802 -277.250664)
			(xy 141.999966 -277.300898) (xy 142.000478 -277.326344) (xy 142.308575 -277.326344) (xy 142.31267 -277.275616)
			(xy 142.324849 -277.226202) (xy 142.344797 -277.179382) (xy 142.371998 -277.136368) (xy 142.405746 -277.098274)
			(xy 142.445168 -277.066087) (xy 142.489242 -277.040641) (xy 142.536828 -277.022594) (xy 142.586692 -277.012414)
			(xy 142.637544 -277.010365) (xy 142.688065 -277.016499) (xy 142.736949 -277.030659) (xy 142.782928 -277.052476)
			(xy 142.824812 -277.081386) (xy 142.861516 -277.116641) (xy 142.892089 -277.157327) (xy 142.91574 -277.20239)
			(xy 142.931856 -277.250664) (xy 142.94002 -277.300898) (xy 142.940532 -277.326344) (xy 142.940029 -277.351333)
			(xy 143.247092 -277.351333) (xy 143.247092 -277.301355) (xy 143.254911 -277.251992) (xy 143.270355 -277.20446)
			(xy 143.293045 -277.159928) (xy 143.322421 -277.119495) (xy 143.357761 -277.084155) (xy 143.398194 -277.054779)
			(xy 143.442726 -277.032089) (xy 143.490258 -277.016645) (xy 143.539621 -277.008826) (xy 143.589599 -277.008826)
			(xy 143.638962 -277.016645) (xy 143.686494 -277.032089) (xy 143.731026 -277.054779) (xy 143.771459 -277.084155)
			(xy 143.806799 -277.119495) (xy 143.836175 -277.159928) (xy 143.858865 -277.20446) (xy 143.874309 -277.251992)
			(xy 143.882128 -277.301355) (xy 143.882618 -277.326344) (xy 143.882128 -277.351333) (xy 143.874309 -277.400696)
			(xy 143.858865 -277.448228) (xy 143.836175 -277.49276) (xy 143.806799 -277.533193) (xy 143.771459 -277.568533)
			(xy 143.731026 -277.597909) (xy 143.686494 -277.620599) (xy 143.638962 -277.636043) (xy 143.589599 -277.643862)
			(xy 143.539621 -277.643862) (xy 143.490258 -277.636043) (xy 143.442726 -277.620599) (xy 143.398194 -277.597909)
			(xy 143.357761 -277.568533) (xy 143.322421 -277.533193) (xy 143.293045 -277.49276) (xy 143.270355 -277.448228)
			(xy 143.254911 -277.400696) (xy 143.247092 -277.351333) (xy 142.940029 -277.351333) (xy 142.94002 -277.35179)
			(xy 142.931856 -277.402024) (xy 142.91574 -277.450298) (xy 142.892089 -277.495361) (xy 142.861516 -277.536047)
			(xy 142.824812 -277.571302) (xy 142.782928 -277.600212) (xy 142.736949 -277.622029) (xy 142.688065 -277.636189)
			(xy 142.637544 -277.642323) (xy 142.586692 -277.640274) (xy 142.536828 -277.630094) (xy 142.489242 -277.612047)
			(xy 142.445168 -277.586601) (xy 142.405746 -277.554414) (xy 142.371998 -277.51632) (xy 142.344797 -277.473306)
			(xy 142.324849 -277.426486) (xy 142.31267 -277.377072) (xy 142.308575 -277.326344) (xy 142.000478 -277.326344)
			(xy 141.999966 -277.35179) (xy 141.991802 -277.402024) (xy 141.975686 -277.450298) (xy 141.952035 -277.495361)
			(xy 141.921462 -277.536047) (xy 141.884758 -277.571302) (xy 141.842874 -277.600212) (xy 141.796895 -277.622029)
			(xy 141.748011 -277.636189) (xy 141.69749 -277.642323) (xy 141.646638 -277.640274) (xy 141.596774 -277.630094)
			(xy 141.549188 -277.612047) (xy 141.505114 -277.586601) (xy 141.465692 -277.554414) (xy 141.431944 -277.51632)
			(xy 141.404743 -277.473306) (xy 141.384795 -277.426486) (xy 141.372616 -277.377072) (xy 141.368521 -277.326344)
			(xy 141.06271 -277.326344) (xy 141.06222 -277.351333) (xy 141.054401 -277.400696) (xy 141.038957 -277.448228)
			(xy 141.016267 -277.49276) (xy 140.986891 -277.533193) (xy 140.951551 -277.568533) (xy 140.911118 -277.597909)
			(xy 140.866586 -277.620599) (xy 140.819054 -277.636043) (xy 140.769691 -277.643862) (xy 140.719713 -277.643862)
			(xy 140.67035 -277.636043) (xy 140.622818 -277.620599) (xy 140.578286 -277.597909) (xy 140.537853 -277.568533)
			(xy 140.502513 -277.533193) (xy 140.473137 -277.49276) (xy 140.450447 -277.448228) (xy 140.435003 -277.400696)
			(xy 140.427184 -277.351333) (xy 140.119867 -277.351333) (xy 140.119858 -277.35179) (xy 140.111694 -277.402024)
			(xy 140.095578 -277.450298) (xy 140.071927 -277.495361) (xy 140.041354 -277.536047) (xy 140.00465 -277.571302)
			(xy 139.962766 -277.600212) (xy 139.916787 -277.622029) (xy 139.867903 -277.636189) (xy 139.817382 -277.642323)
			(xy 139.76653 -277.640274) (xy 139.716666 -277.630094) (xy 139.66908 -277.612047) (xy 139.625006 -277.586601)
			(xy 139.585584 -277.554414) (xy 139.551836 -277.51632) (xy 139.524635 -277.473306) (xy 139.504687 -277.426486)
			(xy 139.492508 -277.377072) (xy 139.488413 -277.326344) (xy 139.182856 -277.326344) (xy 139.182366 -277.351333)
			(xy 139.174547 -277.400696) (xy 139.159103 -277.448228) (xy 139.136413 -277.49276) (xy 139.107037 -277.533193)
			(xy 139.071697 -277.568533) (xy 139.031264 -277.597909) (xy 138.986732 -277.620599) (xy 138.9392 -277.636043)
			(xy 138.889837 -277.643862) (xy 138.839859 -277.643862) (xy 138.790496 -277.636043) (xy 138.742964 -277.620599)
			(xy 138.698432 -277.597909) (xy 138.657999 -277.568533) (xy 138.622659 -277.533193) (xy 138.593283 -277.49276)
			(xy 138.570593 -277.448228) (xy 138.555149 -277.400696) (xy 138.54733 -277.351333) (xy 138.240013 -277.351333)
			(xy 138.240004 -277.35179) (xy 138.23184 -277.402024) (xy 138.215724 -277.450298) (xy 138.192073 -277.495361)
			(xy 138.1615 -277.536047) (xy 138.124796 -277.571302) (xy 138.082912 -277.600212) (xy 138.036933 -277.622029)
			(xy 137.988049 -277.636189) (xy 137.937528 -277.642323) (xy 137.886676 -277.640274) (xy 137.836812 -277.630094)
			(xy 137.789226 -277.612047) (xy 137.745152 -277.586601) (xy 137.70573 -277.554414) (xy 137.671982 -277.51632)
			(xy 137.644781 -277.473306) (xy 137.624833 -277.426486) (xy 137.612654 -277.377072) (xy 137.608559 -277.326344)
			(xy 137.302748 -277.326344) (xy 137.302258 -277.351333) (xy 137.294439 -277.400696) (xy 137.278995 -277.448228)
			(xy 137.256305 -277.49276) (xy 137.226929 -277.533193) (xy 137.191589 -277.568533) (xy 137.151156 -277.597909)
			(xy 137.106624 -277.620599) (xy 137.059092 -277.636043) (xy 137.009729 -277.643862) (xy 136.959751 -277.643862)
			(xy 136.910388 -277.636043) (xy 136.862856 -277.620599) (xy 136.818324 -277.597909) (xy 136.777891 -277.568533)
			(xy 136.742551 -277.533193) (xy 136.713175 -277.49276) (xy 136.690485 -277.448228) (xy 136.675041 -277.400696)
			(xy 136.667222 -277.351333) (xy 136.359905 -277.351333) (xy 136.359896 -277.35179) (xy 136.351732 -277.402024)
			(xy 136.335616 -277.450298) (xy 136.311965 -277.495361) (xy 136.281392 -277.536047) (xy 136.244688 -277.571302)
			(xy 136.202804 -277.600212) (xy 136.156825 -277.622029) (xy 136.107941 -277.636189) (xy 136.05742 -277.642323)
			(xy 136.006568 -277.640274) (xy 135.956704 -277.630094) (xy 135.909118 -277.612047) (xy 135.865044 -277.586601)
			(xy 135.825622 -277.554414) (xy 135.791874 -277.51632) (xy 135.764673 -277.473306) (xy 135.744725 -277.426486)
			(xy 135.732546 -277.377072) (xy 135.728451 -277.326344) (xy 135.420354 -277.326344) (xy 135.419842 -277.35179)
			(xy 135.411678 -277.402024) (xy 135.395562 -277.450298) (xy 135.371911 -277.495361) (xy 135.341338 -277.536047)
			(xy 135.304634 -277.571302) (xy 135.26275 -277.600212) (xy 135.216771 -277.622029) (xy 135.167887 -277.636189)
			(xy 135.117366 -277.642323) (xy 135.066514 -277.640274) (xy 135.01665 -277.630094) (xy 134.969064 -277.612047)
			(xy 134.92499 -277.586601) (xy 134.885568 -277.554414) (xy 134.85182 -277.51632) (xy 134.824619 -277.473306)
			(xy 134.804671 -277.426486) (xy 134.792492 -277.377072) (xy 134.788397 -277.326344) (xy 134.48284 -277.326344)
			(xy 134.48235 -277.351333) (xy 134.474531 -277.400696) (xy 134.459087 -277.448228) (xy 134.436397 -277.49276)
			(xy 134.407021 -277.533193) (xy 134.371681 -277.568533) (xy 134.331248 -277.597909) (xy 134.286716 -277.620599)
			(xy 134.239184 -277.636043) (xy 134.189821 -277.643862) (xy 134.139843 -277.643862) (xy 134.09048 -277.636043)
			(xy 134.042948 -277.620599) (xy 133.998416 -277.597909) (xy 133.957983 -277.568533) (xy 133.922643 -277.533193)
			(xy 133.893267 -277.49276) (xy 133.870577 -277.448228) (xy 133.855133 -277.400696) (xy 133.847314 -277.351333)
			(xy 133.539997 -277.351333) (xy 133.539988 -277.35179) (xy 133.531824 -277.402024) (xy 133.515708 -277.450298)
			(xy 133.492057 -277.495361) (xy 133.461484 -277.536047) (xy 133.42478 -277.571302) (xy 133.382896 -277.600212)
			(xy 133.336917 -277.622029) (xy 133.288033 -277.636189) (xy 133.237512 -277.642323) (xy 133.18666 -277.640274)
			(xy 133.136796 -277.630094) (xy 133.08921 -277.612047) (xy 133.045136 -277.586601) (xy 133.005714 -277.554414)
			(xy 132.971966 -277.51632) (xy 132.944765 -277.473306) (xy 132.924817 -277.426486) (xy 132.912638 -277.377072)
			(xy 132.908543 -277.326344) (xy 132.602732 -277.326344) (xy 132.602242 -277.351333) (xy 132.594423 -277.400696)
			(xy 132.578979 -277.448228) (xy 132.556289 -277.49276) (xy 132.526913 -277.533193) (xy 132.491573 -277.568533)
			(xy 132.45114 -277.597909) (xy 132.406608 -277.620599) (xy 132.359076 -277.636043) (xy 132.309713 -277.643862)
			(xy 132.259735 -277.643862) (xy 132.210372 -277.636043) (xy 132.16284 -277.620599) (xy 132.118308 -277.597909)
			(xy 132.077875 -277.568533) (xy 132.042535 -277.533193) (xy 132.013159 -277.49276) (xy 131.990469 -277.448228)
			(xy 131.975025 -277.400696) (xy 131.967206 -277.351333) (xy 131.659889 -277.351333) (xy 131.65988 -277.35179)
			(xy 131.651716 -277.402024) (xy 131.6356 -277.450298) (xy 131.611949 -277.495361) (xy 131.581376 -277.536047)
			(xy 131.544672 -277.571302) (xy 131.502788 -277.600212) (xy 131.456809 -277.622029) (xy 131.407925 -277.636189)
			(xy 131.357404 -277.642323) (xy 131.306552 -277.640274) (xy 131.256688 -277.630094) (xy 131.209102 -277.612047)
			(xy 131.165028 -277.586601) (xy 131.125606 -277.554414) (xy 131.091858 -277.51632) (xy 131.064657 -277.473306)
			(xy 131.044709 -277.426486) (xy 131.03253 -277.377072) (xy 131.028435 -277.326344) (xy 130.722878 -277.326344)
			(xy 130.722388 -277.351333) (xy 130.714569 -277.400696) (xy 130.699125 -277.448228) (xy 130.676435 -277.49276)
			(xy 130.647059 -277.533193) (xy 130.611719 -277.568533) (xy 130.571286 -277.597909) (xy 130.526754 -277.620599)
			(xy 130.479222 -277.636043) (xy 130.429859 -277.643862) (xy 130.379881 -277.643862) (xy 130.330518 -277.636043)
			(xy 130.282986 -277.620599) (xy 130.238454 -277.597909) (xy 130.198021 -277.568533) (xy 130.162681 -277.533193)
			(xy 130.133305 -277.49276) (xy 130.110615 -277.448228) (xy 130.095171 -277.400696) (xy 130.087352 -277.351333)
			(xy 129.780035 -277.351333) (xy 129.780026 -277.35179) (xy 129.771862 -277.402024) (xy 129.755746 -277.450298)
			(xy 129.732095 -277.495361) (xy 129.701522 -277.536047) (xy 129.664818 -277.571302) (xy 129.622934 -277.600212)
			(xy 129.576955 -277.622029) (xy 129.528071 -277.636189) (xy 129.47755 -277.642323) (xy 129.426698 -277.640274)
			(xy 129.376834 -277.630094) (xy 129.329248 -277.612047) (xy 129.285174 -277.586601) (xy 129.245752 -277.554414)
			(xy 129.212004 -277.51632) (xy 129.184803 -277.473306) (xy 129.164855 -277.426486) (xy 129.152676 -277.377072)
			(xy 129.148581 -277.326344) (xy 128.840484 -277.326344) (xy 128.839972 -277.35179) (xy 128.831808 -277.402024)
			(xy 128.815692 -277.450298) (xy 128.792041 -277.495361) (xy 128.761468 -277.536047) (xy 128.724764 -277.571302)
			(xy 128.68288 -277.600212) (xy 128.636901 -277.622029) (xy 128.588017 -277.636189) (xy 128.537496 -277.642323)
			(xy 128.486644 -277.640274) (xy 128.43678 -277.630094) (xy 128.389194 -277.612047) (xy 128.34512 -277.586601)
			(xy 128.305698 -277.554414) (xy 128.27195 -277.51632) (xy 128.244749 -277.473306) (xy 128.224801 -277.426486)
			(xy 128.212622 -277.377072) (xy 128.208527 -277.326344) (xy 127.167386 -277.326344) (xy 127.167386 -277.78202)
			(xy 127.168038 -277.793995) (xy 127.178922 -277.815328) (xy 127.188214 -277.822914) (xy 127.196342 -277.826978)
			(xy 127.204978 -277.830534) (xy 127.22939 -277.83826) (xy 127.275557 -277.8604) (xy 127.317589 -277.889636)
			(xy 127.354406 -277.925218) (xy 127.38506 -277.966229) (xy 127.408761 -278.011613) (xy 127.424902 -278.060203)
			(xy 127.433065 -278.110749) (xy 127.433578 -278.13635) (xy 127.738627 -278.13635) (xy 127.742722 -278.085622)
			(xy 127.754901 -278.036208) (xy 127.774849 -277.989388) (xy 127.80205 -277.946374) (xy 127.835798 -277.90828)
			(xy 127.87522 -277.876093) (xy 127.919294 -277.850647) (xy 127.96688 -277.8326) (xy 128.016744 -277.82242)
			(xy 128.067596 -277.820371) (xy 128.118117 -277.826505) (xy 128.167001 -277.840665) (xy 128.21298 -277.862482)
			(xy 128.254864 -277.891392) (xy 128.291568 -277.926647) (xy 128.322141 -277.967333) (xy 128.345792 -278.012396)
			(xy 128.361908 -278.06067) (xy 128.370072 -278.110904) (xy 128.370584 -278.13635) (xy 128.370081 -278.161339)
			(xy 128.677144 -278.161339) (xy 128.677144 -278.111361) (xy 128.684963 -278.061998) (xy 128.700407 -278.014466)
			(xy 128.723097 -277.969934) (xy 128.752473 -277.929501) (xy 128.787813 -277.894161) (xy 128.828246 -277.864785)
			(xy 128.872778 -277.842095) (xy 128.92031 -277.826651) (xy 128.969673 -277.818832) (xy 129.019651 -277.818832)
			(xy 129.069014 -277.826651) (xy 129.116546 -277.842095) (xy 129.161078 -277.864785) (xy 129.201511 -277.894161)
			(xy 129.236851 -277.929501) (xy 129.266227 -277.969934) (xy 129.288917 -278.014466) (xy 129.304361 -278.061998)
			(xy 129.31218 -278.111361) (xy 129.31267 -278.13635) (xy 129.618481 -278.13635) (xy 129.622576 -278.085622)
			(xy 129.634755 -278.036208) (xy 129.654703 -277.989388) (xy 129.681904 -277.946374) (xy 129.715652 -277.90828)
			(xy 129.755074 -277.876093) (xy 129.799148 -277.850647) (xy 129.846734 -277.8326) (xy 129.896598 -277.82242)
			(xy 129.94745 -277.820371) (xy 129.997971 -277.826505) (xy 130.046855 -277.840665) (xy 130.092834 -277.862482)
			(xy 130.134718 -277.891392) (xy 130.171422 -277.926647) (xy 130.201995 -277.967333) (xy 130.225646 -278.012396)
			(xy 130.241762 -278.06067) (xy 130.249926 -278.110904) (xy 130.250438 -278.13635) (xy 131.498589 -278.13635)
			(xy 131.502684 -278.085622) (xy 131.514863 -278.036208) (xy 131.534811 -277.989388) (xy 131.562012 -277.946374)
			(xy 131.59576 -277.90828) (xy 131.635182 -277.876093) (xy 131.679256 -277.850647) (xy 131.726842 -277.8326)
			(xy 131.776706 -277.82242) (xy 131.827558 -277.820371) (xy 131.878079 -277.826505) (xy 131.926963 -277.840665)
			(xy 131.972942 -277.862482) (xy 132.014826 -277.891392) (xy 132.05153 -277.926647) (xy 132.082103 -277.967333)
			(xy 132.105754 -278.012396) (xy 132.12187 -278.06067) (xy 132.130034 -278.110904) (xy 132.130546 -278.13635)
			(xy 132.438643 -278.13635) (xy 132.442738 -278.085622) (xy 132.454917 -278.036208) (xy 132.474865 -277.989388)
			(xy 132.502066 -277.946374) (xy 132.535814 -277.90828) (xy 132.575236 -277.876093) (xy 132.61931 -277.850647)
			(xy 132.666896 -277.8326) (xy 132.71676 -277.82242) (xy 132.767612 -277.820371) (xy 132.818133 -277.826505)
			(xy 132.867017 -277.840665) (xy 132.912996 -277.862482) (xy 132.95488 -277.891392) (xy 132.991584 -277.926647)
			(xy 133.022157 -277.967333) (xy 133.045808 -278.012396) (xy 133.061924 -278.06067) (xy 133.070088 -278.110904)
			(xy 133.0706 -278.13635) (xy 133.070097 -278.161339) (xy 133.37716 -278.161339) (xy 133.37716 -278.111361)
			(xy 133.384979 -278.061998) (xy 133.400423 -278.014466) (xy 133.423113 -277.969934) (xy 133.452489 -277.929501)
			(xy 133.487829 -277.894161) (xy 133.528262 -277.864785) (xy 133.572794 -277.842095) (xy 133.620326 -277.826651)
			(xy 133.669689 -277.818832) (xy 133.719667 -277.818832) (xy 133.76903 -277.826651) (xy 133.816562 -277.842095)
			(xy 133.861094 -277.864785) (xy 133.901527 -277.894161) (xy 133.936867 -277.929501) (xy 133.966243 -277.969934)
			(xy 133.988933 -278.014466) (xy 134.004377 -278.061998) (xy 134.012196 -278.111361) (xy 134.012686 -278.13635)
			(xy 134.318497 -278.13635) (xy 134.322592 -278.085622) (xy 134.334771 -278.036208) (xy 134.354719 -277.989388)
			(xy 134.38192 -277.946374) (xy 134.415668 -277.90828) (xy 134.45509 -277.876093) (xy 134.499164 -277.850647)
			(xy 134.54675 -277.8326) (xy 134.596614 -277.82242) (xy 134.647466 -277.820371) (xy 134.697987 -277.826505)
			(xy 134.746871 -277.840665) (xy 134.79285 -277.862482) (xy 134.834734 -277.891392) (xy 134.871438 -277.926647)
			(xy 134.902011 -277.967333) (xy 134.925662 -278.012396) (xy 134.941778 -278.06067) (xy 134.949942 -278.110904)
			(xy 134.950454 -278.13635) (xy 134.949951 -278.161339) (xy 135.257268 -278.161339) (xy 135.257268 -278.111361)
			(xy 135.265087 -278.061998) (xy 135.280531 -278.014466) (xy 135.303221 -277.969934) (xy 135.332597 -277.929501)
			(xy 135.367937 -277.894161) (xy 135.40837 -277.864785) (xy 135.452902 -277.842095) (xy 135.500434 -277.826651)
			(xy 135.549797 -277.818832) (xy 135.599775 -277.818832) (xy 135.649138 -277.826651) (xy 135.69667 -277.842095)
			(xy 135.741202 -277.864785) (xy 135.781635 -277.894161) (xy 135.816975 -277.929501) (xy 135.846351 -277.969934)
			(xy 135.869041 -278.014466) (xy 135.884485 -278.061998) (xy 135.892304 -278.111361) (xy 135.892794 -278.13635)
			(xy 136.198605 -278.13635) (xy 136.2027 -278.085622) (xy 136.214879 -278.036208) (xy 136.234827 -277.989388)
			(xy 136.262028 -277.946374) (xy 136.295776 -277.90828) (xy 136.335198 -277.876093) (xy 136.379272 -277.850647)
			(xy 136.426858 -277.8326) (xy 136.476722 -277.82242) (xy 136.527574 -277.820371) (xy 136.578095 -277.826505)
			(xy 136.626979 -277.840665) (xy 136.672958 -277.862482) (xy 136.714842 -277.891392) (xy 136.751546 -277.926647)
			(xy 136.782119 -277.967333) (xy 136.80577 -278.012396) (xy 136.821886 -278.06067) (xy 136.83005 -278.110904)
			(xy 136.830562 -278.13635) (xy 138.078459 -278.13635) (xy 138.082554 -278.085622) (xy 138.094733 -278.036208)
			(xy 138.114681 -277.989388) (xy 138.141882 -277.946374) (xy 138.17563 -277.90828) (xy 138.215052 -277.876093)
			(xy 138.259126 -277.850647) (xy 138.306712 -277.8326) (xy 138.356576 -277.82242) (xy 138.407428 -277.820371)
			(xy 138.457949 -277.826505) (xy 138.506833 -277.840665) (xy 138.552812 -277.862482) (xy 138.594696 -277.891392)
			(xy 138.6314 -277.926647) (xy 138.661973 -277.967333) (xy 138.685624 -278.012396) (xy 138.70174 -278.06067)
			(xy 138.709904 -278.110904) (xy 138.710416 -278.13635) (xy 139.018513 -278.13635) (xy 139.022608 -278.085622)
			(xy 139.034787 -278.036208) (xy 139.054735 -277.989388) (xy 139.081936 -277.946374) (xy 139.115684 -277.90828)
			(xy 139.155106 -277.876093) (xy 139.19918 -277.850647) (xy 139.246766 -277.8326) (xy 139.29663 -277.82242)
			(xy 139.347482 -277.820371) (xy 139.398003 -277.826505) (xy 139.446887 -277.840665) (xy 139.492866 -277.862482)
			(xy 139.53475 -277.891392) (xy 139.571454 -277.926647) (xy 139.602027 -277.967333) (xy 139.625678 -278.012396)
			(xy 139.641794 -278.06067) (xy 139.649958 -278.110904) (xy 139.65047 -278.13635) (xy 139.649967 -278.161339)
			(xy 139.957284 -278.161339) (xy 139.957284 -278.111361) (xy 139.965103 -278.061998) (xy 139.980547 -278.014466)
			(xy 140.003237 -277.969934) (xy 140.032613 -277.929501) (xy 140.067953 -277.894161) (xy 140.108386 -277.864785)
			(xy 140.152918 -277.842095) (xy 140.20045 -277.826651) (xy 140.249813 -277.818832) (xy 140.299791 -277.818832)
			(xy 140.349154 -277.826651) (xy 140.396686 -277.842095) (xy 140.441218 -277.864785) (xy 140.481651 -277.894161)
			(xy 140.516991 -277.929501) (xy 140.546367 -277.969934) (xy 140.569057 -278.014466) (xy 140.584501 -278.061998)
			(xy 140.59232 -278.111361) (xy 140.59281 -278.13635) (xy 140.898621 -278.13635) (xy 140.902716 -278.085622)
			(xy 140.914895 -278.036208) (xy 140.934843 -277.989388) (xy 140.962044 -277.946374) (xy 140.995792 -277.90828)
			(xy 141.035214 -277.876093) (xy 141.079288 -277.850647) (xy 141.126874 -277.8326) (xy 141.176738 -277.82242)
			(xy 141.22759 -277.820371) (xy 141.278111 -277.826505) (xy 141.326995 -277.840665) (xy 141.372974 -277.862482)
			(xy 141.414858 -277.891392) (xy 141.451562 -277.926647) (xy 141.482135 -277.967333) (xy 141.505786 -278.012396)
			(xy 141.521902 -278.06067) (xy 141.530066 -278.110904) (xy 141.530578 -278.13635) (xy 141.530075 -278.161339)
			(xy 141.837138 -278.161339) (xy 141.837138 -278.111361) (xy 141.844957 -278.061998) (xy 141.860401 -278.014466)
			(xy 141.883091 -277.969934) (xy 141.912467 -277.929501) (xy 141.947807 -277.894161) (xy 141.98824 -277.864785)
			(xy 142.032772 -277.842095) (xy 142.080304 -277.826651) (xy 142.129667 -277.818832) (xy 142.179645 -277.818832)
			(xy 142.229008 -277.826651) (xy 142.27654 -277.842095) (xy 142.321072 -277.864785) (xy 142.361505 -277.894161)
			(xy 142.396845 -277.929501) (xy 142.426221 -277.969934) (xy 142.448911 -278.014466) (xy 142.464355 -278.061998)
			(xy 142.472174 -278.111361) (xy 142.472664 -278.13635) (xy 142.778475 -278.13635) (xy 142.78257 -278.085622)
			(xy 142.794749 -278.036208) (xy 142.814697 -277.989388) (xy 142.841898 -277.946374) (xy 142.875646 -277.90828)
			(xy 142.915068 -277.876093) (xy 142.959142 -277.850647) (xy 143.006728 -277.8326) (xy 143.056592 -277.82242)
			(xy 143.107444 -277.820371) (xy 143.157965 -277.826505) (xy 143.206849 -277.840665) (xy 143.252828 -277.862482)
			(xy 143.294712 -277.891392) (xy 143.331416 -277.926647) (xy 143.361989 -277.967333) (xy 143.38564 -278.012396)
			(xy 143.401756 -278.06067) (xy 143.40992 -278.110904) (xy 143.410432 -278.13635) (xy 143.40992 -278.161796)
			(xy 143.401756 -278.21203) (xy 143.38564 -278.260304) (xy 143.361989 -278.305367) (xy 143.331416 -278.346053)
			(xy 143.294712 -278.381308) (xy 143.252828 -278.410218) (xy 143.206849 -278.432035) (xy 143.157965 -278.446195)
			(xy 143.107444 -278.452329) (xy 143.056592 -278.45028) (xy 143.006728 -278.4401) (xy 142.959142 -278.422053)
			(xy 142.915068 -278.396607) (xy 142.875646 -278.36442) (xy 142.841898 -278.326326) (xy 142.814697 -278.283312)
			(xy 142.794749 -278.236492) (xy 142.78257 -278.187078) (xy 142.778475 -278.13635) (xy 142.472664 -278.13635)
			(xy 142.472174 -278.161339) (xy 142.464355 -278.210702) (xy 142.448911 -278.258234) (xy 142.426221 -278.302766)
			(xy 142.396845 -278.343199) (xy 142.361505 -278.378539) (xy 142.321072 -278.407915) (xy 142.27654 -278.430605)
			(xy 142.229008 -278.446049) (xy 142.179645 -278.453868) (xy 142.129667 -278.453868) (xy 142.080304 -278.446049)
			(xy 142.032772 -278.430605) (xy 141.98824 -278.407915) (xy 141.947807 -278.378539) (xy 141.912467 -278.343199)
			(xy 141.883091 -278.302766) (xy 141.860401 -278.258234) (xy 141.844957 -278.210702) (xy 141.837138 -278.161339)
			(xy 141.530075 -278.161339) (xy 141.530066 -278.161796) (xy 141.521902 -278.21203) (xy 141.505786 -278.260304)
			(xy 141.482135 -278.305367) (xy 141.451562 -278.346053) (xy 141.414858 -278.381308) (xy 141.372974 -278.410218)
			(xy 141.326995 -278.432035) (xy 141.278111 -278.446195) (xy 141.22759 -278.452329) (xy 141.176738 -278.45028)
			(xy 141.126874 -278.4401) (xy 141.079288 -278.422053) (xy 141.035214 -278.396607) (xy 140.995792 -278.36442)
			(xy 140.962044 -278.326326) (xy 140.934843 -278.283312) (xy 140.914895 -278.236492) (xy 140.902716 -278.187078)
			(xy 140.898621 -278.13635) (xy 140.59281 -278.13635) (xy 140.59232 -278.161339) (xy 140.584501 -278.210702)
			(xy 140.569057 -278.258234) (xy 140.546367 -278.302766) (xy 140.516991 -278.343199) (xy 140.481651 -278.378539)
			(xy 140.441218 -278.407915) (xy 140.396686 -278.430605) (xy 140.349154 -278.446049) (xy 140.299791 -278.453868)
			(xy 140.249813 -278.453868) (xy 140.20045 -278.446049) (xy 140.152918 -278.430605) (xy 140.108386 -278.407915)
			(xy 140.067953 -278.378539) (xy 140.032613 -278.343199) (xy 140.003237 -278.302766) (xy 139.980547 -278.258234)
			(xy 139.965103 -278.210702) (xy 139.957284 -278.161339) (xy 139.649967 -278.161339) (xy 139.649958 -278.161796)
			(xy 139.641794 -278.21203) (xy 139.625678 -278.260304) (xy 139.602027 -278.305367) (xy 139.571454 -278.346053)
			(xy 139.53475 -278.381308) (xy 139.492866 -278.410218) (xy 139.446887 -278.432035) (xy 139.398003 -278.446195)
			(xy 139.347482 -278.452329) (xy 139.29663 -278.45028) (xy 139.246766 -278.4401) (xy 139.19918 -278.422053)
			(xy 139.155106 -278.396607) (xy 139.115684 -278.36442) (xy 139.081936 -278.326326) (xy 139.054735 -278.283312)
			(xy 139.034787 -278.236492) (xy 139.022608 -278.187078) (xy 139.018513 -278.13635) (xy 138.710416 -278.13635)
			(xy 138.709904 -278.161796) (xy 138.70174 -278.21203) (xy 138.685624 -278.260304) (xy 138.661973 -278.305367)
			(xy 138.6314 -278.346053) (xy 138.594696 -278.381308) (xy 138.552812 -278.410218) (xy 138.506833 -278.432035)
			(xy 138.457949 -278.446195) (xy 138.407428 -278.452329) (xy 138.356576 -278.45028) (xy 138.306712 -278.4401)
			(xy 138.259126 -278.422053) (xy 138.215052 -278.396607) (xy 138.17563 -278.36442) (xy 138.141882 -278.326326)
			(xy 138.114681 -278.283312) (xy 138.094733 -278.236492) (xy 138.082554 -278.187078) (xy 138.078459 -278.13635)
			(xy 136.830562 -278.13635) (xy 136.83005 -278.161796) (xy 136.821886 -278.21203) (xy 136.80577 -278.260304)
			(xy 136.782119 -278.305367) (xy 136.751546 -278.346053) (xy 136.714842 -278.381308) (xy 136.672958 -278.410218)
			(xy 136.626979 -278.432035) (xy 136.578095 -278.446195) (xy 136.527574 -278.452329) (xy 136.476722 -278.45028)
			(xy 136.426858 -278.4401) (xy 136.379272 -278.422053) (xy 136.335198 -278.396607) (xy 136.295776 -278.36442)
			(xy 136.262028 -278.326326) (xy 136.234827 -278.283312) (xy 136.214879 -278.236492) (xy 136.2027 -278.187078)
			(xy 136.198605 -278.13635) (xy 135.892794 -278.13635) (xy 135.892304 -278.161339) (xy 135.884485 -278.210702)
			(xy 135.869041 -278.258234) (xy 135.846351 -278.302766) (xy 135.816975 -278.343199) (xy 135.781635 -278.378539)
			(xy 135.741202 -278.407915) (xy 135.69667 -278.430605) (xy 135.649138 -278.446049) (xy 135.599775 -278.453868)
			(xy 135.549797 -278.453868) (xy 135.500434 -278.446049) (xy 135.452902 -278.430605) (xy 135.40837 -278.407915)
			(xy 135.367937 -278.378539) (xy 135.332597 -278.343199) (xy 135.303221 -278.302766) (xy 135.280531 -278.258234)
			(xy 135.265087 -278.210702) (xy 135.257268 -278.161339) (xy 134.949951 -278.161339) (xy 134.949942 -278.161796)
			(xy 134.941778 -278.21203) (xy 134.925662 -278.260304) (xy 134.902011 -278.305367) (xy 134.871438 -278.346053)
			(xy 134.834734 -278.381308) (xy 134.79285 -278.410218) (xy 134.746871 -278.432035) (xy 134.697987 -278.446195)
			(xy 134.647466 -278.452329) (xy 134.596614 -278.45028) (xy 134.54675 -278.4401) (xy 134.499164 -278.422053)
			(xy 134.45509 -278.396607) (xy 134.415668 -278.36442) (xy 134.38192 -278.326326) (xy 134.354719 -278.283312)
			(xy 134.334771 -278.236492) (xy 134.322592 -278.187078) (xy 134.318497 -278.13635) (xy 134.012686 -278.13635)
			(xy 134.012196 -278.161339) (xy 134.004377 -278.210702) (xy 133.988933 -278.258234) (xy 133.966243 -278.302766)
			(xy 133.936867 -278.343199) (xy 133.901527 -278.378539) (xy 133.861094 -278.407915) (xy 133.816562 -278.430605)
			(xy 133.76903 -278.446049) (xy 133.719667 -278.453868) (xy 133.669689 -278.453868) (xy 133.620326 -278.446049)
			(xy 133.572794 -278.430605) (xy 133.528262 -278.407915) (xy 133.487829 -278.378539) (xy 133.452489 -278.343199)
			(xy 133.423113 -278.302766) (xy 133.400423 -278.258234) (xy 133.384979 -278.210702) (xy 133.37716 -278.161339)
			(xy 133.070097 -278.161339) (xy 133.070088 -278.161796) (xy 133.061924 -278.21203) (xy 133.045808 -278.260304)
			(xy 133.022157 -278.305367) (xy 132.991584 -278.346053) (xy 132.95488 -278.381308) (xy 132.912996 -278.410218)
			(xy 132.867017 -278.432035) (xy 132.818133 -278.446195) (xy 132.767612 -278.452329) (xy 132.71676 -278.45028)
			(xy 132.666896 -278.4401) (xy 132.61931 -278.422053) (xy 132.575236 -278.396607) (xy 132.535814 -278.36442)
			(xy 132.502066 -278.326326) (xy 132.474865 -278.283312) (xy 132.454917 -278.236492) (xy 132.442738 -278.187078)
			(xy 132.438643 -278.13635) (xy 132.130546 -278.13635) (xy 132.130034 -278.161796) (xy 132.12187 -278.21203)
			(xy 132.105754 -278.260304) (xy 132.082103 -278.305367) (xy 132.05153 -278.346053) (xy 132.014826 -278.381308)
			(xy 131.972942 -278.410218) (xy 131.926963 -278.432035) (xy 131.878079 -278.446195) (xy 131.827558 -278.452329)
			(xy 131.776706 -278.45028) (xy 131.726842 -278.4401) (xy 131.679256 -278.422053) (xy 131.635182 -278.396607)
			(xy 131.59576 -278.36442) (xy 131.562012 -278.326326) (xy 131.534811 -278.283312) (xy 131.514863 -278.236492)
			(xy 131.502684 -278.187078) (xy 131.498589 -278.13635) (xy 130.250438 -278.13635) (xy 130.249926 -278.161796)
			(xy 130.241762 -278.21203) (xy 130.225646 -278.260304) (xy 130.201995 -278.305367) (xy 130.171422 -278.346053)
			(xy 130.134718 -278.381308) (xy 130.092834 -278.410218) (xy 130.046855 -278.432035) (xy 129.997971 -278.446195)
			(xy 129.94745 -278.452329) (xy 129.896598 -278.45028) (xy 129.846734 -278.4401) (xy 129.799148 -278.422053)
			(xy 129.755074 -278.396607) (xy 129.715652 -278.36442) (xy 129.681904 -278.326326) (xy 129.654703 -278.283312)
			(xy 129.634755 -278.236492) (xy 129.622576 -278.187078) (xy 129.618481 -278.13635) (xy 129.31267 -278.13635)
			(xy 129.31218 -278.161339) (xy 129.304361 -278.210702) (xy 129.288917 -278.258234) (xy 129.266227 -278.302766)
			(xy 129.236851 -278.343199) (xy 129.201511 -278.378539) (xy 129.161078 -278.407915) (xy 129.116546 -278.430605)
			(xy 129.069014 -278.446049) (xy 129.019651 -278.453868) (xy 128.969673 -278.453868) (xy 128.92031 -278.446049)
			(xy 128.872778 -278.430605) (xy 128.828246 -278.407915) (xy 128.787813 -278.378539) (xy 128.752473 -278.343199)
			(xy 128.723097 -278.302766) (xy 128.700407 -278.258234) (xy 128.684963 -278.210702) (xy 128.677144 -278.161339)
			(xy 128.370081 -278.161339) (xy 128.370072 -278.161796) (xy 128.361908 -278.21203) (xy 128.345792 -278.260304)
			(xy 128.322141 -278.305367) (xy 128.291568 -278.346053) (xy 128.254864 -278.381308) (xy 128.21298 -278.410218)
			(xy 128.167001 -278.432035) (xy 128.118117 -278.446195) (xy 128.067596 -278.452329) (xy 128.016744 -278.45028)
			(xy 127.96688 -278.4401) (xy 127.919294 -278.422053) (xy 127.87522 -278.396607) (xy 127.835798 -278.36442)
			(xy 127.80205 -278.326326) (xy 127.774849 -278.283312) (xy 127.754901 -278.236492) (xy 127.742722 -278.187078)
			(xy 127.738627 -278.13635) (xy 127.433578 -278.13635) (xy 127.433056 -278.162413) (xy 127.424573 -278.213843)
			(xy 127.40784 -278.26321) (xy 127.383304 -278.309199) (xy 127.351617 -278.350587) (xy 127.313622 -278.386272)
			(xy 127.270331 -278.415305) (xy 127.222895 -278.436913) (xy 127.197866 -278.444198) (xy 127.189031 -278.448554)
			(xy 127.17528 -278.462632) (xy 127.167816 -278.480842) (xy 127.167386 -278.49068) (xy 127.167386 -278.67356)
			(xy 127.167861 -278.683867) (xy 127.175977 -278.702814) (xy 127.19091 -278.717022) (xy 127.200406 -278.721058)
			(xy 127.28702 -278.753316) (xy 127.295733 -278.756159) (xy 127.314048 -278.756126) (xy 127.331182 -278.749658)
			(xy 127.338328 -278.743918) (xy 127.343662 -278.738584) (xy 127.344678 -278.737314) (xy 127.362965 -278.717157)
			(xy 127.405162 -278.68279) (xy 127.45259 -278.656103) (xy 127.503867 -278.637874) (xy 127.557497 -278.628634)
			(xy 127.584708 -278.628094) (xy 127.60972 -278.628585) (xy 127.659129 -278.636412) (xy 127.706704 -278.651871)
			(xy 127.751276 -278.674583) (xy 127.791746 -278.703987) (xy 127.827118 -278.73936) (xy 127.856521 -278.779831)
			(xy 127.879232 -278.824403) (xy 127.89469 -278.871979) (xy 127.902515 -278.921388) (xy 127.902515 -278.946356)
			(xy 128.208527 -278.946356) (xy 128.212622 -278.895628) (xy 128.224801 -278.846214) (xy 128.244749 -278.799394)
			(xy 128.27195 -278.75638) (xy 128.305698 -278.718286) (xy 128.34512 -278.686099) (xy 128.389194 -278.660653)
			(xy 128.43678 -278.642606) (xy 128.486644 -278.632426) (xy 128.537496 -278.630377) (xy 128.588017 -278.636511)
			(xy 128.636901 -278.650671) (xy 128.68288 -278.672488) (xy 128.724764 -278.701398) (xy 128.761468 -278.736653)
			(xy 128.792041 -278.777339) (xy 128.815692 -278.822402) (xy 128.831808 -278.870676) (xy 128.839972 -278.92091)
			(xy 128.840484 -278.946356) (xy 129.148581 -278.946356) (xy 129.152676 -278.895628) (xy 129.164855 -278.846214)
			(xy 129.184803 -278.799394) (xy 129.212004 -278.75638) (xy 129.245752 -278.718286) (xy 129.285174 -278.686099)
			(xy 129.329248 -278.660653) (xy 129.376834 -278.642606) (xy 129.426698 -278.632426) (xy 129.47755 -278.630377)
			(xy 129.528071 -278.636511) (xy 129.576955 -278.650671) (xy 129.622934 -278.672488) (xy 129.664818 -278.701398)
			(xy 129.701522 -278.736653) (xy 129.732095 -278.777339) (xy 129.755746 -278.822402) (xy 129.771862 -278.870676)
			(xy 129.780026 -278.92091) (xy 129.780538 -278.946356) (xy 129.780035 -278.971345) (xy 130.087352 -278.971345)
			(xy 130.087352 -278.921367) (xy 130.095171 -278.872004) (xy 130.110615 -278.824472) (xy 130.133305 -278.77994)
			(xy 130.162681 -278.739507) (xy 130.198021 -278.704167) (xy 130.238454 -278.674791) (xy 130.282986 -278.652101)
			(xy 130.330518 -278.636657) (xy 130.379881 -278.628838) (xy 130.429859 -278.628838) (xy 130.479222 -278.636657)
			(xy 130.526754 -278.652101) (xy 130.571286 -278.674791) (xy 130.611719 -278.704167) (xy 130.647059 -278.739507)
			(xy 130.676435 -278.77994) (xy 130.699125 -278.824472) (xy 130.714569 -278.872004) (xy 130.722388 -278.921367)
			(xy 130.722878 -278.946356) (xy 131.028435 -278.946356) (xy 131.03253 -278.895628) (xy 131.044709 -278.846214)
			(xy 131.064657 -278.799394) (xy 131.091858 -278.75638) (xy 131.125606 -278.718286) (xy 131.165028 -278.686099)
			(xy 131.209102 -278.660653) (xy 131.256688 -278.642606) (xy 131.306552 -278.632426) (xy 131.357404 -278.630377)
			(xy 131.407925 -278.636511) (xy 131.456809 -278.650671) (xy 131.502788 -278.672488) (xy 131.544672 -278.701398)
			(xy 131.581376 -278.736653) (xy 131.611949 -278.777339) (xy 131.6356 -278.822402) (xy 131.651716 -278.870676)
			(xy 131.65988 -278.92091) (xy 131.660392 -278.946356) (xy 131.659889 -278.971345) (xy 131.967206 -278.971345)
			(xy 131.967206 -278.921367) (xy 131.975025 -278.872004) (xy 131.990469 -278.824472) (xy 132.013159 -278.77994)
			(xy 132.042535 -278.739507) (xy 132.077875 -278.704167) (xy 132.118308 -278.674791) (xy 132.16284 -278.652101)
			(xy 132.210372 -278.636657) (xy 132.259735 -278.628838) (xy 132.309713 -278.628838) (xy 132.359076 -278.636657)
			(xy 132.406608 -278.652101) (xy 132.45114 -278.674791) (xy 132.491573 -278.704167) (xy 132.526913 -278.739507)
			(xy 132.556289 -278.77994) (xy 132.578979 -278.824472) (xy 132.594423 -278.872004) (xy 132.602242 -278.921367)
			(xy 132.602732 -278.946356) (xy 132.908543 -278.946356) (xy 132.912638 -278.895628) (xy 132.924817 -278.846214)
			(xy 132.944765 -278.799394) (xy 132.971966 -278.75638) (xy 133.005714 -278.718286) (xy 133.045136 -278.686099)
			(xy 133.08921 -278.660653) (xy 133.136796 -278.642606) (xy 133.18666 -278.632426) (xy 133.237512 -278.630377)
			(xy 133.288033 -278.636511) (xy 133.336917 -278.650671) (xy 133.382896 -278.672488) (xy 133.42478 -278.701398)
			(xy 133.461484 -278.736653) (xy 133.492057 -278.777339) (xy 133.515708 -278.822402) (xy 133.531824 -278.870676)
			(xy 133.539988 -278.92091) (xy 133.5405 -278.946356) (xy 133.539997 -278.971345) (xy 133.847314 -278.971345)
			(xy 133.847314 -278.921367) (xy 133.855133 -278.872004) (xy 133.870577 -278.824472) (xy 133.893267 -278.77994)
			(xy 133.922643 -278.739507) (xy 133.957983 -278.704167) (xy 133.998416 -278.674791) (xy 134.042948 -278.652101)
			(xy 134.09048 -278.636657) (xy 134.139843 -278.628838) (xy 134.189821 -278.628838) (xy 134.239184 -278.636657)
			(xy 134.286716 -278.652101) (xy 134.331248 -278.674791) (xy 134.371681 -278.704167) (xy 134.407021 -278.739507)
			(xy 134.436397 -278.77994) (xy 134.459087 -278.824472) (xy 134.474531 -278.872004) (xy 134.48235 -278.921367)
			(xy 134.48284 -278.946356) (xy 134.788397 -278.946356) (xy 134.792492 -278.895628) (xy 134.804671 -278.846214)
			(xy 134.824619 -278.799394) (xy 134.85182 -278.75638) (xy 134.885568 -278.718286) (xy 134.92499 -278.686099)
			(xy 134.969064 -278.660653) (xy 135.01665 -278.642606) (xy 135.066514 -278.632426) (xy 135.117366 -278.630377)
			(xy 135.167887 -278.636511) (xy 135.216771 -278.650671) (xy 135.26275 -278.672488) (xy 135.304634 -278.701398)
			(xy 135.341338 -278.736653) (xy 135.371911 -278.777339) (xy 135.395562 -278.822402) (xy 135.411678 -278.870676)
			(xy 135.419842 -278.92091) (xy 135.420354 -278.946356) (xy 135.728451 -278.946356) (xy 135.732546 -278.895628)
			(xy 135.744725 -278.846214) (xy 135.764673 -278.799394) (xy 135.791874 -278.75638) (xy 135.825622 -278.718286)
			(xy 135.865044 -278.686099) (xy 135.909118 -278.660653) (xy 135.956704 -278.642606) (xy 136.006568 -278.632426)
			(xy 136.05742 -278.630377) (xy 136.107941 -278.636511) (xy 136.156825 -278.650671) (xy 136.202804 -278.672488)
			(xy 136.244688 -278.701398) (xy 136.281392 -278.736653) (xy 136.311965 -278.777339) (xy 136.335616 -278.822402)
			(xy 136.351732 -278.870676) (xy 136.359896 -278.92091) (xy 136.360408 -278.946356) (xy 136.359905 -278.971345)
			(xy 136.667222 -278.971345) (xy 136.667222 -278.921367) (xy 136.675041 -278.872004) (xy 136.690485 -278.824472)
			(xy 136.713175 -278.77994) (xy 136.742551 -278.739507) (xy 136.777891 -278.704167) (xy 136.818324 -278.674791)
			(xy 136.862856 -278.652101) (xy 136.910388 -278.636657) (xy 136.959751 -278.628838) (xy 137.009729 -278.628838)
			(xy 137.059092 -278.636657) (xy 137.106624 -278.652101) (xy 137.151156 -278.674791) (xy 137.191589 -278.704167)
			(xy 137.226929 -278.739507) (xy 137.256305 -278.77994) (xy 137.278995 -278.824472) (xy 137.294439 -278.872004)
			(xy 137.302258 -278.921367) (xy 137.302748 -278.946356) (xy 137.608559 -278.946356) (xy 137.612654 -278.895628)
			(xy 137.624833 -278.846214) (xy 137.644781 -278.799394) (xy 137.671982 -278.75638) (xy 137.70573 -278.718286)
			(xy 137.745152 -278.686099) (xy 137.789226 -278.660653) (xy 137.836812 -278.642606) (xy 137.886676 -278.632426)
			(xy 137.937528 -278.630377) (xy 137.988049 -278.636511) (xy 138.036933 -278.650671) (xy 138.082912 -278.672488)
			(xy 138.124796 -278.701398) (xy 138.1615 -278.736653) (xy 138.192073 -278.777339) (xy 138.215724 -278.822402)
			(xy 138.23184 -278.870676) (xy 138.240004 -278.92091) (xy 138.240516 -278.946356) (xy 138.240013 -278.971345)
			(xy 138.54733 -278.971345) (xy 138.54733 -278.921367) (xy 138.555149 -278.872004) (xy 138.570593 -278.824472)
			(xy 138.593283 -278.77994) (xy 138.622659 -278.739507) (xy 138.657999 -278.704167) (xy 138.698432 -278.674791)
			(xy 138.742964 -278.652101) (xy 138.790496 -278.636657) (xy 138.839859 -278.628838) (xy 138.889837 -278.628838)
			(xy 138.9392 -278.636657) (xy 138.986732 -278.652101) (xy 139.031264 -278.674791) (xy 139.071697 -278.704167)
			(xy 139.107037 -278.739507) (xy 139.136413 -278.77994) (xy 139.159103 -278.824472) (xy 139.174547 -278.872004)
			(xy 139.182366 -278.921367) (xy 139.182856 -278.946356) (xy 139.488413 -278.946356) (xy 139.492508 -278.895628)
			(xy 139.504687 -278.846214) (xy 139.524635 -278.799394) (xy 139.551836 -278.75638) (xy 139.585584 -278.718286)
			(xy 139.625006 -278.686099) (xy 139.66908 -278.660653) (xy 139.716666 -278.642606) (xy 139.76653 -278.632426)
			(xy 139.817382 -278.630377) (xy 139.867903 -278.636511) (xy 139.916787 -278.650671) (xy 139.962766 -278.672488)
			(xy 140.00465 -278.701398) (xy 140.041354 -278.736653) (xy 140.071927 -278.777339) (xy 140.095578 -278.822402)
			(xy 140.111694 -278.870676) (xy 140.119858 -278.92091) (xy 140.12037 -278.946356) (xy 140.119867 -278.971345)
			(xy 140.427184 -278.971345) (xy 140.427184 -278.921367) (xy 140.435003 -278.872004) (xy 140.450447 -278.824472)
			(xy 140.473137 -278.77994) (xy 140.502513 -278.739507) (xy 140.537853 -278.704167) (xy 140.578286 -278.674791)
			(xy 140.622818 -278.652101) (xy 140.67035 -278.636657) (xy 140.719713 -278.628838) (xy 140.769691 -278.628838)
			(xy 140.819054 -278.636657) (xy 140.866586 -278.652101) (xy 140.911118 -278.674791) (xy 140.951551 -278.704167)
			(xy 140.986891 -278.739507) (xy 141.016267 -278.77994) (xy 141.038957 -278.824472) (xy 141.054401 -278.872004)
			(xy 141.06222 -278.921367) (xy 141.06271 -278.946356) (xy 141.368521 -278.946356) (xy 141.372616 -278.895628)
			(xy 141.384795 -278.846214) (xy 141.404743 -278.799394) (xy 141.431944 -278.75638) (xy 141.465692 -278.718286)
			(xy 141.505114 -278.686099) (xy 141.549188 -278.660653) (xy 141.596774 -278.642606) (xy 141.646638 -278.632426)
			(xy 141.69749 -278.630377) (xy 141.748011 -278.636511) (xy 141.796895 -278.650671) (xy 141.842874 -278.672488)
			(xy 141.884758 -278.701398) (xy 141.921462 -278.736653) (xy 141.952035 -278.777339) (xy 141.975686 -278.822402)
			(xy 141.991802 -278.870676) (xy 141.999966 -278.92091) (xy 142.000478 -278.946356) (xy 142.308575 -278.946356)
			(xy 142.31267 -278.895628) (xy 142.324849 -278.846214) (xy 142.344797 -278.799394) (xy 142.371998 -278.75638)
			(xy 142.405746 -278.718286) (xy 142.445168 -278.686099) (xy 142.489242 -278.660653) (xy 142.536828 -278.642606)
			(xy 142.586692 -278.632426) (xy 142.637544 -278.630377) (xy 142.688065 -278.636511) (xy 142.736949 -278.650671)
			(xy 142.782928 -278.672488) (xy 142.824812 -278.701398) (xy 142.861516 -278.736653) (xy 142.892089 -278.777339)
			(xy 142.91574 -278.822402) (xy 142.931856 -278.870676) (xy 142.94002 -278.92091) (xy 142.940532 -278.946356)
			(xy 142.940029 -278.971345) (xy 143.247092 -278.971345) (xy 143.247092 -278.921367) (xy 143.254911 -278.872004)
			(xy 143.270355 -278.824472) (xy 143.293045 -278.77994) (xy 143.322421 -278.739507) (xy 143.357761 -278.704167)
			(xy 143.398194 -278.674791) (xy 143.442726 -278.652101) (xy 143.490258 -278.636657) (xy 143.539621 -278.628838)
			(xy 143.589599 -278.628838) (xy 143.638962 -278.636657) (xy 143.686494 -278.652101) (xy 143.731026 -278.674791)
			(xy 143.771459 -278.704167) (xy 143.806799 -278.739507) (xy 143.836175 -278.77994) (xy 143.858865 -278.824472)
			(xy 143.874309 -278.872004) (xy 143.882128 -278.921367) (xy 143.882618 -278.946356) (xy 143.882128 -278.971345)
			(xy 143.874309 -279.020708) (xy 143.858865 -279.06824) (xy 143.836175 -279.112772) (xy 143.806799 -279.153205)
			(xy 143.771459 -279.188545) (xy 143.731026 -279.217921) (xy 143.686494 -279.240611) (xy 143.638962 -279.256055)
			(xy 143.589599 -279.263874) (xy 143.539621 -279.263874) (xy 143.490258 -279.256055) (xy 143.442726 -279.240611)
			(xy 143.398194 -279.217921) (xy 143.357761 -279.188545) (xy 143.322421 -279.153205) (xy 143.293045 -279.112772)
			(xy 143.270355 -279.06824) (xy 143.254911 -279.020708) (xy 143.247092 -278.971345) (xy 142.940029 -278.971345)
			(xy 142.94002 -278.971802) (xy 142.931856 -279.022036) (xy 142.91574 -279.07031) (xy 142.892089 -279.115373)
			(xy 142.861516 -279.156059) (xy 142.824812 -279.191314) (xy 142.782928 -279.220224) (xy 142.736949 -279.242041)
			(xy 142.688065 -279.256201) (xy 142.637544 -279.262335) (xy 142.586692 -279.260286) (xy 142.536828 -279.250106)
			(xy 142.489242 -279.232059) (xy 142.445168 -279.206613) (xy 142.405746 -279.174426) (xy 142.371998 -279.136332)
			(xy 142.344797 -279.093318) (xy 142.324849 -279.046498) (xy 142.31267 -278.997084) (xy 142.308575 -278.946356)
			(xy 142.000478 -278.946356) (xy 141.999966 -278.971802) (xy 141.991802 -279.022036) (xy 141.975686 -279.07031)
			(xy 141.952035 -279.115373) (xy 141.921462 -279.156059) (xy 141.884758 -279.191314) (xy 141.842874 -279.220224)
			(xy 141.796895 -279.242041) (xy 141.748011 -279.256201) (xy 141.69749 -279.262335) (xy 141.646638 -279.260286)
			(xy 141.596774 -279.250106) (xy 141.549188 -279.232059) (xy 141.505114 -279.206613) (xy 141.465692 -279.174426)
			(xy 141.431944 -279.136332) (xy 141.404743 -279.093318) (xy 141.384795 -279.046498) (xy 141.372616 -278.997084)
			(xy 141.368521 -278.946356) (xy 141.06271 -278.946356) (xy 141.06222 -278.971345) (xy 141.054401 -279.020708)
			(xy 141.038957 -279.06824) (xy 141.016267 -279.112772) (xy 140.986891 -279.153205) (xy 140.951551 -279.188545)
			(xy 140.911118 -279.217921) (xy 140.866586 -279.240611) (xy 140.819054 -279.256055) (xy 140.769691 -279.263874)
			(xy 140.719713 -279.263874) (xy 140.67035 -279.256055) (xy 140.622818 -279.240611) (xy 140.578286 -279.217921)
			(xy 140.537853 -279.188545) (xy 140.502513 -279.153205) (xy 140.473137 -279.112772) (xy 140.450447 -279.06824)
			(xy 140.435003 -279.020708) (xy 140.427184 -278.971345) (xy 140.119867 -278.971345) (xy 140.119858 -278.971802)
			(xy 140.111694 -279.022036) (xy 140.095578 -279.07031) (xy 140.071927 -279.115373) (xy 140.041354 -279.156059)
			(xy 140.00465 -279.191314) (xy 139.962766 -279.220224) (xy 139.916787 -279.242041) (xy 139.867903 -279.256201)
			(xy 139.817382 -279.262335) (xy 139.76653 -279.260286) (xy 139.716666 -279.250106) (xy 139.66908 -279.232059)
			(xy 139.625006 -279.206613) (xy 139.585584 -279.174426) (xy 139.551836 -279.136332) (xy 139.524635 -279.093318)
			(xy 139.504687 -279.046498) (xy 139.492508 -278.997084) (xy 139.488413 -278.946356) (xy 139.182856 -278.946356)
			(xy 139.182366 -278.971345) (xy 139.174547 -279.020708) (xy 139.159103 -279.06824) (xy 139.136413 -279.112772)
			(xy 139.107037 -279.153205) (xy 139.071697 -279.188545) (xy 139.031264 -279.217921) (xy 138.986732 -279.240611)
			(xy 138.9392 -279.256055) (xy 138.889837 -279.263874) (xy 138.839859 -279.263874) (xy 138.790496 -279.256055)
			(xy 138.742964 -279.240611) (xy 138.698432 -279.217921) (xy 138.657999 -279.188545) (xy 138.622659 -279.153205)
			(xy 138.593283 -279.112772) (xy 138.570593 -279.06824) (xy 138.555149 -279.020708) (xy 138.54733 -278.971345)
			(xy 138.240013 -278.971345) (xy 138.240004 -278.971802) (xy 138.23184 -279.022036) (xy 138.215724 -279.07031)
			(xy 138.192073 -279.115373) (xy 138.1615 -279.156059) (xy 138.124796 -279.191314) (xy 138.082912 -279.220224)
			(xy 138.036933 -279.242041) (xy 137.988049 -279.256201) (xy 137.937528 -279.262335) (xy 137.886676 -279.260286)
			(xy 137.836812 -279.250106) (xy 137.789226 -279.232059) (xy 137.745152 -279.206613) (xy 137.70573 -279.174426)
			(xy 137.671982 -279.136332) (xy 137.644781 -279.093318) (xy 137.624833 -279.046498) (xy 137.612654 -278.997084)
			(xy 137.608559 -278.946356) (xy 137.302748 -278.946356) (xy 137.302258 -278.971345) (xy 137.294439 -279.020708)
			(xy 137.278995 -279.06824) (xy 137.256305 -279.112772) (xy 137.226929 -279.153205) (xy 137.191589 -279.188545)
			(xy 137.151156 -279.217921) (xy 137.106624 -279.240611) (xy 137.059092 -279.256055) (xy 137.009729 -279.263874)
			(xy 136.959751 -279.263874) (xy 136.910388 -279.256055) (xy 136.862856 -279.240611) (xy 136.818324 -279.217921)
			(xy 136.777891 -279.188545) (xy 136.742551 -279.153205) (xy 136.713175 -279.112772) (xy 136.690485 -279.06824)
			(xy 136.675041 -279.020708) (xy 136.667222 -278.971345) (xy 136.359905 -278.971345) (xy 136.359896 -278.971802)
			(xy 136.351732 -279.022036) (xy 136.335616 -279.07031) (xy 136.311965 -279.115373) (xy 136.281392 -279.156059)
			(xy 136.244688 -279.191314) (xy 136.202804 -279.220224) (xy 136.156825 -279.242041) (xy 136.107941 -279.256201)
			(xy 136.05742 -279.262335) (xy 136.006568 -279.260286) (xy 135.956704 -279.250106) (xy 135.909118 -279.232059)
			(xy 135.865044 -279.206613) (xy 135.825622 -279.174426) (xy 135.791874 -279.136332) (xy 135.764673 -279.093318)
			(xy 135.744725 -279.046498) (xy 135.732546 -278.997084) (xy 135.728451 -278.946356) (xy 135.420354 -278.946356)
			(xy 135.419842 -278.971802) (xy 135.411678 -279.022036) (xy 135.395562 -279.07031) (xy 135.371911 -279.115373)
			(xy 135.341338 -279.156059) (xy 135.304634 -279.191314) (xy 135.26275 -279.220224) (xy 135.216771 -279.242041)
			(xy 135.167887 -279.256201) (xy 135.117366 -279.262335) (xy 135.066514 -279.260286) (xy 135.01665 -279.250106)
			(xy 134.969064 -279.232059) (xy 134.92499 -279.206613) (xy 134.885568 -279.174426) (xy 134.85182 -279.136332)
			(xy 134.824619 -279.093318) (xy 134.804671 -279.046498) (xy 134.792492 -278.997084) (xy 134.788397 -278.946356)
			(xy 134.48284 -278.946356) (xy 134.48235 -278.971345) (xy 134.474531 -279.020708) (xy 134.459087 -279.06824)
			(xy 134.436397 -279.112772) (xy 134.407021 -279.153205) (xy 134.371681 -279.188545) (xy 134.331248 -279.217921)
			(xy 134.286716 -279.240611) (xy 134.239184 -279.256055) (xy 134.189821 -279.263874) (xy 134.139843 -279.263874)
			(xy 134.09048 -279.256055) (xy 134.042948 -279.240611) (xy 133.998416 -279.217921) (xy 133.957983 -279.188545)
			(xy 133.922643 -279.153205) (xy 133.893267 -279.112772) (xy 133.870577 -279.06824) (xy 133.855133 -279.020708)
			(xy 133.847314 -278.971345) (xy 133.539997 -278.971345) (xy 133.539988 -278.971802) (xy 133.531824 -279.022036)
			(xy 133.515708 -279.07031) (xy 133.492057 -279.115373) (xy 133.461484 -279.156059) (xy 133.42478 -279.191314)
			(xy 133.382896 -279.220224) (xy 133.336917 -279.242041) (xy 133.288033 -279.256201) (xy 133.237512 -279.262335)
			(xy 133.18666 -279.260286) (xy 133.136796 -279.250106) (xy 133.08921 -279.232059) (xy 133.045136 -279.206613)
			(xy 133.005714 -279.174426) (xy 132.971966 -279.136332) (xy 132.944765 -279.093318) (xy 132.924817 -279.046498)
			(xy 132.912638 -278.997084) (xy 132.908543 -278.946356) (xy 132.602732 -278.946356) (xy 132.602242 -278.971345)
			(xy 132.594423 -279.020708) (xy 132.578979 -279.06824) (xy 132.556289 -279.112772) (xy 132.526913 -279.153205)
			(xy 132.491573 -279.188545) (xy 132.45114 -279.217921) (xy 132.406608 -279.240611) (xy 132.359076 -279.256055)
			(xy 132.309713 -279.263874) (xy 132.259735 -279.263874) (xy 132.210372 -279.256055) (xy 132.16284 -279.240611)
			(xy 132.118308 -279.217921) (xy 132.077875 -279.188545) (xy 132.042535 -279.153205) (xy 132.013159 -279.112772)
			(xy 131.990469 -279.06824) (xy 131.975025 -279.020708) (xy 131.967206 -278.971345) (xy 131.659889 -278.971345)
			(xy 131.65988 -278.971802) (xy 131.651716 -279.022036) (xy 131.6356 -279.07031) (xy 131.611949 -279.115373)
			(xy 131.581376 -279.156059) (xy 131.544672 -279.191314) (xy 131.502788 -279.220224) (xy 131.456809 -279.242041)
			(xy 131.407925 -279.256201) (xy 131.357404 -279.262335) (xy 131.306552 -279.260286) (xy 131.256688 -279.250106)
			(xy 131.209102 -279.232059) (xy 131.165028 -279.206613) (xy 131.125606 -279.174426) (xy 131.091858 -279.136332)
			(xy 131.064657 -279.093318) (xy 131.044709 -279.046498) (xy 131.03253 -278.997084) (xy 131.028435 -278.946356)
			(xy 130.722878 -278.946356) (xy 130.722388 -278.971345) (xy 130.714569 -279.020708) (xy 130.699125 -279.06824)
			(xy 130.676435 -279.112772) (xy 130.647059 -279.153205) (xy 130.611719 -279.188545) (xy 130.571286 -279.217921)
			(xy 130.526754 -279.240611) (xy 130.479222 -279.256055) (xy 130.429859 -279.263874) (xy 130.379881 -279.263874)
			(xy 130.330518 -279.256055) (xy 130.282986 -279.240611) (xy 130.238454 -279.217921) (xy 130.198021 -279.188545)
			(xy 130.162681 -279.153205) (xy 130.133305 -279.112772) (xy 130.110615 -279.06824) (xy 130.095171 -279.020708)
			(xy 130.087352 -278.971345) (xy 129.780035 -278.971345) (xy 129.780026 -278.971802) (xy 129.771862 -279.022036)
			(xy 129.755746 -279.07031) (xy 129.732095 -279.115373) (xy 129.701522 -279.156059) (xy 129.664818 -279.191314)
			(xy 129.622934 -279.220224) (xy 129.576955 -279.242041) (xy 129.528071 -279.256201) (xy 129.47755 -279.262335)
			(xy 129.426698 -279.260286) (xy 129.376834 -279.250106) (xy 129.329248 -279.232059) (xy 129.285174 -279.206613)
			(xy 129.245752 -279.174426) (xy 129.212004 -279.136332) (xy 129.184803 -279.093318) (xy 129.164855 -279.046498)
			(xy 129.152676 -278.997084) (xy 129.148581 -278.946356) (xy 128.840484 -278.946356) (xy 128.839972 -278.971802)
			(xy 128.831808 -279.022036) (xy 128.815692 -279.07031) (xy 128.792041 -279.115373) (xy 128.761468 -279.156059)
			(xy 128.724764 -279.191314) (xy 128.68288 -279.220224) (xy 128.636901 -279.242041) (xy 128.588017 -279.256201)
			(xy 128.537496 -279.262335) (xy 128.486644 -279.260286) (xy 128.43678 -279.250106) (xy 128.389194 -279.232059)
			(xy 128.34512 -279.206613) (xy 128.305698 -279.174426) (xy 128.27195 -279.136332) (xy 128.244749 -279.093318)
			(xy 128.224801 -279.046498) (xy 128.212622 -278.997084) (xy 128.208527 -278.946356) (xy 127.902515 -278.946356)
			(xy 127.902515 -278.971412) (xy 127.89469 -279.020821) (xy 127.879232 -279.068397) (xy 127.856521 -279.112969)
			(xy 127.827118 -279.15344) (xy 127.791746 -279.188813) (xy 127.751276 -279.218217) (xy 127.706704 -279.240929)
			(xy 127.659129 -279.256388) (xy 127.60972 -279.264215) (xy 127.584708 -279.264618) (xy 127.559015 -279.264126)
			(xy 127.508298 -279.255868) (xy 127.459567 -279.239566) (xy 127.41409 -279.215644) (xy 127.373049 -279.184723)
			(xy 127.337512 -279.147607) (xy 127.308402 -279.105263) (xy 127.286477 -279.05879) (xy 127.272306 -279.009397)
			(xy 127.268732 -278.983948) (xy 127.268732 -278.983694) (xy 127.267462 -278.973788) (xy 127.259334 -278.958548)
			(xy 127.252476 -278.95169) (xy 127.250444 -278.950166) (xy 127.241823 -278.943721) (xy 127.221073 -278.938065)
			(xy 127.199822 -278.941375) (xy 127.181775 -278.953072) (xy 127.170076 -278.971119) (xy 127.167894 -278.981662)
			(xy 127.167386 -278.989536) (xy 127.167386 -279.06599) (xy 127.166846 -279.075825) (xy 127.159252 -279.09398)
			(xy 127.152654 -279.101296) (xy 126.801118 -279.452832) (xy 126.794405 -279.46007) (xy 126.786813 -279.478275)
			(xy 126.786386 -279.488138) (xy 126.786386 -279.756362) (xy 127.738627 -279.756362) (xy 127.742722 -279.705634)
			(xy 127.754901 -279.65622) (xy 127.774849 -279.6094) (xy 127.80205 -279.566386) (xy 127.835798 -279.528292)
			(xy 127.87522 -279.496105) (xy 127.919294 -279.470659) (xy 127.96688 -279.452612) (xy 128.016744 -279.442432)
			(xy 128.067596 -279.440383) (xy 128.118117 -279.446517) (xy 128.167001 -279.460677) (xy 128.21298 -279.482494)
			(xy 128.254864 -279.511404) (xy 128.291568 -279.546659) (xy 128.322141 -279.587345) (xy 128.345792 -279.632408)
			(xy 128.361908 -279.680682) (xy 128.370072 -279.730916) (xy 128.370584 -279.756362) (xy 128.370081 -279.781351)
			(xy 128.677144 -279.781351) (xy 128.677144 -279.731373) (xy 128.684963 -279.68201) (xy 128.700407 -279.634478)
			(xy 128.723097 -279.589946) (xy 128.752473 -279.549513) (xy 128.787813 -279.514173) (xy 128.828246 -279.484797)
			(xy 128.872778 -279.462107) (xy 128.92031 -279.446663) (xy 128.969673 -279.438844) (xy 129.019651 -279.438844)
			(xy 129.069014 -279.446663) (xy 129.116546 -279.462107) (xy 129.161078 -279.484797) (xy 129.201511 -279.514173)
			(xy 129.236851 -279.549513) (xy 129.266227 -279.589946) (xy 129.288917 -279.634478) (xy 129.304361 -279.68201)
			(xy 129.31218 -279.731373) (xy 129.31267 -279.756362) (xy 129.618481 -279.756362) (xy 129.622576 -279.705634)
			(xy 129.634755 -279.65622) (xy 129.654703 -279.6094) (xy 129.681904 -279.566386) (xy 129.715652 -279.528292)
			(xy 129.755074 -279.496105) (xy 129.799148 -279.470659) (xy 129.846734 -279.452612) (xy 129.896598 -279.442432)
			(xy 129.94745 -279.440383) (xy 129.997971 -279.446517) (xy 130.046855 -279.460677) (xy 130.092834 -279.482494)
			(xy 130.134718 -279.511404) (xy 130.171422 -279.546659) (xy 130.201995 -279.587345) (xy 130.225646 -279.632408)
			(xy 130.241762 -279.680682) (xy 130.249926 -279.730916) (xy 130.250438 -279.756362) (xy 130.249935 -279.781351)
			(xy 130.557252 -279.781351) (xy 130.557252 -279.731373) (xy 130.565071 -279.68201) (xy 130.580515 -279.634478)
			(xy 130.603205 -279.589946) (xy 130.632581 -279.549513) (xy 130.667921 -279.514173) (xy 130.708354 -279.484797)
			(xy 130.752886 -279.462107) (xy 130.800418 -279.446663) (xy 130.849781 -279.438844) (xy 130.899759 -279.438844)
			(xy 130.949122 -279.446663) (xy 130.996654 -279.462107) (xy 131.041186 -279.484797) (xy 131.081619 -279.514173)
			(xy 131.116959 -279.549513) (xy 131.146335 -279.589946) (xy 131.169025 -279.634478) (xy 131.184469 -279.68201)
			(xy 131.192288 -279.731373) (xy 131.192778 -279.756362) (xy 131.498589 -279.756362) (xy 131.502684 -279.705634)
			(xy 131.514863 -279.65622) (xy 131.534811 -279.6094) (xy 131.562012 -279.566386) (xy 131.59576 -279.528292)
			(xy 131.635182 -279.496105) (xy 131.679256 -279.470659) (xy 131.726842 -279.452612) (xy 131.776706 -279.442432)
			(xy 131.827558 -279.440383) (xy 131.878079 -279.446517) (xy 131.926963 -279.460677) (xy 131.972942 -279.482494)
			(xy 132.014826 -279.511404) (xy 132.05153 -279.546659) (xy 132.082103 -279.587345) (xy 132.105754 -279.632408)
			(xy 132.12187 -279.680682) (xy 132.130034 -279.730916) (xy 132.130546 -279.756362) (xy 132.438643 -279.756362)
			(xy 132.442738 -279.705634) (xy 132.454917 -279.65622) (xy 132.474865 -279.6094) (xy 132.502066 -279.566386)
			(xy 132.535814 -279.528292) (xy 132.575236 -279.496105) (xy 132.61931 -279.470659) (xy 132.666896 -279.452612)
			(xy 132.71676 -279.442432) (xy 132.767612 -279.440383) (xy 132.818133 -279.446517) (xy 132.867017 -279.460677)
			(xy 132.912996 -279.482494) (xy 132.95488 -279.511404) (xy 132.991584 -279.546659) (xy 133.022157 -279.587345)
			(xy 133.045808 -279.632408) (xy 133.061924 -279.680682) (xy 133.070088 -279.730916) (xy 133.0706 -279.756362)
			(xy 133.070097 -279.781351) (xy 133.37716 -279.781351) (xy 133.37716 -279.731373) (xy 133.384979 -279.68201)
			(xy 133.400423 -279.634478) (xy 133.423113 -279.589946) (xy 133.452489 -279.549513) (xy 133.487829 -279.514173)
			(xy 133.528262 -279.484797) (xy 133.572794 -279.462107) (xy 133.620326 -279.446663) (xy 133.669689 -279.438844)
			(xy 133.719667 -279.438844) (xy 133.76903 -279.446663) (xy 133.816562 -279.462107) (xy 133.861094 -279.484797)
			(xy 133.901527 -279.514173) (xy 133.936867 -279.549513) (xy 133.966243 -279.589946) (xy 133.988933 -279.634478)
			(xy 134.004377 -279.68201) (xy 134.012196 -279.731373) (xy 134.012686 -279.756362) (xy 134.318497 -279.756362)
			(xy 134.322592 -279.705634) (xy 134.334771 -279.65622) (xy 134.354719 -279.6094) (xy 134.38192 -279.566386)
			(xy 134.415668 -279.528292) (xy 134.45509 -279.496105) (xy 134.499164 -279.470659) (xy 134.54675 -279.452612)
			(xy 134.596614 -279.442432) (xy 134.647466 -279.440383) (xy 134.697987 -279.446517) (xy 134.746871 -279.460677)
			(xy 134.79285 -279.482494) (xy 134.834734 -279.511404) (xy 134.871438 -279.546659) (xy 134.902011 -279.587345)
			(xy 134.925662 -279.632408) (xy 134.941778 -279.680682) (xy 134.949942 -279.730916) (xy 134.950454 -279.756362)
			(xy 134.949951 -279.781351) (xy 135.257268 -279.781351) (xy 135.257268 -279.731373) (xy 135.265087 -279.68201)
			(xy 135.280531 -279.634478) (xy 135.303221 -279.589946) (xy 135.332597 -279.549513) (xy 135.367937 -279.514173)
			(xy 135.40837 -279.484797) (xy 135.452902 -279.462107) (xy 135.500434 -279.446663) (xy 135.549797 -279.438844)
			(xy 135.599775 -279.438844) (xy 135.649138 -279.446663) (xy 135.69667 -279.462107) (xy 135.741202 -279.484797)
			(xy 135.781635 -279.514173) (xy 135.816975 -279.549513) (xy 135.846351 -279.589946) (xy 135.869041 -279.634478)
			(xy 135.884485 -279.68201) (xy 135.892304 -279.731373) (xy 135.892794 -279.756362) (xy 136.198605 -279.756362)
			(xy 136.2027 -279.705634) (xy 136.214879 -279.65622) (xy 136.234827 -279.6094) (xy 136.262028 -279.566386)
			(xy 136.295776 -279.528292) (xy 136.335198 -279.496105) (xy 136.379272 -279.470659) (xy 136.426858 -279.452612)
			(xy 136.476722 -279.442432) (xy 136.527574 -279.440383) (xy 136.578095 -279.446517) (xy 136.626979 -279.460677)
			(xy 136.672958 -279.482494) (xy 136.714842 -279.511404) (xy 136.751546 -279.546659) (xy 136.782119 -279.587345)
			(xy 136.80577 -279.632408) (xy 136.821886 -279.680682) (xy 136.83005 -279.730916) (xy 136.830562 -279.756362)
			(xy 136.830059 -279.781351) (xy 137.137122 -279.781351) (xy 137.137122 -279.731373) (xy 137.144941 -279.68201)
			(xy 137.160385 -279.634478) (xy 137.183075 -279.589946) (xy 137.212451 -279.549513) (xy 137.247791 -279.514173)
			(xy 137.288224 -279.484797) (xy 137.332756 -279.462107) (xy 137.380288 -279.446663) (xy 137.429651 -279.438844)
			(xy 137.479629 -279.438844) (xy 137.528992 -279.446663) (xy 137.576524 -279.462107) (xy 137.621056 -279.484797)
			(xy 137.661489 -279.514173) (xy 137.696829 -279.549513) (xy 137.726205 -279.589946) (xy 137.748895 -279.634478)
			(xy 137.764339 -279.68201) (xy 137.772158 -279.731373) (xy 137.772648 -279.756362) (xy 138.078459 -279.756362)
			(xy 138.082554 -279.705634) (xy 138.094733 -279.65622) (xy 138.114681 -279.6094) (xy 138.141882 -279.566386)
			(xy 138.17563 -279.528292) (xy 138.215052 -279.496105) (xy 138.259126 -279.470659) (xy 138.306712 -279.452612)
			(xy 138.356576 -279.442432) (xy 138.407428 -279.440383) (xy 138.457949 -279.446517) (xy 138.506833 -279.460677)
			(xy 138.552812 -279.482494) (xy 138.594696 -279.511404) (xy 138.6314 -279.546659) (xy 138.661973 -279.587345)
			(xy 138.685624 -279.632408) (xy 138.70174 -279.680682) (xy 138.709904 -279.730916) (xy 138.710416 -279.756362)
			(xy 139.018513 -279.756362) (xy 139.022608 -279.705634) (xy 139.034787 -279.65622) (xy 139.054735 -279.6094)
			(xy 139.081936 -279.566386) (xy 139.115684 -279.528292) (xy 139.155106 -279.496105) (xy 139.19918 -279.470659)
			(xy 139.246766 -279.452612) (xy 139.29663 -279.442432) (xy 139.347482 -279.440383) (xy 139.398003 -279.446517)
			(xy 139.446887 -279.460677) (xy 139.492866 -279.482494) (xy 139.53475 -279.511404) (xy 139.571454 -279.546659)
			(xy 139.602027 -279.587345) (xy 139.625678 -279.632408) (xy 139.641794 -279.680682) (xy 139.649958 -279.730916)
			(xy 139.65047 -279.756362) (xy 139.649967 -279.781351) (xy 139.957284 -279.781351) (xy 139.957284 -279.731373)
			(xy 139.965103 -279.68201) (xy 139.980547 -279.634478) (xy 140.003237 -279.589946) (xy 140.032613 -279.549513)
			(xy 140.067953 -279.514173) (xy 140.108386 -279.484797) (xy 140.152918 -279.462107) (xy 140.20045 -279.446663)
			(xy 140.249813 -279.438844) (xy 140.299791 -279.438844) (xy 140.349154 -279.446663) (xy 140.396686 -279.462107)
			(xy 140.441218 -279.484797) (xy 140.481651 -279.514173) (xy 140.516991 -279.549513) (xy 140.546367 -279.589946)
			(xy 140.569057 -279.634478) (xy 140.584501 -279.68201) (xy 140.59232 -279.731373) (xy 140.59281 -279.756362)
			(xy 140.898621 -279.756362) (xy 140.902716 -279.705634) (xy 140.914895 -279.65622) (xy 140.934843 -279.6094)
			(xy 140.962044 -279.566386) (xy 140.995792 -279.528292) (xy 141.035214 -279.496105) (xy 141.079288 -279.470659)
			(xy 141.126874 -279.452612) (xy 141.176738 -279.442432) (xy 141.22759 -279.440383) (xy 141.278111 -279.446517)
			(xy 141.326995 -279.460677) (xy 141.372974 -279.482494) (xy 141.414858 -279.511404) (xy 141.451562 -279.546659)
			(xy 141.482135 -279.587345) (xy 141.505786 -279.632408) (xy 141.521902 -279.680682) (xy 141.530066 -279.730916)
			(xy 141.530578 -279.756362) (xy 141.530075 -279.781351) (xy 141.837138 -279.781351) (xy 141.837138 -279.731373)
			(xy 141.844957 -279.68201) (xy 141.860401 -279.634478) (xy 141.883091 -279.589946) (xy 141.912467 -279.549513)
			(xy 141.947807 -279.514173) (xy 141.98824 -279.484797) (xy 142.032772 -279.462107) (xy 142.080304 -279.446663)
			(xy 142.129667 -279.438844) (xy 142.179645 -279.438844) (xy 142.229008 -279.446663) (xy 142.27654 -279.462107)
			(xy 142.321072 -279.484797) (xy 142.361505 -279.514173) (xy 142.396845 -279.549513) (xy 142.426221 -279.589946)
			(xy 142.448911 -279.634478) (xy 142.464355 -279.68201) (xy 142.472174 -279.731373) (xy 142.472664 -279.756362)
			(xy 142.778475 -279.756362) (xy 142.78257 -279.705634) (xy 142.794749 -279.65622) (xy 142.814697 -279.6094)
			(xy 142.841898 -279.566386) (xy 142.875646 -279.528292) (xy 142.915068 -279.496105) (xy 142.959142 -279.470659)
			(xy 143.006728 -279.452612) (xy 143.056592 -279.442432) (xy 143.107444 -279.440383) (xy 143.157965 -279.446517)
			(xy 143.206849 -279.460677) (xy 143.252828 -279.482494) (xy 143.294712 -279.511404) (xy 143.331416 -279.546659)
			(xy 143.361989 -279.587345) (xy 143.38564 -279.632408) (xy 143.401756 -279.680682) (xy 143.40992 -279.730916)
			(xy 143.410432 -279.756362) (xy 143.409929 -279.781351) (xy 143.717246 -279.781351) (xy 143.717246 -279.731373)
			(xy 143.725065 -279.68201) (xy 143.740509 -279.634478) (xy 143.763199 -279.589946) (xy 143.792575 -279.549513)
			(xy 143.827915 -279.514173) (xy 143.868348 -279.484797) (xy 143.91288 -279.462107) (xy 143.960412 -279.446663)
			(xy 144.009775 -279.438844) (xy 144.059753 -279.438844) (xy 144.109116 -279.446663) (xy 144.156648 -279.462107)
			(xy 144.20118 -279.484797) (xy 144.241613 -279.514173) (xy 144.276953 -279.549513) (xy 144.306329 -279.589946)
			(xy 144.329019 -279.634478) (xy 144.344463 -279.68201) (xy 144.352282 -279.731373) (xy 144.352772 -279.756362)
			(xy 144.352282 -279.781351) (xy 144.344463 -279.830714) (xy 144.329019 -279.878246) (xy 144.306329 -279.922778)
			(xy 144.276953 -279.963211) (xy 144.241613 -279.998551) (xy 144.20118 -280.027927) (xy 144.156648 -280.050617)
			(xy 144.109116 -280.066061) (xy 144.059753 -280.07388) (xy 144.009775 -280.07388) (xy 143.960412 -280.066061)
			(xy 143.91288 -280.050617) (xy 143.868348 -280.027927) (xy 143.827915 -279.998551) (xy 143.792575 -279.963211)
			(xy 143.763199 -279.922778) (xy 143.740509 -279.878246) (xy 143.725065 -279.830714) (xy 143.717246 -279.781351)
			(xy 143.409929 -279.781351) (xy 143.40992 -279.781808) (xy 143.401756 -279.832042) (xy 143.38564 -279.880316)
			(xy 143.361989 -279.925379) (xy 143.331416 -279.966065) (xy 143.294712 -280.00132) (xy 143.252828 -280.03023)
			(xy 143.206849 -280.052047) (xy 143.157965 -280.066207) (xy 143.107444 -280.072341) (xy 143.056592 -280.070292)
			(xy 143.006728 -280.060112) (xy 142.959142 -280.042065) (xy 142.915068 -280.016619) (xy 142.875646 -279.984432)
			(xy 142.841898 -279.946338) (xy 142.814697 -279.903324) (xy 142.794749 -279.856504) (xy 142.78257 -279.80709)
			(xy 142.778475 -279.756362) (xy 142.472664 -279.756362) (xy 142.472174 -279.781351) (xy 142.464355 -279.830714)
			(xy 142.448911 -279.878246) (xy 142.426221 -279.922778) (xy 142.396845 -279.963211) (xy 142.361505 -279.998551)
			(xy 142.321072 -280.027927) (xy 142.27654 -280.050617) (xy 142.229008 -280.066061) (xy 142.179645 -280.07388)
			(xy 142.129667 -280.07388) (xy 142.080304 -280.066061) (xy 142.032772 -280.050617) (xy 141.98824 -280.027927)
			(xy 141.947807 -279.998551) (xy 141.912467 -279.963211) (xy 141.883091 -279.922778) (xy 141.860401 -279.878246)
			(xy 141.844957 -279.830714) (xy 141.837138 -279.781351) (xy 141.530075 -279.781351) (xy 141.530066 -279.781808)
			(xy 141.521902 -279.832042) (xy 141.505786 -279.880316) (xy 141.482135 -279.925379) (xy 141.451562 -279.966065)
			(xy 141.414858 -280.00132) (xy 141.372974 -280.03023) (xy 141.326995 -280.052047) (xy 141.278111 -280.066207)
			(xy 141.22759 -280.072341) (xy 141.176738 -280.070292) (xy 141.126874 -280.060112) (xy 141.079288 -280.042065)
			(xy 141.035214 -280.016619) (xy 140.995792 -279.984432) (xy 140.962044 -279.946338) (xy 140.934843 -279.903324)
			(xy 140.914895 -279.856504) (xy 140.902716 -279.80709) (xy 140.898621 -279.756362) (xy 140.59281 -279.756362)
			(xy 140.59232 -279.781351) (xy 140.584501 -279.830714) (xy 140.569057 -279.878246) (xy 140.546367 -279.922778)
			(xy 140.516991 -279.963211) (xy 140.481651 -279.998551) (xy 140.441218 -280.027927) (xy 140.396686 -280.050617)
			(xy 140.349154 -280.066061) (xy 140.299791 -280.07388) (xy 140.249813 -280.07388) (xy 140.20045 -280.066061)
			(xy 140.152918 -280.050617) (xy 140.108386 -280.027927) (xy 140.067953 -279.998551) (xy 140.032613 -279.963211)
			(xy 140.003237 -279.922778) (xy 139.980547 -279.878246) (xy 139.965103 -279.830714) (xy 139.957284 -279.781351)
			(xy 139.649967 -279.781351) (xy 139.649958 -279.781808) (xy 139.641794 -279.832042) (xy 139.625678 -279.880316)
			(xy 139.602027 -279.925379) (xy 139.571454 -279.966065) (xy 139.53475 -280.00132) (xy 139.492866 -280.03023)
			(xy 139.446887 -280.052047) (xy 139.398003 -280.066207) (xy 139.347482 -280.072341) (xy 139.29663 -280.070292)
			(xy 139.246766 -280.060112) (xy 139.19918 -280.042065) (xy 139.155106 -280.016619) (xy 139.115684 -279.984432)
			(xy 139.081936 -279.946338) (xy 139.054735 -279.903324) (xy 139.034787 -279.856504) (xy 139.022608 -279.80709)
			(xy 139.018513 -279.756362) (xy 138.710416 -279.756362) (xy 138.709904 -279.781808) (xy 138.70174 -279.832042)
			(xy 138.685624 -279.880316) (xy 138.661973 -279.925379) (xy 138.6314 -279.966065) (xy 138.594696 -280.00132)
			(xy 138.552812 -280.03023) (xy 138.506833 -280.052047) (xy 138.457949 -280.066207) (xy 138.407428 -280.072341)
			(xy 138.356576 -280.070292) (xy 138.306712 -280.060112) (xy 138.259126 -280.042065) (xy 138.215052 -280.016619)
			(xy 138.17563 -279.984432) (xy 138.141882 -279.946338) (xy 138.114681 -279.903324) (xy 138.094733 -279.856504)
			(xy 138.082554 -279.80709) (xy 138.078459 -279.756362) (xy 137.772648 -279.756362) (xy 137.772158 -279.781351)
			(xy 137.764339 -279.830714) (xy 137.748895 -279.878246) (xy 137.726205 -279.922778) (xy 137.696829 -279.963211)
			(xy 137.661489 -279.998551) (xy 137.621056 -280.027927) (xy 137.576524 -280.050617) (xy 137.528992 -280.066061)
			(xy 137.479629 -280.07388) (xy 137.429651 -280.07388) (xy 137.380288 -280.066061) (xy 137.332756 -280.050617)
			(xy 137.288224 -280.027927) (xy 137.247791 -279.998551) (xy 137.212451 -279.963211) (xy 137.183075 -279.922778)
			(xy 137.160385 -279.878246) (xy 137.144941 -279.830714) (xy 137.137122 -279.781351) (xy 136.830059 -279.781351)
			(xy 136.83005 -279.781808) (xy 136.821886 -279.832042) (xy 136.80577 -279.880316) (xy 136.782119 -279.925379)
			(xy 136.751546 -279.966065) (xy 136.714842 -280.00132) (xy 136.672958 -280.03023) (xy 136.626979 -280.052047)
			(xy 136.578095 -280.066207) (xy 136.527574 -280.072341) (xy 136.476722 -280.070292) (xy 136.426858 -280.060112)
			(xy 136.379272 -280.042065) (xy 136.335198 -280.016619) (xy 136.295776 -279.984432) (xy 136.262028 -279.946338)
			(xy 136.234827 -279.903324) (xy 136.214879 -279.856504) (xy 136.2027 -279.80709) (xy 136.198605 -279.756362)
			(xy 135.892794 -279.756362) (xy 135.892304 -279.781351) (xy 135.884485 -279.830714) (xy 135.869041 -279.878246)
			(xy 135.846351 -279.922778) (xy 135.816975 -279.963211) (xy 135.781635 -279.998551) (xy 135.741202 -280.027927)
			(xy 135.69667 -280.050617) (xy 135.649138 -280.066061) (xy 135.599775 -280.07388) (xy 135.549797 -280.07388)
			(xy 135.500434 -280.066061) (xy 135.452902 -280.050617) (xy 135.40837 -280.027927) (xy 135.367937 -279.998551)
			(xy 135.332597 -279.963211) (xy 135.303221 -279.922778) (xy 135.280531 -279.878246) (xy 135.265087 -279.830714)
			(xy 135.257268 -279.781351) (xy 134.949951 -279.781351) (xy 134.949942 -279.781808) (xy 134.941778 -279.832042)
			(xy 134.925662 -279.880316) (xy 134.902011 -279.925379) (xy 134.871438 -279.966065) (xy 134.834734 -280.00132)
			(xy 134.79285 -280.03023) (xy 134.746871 -280.052047) (xy 134.697987 -280.066207) (xy 134.647466 -280.072341)
			(xy 134.596614 -280.070292) (xy 134.54675 -280.060112) (xy 134.499164 -280.042065) (xy 134.45509 -280.016619)
			(xy 134.415668 -279.984432) (xy 134.38192 -279.946338) (xy 134.354719 -279.903324) (xy 134.334771 -279.856504)
			(xy 134.322592 -279.80709) (xy 134.318497 -279.756362) (xy 134.012686 -279.756362) (xy 134.012196 -279.781351)
			(xy 134.004377 -279.830714) (xy 133.988933 -279.878246) (xy 133.966243 -279.922778) (xy 133.936867 -279.963211)
			(xy 133.901527 -279.998551) (xy 133.861094 -280.027927) (xy 133.816562 -280.050617) (xy 133.76903 -280.066061)
			(xy 133.719667 -280.07388) (xy 133.669689 -280.07388) (xy 133.620326 -280.066061) (xy 133.572794 -280.050617)
			(xy 133.528262 -280.027927) (xy 133.487829 -279.998551) (xy 133.452489 -279.963211) (xy 133.423113 -279.922778)
			(xy 133.400423 -279.878246) (xy 133.384979 -279.830714) (xy 133.37716 -279.781351) (xy 133.070097 -279.781351)
			(xy 133.070088 -279.781808) (xy 133.061924 -279.832042) (xy 133.045808 -279.880316) (xy 133.022157 -279.925379)
			(xy 132.991584 -279.966065) (xy 132.95488 -280.00132) (xy 132.912996 -280.03023) (xy 132.867017 -280.052047)
			(xy 132.818133 -280.066207) (xy 132.767612 -280.072341) (xy 132.71676 -280.070292) (xy 132.666896 -280.060112)
			(xy 132.61931 -280.042065) (xy 132.575236 -280.016619) (xy 132.535814 -279.984432) (xy 132.502066 -279.946338)
			(xy 132.474865 -279.903324) (xy 132.454917 -279.856504) (xy 132.442738 -279.80709) (xy 132.438643 -279.756362)
			(xy 132.130546 -279.756362) (xy 132.130034 -279.781808) (xy 132.12187 -279.832042) (xy 132.105754 -279.880316)
			(xy 132.082103 -279.925379) (xy 132.05153 -279.966065) (xy 132.014826 -280.00132) (xy 131.972942 -280.03023)
			(xy 131.926963 -280.052047) (xy 131.878079 -280.066207) (xy 131.827558 -280.072341) (xy 131.776706 -280.070292)
			(xy 131.726842 -280.060112) (xy 131.679256 -280.042065) (xy 131.635182 -280.016619) (xy 131.59576 -279.984432)
			(xy 131.562012 -279.946338) (xy 131.534811 -279.903324) (xy 131.514863 -279.856504) (xy 131.502684 -279.80709)
			(xy 131.498589 -279.756362) (xy 131.192778 -279.756362) (xy 131.192288 -279.781351) (xy 131.184469 -279.830714)
			(xy 131.169025 -279.878246) (xy 131.146335 -279.922778) (xy 131.116959 -279.963211) (xy 131.081619 -279.998551)
			(xy 131.041186 -280.027927) (xy 130.996654 -280.050617) (xy 130.949122 -280.066061) (xy 130.899759 -280.07388)
			(xy 130.849781 -280.07388) (xy 130.800418 -280.066061) (xy 130.752886 -280.050617) (xy 130.708354 -280.027927)
			(xy 130.667921 -279.998551) (xy 130.632581 -279.963211) (xy 130.603205 -279.922778) (xy 130.580515 -279.878246)
			(xy 130.565071 -279.830714) (xy 130.557252 -279.781351) (xy 130.249935 -279.781351) (xy 130.249926 -279.781808)
			(xy 130.241762 -279.832042) (xy 130.225646 -279.880316) (xy 130.201995 -279.925379) (xy 130.171422 -279.966065)
			(xy 130.134718 -280.00132) (xy 130.092834 -280.03023) (xy 130.046855 -280.052047) (xy 129.997971 -280.066207)
			(xy 129.94745 -280.072341) (xy 129.896598 -280.070292) (xy 129.846734 -280.060112) (xy 129.799148 -280.042065)
			(xy 129.755074 -280.016619) (xy 129.715652 -279.984432) (xy 129.681904 -279.946338) (xy 129.654703 -279.903324)
			(xy 129.634755 -279.856504) (xy 129.622576 -279.80709) (xy 129.618481 -279.756362) (xy 129.31267 -279.756362)
			(xy 129.31218 -279.781351) (xy 129.304361 -279.830714) (xy 129.288917 -279.878246) (xy 129.266227 -279.922778)
			(xy 129.236851 -279.963211) (xy 129.201511 -279.998551) (xy 129.161078 -280.027927) (xy 129.116546 -280.050617)
			(xy 129.069014 -280.066061) (xy 129.019651 -280.07388) (xy 128.969673 -280.07388) (xy 128.92031 -280.066061)
			(xy 128.872778 -280.050617) (xy 128.828246 -280.027927) (xy 128.787813 -279.998551) (xy 128.752473 -279.963211)
			(xy 128.723097 -279.922778) (xy 128.700407 -279.878246) (xy 128.684963 -279.830714) (xy 128.677144 -279.781351)
			(xy 128.370081 -279.781351) (xy 128.370072 -279.781808) (xy 128.361908 -279.832042) (xy 128.345792 -279.880316)
			(xy 128.322141 -279.925379) (xy 128.291568 -279.966065) (xy 128.254864 -280.00132) (xy 128.21298 -280.03023)
			(xy 128.167001 -280.052047) (xy 128.118117 -280.066207) (xy 128.067596 -280.072341) (xy 128.016744 -280.070292)
			(xy 127.96688 -280.060112) (xy 127.919294 -280.042065) (xy 127.87522 -280.016619) (xy 127.835798 -279.984432)
			(xy 127.80205 -279.946338) (xy 127.774849 -279.903324) (xy 127.754901 -279.856504) (xy 127.742722 -279.80709)
			(xy 127.738627 -279.756362) (xy 126.786386 -279.756362) (xy 126.786386 -280.23947) (xy 126.786608 -280.246073)
			(xy 126.790085 -280.258813) (xy 126.793244 -280.264616) (xy 126.804166 -280.28392) (xy 126.810516 -280.292556)
			(xy 126.815342 -280.29789) (xy 126.820676 -280.301446) (xy 126.842134 -280.31633) (xy 126.880329 -280.351938)
			(xy 126.912195 -280.393306) (xy 126.936876 -280.439324) (xy 126.953709 -280.488756) (xy 126.962241 -280.540273)
			(xy 126.962244 -280.591357) (xy 127.26719 -280.591357) (xy 127.26719 -280.541379) (xy 127.275009 -280.492016)
			(xy 127.290453 -280.444484) (xy 127.313143 -280.399952) (xy 127.342519 -280.359519) (xy 127.377859 -280.324179)
			(xy 127.418292 -280.294803) (xy 127.462824 -280.272113) (xy 127.510356 -280.256669) (xy 127.559719 -280.24885)
			(xy 127.609697 -280.24885) (xy 127.65906 -280.256669) (xy 127.706592 -280.272113) (xy 127.751124 -280.294803)
			(xy 127.791557 -280.324179) (xy 127.826897 -280.359519) (xy 127.856273 -280.399952) (xy 127.878963 -280.444484)
			(xy 127.894407 -280.492016) (xy 127.902226 -280.541379) (xy 127.902716 -280.566368) (xy 128.208527 -280.566368)
			(xy 128.212622 -280.51564) (xy 128.224801 -280.466226) (xy 128.244749 -280.419406) (xy 128.27195 -280.376392)
			(xy 128.305698 -280.338298) (xy 128.34512 -280.306111) (xy 128.389194 -280.280665) (xy 128.43678 -280.262618)
			(xy 128.486644 -280.252438) (xy 128.537496 -280.250389) (xy 128.588017 -280.256523) (xy 128.636901 -280.270683)
			(xy 128.68288 -280.2925) (xy 128.724764 -280.32141) (xy 128.761468 -280.356665) (xy 128.792041 -280.397351)
			(xy 128.815692 -280.442414) (xy 128.831808 -280.490688) (xy 128.839972 -280.540922) (xy 128.840484 -280.566368)
			(xy 129.148581 -280.566368) (xy 129.152676 -280.51564) (xy 129.164855 -280.466226) (xy 129.184803 -280.419406)
			(xy 129.212004 -280.376392) (xy 129.245752 -280.338298) (xy 129.285174 -280.306111) (xy 129.329248 -280.280665)
			(xy 129.376834 -280.262618) (xy 129.426698 -280.252438) (xy 129.47755 -280.250389) (xy 129.528071 -280.256523)
			(xy 129.576955 -280.270683) (xy 129.622934 -280.2925) (xy 129.664818 -280.32141) (xy 129.701522 -280.356665)
			(xy 129.732095 -280.397351) (xy 129.755746 -280.442414) (xy 129.771862 -280.490688) (xy 129.780026 -280.540922)
			(xy 129.780538 -280.566368) (xy 131.028435 -280.566368) (xy 131.03253 -280.51564) (xy 131.044709 -280.466226)
			(xy 131.064657 -280.419406) (xy 131.091858 -280.376392) (xy 131.125606 -280.338298) (xy 131.165028 -280.306111)
			(xy 131.209102 -280.280665) (xy 131.256688 -280.262618) (xy 131.306552 -280.252438) (xy 131.357404 -280.250389)
			(xy 131.407925 -280.256523) (xy 131.456809 -280.270683) (xy 131.502788 -280.2925) (xy 131.544672 -280.32141)
			(xy 131.581376 -280.356665) (xy 131.611949 -280.397351) (xy 131.6356 -280.442414) (xy 131.651716 -280.490688)
			(xy 131.65988 -280.540922) (xy 131.660392 -280.566368) (xy 131.659889 -280.591357) (xy 131.967206 -280.591357)
			(xy 131.967206 -280.541379) (xy 131.975025 -280.492016) (xy 131.990469 -280.444484) (xy 132.013159 -280.399952)
			(xy 132.042535 -280.359519) (xy 132.077875 -280.324179) (xy 132.118308 -280.294803) (xy 132.16284 -280.272113)
			(xy 132.210372 -280.256669) (xy 132.259735 -280.24885) (xy 132.309713 -280.24885) (xy 132.359076 -280.256669)
			(xy 132.406608 -280.272113) (xy 132.45114 -280.294803) (xy 132.491573 -280.324179) (xy 132.526913 -280.359519)
			(xy 132.556289 -280.399952) (xy 132.578979 -280.444484) (xy 132.594423 -280.492016) (xy 132.602242 -280.541379)
			(xy 132.602732 -280.566368) (xy 132.908543 -280.566368) (xy 132.912638 -280.51564) (xy 132.924817 -280.466226)
			(xy 132.944765 -280.419406) (xy 132.971966 -280.376392) (xy 133.005714 -280.338298) (xy 133.045136 -280.306111)
			(xy 133.08921 -280.280665) (xy 133.136796 -280.262618) (xy 133.18666 -280.252438) (xy 133.237512 -280.250389)
			(xy 133.288033 -280.256523) (xy 133.336917 -280.270683) (xy 133.382896 -280.2925) (xy 133.42478 -280.32141)
			(xy 133.461484 -280.356665) (xy 133.492057 -280.397351) (xy 133.515708 -280.442414) (xy 133.531824 -280.490688)
			(xy 133.539988 -280.540922) (xy 133.5405 -280.566368) (xy 133.539997 -280.591357) (xy 133.847314 -280.591357)
			(xy 133.847314 -280.541379) (xy 133.855133 -280.492016) (xy 133.870577 -280.444484) (xy 133.893267 -280.399952)
			(xy 133.922643 -280.359519) (xy 133.957983 -280.324179) (xy 133.998416 -280.294803) (xy 134.042948 -280.272113)
			(xy 134.09048 -280.256669) (xy 134.139843 -280.24885) (xy 134.189821 -280.24885) (xy 134.239184 -280.256669)
			(xy 134.286716 -280.272113) (xy 134.331248 -280.294803) (xy 134.371681 -280.324179) (xy 134.407021 -280.359519)
			(xy 134.436397 -280.399952) (xy 134.459087 -280.444484) (xy 134.474531 -280.492016) (xy 134.48235 -280.541379)
			(xy 134.48284 -280.566368) (xy 134.788397 -280.566368) (xy 134.792492 -280.51564) (xy 134.804671 -280.466226)
			(xy 134.824619 -280.419406) (xy 134.85182 -280.376392) (xy 134.885568 -280.338298) (xy 134.92499 -280.306111)
			(xy 134.969064 -280.280665) (xy 135.01665 -280.262618) (xy 135.066514 -280.252438) (xy 135.117366 -280.250389)
			(xy 135.167887 -280.256523) (xy 135.216771 -280.270683) (xy 135.26275 -280.2925) (xy 135.304634 -280.32141)
			(xy 135.341338 -280.356665) (xy 135.371911 -280.397351) (xy 135.395562 -280.442414) (xy 135.411678 -280.490688)
			(xy 135.419842 -280.540922) (xy 135.420354 -280.566368) (xy 135.728451 -280.566368) (xy 135.732546 -280.51564)
			(xy 135.744725 -280.466226) (xy 135.764673 -280.419406) (xy 135.791874 -280.376392) (xy 135.825622 -280.338298)
			(xy 135.865044 -280.306111) (xy 135.909118 -280.280665) (xy 135.956704 -280.262618) (xy 136.006568 -280.252438)
			(xy 136.05742 -280.250389) (xy 136.107941 -280.256523) (xy 136.156825 -280.270683) (xy 136.202804 -280.2925)
			(xy 136.244688 -280.32141) (xy 136.281392 -280.356665) (xy 136.311965 -280.397351) (xy 136.335616 -280.442414)
			(xy 136.351732 -280.490688) (xy 136.359896 -280.540922) (xy 136.360408 -280.566368) (xy 137.608559 -280.566368)
			(xy 137.612654 -280.51564) (xy 137.624833 -280.466226) (xy 137.644781 -280.419406) (xy 137.671982 -280.376392)
			(xy 137.70573 -280.338298) (xy 137.745152 -280.306111) (xy 137.789226 -280.280665) (xy 137.836812 -280.262618)
			(xy 137.886676 -280.252438) (xy 137.937528 -280.250389) (xy 137.988049 -280.256523) (xy 138.036933 -280.270683)
			(xy 138.082912 -280.2925) (xy 138.124796 -280.32141) (xy 138.1615 -280.356665) (xy 138.192073 -280.397351)
			(xy 138.215724 -280.442414) (xy 138.23184 -280.490688) (xy 138.240004 -280.540922) (xy 138.240516 -280.566368)
			(xy 138.240013 -280.591357) (xy 138.54733 -280.591357) (xy 138.54733 -280.541379) (xy 138.555149 -280.492016)
			(xy 138.570593 -280.444484) (xy 138.593283 -280.399952) (xy 138.622659 -280.359519) (xy 138.657999 -280.324179)
			(xy 138.698432 -280.294803) (xy 138.742964 -280.272113) (xy 138.790496 -280.256669) (xy 138.839859 -280.24885)
			(xy 138.889837 -280.24885) (xy 138.9392 -280.256669) (xy 138.986732 -280.272113) (xy 139.031264 -280.294803)
			(xy 139.071697 -280.324179) (xy 139.107037 -280.359519) (xy 139.136413 -280.399952) (xy 139.159103 -280.444484)
			(xy 139.174547 -280.492016) (xy 139.182366 -280.541379) (xy 139.182856 -280.566368) (xy 139.488413 -280.566368)
			(xy 139.492508 -280.51564) (xy 139.504687 -280.466226) (xy 139.524635 -280.419406) (xy 139.551836 -280.376392)
			(xy 139.585584 -280.338298) (xy 139.625006 -280.306111) (xy 139.66908 -280.280665) (xy 139.716666 -280.262618)
			(xy 139.76653 -280.252438) (xy 139.817382 -280.250389) (xy 139.867903 -280.256523) (xy 139.916787 -280.270683)
			(xy 139.962766 -280.2925) (xy 140.00465 -280.32141) (xy 140.041354 -280.356665) (xy 140.071927 -280.397351)
			(xy 140.095578 -280.442414) (xy 140.111694 -280.490688) (xy 140.119858 -280.540922) (xy 140.12037 -280.566368)
			(xy 140.119867 -280.591357) (xy 140.427184 -280.591357) (xy 140.427184 -280.541379) (xy 140.435003 -280.492016)
			(xy 140.450447 -280.444484) (xy 140.473137 -280.399952) (xy 140.502513 -280.359519) (xy 140.537853 -280.324179)
			(xy 140.578286 -280.294803) (xy 140.622818 -280.272113) (xy 140.67035 -280.256669) (xy 140.719713 -280.24885)
			(xy 140.769691 -280.24885) (xy 140.819054 -280.256669) (xy 140.866586 -280.272113) (xy 140.911118 -280.294803)
			(xy 140.951551 -280.324179) (xy 140.986891 -280.359519) (xy 141.016267 -280.399952) (xy 141.038957 -280.444484)
			(xy 141.054401 -280.492016) (xy 141.06222 -280.541379) (xy 141.06271 -280.566368) (xy 141.368521 -280.566368)
			(xy 141.372616 -280.51564) (xy 141.384795 -280.466226) (xy 141.404743 -280.419406) (xy 141.431944 -280.376392)
			(xy 141.465692 -280.338298) (xy 141.505114 -280.306111) (xy 141.549188 -280.280665) (xy 141.596774 -280.262618)
			(xy 141.646638 -280.252438) (xy 141.69749 -280.250389) (xy 141.748011 -280.256523) (xy 141.796895 -280.270683)
			(xy 141.842874 -280.2925) (xy 141.884758 -280.32141) (xy 141.921462 -280.356665) (xy 141.952035 -280.397351)
			(xy 141.975686 -280.442414) (xy 141.991802 -280.490688) (xy 141.999966 -280.540922) (xy 142.000478 -280.566368)
			(xy 142.308575 -280.566368) (xy 142.31267 -280.51564) (xy 142.324849 -280.466226) (xy 142.344797 -280.419406)
			(xy 142.371998 -280.376392) (xy 142.405746 -280.338298) (xy 142.445168 -280.306111) (xy 142.489242 -280.280665)
			(xy 142.536828 -280.262618) (xy 142.586692 -280.252438) (xy 142.637544 -280.250389) (xy 142.688065 -280.256523)
			(xy 142.736949 -280.270683) (xy 142.782928 -280.2925) (xy 142.824812 -280.32141) (xy 142.861516 -280.356665)
			(xy 142.892089 -280.397351) (xy 142.91574 -280.442414) (xy 142.931856 -280.490688) (xy 142.94002 -280.540922)
			(xy 142.940532 -280.566368) (xy 142.94002 -280.591814) (xy 142.931856 -280.642048) (xy 142.91574 -280.690322)
			(xy 142.892089 -280.735385) (xy 142.861516 -280.776071) (xy 142.824812 -280.811326) (xy 142.782928 -280.840236)
			(xy 142.736949 -280.862053) (xy 142.688065 -280.876213) (xy 142.637544 -280.882347) (xy 142.586692 -280.880298)
			(xy 142.536828 -280.870118) (xy 142.489242 -280.852071) (xy 142.445168 -280.826625) (xy 142.405746 -280.794438)
			(xy 142.371998 -280.756344) (xy 142.344797 -280.71333) (xy 142.324849 -280.66651) (xy 142.31267 -280.617096)
			(xy 142.308575 -280.566368) (xy 142.000478 -280.566368) (xy 141.999966 -280.591814) (xy 141.991802 -280.642048)
			(xy 141.975686 -280.690322) (xy 141.952035 -280.735385) (xy 141.921462 -280.776071) (xy 141.884758 -280.811326)
			(xy 141.842874 -280.840236) (xy 141.796895 -280.862053) (xy 141.748011 -280.876213) (xy 141.69749 -280.882347)
			(xy 141.646638 -280.880298) (xy 141.596774 -280.870118) (xy 141.549188 -280.852071) (xy 141.505114 -280.826625)
			(xy 141.465692 -280.794438) (xy 141.431944 -280.756344) (xy 141.404743 -280.71333) (xy 141.384795 -280.66651)
			(xy 141.372616 -280.617096) (xy 141.368521 -280.566368) (xy 141.06271 -280.566368) (xy 141.06222 -280.591357)
			(xy 141.054401 -280.64072) (xy 141.038957 -280.688252) (xy 141.016267 -280.732784) (xy 140.986891 -280.773217)
			(xy 140.951551 -280.808557) (xy 140.911118 -280.837933) (xy 140.866586 -280.860623) (xy 140.819054 -280.876067)
			(xy 140.769691 -280.883886) (xy 140.719713 -280.883886) (xy 140.67035 -280.876067) (xy 140.622818 -280.860623)
			(xy 140.578286 -280.837933) (xy 140.537853 -280.808557) (xy 140.502513 -280.773217) (xy 140.473137 -280.732784)
			(xy 140.450447 -280.688252) (xy 140.435003 -280.64072) (xy 140.427184 -280.591357) (xy 140.119867 -280.591357)
			(xy 140.119858 -280.591814) (xy 140.111694 -280.642048) (xy 140.095578 -280.690322) (xy 140.071927 -280.735385)
			(xy 140.041354 -280.776071) (xy 140.00465 -280.811326) (xy 139.962766 -280.840236) (xy 139.916787 -280.862053)
			(xy 139.867903 -280.876213) (xy 139.817382 -280.882347) (xy 139.76653 -280.880298) (xy 139.716666 -280.870118)
			(xy 139.66908 -280.852071) (xy 139.625006 -280.826625) (xy 139.585584 -280.794438) (xy 139.551836 -280.756344)
			(xy 139.524635 -280.71333) (xy 139.504687 -280.66651) (xy 139.492508 -280.617096) (xy 139.488413 -280.566368)
			(xy 139.182856 -280.566368) (xy 139.182366 -280.591357) (xy 139.174547 -280.64072) (xy 139.159103 -280.688252)
			(xy 139.136413 -280.732784) (xy 139.107037 -280.773217) (xy 139.071697 -280.808557) (xy 139.031264 -280.837933)
			(xy 138.986732 -280.860623) (xy 138.9392 -280.876067) (xy 138.889837 -280.883886) (xy 138.839859 -280.883886)
			(xy 138.790496 -280.876067) (xy 138.742964 -280.860623) (xy 138.698432 -280.837933) (xy 138.657999 -280.808557)
			(xy 138.622659 -280.773217) (xy 138.593283 -280.732784) (xy 138.570593 -280.688252) (xy 138.555149 -280.64072)
			(xy 138.54733 -280.591357) (xy 138.240013 -280.591357) (xy 138.240004 -280.591814) (xy 138.23184 -280.642048)
			(xy 138.215724 -280.690322) (xy 138.192073 -280.735385) (xy 138.1615 -280.776071) (xy 138.124796 -280.811326)
			(xy 138.082912 -280.840236) (xy 138.036933 -280.862053) (xy 137.988049 -280.876213) (xy 137.937528 -280.882347)
			(xy 137.886676 -280.880298) (xy 137.836812 -280.870118) (xy 137.789226 -280.852071) (xy 137.745152 -280.826625)
			(xy 137.70573 -280.794438) (xy 137.671982 -280.756344) (xy 137.644781 -280.71333) (xy 137.624833 -280.66651)
			(xy 137.612654 -280.617096) (xy 137.608559 -280.566368) (xy 136.360408 -280.566368) (xy 136.359896 -280.591814)
			(xy 136.351732 -280.642048) (xy 136.335616 -280.690322) (xy 136.311965 -280.735385) (xy 136.281392 -280.776071)
			(xy 136.244688 -280.811326) (xy 136.202804 -280.840236) (xy 136.156825 -280.862053) (xy 136.107941 -280.876213)
			(xy 136.05742 -280.882347) (xy 136.006568 -280.880298) (xy 135.956704 -280.870118) (xy 135.909118 -280.852071)
			(xy 135.865044 -280.826625) (xy 135.825622 -280.794438) (xy 135.791874 -280.756344) (xy 135.764673 -280.71333)
			(xy 135.744725 -280.66651) (xy 135.732546 -280.617096) (xy 135.728451 -280.566368) (xy 135.420354 -280.566368)
			(xy 135.419842 -280.591814) (xy 135.411678 -280.642048) (xy 135.395562 -280.690322) (xy 135.371911 -280.735385)
			(xy 135.341338 -280.776071) (xy 135.304634 -280.811326) (xy 135.26275 -280.840236) (xy 135.216771 -280.862053)
			(xy 135.167887 -280.876213) (xy 135.117366 -280.882347) (xy 135.066514 -280.880298) (xy 135.01665 -280.870118)
			(xy 134.969064 -280.852071) (xy 134.92499 -280.826625) (xy 134.885568 -280.794438) (xy 134.85182 -280.756344)
			(xy 134.824619 -280.71333) (xy 134.804671 -280.66651) (xy 134.792492 -280.617096) (xy 134.788397 -280.566368)
			(xy 134.48284 -280.566368) (xy 134.48235 -280.591357) (xy 134.474531 -280.64072) (xy 134.459087 -280.688252)
			(xy 134.436397 -280.732784) (xy 134.407021 -280.773217) (xy 134.371681 -280.808557) (xy 134.331248 -280.837933)
			(xy 134.286716 -280.860623) (xy 134.239184 -280.876067) (xy 134.189821 -280.883886) (xy 134.139843 -280.883886)
			(xy 134.09048 -280.876067) (xy 134.042948 -280.860623) (xy 133.998416 -280.837933) (xy 133.957983 -280.808557)
			(xy 133.922643 -280.773217) (xy 133.893267 -280.732784) (xy 133.870577 -280.688252) (xy 133.855133 -280.64072)
			(xy 133.847314 -280.591357) (xy 133.539997 -280.591357) (xy 133.539988 -280.591814) (xy 133.531824 -280.642048)
			(xy 133.515708 -280.690322) (xy 133.492057 -280.735385) (xy 133.461484 -280.776071) (xy 133.42478 -280.811326)
			(xy 133.382896 -280.840236) (xy 133.336917 -280.862053) (xy 133.288033 -280.876213) (xy 133.237512 -280.882347)
			(xy 133.18666 -280.880298) (xy 133.136796 -280.870118) (xy 133.08921 -280.852071) (xy 133.045136 -280.826625)
			(xy 133.005714 -280.794438) (xy 132.971966 -280.756344) (xy 132.944765 -280.71333) (xy 132.924817 -280.66651)
			(xy 132.912638 -280.617096) (xy 132.908543 -280.566368) (xy 132.602732 -280.566368) (xy 132.602242 -280.591357)
			(xy 132.594423 -280.64072) (xy 132.578979 -280.688252) (xy 132.556289 -280.732784) (xy 132.526913 -280.773217)
			(xy 132.491573 -280.808557) (xy 132.45114 -280.837933) (xy 132.406608 -280.860623) (xy 132.359076 -280.876067)
			(xy 132.309713 -280.883886) (xy 132.259735 -280.883886) (xy 132.210372 -280.876067) (xy 132.16284 -280.860623)
			(xy 132.118308 -280.837933) (xy 132.077875 -280.808557) (xy 132.042535 -280.773217) (xy 132.013159 -280.732784)
			(xy 131.990469 -280.688252) (xy 131.975025 -280.64072) (xy 131.967206 -280.591357) (xy 131.659889 -280.591357)
			(xy 131.65988 -280.591814) (xy 131.651716 -280.642048) (xy 131.6356 -280.690322) (xy 131.611949 -280.735385)
			(xy 131.581376 -280.776071) (xy 131.544672 -280.811326) (xy 131.502788 -280.840236) (xy 131.456809 -280.862053)
			(xy 131.407925 -280.876213) (xy 131.357404 -280.882347) (xy 131.306552 -280.880298) (xy 131.256688 -280.870118)
			(xy 131.209102 -280.852071) (xy 131.165028 -280.826625) (xy 131.125606 -280.794438) (xy 131.091858 -280.756344)
			(xy 131.064657 -280.71333) (xy 131.044709 -280.66651) (xy 131.03253 -280.617096) (xy 131.028435 -280.566368)
			(xy 129.780538 -280.566368) (xy 129.780026 -280.591814) (xy 129.771862 -280.642048) (xy 129.755746 -280.690322)
			(xy 129.732095 -280.735385) (xy 129.701522 -280.776071) (xy 129.664818 -280.811326) (xy 129.622934 -280.840236)
			(xy 129.576955 -280.862053) (xy 129.528071 -280.876213) (xy 129.47755 -280.882347) (xy 129.426698 -280.880298)
			(xy 129.376834 -280.870118) (xy 129.329248 -280.852071) (xy 129.285174 -280.826625) (xy 129.245752 -280.794438)
			(xy 129.212004 -280.756344) (xy 129.184803 -280.71333) (xy 129.164855 -280.66651) (xy 129.152676 -280.617096)
			(xy 129.148581 -280.566368) (xy 128.840484 -280.566368) (xy 128.839972 -280.591814) (xy 128.831808 -280.642048)
			(xy 128.815692 -280.690322) (xy 128.792041 -280.735385) (xy 128.761468 -280.776071) (xy 128.724764 -280.811326)
			(xy 128.68288 -280.840236) (xy 128.636901 -280.862053) (xy 128.588017 -280.876213) (xy 128.537496 -280.882347)
			(xy 128.486644 -280.880298) (xy 128.43678 -280.870118) (xy 128.389194 -280.852071) (xy 128.34512 -280.826625)
			(xy 128.305698 -280.794438) (xy 128.27195 -280.756344) (xy 128.244749 -280.71333) (xy 128.224801 -280.66651)
			(xy 128.212622 -280.617096) (xy 128.208527 -280.566368) (xy 127.902716 -280.566368) (xy 127.902226 -280.591357)
			(xy 127.894407 -280.64072) (xy 127.878963 -280.688252) (xy 127.856273 -280.732784) (xy 127.826897 -280.773217)
			(xy 127.791557 -280.808557) (xy 127.751124 -280.837933) (xy 127.706592 -280.860623) (xy 127.65906 -280.876067)
			(xy 127.609697 -280.883886) (xy 127.559719 -280.883886) (xy 127.510356 -280.876067) (xy 127.462824 -280.860623)
			(xy 127.418292 -280.837933) (xy 127.377859 -280.808557) (xy 127.342519 -280.773217) (xy 127.313143 -280.732784)
			(xy 127.290453 -280.688252) (xy 127.275009 -280.64072) (xy 127.26719 -280.591357) (xy 126.962244 -280.591357)
			(xy 126.962244 -280.592492) (xy 126.953718 -280.64401) (xy 126.93689 -280.693443) (xy 126.912215 -280.739464)
			(xy 126.880353 -280.780836) (xy 126.842162 -280.816448) (xy 126.820676 -280.83129) (xy 126.815342 -280.834846)
			(xy 126.810516 -280.84018) (xy 126.804166 -280.848816) (xy 126.793244 -280.86812) (xy 126.790123 -280.873938)
			(xy 126.786646 -280.886669) (xy 126.786386 -280.893266) (xy 126.786386 -281.029156) (xy 126.787389 -281.038172)
			(xy 126.794848 -281.054697) (xy 126.807554 -281.06763) (xy 126.815596 -281.071828) (xy 126.889256 -281.111706)
			(xy 126.894884 -281.114532) (xy 126.907091 -281.117619) (xy 126.913386 -281.117802) (xy 126.921514 -281.117802)
			(xy 126.935484 -281.113738) (xy 126.942596 -281.108912) (xy 126.961928 -281.096965) (xy 127.003259 -281.078076)
			(xy 127.046856 -281.065254) (xy 127.091833 -281.058759) (xy 127.114554 -281.058366) (xy 127.121412 -281.058366)
			(xy 127.146064 -281.059336) (xy 127.194641 -281.067952) (xy 127.241304 -281.083966) (xy 127.284934 -281.106994)
			(xy 127.324484 -281.136484) (xy 127.359005 -281.171728) (xy 127.38767 -281.21188) (xy 127.40979 -281.255978)
			(xy 127.424834 -281.302962) (xy 127.432441 -281.351707) (xy 127.432816 -281.376374) (xy 127.738627 -281.376374)
			(xy 127.742722 -281.325646) (xy 127.754901 -281.276232) (xy 127.774849 -281.229412) (xy 127.80205 -281.186398)
			(xy 127.835798 -281.148304) (xy 127.87522 -281.116117) (xy 127.919294 -281.090671) (xy 127.96688 -281.072624)
			(xy 128.016744 -281.062444) (xy 128.067596 -281.060395) (xy 128.118117 -281.066529) (xy 128.167001 -281.080689)
			(xy 128.21298 -281.102506) (xy 128.254864 -281.131416) (xy 128.291568 -281.166671) (xy 128.322141 -281.207357)
			(xy 128.345792 -281.25242) (xy 128.361908 -281.300694) (xy 128.370072 -281.350928) (xy 128.370584 -281.376374)
			(xy 128.370081 -281.401363) (xy 128.677144 -281.401363) (xy 128.677144 -281.351385) (xy 128.684963 -281.302022)
			(xy 128.700407 -281.25449) (xy 128.723097 -281.209958) (xy 128.752473 -281.169525) (xy 128.787813 -281.134185)
			(xy 128.828246 -281.104809) (xy 128.872778 -281.082119) (xy 128.92031 -281.066675) (xy 128.969673 -281.058856)
			(xy 129.019651 -281.058856) (xy 129.069014 -281.066675) (xy 129.116546 -281.082119) (xy 129.161078 -281.104809)
			(xy 129.201511 -281.134185) (xy 129.236851 -281.169525) (xy 129.266227 -281.209958) (xy 129.288917 -281.25449)
			(xy 129.304361 -281.302022) (xy 129.31218 -281.351385) (xy 129.31267 -281.376374) (xy 129.618481 -281.376374)
			(xy 129.622576 -281.325646) (xy 129.634755 -281.276232) (xy 129.654703 -281.229412) (xy 129.681904 -281.186398)
			(xy 129.715652 -281.148304) (xy 129.755074 -281.116117) (xy 129.799148 -281.090671) (xy 129.846734 -281.072624)
			(xy 129.896598 -281.062444) (xy 129.94745 -281.060395) (xy 129.997971 -281.066529) (xy 130.046855 -281.080689)
			(xy 130.092834 -281.102506) (xy 130.134718 -281.131416) (xy 130.171422 -281.166671) (xy 130.201995 -281.207357)
			(xy 130.225646 -281.25242) (xy 130.241762 -281.300694) (xy 130.249926 -281.350928) (xy 130.250438 -281.376374)
			(xy 130.249935 -281.401363) (xy 130.557252 -281.401363) (xy 130.557252 -281.351385) (xy 130.565071 -281.302022)
			(xy 130.580515 -281.25449) (xy 130.603205 -281.209958) (xy 130.632581 -281.169525) (xy 130.667921 -281.134185)
			(xy 130.708354 -281.104809) (xy 130.752886 -281.082119) (xy 130.800418 -281.066675) (xy 130.849781 -281.058856)
			(xy 130.899759 -281.058856) (xy 130.949122 -281.066675) (xy 130.996654 -281.082119) (xy 131.041186 -281.104809)
			(xy 131.081619 -281.134185) (xy 131.116959 -281.169525) (xy 131.146335 -281.209958) (xy 131.169025 -281.25449)
			(xy 131.184469 -281.302022) (xy 131.192288 -281.351385) (xy 131.192778 -281.376374) (xy 131.498589 -281.376374)
			(xy 131.502684 -281.325646) (xy 131.514863 -281.276232) (xy 131.534811 -281.229412) (xy 131.562012 -281.186398)
			(xy 131.59576 -281.148304) (xy 131.635182 -281.116117) (xy 131.679256 -281.090671) (xy 131.726842 -281.072624)
			(xy 131.776706 -281.062444) (xy 131.827558 -281.060395) (xy 131.878079 -281.066529) (xy 131.926963 -281.080689)
			(xy 131.972942 -281.102506) (xy 132.014826 -281.131416) (xy 132.05153 -281.166671) (xy 132.082103 -281.207357)
			(xy 132.105754 -281.25242) (xy 132.12187 -281.300694) (xy 132.130034 -281.350928) (xy 132.130546 -281.376374)
			(xy 132.438643 -281.376374) (xy 132.442738 -281.325646) (xy 132.454917 -281.276232) (xy 132.474865 -281.229412)
			(xy 132.502066 -281.186398) (xy 132.535814 -281.148304) (xy 132.575236 -281.116117) (xy 132.61931 -281.090671)
			(xy 132.666896 -281.072624) (xy 132.71676 -281.062444) (xy 132.767612 -281.060395) (xy 132.818133 -281.066529)
			(xy 132.867017 -281.080689) (xy 132.912996 -281.102506) (xy 132.95488 -281.131416) (xy 132.991584 -281.166671)
			(xy 133.022157 -281.207357) (xy 133.045808 -281.25242) (xy 133.061924 -281.300694) (xy 133.070088 -281.350928)
			(xy 133.0706 -281.376374) (xy 133.070097 -281.401363) (xy 133.37716 -281.401363) (xy 133.37716 -281.351385)
			(xy 133.384979 -281.302022) (xy 133.400423 -281.25449) (xy 133.423113 -281.209958) (xy 133.452489 -281.169525)
			(xy 133.487829 -281.134185) (xy 133.528262 -281.104809) (xy 133.572794 -281.082119) (xy 133.620326 -281.066675)
			(xy 133.669689 -281.058856) (xy 133.719667 -281.058856) (xy 133.76903 -281.066675) (xy 133.816562 -281.082119)
			(xy 133.861094 -281.104809) (xy 133.901527 -281.134185) (xy 133.936867 -281.169525) (xy 133.966243 -281.209958)
			(xy 133.988933 -281.25449) (xy 134.004377 -281.302022) (xy 134.012196 -281.351385) (xy 134.012686 -281.376374)
			(xy 134.318497 -281.376374) (xy 134.322592 -281.325646) (xy 134.334771 -281.276232) (xy 134.354719 -281.229412)
			(xy 134.38192 -281.186398) (xy 134.415668 -281.148304) (xy 134.45509 -281.116117) (xy 134.499164 -281.090671)
			(xy 134.54675 -281.072624) (xy 134.596614 -281.062444) (xy 134.647466 -281.060395) (xy 134.697987 -281.066529)
			(xy 134.746871 -281.080689) (xy 134.79285 -281.102506) (xy 134.834734 -281.131416) (xy 134.871438 -281.166671)
			(xy 134.902011 -281.207357) (xy 134.925662 -281.25242) (xy 134.941778 -281.300694) (xy 134.949942 -281.350928)
			(xy 134.950454 -281.376374) (xy 134.949951 -281.401363) (xy 135.257268 -281.401363) (xy 135.257268 -281.351385)
			(xy 135.265087 -281.302022) (xy 135.280531 -281.25449) (xy 135.303221 -281.209958) (xy 135.332597 -281.169525)
			(xy 135.367937 -281.134185) (xy 135.40837 -281.104809) (xy 135.452902 -281.082119) (xy 135.500434 -281.066675)
			(xy 135.549797 -281.058856) (xy 135.599775 -281.058856) (xy 135.649138 -281.066675) (xy 135.69667 -281.082119)
			(xy 135.741202 -281.104809) (xy 135.781635 -281.134185) (xy 135.816975 -281.169525) (xy 135.846351 -281.209958)
			(xy 135.869041 -281.25449) (xy 135.884485 -281.302022) (xy 135.892304 -281.351385) (xy 135.892794 -281.376374)
			(xy 136.198605 -281.376374) (xy 136.2027 -281.325646) (xy 136.214879 -281.276232) (xy 136.234827 -281.229412)
			(xy 136.262028 -281.186398) (xy 136.295776 -281.148304) (xy 136.335198 -281.116117) (xy 136.379272 -281.090671)
			(xy 136.426858 -281.072624) (xy 136.476722 -281.062444) (xy 136.527574 -281.060395) (xy 136.578095 -281.066529)
			(xy 136.626979 -281.080689) (xy 136.672958 -281.102506) (xy 136.714842 -281.131416) (xy 136.751546 -281.166671)
			(xy 136.782119 -281.207357) (xy 136.80577 -281.25242) (xy 136.821886 -281.300694) (xy 136.83005 -281.350928)
			(xy 136.830562 -281.376374) (xy 136.830059 -281.401363) (xy 137.137122 -281.401363) (xy 137.137122 -281.351385)
			(xy 137.144941 -281.302022) (xy 137.160385 -281.25449) (xy 137.183075 -281.209958) (xy 137.212451 -281.169525)
			(xy 137.247791 -281.134185) (xy 137.288224 -281.104809) (xy 137.332756 -281.082119) (xy 137.380288 -281.066675)
			(xy 137.429651 -281.058856) (xy 137.479629 -281.058856) (xy 137.528992 -281.066675) (xy 137.576524 -281.082119)
			(xy 137.621056 -281.104809) (xy 137.661489 -281.134185) (xy 137.696829 -281.169525) (xy 137.726205 -281.209958)
			(xy 137.748895 -281.25449) (xy 137.764339 -281.302022) (xy 137.772158 -281.351385) (xy 137.772648 -281.376374)
			(xy 138.078459 -281.376374) (xy 138.082554 -281.325646) (xy 138.094733 -281.276232) (xy 138.114681 -281.229412)
			(xy 138.141882 -281.186398) (xy 138.17563 -281.148304) (xy 138.215052 -281.116117) (xy 138.259126 -281.090671)
			(xy 138.306712 -281.072624) (xy 138.356576 -281.062444) (xy 138.407428 -281.060395) (xy 138.457949 -281.066529)
			(xy 138.506833 -281.080689) (xy 138.552812 -281.102506) (xy 138.594696 -281.131416) (xy 138.6314 -281.166671)
			(xy 138.661973 -281.207357) (xy 138.685624 -281.25242) (xy 138.70174 -281.300694) (xy 138.709904 -281.350928)
			(xy 138.710416 -281.376374) (xy 139.018513 -281.376374) (xy 139.022608 -281.325646) (xy 139.034787 -281.276232)
			(xy 139.054735 -281.229412) (xy 139.081936 -281.186398) (xy 139.115684 -281.148304) (xy 139.155106 -281.116117)
			(xy 139.19918 -281.090671) (xy 139.246766 -281.072624) (xy 139.29663 -281.062444) (xy 139.347482 -281.060395)
			(xy 139.398003 -281.066529) (xy 139.446887 -281.080689) (xy 139.492866 -281.102506) (xy 139.53475 -281.131416)
			(xy 139.571454 -281.166671) (xy 139.602027 -281.207357) (xy 139.625678 -281.25242) (xy 139.641794 -281.300694)
			(xy 139.649958 -281.350928) (xy 139.65047 -281.376374) (xy 139.649967 -281.401363) (xy 139.957284 -281.401363)
			(xy 139.957284 -281.351385) (xy 139.965103 -281.302022) (xy 139.980547 -281.25449) (xy 140.003237 -281.209958)
			(xy 140.032613 -281.169525) (xy 140.067953 -281.134185) (xy 140.108386 -281.104809) (xy 140.152918 -281.082119)
			(xy 140.20045 -281.066675) (xy 140.249813 -281.058856) (xy 140.299791 -281.058856) (xy 140.349154 -281.066675)
			(xy 140.396686 -281.082119) (xy 140.441218 -281.104809) (xy 140.481651 -281.134185) (xy 140.516991 -281.169525)
			(xy 140.546367 -281.209958) (xy 140.569057 -281.25449) (xy 140.584501 -281.302022) (xy 140.59232 -281.351385)
			(xy 140.59281 -281.376374) (xy 140.898621 -281.376374) (xy 140.902716 -281.325646) (xy 140.914895 -281.276232)
			(xy 140.934843 -281.229412) (xy 140.962044 -281.186398) (xy 140.995792 -281.148304) (xy 141.035214 -281.116117)
			(xy 141.079288 -281.090671) (xy 141.126874 -281.072624) (xy 141.176738 -281.062444) (xy 141.22759 -281.060395)
			(xy 141.278111 -281.066529) (xy 141.326995 -281.080689) (xy 141.372974 -281.102506) (xy 141.414858 -281.131416)
			(xy 141.451562 -281.166671) (xy 141.482135 -281.207357) (xy 141.505786 -281.25242) (xy 141.521902 -281.300694)
			(xy 141.530066 -281.350928) (xy 141.530578 -281.376374) (xy 141.530075 -281.401363) (xy 141.837138 -281.401363)
			(xy 141.837138 -281.351385) (xy 141.844957 -281.302022) (xy 141.860401 -281.25449) (xy 141.883091 -281.209958)
			(xy 141.912467 -281.169525) (xy 141.947807 -281.134185) (xy 141.98824 -281.104809) (xy 142.032772 -281.082119)
			(xy 142.080304 -281.066675) (xy 142.129667 -281.058856) (xy 142.179645 -281.058856) (xy 142.229008 -281.066675)
			(xy 142.27654 -281.082119) (xy 142.321072 -281.104809) (xy 142.361505 -281.134185) (xy 142.396845 -281.169525)
			(xy 142.426221 -281.209958) (xy 142.448911 -281.25449) (xy 142.464355 -281.302022) (xy 142.472174 -281.351385)
			(xy 142.472664 -281.376374) (xy 142.778475 -281.376374) (xy 142.78257 -281.325646) (xy 142.794749 -281.276232)
			(xy 142.814697 -281.229412) (xy 142.841898 -281.186398) (xy 142.875646 -281.148304) (xy 142.915068 -281.116117)
			(xy 142.959142 -281.090671) (xy 143.006728 -281.072624) (xy 143.056592 -281.062444) (xy 143.107444 -281.060395)
			(xy 143.157965 -281.066529) (xy 143.206849 -281.080689) (xy 143.252828 -281.102506) (xy 143.294712 -281.131416)
			(xy 143.331416 -281.166671) (xy 143.361989 -281.207357) (xy 143.38564 -281.25242) (xy 143.401756 -281.300694)
			(xy 143.40992 -281.350928) (xy 143.410432 -281.376374) (xy 143.409929 -281.401363) (xy 143.717246 -281.401363)
			(xy 143.717246 -281.351385) (xy 143.725065 -281.302022) (xy 143.740509 -281.25449) (xy 143.763199 -281.209958)
			(xy 143.792575 -281.169525) (xy 143.827915 -281.134185) (xy 143.868348 -281.104809) (xy 143.91288 -281.082119)
			(xy 143.960412 -281.066675) (xy 144.009775 -281.058856) (xy 144.059753 -281.058856) (xy 144.109116 -281.066675)
			(xy 144.156648 -281.082119) (xy 144.20118 -281.104809) (xy 144.241613 -281.134185) (xy 144.276953 -281.169525)
			(xy 144.306329 -281.209958) (xy 144.329019 -281.25449) (xy 144.344463 -281.302022) (xy 144.352282 -281.351385)
			(xy 144.352772 -281.376374) (xy 144.352282 -281.401363) (xy 144.344463 -281.450726) (xy 144.329019 -281.498258)
			(xy 144.306329 -281.54279) (xy 144.276953 -281.583223) (xy 144.241613 -281.618563) (xy 144.20118 -281.647939)
			(xy 144.156648 -281.670629) (xy 144.109116 -281.686073) (xy 144.059753 -281.693892) (xy 144.009775 -281.693892)
			(xy 143.960412 -281.686073) (xy 143.91288 -281.670629) (xy 143.868348 -281.647939) (xy 143.827915 -281.618563)
			(xy 143.792575 -281.583223) (xy 143.763199 -281.54279) (xy 143.740509 -281.498258) (xy 143.725065 -281.450726)
			(xy 143.717246 -281.401363) (xy 143.409929 -281.401363) (xy 143.40992 -281.40182) (xy 143.401756 -281.452054)
			(xy 143.38564 -281.500328) (xy 143.361989 -281.545391) (xy 143.331416 -281.586077) (xy 143.294712 -281.621332)
			(xy 143.252828 -281.650242) (xy 143.206849 -281.672059) (xy 143.157965 -281.686219) (xy 143.107444 -281.692353)
			(xy 143.056592 -281.690304) (xy 143.006728 -281.680124) (xy 142.959142 -281.662077) (xy 142.915068 -281.636631)
			(xy 142.875646 -281.604444) (xy 142.841898 -281.56635) (xy 142.814697 -281.523336) (xy 142.794749 -281.476516)
			(xy 142.78257 -281.427102) (xy 142.778475 -281.376374) (xy 142.472664 -281.376374) (xy 142.472174 -281.401363)
			(xy 142.464355 -281.450726) (xy 142.448911 -281.498258) (xy 142.426221 -281.54279) (xy 142.396845 -281.583223)
			(xy 142.361505 -281.618563) (xy 142.321072 -281.647939) (xy 142.27654 -281.670629) (xy 142.229008 -281.686073)
			(xy 142.179645 -281.693892) (xy 142.129667 -281.693892) (xy 142.080304 -281.686073) (xy 142.032772 -281.670629)
			(xy 141.98824 -281.647939) (xy 141.947807 -281.618563) (xy 141.912467 -281.583223) (xy 141.883091 -281.54279)
			(xy 141.860401 -281.498258) (xy 141.844957 -281.450726) (xy 141.837138 -281.401363) (xy 141.530075 -281.401363)
			(xy 141.530066 -281.40182) (xy 141.521902 -281.452054) (xy 141.505786 -281.500328) (xy 141.482135 -281.545391)
			(xy 141.451562 -281.586077) (xy 141.414858 -281.621332) (xy 141.372974 -281.650242) (xy 141.326995 -281.672059)
			(xy 141.278111 -281.686219) (xy 141.22759 -281.692353) (xy 141.176738 -281.690304) (xy 141.126874 -281.680124)
			(xy 141.079288 -281.662077) (xy 141.035214 -281.636631) (xy 140.995792 -281.604444) (xy 140.962044 -281.56635)
			(xy 140.934843 -281.523336) (xy 140.914895 -281.476516) (xy 140.902716 -281.427102) (xy 140.898621 -281.376374)
			(xy 140.59281 -281.376374) (xy 140.59232 -281.401363) (xy 140.584501 -281.450726) (xy 140.569057 -281.498258)
			(xy 140.546367 -281.54279) (xy 140.516991 -281.583223) (xy 140.481651 -281.618563) (xy 140.441218 -281.647939)
			(xy 140.396686 -281.670629) (xy 140.349154 -281.686073) (xy 140.299791 -281.693892) (xy 140.249813 -281.693892)
			(xy 140.20045 -281.686073) (xy 140.152918 -281.670629) (xy 140.108386 -281.647939) (xy 140.067953 -281.618563)
			(xy 140.032613 -281.583223) (xy 140.003237 -281.54279) (xy 139.980547 -281.498258) (xy 139.965103 -281.450726)
			(xy 139.957284 -281.401363) (xy 139.649967 -281.401363) (xy 139.649958 -281.40182) (xy 139.641794 -281.452054)
			(xy 139.625678 -281.500328) (xy 139.602027 -281.545391) (xy 139.571454 -281.586077) (xy 139.53475 -281.621332)
			(xy 139.492866 -281.650242) (xy 139.446887 -281.672059) (xy 139.398003 -281.686219) (xy 139.347482 -281.692353)
			(xy 139.29663 -281.690304) (xy 139.246766 -281.680124) (xy 139.19918 -281.662077) (xy 139.155106 -281.636631)
			(xy 139.115684 -281.604444) (xy 139.081936 -281.56635) (xy 139.054735 -281.523336) (xy 139.034787 -281.476516)
			(xy 139.022608 -281.427102) (xy 139.018513 -281.376374) (xy 138.710416 -281.376374) (xy 138.709904 -281.40182)
			(xy 138.70174 -281.452054) (xy 138.685624 -281.500328) (xy 138.661973 -281.545391) (xy 138.6314 -281.586077)
			(xy 138.594696 -281.621332) (xy 138.552812 -281.650242) (xy 138.506833 -281.672059) (xy 138.457949 -281.686219)
			(xy 138.407428 -281.692353) (xy 138.356576 -281.690304) (xy 138.306712 -281.680124) (xy 138.259126 -281.662077)
			(xy 138.215052 -281.636631) (xy 138.17563 -281.604444) (xy 138.141882 -281.56635) (xy 138.114681 -281.523336)
			(xy 138.094733 -281.476516) (xy 138.082554 -281.427102) (xy 138.078459 -281.376374) (xy 137.772648 -281.376374)
			(xy 137.772158 -281.401363) (xy 137.764339 -281.450726) (xy 137.748895 -281.498258) (xy 137.726205 -281.54279)
			(xy 137.696829 -281.583223) (xy 137.661489 -281.618563) (xy 137.621056 -281.647939) (xy 137.576524 -281.670629)
			(xy 137.528992 -281.686073) (xy 137.479629 -281.693892) (xy 137.429651 -281.693892) (xy 137.380288 -281.686073)
			(xy 137.332756 -281.670629) (xy 137.288224 -281.647939) (xy 137.247791 -281.618563) (xy 137.212451 -281.583223)
			(xy 137.183075 -281.54279) (xy 137.160385 -281.498258) (xy 137.144941 -281.450726) (xy 137.137122 -281.401363)
			(xy 136.830059 -281.401363) (xy 136.83005 -281.40182) (xy 136.821886 -281.452054) (xy 136.80577 -281.500328)
			(xy 136.782119 -281.545391) (xy 136.751546 -281.586077) (xy 136.714842 -281.621332) (xy 136.672958 -281.650242)
			(xy 136.626979 -281.672059) (xy 136.578095 -281.686219) (xy 136.527574 -281.692353) (xy 136.476722 -281.690304)
			(xy 136.426858 -281.680124) (xy 136.379272 -281.662077) (xy 136.335198 -281.636631) (xy 136.295776 -281.604444)
			(xy 136.262028 -281.56635) (xy 136.234827 -281.523336) (xy 136.214879 -281.476516) (xy 136.2027 -281.427102)
			(xy 136.198605 -281.376374) (xy 135.892794 -281.376374) (xy 135.892304 -281.401363) (xy 135.884485 -281.450726)
			(xy 135.869041 -281.498258) (xy 135.846351 -281.54279) (xy 135.816975 -281.583223) (xy 135.781635 -281.618563)
			(xy 135.741202 -281.647939) (xy 135.69667 -281.670629) (xy 135.649138 -281.686073) (xy 135.599775 -281.693892)
			(xy 135.549797 -281.693892) (xy 135.500434 -281.686073) (xy 135.452902 -281.670629) (xy 135.40837 -281.647939)
			(xy 135.367937 -281.618563) (xy 135.332597 -281.583223) (xy 135.303221 -281.54279) (xy 135.280531 -281.498258)
			(xy 135.265087 -281.450726) (xy 135.257268 -281.401363) (xy 134.949951 -281.401363) (xy 134.949942 -281.40182)
			(xy 134.941778 -281.452054) (xy 134.925662 -281.500328) (xy 134.902011 -281.545391) (xy 134.871438 -281.586077)
			(xy 134.834734 -281.621332) (xy 134.79285 -281.650242) (xy 134.746871 -281.672059) (xy 134.697987 -281.686219)
			(xy 134.647466 -281.692353) (xy 134.596614 -281.690304) (xy 134.54675 -281.680124) (xy 134.499164 -281.662077)
			(xy 134.45509 -281.636631) (xy 134.415668 -281.604444) (xy 134.38192 -281.56635) (xy 134.354719 -281.523336)
			(xy 134.334771 -281.476516) (xy 134.322592 -281.427102) (xy 134.318497 -281.376374) (xy 134.012686 -281.376374)
			(xy 134.012196 -281.401363) (xy 134.004377 -281.450726) (xy 133.988933 -281.498258) (xy 133.966243 -281.54279)
			(xy 133.936867 -281.583223) (xy 133.901527 -281.618563) (xy 133.861094 -281.647939) (xy 133.816562 -281.670629)
			(xy 133.76903 -281.686073) (xy 133.719667 -281.693892) (xy 133.669689 -281.693892) (xy 133.620326 -281.686073)
			(xy 133.572794 -281.670629) (xy 133.528262 -281.647939) (xy 133.487829 -281.618563) (xy 133.452489 -281.583223)
			(xy 133.423113 -281.54279) (xy 133.400423 -281.498258) (xy 133.384979 -281.450726) (xy 133.37716 -281.401363)
			(xy 133.070097 -281.401363) (xy 133.070088 -281.40182) (xy 133.061924 -281.452054) (xy 133.045808 -281.500328)
			(xy 133.022157 -281.545391) (xy 132.991584 -281.586077) (xy 132.95488 -281.621332) (xy 132.912996 -281.650242)
			(xy 132.867017 -281.672059) (xy 132.818133 -281.686219) (xy 132.767612 -281.692353) (xy 132.71676 -281.690304)
			(xy 132.666896 -281.680124) (xy 132.61931 -281.662077) (xy 132.575236 -281.636631) (xy 132.535814 -281.604444)
			(xy 132.502066 -281.56635) (xy 132.474865 -281.523336) (xy 132.454917 -281.476516) (xy 132.442738 -281.427102)
			(xy 132.438643 -281.376374) (xy 132.130546 -281.376374) (xy 132.130034 -281.40182) (xy 132.12187 -281.452054)
			(xy 132.105754 -281.500328) (xy 132.082103 -281.545391) (xy 132.05153 -281.586077) (xy 132.014826 -281.621332)
			(xy 131.972942 -281.650242) (xy 131.926963 -281.672059) (xy 131.878079 -281.686219) (xy 131.827558 -281.692353)
			(xy 131.776706 -281.690304) (xy 131.726842 -281.680124) (xy 131.679256 -281.662077) (xy 131.635182 -281.636631)
			(xy 131.59576 -281.604444) (xy 131.562012 -281.56635) (xy 131.534811 -281.523336) (xy 131.514863 -281.476516)
			(xy 131.502684 -281.427102) (xy 131.498589 -281.376374) (xy 131.192778 -281.376374) (xy 131.192288 -281.401363)
			(xy 131.184469 -281.450726) (xy 131.169025 -281.498258) (xy 131.146335 -281.54279) (xy 131.116959 -281.583223)
			(xy 131.081619 -281.618563) (xy 131.041186 -281.647939) (xy 130.996654 -281.670629) (xy 130.949122 -281.686073)
			(xy 130.899759 -281.693892) (xy 130.849781 -281.693892) (xy 130.800418 -281.686073) (xy 130.752886 -281.670629)
			(xy 130.708354 -281.647939) (xy 130.667921 -281.618563) (xy 130.632581 -281.583223) (xy 130.603205 -281.54279)
			(xy 130.580515 -281.498258) (xy 130.565071 -281.450726) (xy 130.557252 -281.401363) (xy 130.249935 -281.401363)
			(xy 130.249926 -281.40182) (xy 130.241762 -281.452054) (xy 130.225646 -281.500328) (xy 130.201995 -281.545391)
			(xy 130.171422 -281.586077) (xy 130.134718 -281.621332) (xy 130.092834 -281.650242) (xy 130.046855 -281.672059)
			(xy 129.997971 -281.686219) (xy 129.94745 -281.692353) (xy 129.896598 -281.690304) (xy 129.846734 -281.680124)
			(xy 129.799148 -281.662077) (xy 129.755074 -281.636631) (xy 129.715652 -281.604444) (xy 129.681904 -281.56635)
			(xy 129.654703 -281.523336) (xy 129.634755 -281.476516) (xy 129.622576 -281.427102) (xy 129.618481 -281.376374)
			(xy 129.31267 -281.376374) (xy 129.31218 -281.401363) (xy 129.304361 -281.450726) (xy 129.288917 -281.498258)
			(xy 129.266227 -281.54279) (xy 129.236851 -281.583223) (xy 129.201511 -281.618563) (xy 129.161078 -281.647939)
			(xy 129.116546 -281.670629) (xy 129.069014 -281.686073) (xy 129.019651 -281.693892) (xy 128.969673 -281.693892)
			(xy 128.92031 -281.686073) (xy 128.872778 -281.670629) (xy 128.828246 -281.647939) (xy 128.787813 -281.618563)
			(xy 128.752473 -281.583223) (xy 128.723097 -281.54279) (xy 128.700407 -281.498258) (xy 128.684963 -281.450726)
			(xy 128.677144 -281.401363) (xy 128.370081 -281.401363) (xy 128.370072 -281.40182) (xy 128.361908 -281.452054)
			(xy 128.345792 -281.500328) (xy 128.322141 -281.545391) (xy 128.291568 -281.586077) (xy 128.254864 -281.621332)
			(xy 128.21298 -281.650242) (xy 128.167001 -281.672059) (xy 128.118117 -281.686219) (xy 128.067596 -281.692353)
			(xy 128.016744 -281.690304) (xy 127.96688 -281.680124) (xy 127.919294 -281.662077) (xy 127.87522 -281.636631)
			(xy 127.835798 -281.604444) (xy 127.80205 -281.56635) (xy 127.774849 -281.523336) (xy 127.754901 -281.476516)
			(xy 127.742722 -281.427102) (xy 127.738627 -281.376374) (xy 127.432816 -281.376374) (xy 127.432336 -281.401263)
			(xy 127.424584 -281.450435) (xy 127.409265 -281.497797) (xy 127.386754 -281.542195) (xy 127.3576 -281.582543)
			(xy 127.322516 -281.617856) (xy 127.282358 -281.647271) (xy 127.238108 -281.67007) (xy 127.190846 -281.685696)
			(xy 127.141726 -281.693767) (xy 127.11684 -281.694382) (xy 127.114554 -281.694382) (xy 127.085147 -281.693683)
			(xy 127.027341 -281.682839) (xy 126.972508 -281.661566) (xy 126.947168 -281.64663) (xy 126.94158 -281.643328)
			(xy 126.92634 -281.638502) (xy 126.916557 -281.636112) (xy 126.896548 -281.638193) (xy 126.887478 -281.642566)
			(xy 126.813056 -281.682444) (xy 126.805325 -281.687013) (xy 126.793432 -281.700453) (xy 126.786897 -281.717167)
			(xy 126.786386 -281.726132) (xy 126.786386 -281.858974) (xy 126.787148 -281.86761) (xy 126.787148 -281.868118)
			(xy 126.788043 -281.872243) (xy 126.790982 -281.880154) (xy 126.79299 -281.883866) (xy 126.803912 -281.903424)
			(xy 126.805944 -281.906726) (xy 126.820422 -281.921204) (xy 126.821184 -281.921712) (xy 126.824232 -281.923744)
			(xy 126.8349 -281.931364) (xy 126.855456 -281.947353) (xy 126.891566 -281.984876) (xy 126.921091 -282.027773)
			(xy 126.943243 -282.074902) (xy 126.957434 -282.125006) (xy 126.960884 -282.15082) (xy 126.962662 -282.17749)
			(xy 126.962662 -282.18638) (xy 128.208527 -282.18638) (xy 128.212622 -282.135652) (xy 128.224801 -282.086238)
			(xy 128.244749 -282.039418) (xy 128.27195 -281.996404) (xy 128.305698 -281.95831) (xy 128.34512 -281.926123)
			(xy 128.389194 -281.900677) (xy 128.43678 -281.88263) (xy 128.486644 -281.87245) (xy 128.537496 -281.870401)
			(xy 128.588017 -281.876535) (xy 128.636901 -281.890695) (xy 128.68288 -281.912512) (xy 128.724764 -281.941422)
			(xy 128.761468 -281.976677) (xy 128.792041 -282.017363) (xy 128.815692 -282.062426) (xy 128.831808 -282.1107)
			(xy 128.839972 -282.160934) (xy 128.840484 -282.18638) (xy 129.148581 -282.18638) (xy 129.152676 -282.135652)
			(xy 129.164855 -282.086238) (xy 129.184803 -282.039418) (xy 129.212004 -281.996404) (xy 129.245752 -281.95831)
			(xy 129.285174 -281.926123) (xy 129.329248 -281.900677) (xy 129.376834 -281.88263) (xy 129.426698 -281.87245)
			(xy 129.47755 -281.870401) (xy 129.528071 -281.876535) (xy 129.576955 -281.890695) (xy 129.622934 -281.912512)
			(xy 129.664818 -281.941422) (xy 129.701522 -281.976677) (xy 129.732095 -282.017363) (xy 129.755746 -282.062426)
			(xy 129.771862 -282.1107) (xy 129.780026 -282.160934) (xy 129.780538 -282.18638) (xy 129.780035 -282.211369)
			(xy 130.087352 -282.211369) (xy 130.087352 -282.161391) (xy 130.095171 -282.112028) (xy 130.110615 -282.064496)
			(xy 130.133305 -282.019964) (xy 130.162681 -281.979531) (xy 130.198021 -281.944191) (xy 130.238454 -281.914815)
			(xy 130.282986 -281.892125) (xy 130.330518 -281.876681) (xy 130.379881 -281.868862) (xy 130.429859 -281.868862)
			(xy 130.479222 -281.876681) (xy 130.526754 -281.892125) (xy 130.571286 -281.914815) (xy 130.611719 -281.944191)
			(xy 130.647059 -281.979531) (xy 130.676435 -282.019964) (xy 130.699125 -282.064496) (xy 130.714569 -282.112028)
			(xy 130.722388 -282.161391) (xy 130.722878 -282.18638) (xy 131.028435 -282.18638) (xy 131.03253 -282.135652)
			(xy 131.044709 -282.086238) (xy 131.064657 -282.039418) (xy 131.091858 -281.996404) (xy 131.125606 -281.95831)
			(xy 131.165028 -281.926123) (xy 131.209102 -281.900677) (xy 131.256688 -281.88263) (xy 131.306552 -281.87245)
			(xy 131.357404 -281.870401) (xy 131.407925 -281.876535) (xy 131.456809 -281.890695) (xy 131.502788 -281.912512)
			(xy 131.544672 -281.941422) (xy 131.581376 -281.976677) (xy 131.611949 -282.017363) (xy 131.6356 -282.062426)
			(xy 131.651716 -282.1107) (xy 131.65988 -282.160934) (xy 131.660392 -282.18638) (xy 131.659889 -282.211369)
			(xy 131.967206 -282.211369) (xy 131.967206 -282.161391) (xy 131.975025 -282.112028) (xy 131.990469 -282.064496)
			(xy 132.013159 -282.019964) (xy 132.042535 -281.979531) (xy 132.077875 -281.944191) (xy 132.118308 -281.914815)
			(xy 132.16284 -281.892125) (xy 132.210372 -281.876681) (xy 132.259735 -281.868862) (xy 132.309713 -281.868862)
			(xy 132.359076 -281.876681) (xy 132.406608 -281.892125) (xy 132.45114 -281.914815) (xy 132.491573 -281.944191)
			(xy 132.526913 -281.979531) (xy 132.556289 -282.019964) (xy 132.578979 -282.064496) (xy 132.594423 -282.112028)
			(xy 132.602242 -282.161391) (xy 132.602732 -282.18638) (xy 132.908543 -282.18638) (xy 132.912638 -282.135652)
			(xy 132.924817 -282.086238) (xy 132.944765 -282.039418) (xy 132.971966 -281.996404) (xy 133.005714 -281.95831)
			(xy 133.045136 -281.926123) (xy 133.08921 -281.900677) (xy 133.136796 -281.88263) (xy 133.18666 -281.87245)
			(xy 133.237512 -281.870401) (xy 133.288033 -281.876535) (xy 133.336917 -281.890695) (xy 133.382896 -281.912512)
			(xy 133.42478 -281.941422) (xy 133.461484 -281.976677) (xy 133.492057 -282.017363) (xy 133.515708 -282.062426)
			(xy 133.531824 -282.1107) (xy 133.539988 -282.160934) (xy 133.5405 -282.18638) (xy 133.539997 -282.211369)
			(xy 133.847314 -282.211369) (xy 133.847314 -282.161391) (xy 133.855133 -282.112028) (xy 133.870577 -282.064496)
			(xy 133.893267 -282.019964) (xy 133.922643 -281.979531) (xy 133.957983 -281.944191) (xy 133.998416 -281.914815)
			(xy 134.042948 -281.892125) (xy 134.09048 -281.876681) (xy 134.139843 -281.868862) (xy 134.189821 -281.868862)
			(xy 134.239184 -281.876681) (xy 134.286716 -281.892125) (xy 134.331248 -281.914815) (xy 134.371681 -281.944191)
			(xy 134.407021 -281.979531) (xy 134.436397 -282.019964) (xy 134.459087 -282.064496) (xy 134.474531 -282.112028)
			(xy 134.48235 -282.161391) (xy 134.48284 -282.18638) (xy 134.788397 -282.18638) (xy 134.792492 -282.135652)
			(xy 134.804671 -282.086238) (xy 134.824619 -282.039418) (xy 134.85182 -281.996404) (xy 134.885568 -281.95831)
			(xy 134.92499 -281.926123) (xy 134.969064 -281.900677) (xy 135.01665 -281.88263) (xy 135.066514 -281.87245)
			(xy 135.117366 -281.870401) (xy 135.167887 -281.876535) (xy 135.216771 -281.890695) (xy 135.26275 -281.912512)
			(xy 135.304634 -281.941422) (xy 135.341338 -281.976677) (xy 135.371911 -282.017363) (xy 135.395562 -282.062426)
			(xy 135.411678 -282.1107) (xy 135.419842 -282.160934) (xy 135.420354 -282.18638) (xy 135.728451 -282.18638)
			(xy 135.732546 -282.135652) (xy 135.744725 -282.086238) (xy 135.764673 -282.039418) (xy 135.791874 -281.996404)
			(xy 135.825622 -281.95831) (xy 135.865044 -281.926123) (xy 135.909118 -281.900677) (xy 135.956704 -281.88263)
			(xy 136.006568 -281.87245) (xy 136.05742 -281.870401) (xy 136.107941 -281.876535) (xy 136.156825 -281.890695)
			(xy 136.202804 -281.912512) (xy 136.244688 -281.941422) (xy 136.281392 -281.976677) (xy 136.311965 -282.017363)
			(xy 136.335616 -282.062426) (xy 136.351732 -282.1107) (xy 136.359896 -282.160934) (xy 136.360408 -282.18638)
			(xy 136.359905 -282.211369) (xy 136.667222 -282.211369) (xy 136.667222 -282.161391) (xy 136.675041 -282.112028)
			(xy 136.690485 -282.064496) (xy 136.713175 -282.019964) (xy 136.742551 -281.979531) (xy 136.777891 -281.944191)
			(xy 136.818324 -281.914815) (xy 136.862856 -281.892125) (xy 136.910388 -281.876681) (xy 136.959751 -281.868862)
			(xy 137.009729 -281.868862) (xy 137.059092 -281.876681) (xy 137.106624 -281.892125) (xy 137.151156 -281.914815)
			(xy 137.191589 -281.944191) (xy 137.226929 -281.979531) (xy 137.256305 -282.019964) (xy 137.278995 -282.064496)
			(xy 137.294439 -282.112028) (xy 137.302258 -282.161391) (xy 137.302748 -282.18638) (xy 137.608559 -282.18638)
			(xy 137.612654 -282.135652) (xy 137.624833 -282.086238) (xy 137.644781 -282.039418) (xy 137.671982 -281.996404)
			(xy 137.70573 -281.95831) (xy 137.745152 -281.926123) (xy 137.789226 -281.900677) (xy 137.836812 -281.88263)
			(xy 137.886676 -281.87245) (xy 137.937528 -281.870401) (xy 137.988049 -281.876535) (xy 138.036933 -281.890695)
			(xy 138.082912 -281.912512) (xy 138.124796 -281.941422) (xy 138.1615 -281.976677) (xy 138.192073 -282.017363)
			(xy 138.215724 -282.062426) (xy 138.23184 -282.1107) (xy 138.240004 -282.160934) (xy 138.240516 -282.18638)
			(xy 138.240013 -282.211369) (xy 138.54733 -282.211369) (xy 138.54733 -282.161391) (xy 138.555149 -282.112028)
			(xy 138.570593 -282.064496) (xy 138.593283 -282.019964) (xy 138.622659 -281.979531) (xy 138.657999 -281.944191)
			(xy 138.698432 -281.914815) (xy 138.742964 -281.892125) (xy 138.790496 -281.876681) (xy 138.839859 -281.868862)
			(xy 138.889837 -281.868862) (xy 138.9392 -281.876681) (xy 138.986732 -281.892125) (xy 139.031264 -281.914815)
			(xy 139.071697 -281.944191) (xy 139.107037 -281.979531) (xy 139.136413 -282.019964) (xy 139.159103 -282.064496)
			(xy 139.174547 -282.112028) (xy 139.182366 -282.161391) (xy 139.182856 -282.18638) (xy 139.488413 -282.18638)
			(xy 139.492508 -282.135652) (xy 139.504687 -282.086238) (xy 139.524635 -282.039418) (xy 139.551836 -281.996404)
			(xy 139.585584 -281.95831) (xy 139.625006 -281.926123) (xy 139.66908 -281.900677) (xy 139.716666 -281.88263)
			(xy 139.76653 -281.87245) (xy 139.817382 -281.870401) (xy 139.867903 -281.876535) (xy 139.916787 -281.890695)
			(xy 139.962766 -281.912512) (xy 140.00465 -281.941422) (xy 140.041354 -281.976677) (xy 140.071927 -282.017363)
			(xy 140.095578 -282.062426) (xy 140.111694 -282.1107) (xy 140.119858 -282.160934) (xy 140.12037 -282.18638)
			(xy 140.119867 -282.211369) (xy 140.427184 -282.211369) (xy 140.427184 -282.161391) (xy 140.435003 -282.112028)
			(xy 140.450447 -282.064496) (xy 140.473137 -282.019964) (xy 140.502513 -281.979531) (xy 140.537853 -281.944191)
			(xy 140.578286 -281.914815) (xy 140.622818 -281.892125) (xy 140.67035 -281.876681) (xy 140.719713 -281.868862)
			(xy 140.769691 -281.868862) (xy 140.819054 -281.876681) (xy 140.866586 -281.892125) (xy 140.911118 -281.914815)
			(xy 140.951551 -281.944191) (xy 140.986891 -281.979531) (xy 141.016267 -282.019964) (xy 141.038957 -282.064496)
			(xy 141.054401 -282.112028) (xy 141.06222 -282.161391) (xy 141.06271 -282.18638) (xy 141.368521 -282.18638)
			(xy 141.372616 -282.135652) (xy 141.384795 -282.086238) (xy 141.404743 -282.039418) (xy 141.431944 -281.996404)
			(xy 141.465692 -281.95831) (xy 141.505114 -281.926123) (xy 141.549188 -281.900677) (xy 141.596774 -281.88263)
			(xy 141.646638 -281.87245) (xy 141.69749 -281.870401) (xy 141.748011 -281.876535) (xy 141.796895 -281.890695)
			(xy 141.842874 -281.912512) (xy 141.884758 -281.941422) (xy 141.921462 -281.976677) (xy 141.952035 -282.017363)
			(xy 141.975686 -282.062426) (xy 141.991802 -282.1107) (xy 141.999966 -282.160934) (xy 142.000478 -282.18638)
			(xy 142.308575 -282.18638) (xy 142.31267 -282.135652) (xy 142.324849 -282.086238) (xy 142.344797 -282.039418)
			(xy 142.371998 -281.996404) (xy 142.405746 -281.95831) (xy 142.445168 -281.926123) (xy 142.489242 -281.900677)
			(xy 142.536828 -281.88263) (xy 142.586692 -281.87245) (xy 142.637544 -281.870401) (xy 142.688065 -281.876535)
			(xy 142.736949 -281.890695) (xy 142.782928 -281.912512) (xy 142.824812 -281.941422) (xy 142.861516 -281.976677)
			(xy 142.892089 -282.017363) (xy 142.91574 -282.062426) (xy 142.931856 -282.1107) (xy 142.94002 -282.160934)
			(xy 142.940532 -282.18638) (xy 142.940029 -282.211369) (xy 143.247092 -282.211369) (xy 143.247092 -282.161391)
			(xy 143.254911 -282.112028) (xy 143.270355 -282.064496) (xy 143.293045 -282.019964) (xy 143.322421 -281.979531)
			(xy 143.357761 -281.944191) (xy 143.398194 -281.914815) (xy 143.442726 -281.892125) (xy 143.490258 -281.876681)
			(xy 143.539621 -281.868862) (xy 143.589599 -281.868862) (xy 143.638962 -281.876681) (xy 143.686494 -281.892125)
			(xy 143.731026 -281.914815) (xy 143.771459 -281.944191) (xy 143.806799 -281.979531) (xy 143.836175 -282.019964)
			(xy 143.858865 -282.064496) (xy 143.874309 -282.112028) (xy 143.882128 -282.161391) (xy 143.882618 -282.18638)
			(xy 143.882128 -282.211369) (xy 143.874309 -282.260732) (xy 143.858865 -282.308264) (xy 143.836175 -282.352796)
			(xy 143.806799 -282.393229) (xy 143.771459 -282.428569) (xy 143.731026 -282.457945) (xy 143.686494 -282.480635)
			(xy 143.638962 -282.496079) (xy 143.589599 -282.503898) (xy 143.539621 -282.503898) (xy 143.490258 -282.496079)
			(xy 143.442726 -282.480635) (xy 143.398194 -282.457945) (xy 143.357761 -282.428569) (xy 143.322421 -282.393229)
			(xy 143.293045 -282.352796) (xy 143.270355 -282.308264) (xy 143.254911 -282.260732) (xy 143.247092 -282.211369)
			(xy 142.940029 -282.211369) (xy 142.94002 -282.211826) (xy 142.931856 -282.26206) (xy 142.91574 -282.310334)
			(xy 142.892089 -282.355397) (xy 142.861516 -282.396083) (xy 142.824812 -282.431338) (xy 142.782928 -282.460248)
			(xy 142.736949 -282.482065) (xy 142.688065 -282.496225) (xy 142.637544 -282.502359) (xy 142.586692 -282.50031)
			(xy 142.536828 -282.49013) (xy 142.489242 -282.472083) (xy 142.445168 -282.446637) (xy 142.405746 -282.41445)
			(xy 142.371998 -282.376356) (xy 142.344797 -282.333342) (xy 142.324849 -282.286522) (xy 142.31267 -282.237108)
			(xy 142.308575 -282.18638) (xy 142.000478 -282.18638) (xy 141.999966 -282.211826) (xy 141.991802 -282.26206)
			(xy 141.975686 -282.310334) (xy 141.952035 -282.355397) (xy 141.921462 -282.396083) (xy 141.884758 -282.431338)
			(xy 141.842874 -282.460248) (xy 141.796895 -282.482065) (xy 141.748011 -282.496225) (xy 141.69749 -282.502359)
			(xy 141.646638 -282.50031) (xy 141.596774 -282.49013) (xy 141.549188 -282.472083) (xy 141.505114 -282.446637)
			(xy 141.465692 -282.41445) (xy 141.431944 -282.376356) (xy 141.404743 -282.333342) (xy 141.384795 -282.286522)
			(xy 141.372616 -282.237108) (xy 141.368521 -282.18638) (xy 141.06271 -282.18638) (xy 141.06222 -282.211369)
			(xy 141.054401 -282.260732) (xy 141.038957 -282.308264) (xy 141.016267 -282.352796) (xy 140.986891 -282.393229)
			(xy 140.951551 -282.428569) (xy 140.911118 -282.457945) (xy 140.866586 -282.480635) (xy 140.819054 -282.496079)
			(xy 140.769691 -282.503898) (xy 140.719713 -282.503898) (xy 140.67035 -282.496079) (xy 140.622818 -282.480635)
			(xy 140.578286 -282.457945) (xy 140.537853 -282.428569) (xy 140.502513 -282.393229) (xy 140.473137 -282.352796)
			(xy 140.450447 -282.308264) (xy 140.435003 -282.260732) (xy 140.427184 -282.211369) (xy 140.119867 -282.211369)
			(xy 140.119858 -282.211826) (xy 140.111694 -282.26206) (xy 140.095578 -282.310334) (xy 140.071927 -282.355397)
			(xy 140.041354 -282.396083) (xy 140.00465 -282.431338) (xy 139.962766 -282.460248) (xy 139.916787 -282.482065)
			(xy 139.867903 -282.496225) (xy 139.817382 -282.502359) (xy 139.76653 -282.50031) (xy 139.716666 -282.49013)
			(xy 139.66908 -282.472083) (xy 139.625006 -282.446637) (xy 139.585584 -282.41445) (xy 139.551836 -282.376356)
			(xy 139.524635 -282.333342) (xy 139.504687 -282.286522) (xy 139.492508 -282.237108) (xy 139.488413 -282.18638)
			(xy 139.182856 -282.18638) (xy 139.182366 -282.211369) (xy 139.174547 -282.260732) (xy 139.159103 -282.308264)
			(xy 139.136413 -282.352796) (xy 139.107037 -282.393229) (xy 139.071697 -282.428569) (xy 139.031264 -282.457945)
			(xy 138.986732 -282.480635) (xy 138.9392 -282.496079) (xy 138.889837 -282.503898) (xy 138.839859 -282.503898)
			(xy 138.790496 -282.496079) (xy 138.742964 -282.480635) (xy 138.698432 -282.457945) (xy 138.657999 -282.428569)
			(xy 138.622659 -282.393229) (xy 138.593283 -282.352796) (xy 138.570593 -282.308264) (xy 138.555149 -282.260732)
			(xy 138.54733 -282.211369) (xy 138.240013 -282.211369) (xy 138.240004 -282.211826) (xy 138.23184 -282.26206)
			(xy 138.215724 -282.310334) (xy 138.192073 -282.355397) (xy 138.1615 -282.396083) (xy 138.124796 -282.431338)
			(xy 138.082912 -282.460248) (xy 138.036933 -282.482065) (xy 137.988049 -282.496225) (xy 137.937528 -282.502359)
			(xy 137.886676 -282.50031) (xy 137.836812 -282.49013) (xy 137.789226 -282.472083) (xy 137.745152 -282.446637)
			(xy 137.70573 -282.41445) (xy 137.671982 -282.376356) (xy 137.644781 -282.333342) (xy 137.624833 -282.286522)
			(xy 137.612654 -282.237108) (xy 137.608559 -282.18638) (xy 137.302748 -282.18638) (xy 137.302258 -282.211369)
			(xy 137.294439 -282.260732) (xy 137.278995 -282.308264) (xy 137.256305 -282.352796) (xy 137.226929 -282.393229)
			(xy 137.191589 -282.428569) (xy 137.151156 -282.457945) (xy 137.106624 -282.480635) (xy 137.059092 -282.496079)
			(xy 137.009729 -282.503898) (xy 136.959751 -282.503898) (xy 136.910388 -282.496079) (xy 136.862856 -282.480635)
			(xy 136.818324 -282.457945) (xy 136.777891 -282.428569) (xy 136.742551 -282.393229) (xy 136.713175 -282.352796)
			(xy 136.690485 -282.308264) (xy 136.675041 -282.260732) (xy 136.667222 -282.211369) (xy 136.359905 -282.211369)
			(xy 136.359896 -282.211826) (xy 136.351732 -282.26206) (xy 136.335616 -282.310334) (xy 136.311965 -282.355397)
			(xy 136.281392 -282.396083) (xy 136.244688 -282.431338) (xy 136.202804 -282.460248) (xy 136.156825 -282.482065)
			(xy 136.107941 -282.496225) (xy 136.05742 -282.502359) (xy 136.006568 -282.50031) (xy 135.956704 -282.49013)
			(xy 135.909118 -282.472083) (xy 135.865044 -282.446637) (xy 135.825622 -282.41445) (xy 135.791874 -282.376356)
			(xy 135.764673 -282.333342) (xy 135.744725 -282.286522) (xy 135.732546 -282.237108) (xy 135.728451 -282.18638)
			(xy 135.420354 -282.18638) (xy 135.419842 -282.211826) (xy 135.411678 -282.26206) (xy 135.395562 -282.310334)
			(xy 135.371911 -282.355397) (xy 135.341338 -282.396083) (xy 135.304634 -282.431338) (xy 135.26275 -282.460248)
			(xy 135.216771 -282.482065) (xy 135.167887 -282.496225) (xy 135.117366 -282.502359) (xy 135.066514 -282.50031)
			(xy 135.01665 -282.49013) (xy 134.969064 -282.472083) (xy 134.92499 -282.446637) (xy 134.885568 -282.41445)
			(xy 134.85182 -282.376356) (xy 134.824619 -282.333342) (xy 134.804671 -282.286522) (xy 134.792492 -282.237108)
			(xy 134.788397 -282.18638) (xy 134.48284 -282.18638) (xy 134.48235 -282.211369) (xy 134.474531 -282.260732)
			(xy 134.459087 -282.308264) (xy 134.436397 -282.352796) (xy 134.407021 -282.393229) (xy 134.371681 -282.428569)
			(xy 134.331248 -282.457945) (xy 134.286716 -282.480635) (xy 134.239184 -282.496079) (xy 134.189821 -282.503898)
			(xy 134.139843 -282.503898) (xy 134.09048 -282.496079) (xy 134.042948 -282.480635) (xy 133.998416 -282.457945)
			(xy 133.957983 -282.428569) (xy 133.922643 -282.393229) (xy 133.893267 -282.352796) (xy 133.870577 -282.308264)
			(xy 133.855133 -282.260732) (xy 133.847314 -282.211369) (xy 133.539997 -282.211369) (xy 133.539988 -282.211826)
			(xy 133.531824 -282.26206) (xy 133.515708 -282.310334) (xy 133.492057 -282.355397) (xy 133.461484 -282.396083)
			(xy 133.42478 -282.431338) (xy 133.382896 -282.460248) (xy 133.336917 -282.482065) (xy 133.288033 -282.496225)
			(xy 133.237512 -282.502359) (xy 133.18666 -282.50031) (xy 133.136796 -282.49013) (xy 133.08921 -282.472083)
			(xy 133.045136 -282.446637) (xy 133.005714 -282.41445) (xy 132.971966 -282.376356) (xy 132.944765 -282.333342)
			(xy 132.924817 -282.286522) (xy 132.912638 -282.237108) (xy 132.908543 -282.18638) (xy 132.602732 -282.18638)
			(xy 132.602242 -282.211369) (xy 132.594423 -282.260732) (xy 132.578979 -282.308264) (xy 132.556289 -282.352796)
			(xy 132.526913 -282.393229) (xy 132.491573 -282.428569) (xy 132.45114 -282.457945) (xy 132.406608 -282.480635)
			(xy 132.359076 -282.496079) (xy 132.309713 -282.503898) (xy 132.259735 -282.503898) (xy 132.210372 -282.496079)
			(xy 132.16284 -282.480635) (xy 132.118308 -282.457945) (xy 132.077875 -282.428569) (xy 132.042535 -282.393229)
			(xy 132.013159 -282.352796) (xy 131.990469 -282.308264) (xy 131.975025 -282.260732) (xy 131.967206 -282.211369)
			(xy 131.659889 -282.211369) (xy 131.65988 -282.211826) (xy 131.651716 -282.26206) (xy 131.6356 -282.310334)
			(xy 131.611949 -282.355397) (xy 131.581376 -282.396083) (xy 131.544672 -282.431338) (xy 131.502788 -282.460248)
			(xy 131.456809 -282.482065) (xy 131.407925 -282.496225) (xy 131.357404 -282.502359) (xy 131.306552 -282.50031)
			(xy 131.256688 -282.49013) (xy 131.209102 -282.472083) (xy 131.165028 -282.446637) (xy 131.125606 -282.41445)
			(xy 131.091858 -282.376356) (xy 131.064657 -282.333342) (xy 131.044709 -282.286522) (xy 131.03253 -282.237108)
			(xy 131.028435 -282.18638) (xy 130.722878 -282.18638) (xy 130.722388 -282.211369) (xy 130.714569 -282.260732)
			(xy 130.699125 -282.308264) (xy 130.676435 -282.352796) (xy 130.647059 -282.393229) (xy 130.611719 -282.428569)
			(xy 130.571286 -282.457945) (xy 130.526754 -282.480635) (xy 130.479222 -282.496079) (xy 130.429859 -282.503898)
			(xy 130.379881 -282.503898) (xy 130.330518 -282.496079) (xy 130.282986 -282.480635) (xy 130.238454 -282.457945)
			(xy 130.198021 -282.428569) (xy 130.162681 -282.393229) (xy 130.133305 -282.352796) (xy 130.110615 -282.308264)
			(xy 130.095171 -282.260732) (xy 130.087352 -282.211369) (xy 129.780035 -282.211369) (xy 129.780026 -282.211826)
			(xy 129.771862 -282.26206) (xy 129.755746 -282.310334) (xy 129.732095 -282.355397) (xy 129.701522 -282.396083)
			(xy 129.664818 -282.431338) (xy 129.622934 -282.460248) (xy 129.576955 -282.482065) (xy 129.528071 -282.496225)
			(xy 129.47755 -282.502359) (xy 129.426698 -282.50031) (xy 129.376834 -282.49013) (xy 129.329248 -282.472083)
			(xy 129.285174 -282.446637) (xy 129.245752 -282.41445) (xy 129.212004 -282.376356) (xy 129.184803 -282.333342)
			(xy 129.164855 -282.286522) (xy 129.152676 -282.237108) (xy 129.148581 -282.18638) (xy 128.840484 -282.18638)
			(xy 128.839972 -282.211826) (xy 128.831808 -282.26206) (xy 128.815692 -282.310334) (xy 128.792041 -282.355397)
			(xy 128.761468 -282.396083) (xy 128.724764 -282.431338) (xy 128.68288 -282.460248) (xy 128.636901 -282.482065)
			(xy 128.588017 -282.496225) (xy 128.537496 -282.502359) (xy 128.486644 -282.50031) (xy 128.43678 -282.49013)
			(xy 128.389194 -282.472083) (xy 128.34512 -282.446637) (xy 128.305698 -282.41445) (xy 128.27195 -282.376356)
			(xy 128.244749 -282.333342) (xy 128.224801 -282.286522) (xy 128.212622 -282.237108) (xy 128.208527 -282.18638)
			(xy 126.962662 -282.18638) (xy 126.962662 -282.186634) (xy 126.962208 -282.210905) (xy 126.954838 -282.258883)
			(xy 126.940258 -282.305183) (xy 126.918808 -282.348728) (xy 126.890987 -282.388506) (xy 126.874524 -282.406344)
			(xy 126.867412 -282.41371) (xy 126.8603 -282.431998) (xy 126.8603 -282.442158) (xy 126.860901 -282.452019)
			(xy 126.868597 -282.470196) (xy 126.875286 -282.477464) (xy 127.061722 -282.6639) (xy 127.065596 -282.667562)
			(xy 127.074565 -282.67332) (xy 127.079502 -282.67533) (xy 127.089154 -282.67914) (xy 127.099822 -282.678632)
			(xy 127.1143 -282.678378) (xy 127.115062 -282.678378) (xy 127.140038 -282.678888) (xy 127.18937 -282.686739)
			(xy 127.236868 -282.702206) (xy 127.281364 -282.724909) (xy 127.321763 -282.75429) (xy 127.357071 -282.789626)
			(xy 127.386421 -282.830048) (xy 127.409089 -282.874561) (xy 127.424519 -282.922071) (xy 127.432332 -282.97141)
			(xy 127.432816 -282.996386) (xy 127.738627 -282.996386) (xy 127.742722 -282.945658) (xy 127.754901 -282.896244)
			(xy 127.774849 -282.849424) (xy 127.80205 -282.80641) (xy 127.835798 -282.768316) (xy 127.87522 -282.736129)
			(xy 127.919294 -282.710683) (xy 127.96688 -282.692636) (xy 128.016744 -282.682456) (xy 128.067596 -282.680407)
			(xy 128.118117 -282.686541) (xy 128.167001 -282.700701) (xy 128.21298 -282.722518) (xy 128.254864 -282.751428)
			(xy 128.291568 -282.786683) (xy 128.322141 -282.827369) (xy 128.345792 -282.872432) (xy 128.361908 -282.920706)
			(xy 128.370072 -282.97094) (xy 128.370584 -282.996386) (xy 128.370081 -283.021375) (xy 128.677144 -283.021375)
			(xy 128.677144 -282.971397) (xy 128.684963 -282.922034) (xy 128.700407 -282.874502) (xy 128.723097 -282.82997)
			(xy 128.752473 -282.789537) (xy 128.787813 -282.754197) (xy 128.828246 -282.724821) (xy 128.872778 -282.702131)
			(xy 128.92031 -282.686687) (xy 128.969673 -282.678868) (xy 129.019651 -282.678868) (xy 129.069014 -282.686687)
			(xy 129.116546 -282.702131) (xy 129.161078 -282.724821) (xy 129.201511 -282.754197) (xy 129.236851 -282.789537)
			(xy 129.266227 -282.82997) (xy 129.288917 -282.874502) (xy 129.304361 -282.922034) (xy 129.31218 -282.971397)
			(xy 129.31267 -282.996386) (xy 129.618481 -282.996386) (xy 129.622576 -282.945658) (xy 129.634755 -282.896244)
			(xy 129.654703 -282.849424) (xy 129.681904 -282.80641) (xy 129.715652 -282.768316) (xy 129.755074 -282.736129)
			(xy 129.799148 -282.710683) (xy 129.846734 -282.692636) (xy 129.896598 -282.682456) (xy 129.94745 -282.680407)
			(xy 129.997971 -282.686541) (xy 130.046855 -282.700701) (xy 130.092834 -282.722518) (xy 130.134718 -282.751428)
			(xy 130.171422 -282.786683) (xy 130.201995 -282.827369) (xy 130.225646 -282.872432) (xy 130.241762 -282.920706)
			(xy 130.249926 -282.97094) (xy 130.250438 -282.996386) (xy 131.498589 -282.996386) (xy 131.502684 -282.945658)
			(xy 131.514863 -282.896244) (xy 131.534811 -282.849424) (xy 131.562012 -282.80641) (xy 131.59576 -282.768316)
			(xy 131.635182 -282.736129) (xy 131.679256 -282.710683) (xy 131.726842 -282.692636) (xy 131.776706 -282.682456)
			(xy 131.827558 -282.680407) (xy 131.878079 -282.686541) (xy 131.926963 -282.700701) (xy 131.972942 -282.722518)
			(xy 132.014826 -282.751428) (xy 132.05153 -282.786683) (xy 132.082103 -282.827369) (xy 132.105754 -282.872432)
			(xy 132.12187 -282.920706) (xy 132.130034 -282.97094) (xy 132.130546 -282.996386) (xy 132.438643 -282.996386)
			(xy 132.442738 -282.945658) (xy 132.454917 -282.896244) (xy 132.474865 -282.849424) (xy 132.502066 -282.80641)
			(xy 132.535814 -282.768316) (xy 132.575236 -282.736129) (xy 132.61931 -282.710683) (xy 132.666896 -282.692636)
			(xy 132.71676 -282.682456) (xy 132.767612 -282.680407) (xy 132.818133 -282.686541) (xy 132.867017 -282.700701)
			(xy 132.912996 -282.722518) (xy 132.95488 -282.751428) (xy 132.991584 -282.786683) (xy 133.022157 -282.827369)
			(xy 133.045808 -282.872432) (xy 133.061924 -282.920706) (xy 133.070088 -282.97094) (xy 133.0706 -282.996386)
			(xy 133.070097 -283.021375) (xy 133.37716 -283.021375) (xy 133.37716 -282.971397) (xy 133.384979 -282.922034)
			(xy 133.400423 -282.874502) (xy 133.423113 -282.82997) (xy 133.452489 -282.789537) (xy 133.487829 -282.754197)
			(xy 133.528262 -282.724821) (xy 133.572794 -282.702131) (xy 133.620326 -282.686687) (xy 133.669689 -282.678868)
			(xy 133.719667 -282.678868) (xy 133.76903 -282.686687) (xy 133.816562 -282.702131) (xy 133.861094 -282.724821)
			(xy 133.901527 -282.754197) (xy 133.936867 -282.789537) (xy 133.966243 -282.82997) (xy 133.988933 -282.874502)
			(xy 134.004377 -282.922034) (xy 134.012196 -282.971397) (xy 134.012686 -282.996386) (xy 134.318497 -282.996386)
			(xy 134.322592 -282.945658) (xy 134.334771 -282.896244) (xy 134.354719 -282.849424) (xy 134.38192 -282.80641)
			(xy 134.415668 -282.768316) (xy 134.45509 -282.736129) (xy 134.499164 -282.710683) (xy 134.54675 -282.692636)
			(xy 134.596614 -282.682456) (xy 134.647466 -282.680407) (xy 134.697987 -282.686541) (xy 134.746871 -282.700701)
			(xy 134.79285 -282.722518) (xy 134.834734 -282.751428) (xy 134.871438 -282.786683) (xy 134.902011 -282.827369)
			(xy 134.925662 -282.872432) (xy 134.941778 -282.920706) (xy 134.949942 -282.97094) (xy 134.950454 -282.996386)
			(xy 134.949951 -283.021375) (xy 135.257268 -283.021375) (xy 135.257268 -282.971397) (xy 135.265087 -282.922034)
			(xy 135.280531 -282.874502) (xy 135.303221 -282.82997) (xy 135.332597 -282.789537) (xy 135.367937 -282.754197)
			(xy 135.40837 -282.724821) (xy 135.452902 -282.702131) (xy 135.500434 -282.686687) (xy 135.549797 -282.678868)
			(xy 135.599775 -282.678868) (xy 135.649138 -282.686687) (xy 135.69667 -282.702131) (xy 135.741202 -282.724821)
			(xy 135.781635 -282.754197) (xy 135.816975 -282.789537) (xy 135.846351 -282.82997) (xy 135.869041 -282.874502)
			(xy 135.884485 -282.922034) (xy 135.892304 -282.971397) (xy 135.892794 -282.996386) (xy 136.198605 -282.996386)
			(xy 136.2027 -282.945658) (xy 136.214879 -282.896244) (xy 136.234827 -282.849424) (xy 136.262028 -282.80641)
			(xy 136.295776 -282.768316) (xy 136.335198 -282.736129) (xy 136.379272 -282.710683) (xy 136.426858 -282.692636)
			(xy 136.476722 -282.682456) (xy 136.527574 -282.680407) (xy 136.578095 -282.686541) (xy 136.626979 -282.700701)
			(xy 136.672958 -282.722518) (xy 136.714842 -282.751428) (xy 136.751546 -282.786683) (xy 136.782119 -282.827369)
			(xy 136.80577 -282.872432) (xy 136.821886 -282.920706) (xy 136.83005 -282.97094) (xy 136.830562 -282.996386)
			(xy 138.078459 -282.996386) (xy 138.082554 -282.945658) (xy 138.094733 -282.896244) (xy 138.114681 -282.849424)
			(xy 138.141882 -282.80641) (xy 138.17563 -282.768316) (xy 138.215052 -282.736129) (xy 138.259126 -282.710683)
			(xy 138.306712 -282.692636) (xy 138.356576 -282.682456) (xy 138.407428 -282.680407) (xy 138.457949 -282.686541)
			(xy 138.506833 -282.700701) (xy 138.552812 -282.722518) (xy 138.594696 -282.751428) (xy 138.6314 -282.786683)
			(xy 138.661973 -282.827369) (xy 138.685624 -282.872432) (xy 138.70174 -282.920706) (xy 138.709904 -282.97094)
			(xy 138.710416 -282.996386) (xy 139.018513 -282.996386) (xy 139.022608 -282.945658) (xy 139.034787 -282.896244)
			(xy 139.054735 -282.849424) (xy 139.081936 -282.80641) (xy 139.115684 -282.768316) (xy 139.155106 -282.736129)
			(xy 139.19918 -282.710683) (xy 139.246766 -282.692636) (xy 139.29663 -282.682456) (xy 139.347482 -282.680407)
			(xy 139.398003 -282.686541) (xy 139.446887 -282.700701) (xy 139.492866 -282.722518) (xy 139.53475 -282.751428)
			(xy 139.571454 -282.786683) (xy 139.602027 -282.827369) (xy 139.625678 -282.872432) (xy 139.641794 -282.920706)
			(xy 139.649958 -282.97094) (xy 139.65047 -282.996386) (xy 139.649967 -283.021375) (xy 139.957284 -283.021375)
			(xy 139.957284 -282.971397) (xy 139.965103 -282.922034) (xy 139.980547 -282.874502) (xy 140.003237 -282.82997)
			(xy 140.032613 -282.789537) (xy 140.067953 -282.754197) (xy 140.108386 -282.724821) (xy 140.152918 -282.702131)
			(xy 140.20045 -282.686687) (xy 140.249813 -282.678868) (xy 140.299791 -282.678868) (xy 140.349154 -282.686687)
			(xy 140.396686 -282.702131) (xy 140.441218 -282.724821) (xy 140.481651 -282.754197) (xy 140.516991 -282.789537)
			(xy 140.546367 -282.82997) (xy 140.569057 -282.874502) (xy 140.584501 -282.922034) (xy 140.59232 -282.971397)
			(xy 140.59281 -282.996386) (xy 140.898621 -282.996386) (xy 140.902716 -282.945658) (xy 140.914895 -282.896244)
			(xy 140.934843 -282.849424) (xy 140.962044 -282.80641) (xy 140.995792 -282.768316) (xy 141.035214 -282.736129)
			(xy 141.079288 -282.710683) (xy 141.126874 -282.692636) (xy 141.176738 -282.682456) (xy 141.22759 -282.680407)
			(xy 141.278111 -282.686541) (xy 141.326995 -282.700701) (xy 141.372974 -282.722518) (xy 141.414858 -282.751428)
			(xy 141.451562 -282.786683) (xy 141.482135 -282.827369) (xy 141.505786 -282.872432) (xy 141.521902 -282.920706)
			(xy 141.530066 -282.97094) (xy 141.530578 -282.996386) (xy 141.530075 -283.021375) (xy 141.837138 -283.021375)
			(xy 141.837138 -282.971397) (xy 141.844957 -282.922034) (xy 141.860401 -282.874502) (xy 141.883091 -282.82997)
			(xy 141.912467 -282.789537) (xy 141.947807 -282.754197) (xy 141.98824 -282.724821) (xy 142.032772 -282.702131)
			(xy 142.080304 -282.686687) (xy 142.129667 -282.678868) (xy 142.179645 -282.678868) (xy 142.229008 -282.686687)
			(xy 142.27654 -282.702131) (xy 142.321072 -282.724821) (xy 142.361505 -282.754197) (xy 142.396845 -282.789537)
			(xy 142.426221 -282.82997) (xy 142.448911 -282.874502) (xy 142.464355 -282.922034) (xy 142.472174 -282.971397)
			(xy 142.472664 -282.996386) (xy 142.778475 -282.996386) (xy 142.78257 -282.945658) (xy 142.794749 -282.896244)
			(xy 142.814697 -282.849424) (xy 142.841898 -282.80641) (xy 142.875646 -282.768316) (xy 142.915068 -282.736129)
			(xy 142.959142 -282.710683) (xy 143.006728 -282.692636) (xy 143.056592 -282.682456) (xy 143.107444 -282.680407)
			(xy 143.157965 -282.686541) (xy 143.206849 -282.700701) (xy 143.252828 -282.722518) (xy 143.294712 -282.751428)
			(xy 143.331416 -282.786683) (xy 143.361989 -282.827369) (xy 143.38564 -282.872432) (xy 143.401756 -282.920706)
			(xy 143.40992 -282.97094) (xy 143.410432 -282.996386) (xy 143.40992 -283.021832) (xy 143.401756 -283.072066)
			(xy 143.38564 -283.12034) (xy 143.361989 -283.165403) (xy 143.331416 -283.206089) (xy 143.294712 -283.241344)
			(xy 143.252828 -283.270254) (xy 143.206849 -283.292071) (xy 143.157965 -283.306231) (xy 143.107444 -283.312365)
			(xy 143.056592 -283.310316) (xy 143.006728 -283.300136) (xy 142.959142 -283.282089) (xy 142.915068 -283.256643)
			(xy 142.875646 -283.224456) (xy 142.841898 -283.186362) (xy 142.814697 -283.143348) (xy 142.794749 -283.096528)
			(xy 142.78257 -283.047114) (xy 142.778475 -282.996386) (xy 142.472664 -282.996386) (xy 142.472174 -283.021375)
			(xy 142.464355 -283.070738) (xy 142.448911 -283.11827) (xy 142.426221 -283.162802) (xy 142.396845 -283.203235)
			(xy 142.361505 -283.238575) (xy 142.321072 -283.267951) (xy 142.27654 -283.290641) (xy 142.229008 -283.306085)
			(xy 142.179645 -283.313904) (xy 142.129667 -283.313904) (xy 142.080304 -283.306085) (xy 142.032772 -283.290641)
			(xy 141.98824 -283.267951) (xy 141.947807 -283.238575) (xy 141.912467 -283.203235) (xy 141.883091 -283.162802)
			(xy 141.860401 -283.11827) (xy 141.844957 -283.070738) (xy 141.837138 -283.021375) (xy 141.530075 -283.021375)
			(xy 141.530066 -283.021832) (xy 141.521902 -283.072066) (xy 141.505786 -283.12034) (xy 141.482135 -283.165403)
			(xy 141.451562 -283.206089) (xy 141.414858 -283.241344) (xy 141.372974 -283.270254) (xy 141.326995 -283.292071)
			(xy 141.278111 -283.306231) (xy 141.22759 -283.312365) (xy 141.176738 -283.310316) (xy 141.126874 -283.300136)
			(xy 141.079288 -283.282089) (xy 141.035214 -283.256643) (xy 140.995792 -283.224456) (xy 140.962044 -283.186362)
			(xy 140.934843 -283.143348) (xy 140.914895 -283.096528) (xy 140.902716 -283.047114) (xy 140.898621 -282.996386)
			(xy 140.59281 -282.996386) (xy 140.59232 -283.021375) (xy 140.584501 -283.070738) (xy 140.569057 -283.11827)
			(xy 140.546367 -283.162802) (xy 140.516991 -283.203235) (xy 140.481651 -283.238575) (xy 140.441218 -283.267951)
			(xy 140.396686 -283.290641) (xy 140.349154 -283.306085) (xy 140.299791 -283.313904) (xy 140.249813 -283.313904)
			(xy 140.20045 -283.306085) (xy 140.152918 -283.290641) (xy 140.108386 -283.267951) (xy 140.067953 -283.238575)
			(xy 140.032613 -283.203235) (xy 140.003237 -283.162802) (xy 139.980547 -283.11827) (xy 139.965103 -283.070738)
			(xy 139.957284 -283.021375) (xy 139.649967 -283.021375) (xy 139.649958 -283.021832) (xy 139.641794 -283.072066)
			(xy 139.625678 -283.12034) (xy 139.602027 -283.165403) (xy 139.571454 -283.206089) (xy 139.53475 -283.241344)
			(xy 139.492866 -283.270254) (xy 139.446887 -283.292071) (xy 139.398003 -283.306231) (xy 139.347482 -283.312365)
			(xy 139.29663 -283.310316) (xy 139.246766 -283.300136) (xy 139.19918 -283.282089) (xy 139.155106 -283.256643)
			(xy 139.115684 -283.224456) (xy 139.081936 -283.186362) (xy 139.054735 -283.143348) (xy 139.034787 -283.096528)
			(xy 139.022608 -283.047114) (xy 139.018513 -282.996386) (xy 138.710416 -282.996386) (xy 138.709904 -283.021832)
			(xy 138.70174 -283.072066) (xy 138.685624 -283.12034) (xy 138.661973 -283.165403) (xy 138.6314 -283.206089)
			(xy 138.594696 -283.241344) (xy 138.552812 -283.270254) (xy 138.506833 -283.292071) (xy 138.457949 -283.306231)
			(xy 138.407428 -283.312365) (xy 138.356576 -283.310316) (xy 138.306712 -283.300136) (xy 138.259126 -283.282089)
			(xy 138.215052 -283.256643) (xy 138.17563 -283.224456) (xy 138.141882 -283.186362) (xy 138.114681 -283.143348)
			(xy 138.094733 -283.096528) (xy 138.082554 -283.047114) (xy 138.078459 -282.996386) (xy 136.830562 -282.996386)
			(xy 136.83005 -283.021832) (xy 136.821886 -283.072066) (xy 136.80577 -283.12034) (xy 136.782119 -283.165403)
			(xy 136.751546 -283.206089) (xy 136.714842 -283.241344) (xy 136.672958 -283.270254) (xy 136.626979 -283.292071)
			(xy 136.578095 -283.306231) (xy 136.527574 -283.312365) (xy 136.476722 -283.310316) (xy 136.426858 -283.300136)
			(xy 136.379272 -283.282089) (xy 136.335198 -283.256643) (xy 136.295776 -283.224456) (xy 136.262028 -283.186362)
			(xy 136.234827 -283.143348) (xy 136.214879 -283.096528) (xy 136.2027 -283.047114) (xy 136.198605 -282.996386)
			(xy 135.892794 -282.996386) (xy 135.892304 -283.021375) (xy 135.884485 -283.070738) (xy 135.869041 -283.11827)
			(xy 135.846351 -283.162802) (xy 135.816975 -283.203235) (xy 135.781635 -283.238575) (xy 135.741202 -283.267951)
			(xy 135.69667 -283.290641) (xy 135.649138 -283.306085) (xy 135.599775 -283.313904) (xy 135.549797 -283.313904)
			(xy 135.500434 -283.306085) (xy 135.452902 -283.290641) (xy 135.40837 -283.267951) (xy 135.367937 -283.238575)
			(xy 135.332597 -283.203235) (xy 135.303221 -283.162802) (xy 135.280531 -283.11827) (xy 135.265087 -283.070738)
			(xy 135.257268 -283.021375) (xy 134.949951 -283.021375) (xy 134.949942 -283.021832) (xy 134.941778 -283.072066)
			(xy 134.925662 -283.12034) (xy 134.902011 -283.165403) (xy 134.871438 -283.206089) (xy 134.834734 -283.241344)
			(xy 134.79285 -283.270254) (xy 134.746871 -283.292071) (xy 134.697987 -283.306231) (xy 134.647466 -283.312365)
			(xy 134.596614 -283.310316) (xy 134.54675 -283.300136) (xy 134.499164 -283.282089) (xy 134.45509 -283.256643)
			(xy 134.415668 -283.224456) (xy 134.38192 -283.186362) (xy 134.354719 -283.143348) (xy 134.334771 -283.096528)
			(xy 134.322592 -283.047114) (xy 134.318497 -282.996386) (xy 134.012686 -282.996386) (xy 134.012196 -283.021375)
			(xy 134.004377 -283.070738) (xy 133.988933 -283.11827) (xy 133.966243 -283.162802) (xy 133.936867 -283.203235)
			(xy 133.901527 -283.238575) (xy 133.861094 -283.267951) (xy 133.816562 -283.290641) (xy 133.76903 -283.306085)
			(xy 133.719667 -283.313904) (xy 133.669689 -283.313904) (xy 133.620326 -283.306085) (xy 133.572794 -283.290641)
			(xy 133.528262 -283.267951) (xy 133.487829 -283.238575) (xy 133.452489 -283.203235) (xy 133.423113 -283.162802)
			(xy 133.400423 -283.11827) (xy 133.384979 -283.070738) (xy 133.37716 -283.021375) (xy 133.070097 -283.021375)
			(xy 133.070088 -283.021832) (xy 133.061924 -283.072066) (xy 133.045808 -283.12034) (xy 133.022157 -283.165403)
			(xy 132.991584 -283.206089) (xy 132.95488 -283.241344) (xy 132.912996 -283.270254) (xy 132.867017 -283.292071)
			(xy 132.818133 -283.306231) (xy 132.767612 -283.312365) (xy 132.71676 -283.310316) (xy 132.666896 -283.300136)
			(xy 132.61931 -283.282089) (xy 132.575236 -283.256643) (xy 132.535814 -283.224456) (xy 132.502066 -283.186362)
			(xy 132.474865 -283.143348) (xy 132.454917 -283.096528) (xy 132.442738 -283.047114) (xy 132.438643 -282.996386)
			(xy 132.130546 -282.996386) (xy 132.130034 -283.021832) (xy 132.12187 -283.072066) (xy 132.105754 -283.12034)
			(xy 132.082103 -283.165403) (xy 132.05153 -283.206089) (xy 132.014826 -283.241344) (xy 131.972942 -283.270254)
			(xy 131.926963 -283.292071) (xy 131.878079 -283.306231) (xy 131.827558 -283.312365) (xy 131.776706 -283.310316)
			(xy 131.726842 -283.300136) (xy 131.679256 -283.282089) (xy 131.635182 -283.256643) (xy 131.59576 -283.224456)
			(xy 131.562012 -283.186362) (xy 131.534811 -283.143348) (xy 131.514863 -283.096528) (xy 131.502684 -283.047114)
			(xy 131.498589 -282.996386) (xy 130.250438 -282.996386) (xy 130.249926 -283.021832) (xy 130.241762 -283.072066)
			(xy 130.225646 -283.12034) (xy 130.201995 -283.165403) (xy 130.171422 -283.206089) (xy 130.134718 -283.241344)
			(xy 130.092834 -283.270254) (xy 130.046855 -283.292071) (xy 129.997971 -283.306231) (xy 129.94745 -283.312365)
			(xy 129.896598 -283.310316) (xy 129.846734 -283.300136) (xy 129.799148 -283.282089) (xy 129.755074 -283.256643)
			(xy 129.715652 -283.224456) (xy 129.681904 -283.186362) (xy 129.654703 -283.143348) (xy 129.634755 -283.096528)
			(xy 129.622576 -283.047114) (xy 129.618481 -282.996386) (xy 129.31267 -282.996386) (xy 129.31218 -283.021375)
			(xy 129.304361 -283.070738) (xy 129.288917 -283.11827) (xy 129.266227 -283.162802) (xy 129.236851 -283.203235)
			(xy 129.201511 -283.238575) (xy 129.161078 -283.267951) (xy 129.116546 -283.290641) (xy 129.069014 -283.306085)
			(xy 129.019651 -283.313904) (xy 128.969673 -283.313904) (xy 128.92031 -283.306085) (xy 128.872778 -283.290641)
			(xy 128.828246 -283.267951) (xy 128.787813 -283.238575) (xy 128.752473 -283.203235) (xy 128.723097 -283.162802)
			(xy 128.700407 -283.11827) (xy 128.684963 -283.070738) (xy 128.677144 -283.021375) (xy 128.370081 -283.021375)
			(xy 128.370072 -283.021832) (xy 128.361908 -283.072066) (xy 128.345792 -283.12034) (xy 128.322141 -283.165403)
			(xy 128.291568 -283.206089) (xy 128.254864 -283.241344) (xy 128.21298 -283.270254) (xy 128.167001 -283.292071)
			(xy 128.118117 -283.306231) (xy 128.067596 -283.312365) (xy 128.016744 -283.310316) (xy 127.96688 -283.300136)
			(xy 127.919294 -283.282089) (xy 127.87522 -283.256643) (xy 127.835798 -283.224456) (xy 127.80205 -283.186362)
			(xy 127.774849 -283.143348) (xy 127.754901 -283.096528) (xy 127.742722 -283.047114) (xy 127.738627 -282.996386)
			(xy 127.432816 -282.996386) (xy 127.432243 -283.023717) (xy 127.422891 -283.077572) (xy 127.404478 -283.129039)
			(xy 127.377543 -283.176604) (xy 127.34288 -283.218869) (xy 127.32258 -283.237178) (xy 127.321056 -283.238448)
			(xy 127.317754 -283.24175) (xy 127.314955 -283.244708) (xy 127.310237 -283.251346) (xy 127.308356 -283.254958)
			(xy 127.29845 -283.27604) (xy 127.296926 -283.280358) (xy 127.295778 -283.28413) (xy 127.294498 -283.291911)
			(xy 127.294386 -283.295852) (xy 127.294386 -283.428186) (xy 127.295148 -283.436568) (xy 127.296672 -283.444696)
			(xy 127.297916 -283.449942) (xy 127.302259 -283.459808) (xy 127.305308 -283.464254) (xy 127.31115 -283.472382)
			(xy 127.391414 -283.521404) (xy 127.399462 -283.52529) (xy 127.417152 -283.527758) (xy 127.425958 -283.52623)
			(xy 127.439928 -283.522928) (xy 127.445262 -283.520388) (xy 127.446024 -283.520134) (xy 127.467052 -283.510409)
			(xy 127.511238 -283.496479) (xy 127.556979 -283.489125) (xy 127.580136 -283.488384) (xy 127.590042 -283.488384)
			(xy 127.614754 -283.489269) (xy 127.663469 -283.497743) (xy 127.710285 -283.513656) (xy 127.754074 -283.536625)
			(xy 127.793778 -283.566096) (xy 127.828442 -283.601357) (xy 127.85723 -283.64156) (xy 127.879447 -283.685734)
			(xy 127.894558 -283.732816) (xy 127.902198 -283.781668) (xy 127.902716 -283.806392) (xy 128.208527 -283.806392)
			(xy 128.212622 -283.755664) (xy 128.224801 -283.70625) (xy 128.244749 -283.65943) (xy 128.27195 -283.616416)
			(xy 128.305698 -283.578322) (xy 128.34512 -283.546135) (xy 128.389194 -283.520689) (xy 128.43678 -283.502642)
			(xy 128.486644 -283.492462) (xy 128.537496 -283.490413) (xy 128.588017 -283.496547) (xy 128.636901 -283.510707)
			(xy 128.68288 -283.532524) (xy 128.724764 -283.561434) (xy 128.761468 -283.596689) (xy 128.792041 -283.637375)
			(xy 128.815692 -283.682438) (xy 128.831808 -283.730712) (xy 128.839972 -283.780946) (xy 128.840484 -283.806392)
			(xy 129.148581 -283.806392) (xy 129.152676 -283.755664) (xy 129.164855 -283.70625) (xy 129.184803 -283.65943)
			(xy 129.212004 -283.616416) (xy 129.245752 -283.578322) (xy 129.285174 -283.546135) (xy 129.329248 -283.520689)
			(xy 129.376834 -283.502642) (xy 129.426698 -283.492462) (xy 129.47755 -283.490413) (xy 129.528071 -283.496547)
			(xy 129.576955 -283.510707) (xy 129.622934 -283.532524) (xy 129.664818 -283.561434) (xy 129.701522 -283.596689)
			(xy 129.732095 -283.637375) (xy 129.755746 -283.682438) (xy 129.771862 -283.730712) (xy 129.780026 -283.780946)
			(xy 129.780538 -283.806392) (xy 129.780035 -283.831381) (xy 130.087352 -283.831381) (xy 130.087352 -283.781403)
			(xy 130.095171 -283.73204) (xy 130.110615 -283.684508) (xy 130.133305 -283.639976) (xy 130.162681 -283.599543)
			(xy 130.198021 -283.564203) (xy 130.238454 -283.534827) (xy 130.282986 -283.512137) (xy 130.330518 -283.496693)
			(xy 130.379881 -283.488874) (xy 130.429859 -283.488874) (xy 130.479222 -283.496693) (xy 130.526754 -283.512137)
			(xy 130.571286 -283.534827) (xy 130.611719 -283.564203) (xy 130.647059 -283.599543) (xy 130.676435 -283.639976)
			(xy 130.699125 -283.684508) (xy 130.714569 -283.73204) (xy 130.722388 -283.781403) (xy 130.722878 -283.806392)
			(xy 131.028435 -283.806392) (xy 131.03253 -283.755664) (xy 131.044709 -283.70625) (xy 131.064657 -283.65943)
			(xy 131.091858 -283.616416) (xy 131.125606 -283.578322) (xy 131.165028 -283.546135) (xy 131.209102 -283.520689)
			(xy 131.256688 -283.502642) (xy 131.306552 -283.492462) (xy 131.357404 -283.490413) (xy 131.407925 -283.496547)
			(xy 131.456809 -283.510707) (xy 131.502788 -283.532524) (xy 131.544672 -283.561434) (xy 131.581376 -283.596689)
			(xy 131.611949 -283.637375) (xy 131.6356 -283.682438) (xy 131.651716 -283.730712) (xy 131.65988 -283.780946)
			(xy 131.660392 -283.806392) (xy 131.659889 -283.831381) (xy 131.967206 -283.831381) (xy 131.967206 -283.781403)
			(xy 131.975025 -283.73204) (xy 131.990469 -283.684508) (xy 132.013159 -283.639976) (xy 132.042535 -283.599543)
			(xy 132.077875 -283.564203) (xy 132.118308 -283.534827) (xy 132.16284 -283.512137) (xy 132.210372 -283.496693)
			(xy 132.259735 -283.488874) (xy 132.309713 -283.488874) (xy 132.359076 -283.496693) (xy 132.406608 -283.512137)
			(xy 132.45114 -283.534827) (xy 132.491573 -283.564203) (xy 132.526913 -283.599543) (xy 132.556289 -283.639976)
			(xy 132.578979 -283.684508) (xy 132.594423 -283.73204) (xy 132.602242 -283.781403) (xy 132.602732 -283.806392)
			(xy 132.908543 -283.806392) (xy 132.912638 -283.755664) (xy 132.924817 -283.70625) (xy 132.944765 -283.65943)
			(xy 132.971966 -283.616416) (xy 133.005714 -283.578322) (xy 133.045136 -283.546135) (xy 133.08921 -283.520689)
			(xy 133.136796 -283.502642) (xy 133.18666 -283.492462) (xy 133.237512 -283.490413) (xy 133.288033 -283.496547)
			(xy 133.336917 -283.510707) (xy 133.382896 -283.532524) (xy 133.42478 -283.561434) (xy 133.461484 -283.596689)
			(xy 133.492057 -283.637375) (xy 133.515708 -283.682438) (xy 133.531824 -283.730712) (xy 133.539988 -283.780946)
			(xy 133.5405 -283.806392) (xy 133.539997 -283.831381) (xy 133.847314 -283.831381) (xy 133.847314 -283.781403)
			(xy 133.855133 -283.73204) (xy 133.870577 -283.684508) (xy 133.893267 -283.639976) (xy 133.922643 -283.599543)
			(xy 133.957983 -283.564203) (xy 133.998416 -283.534827) (xy 134.042948 -283.512137) (xy 134.09048 -283.496693)
			(xy 134.139843 -283.488874) (xy 134.189821 -283.488874) (xy 134.239184 -283.496693) (xy 134.286716 -283.512137)
			(xy 134.331248 -283.534827) (xy 134.371681 -283.564203) (xy 134.407021 -283.599543) (xy 134.436397 -283.639976)
			(xy 134.459087 -283.684508) (xy 134.474531 -283.73204) (xy 134.48235 -283.781403) (xy 134.48284 -283.806392)
			(xy 134.788397 -283.806392) (xy 134.792492 -283.755664) (xy 134.804671 -283.70625) (xy 134.824619 -283.65943)
			(xy 134.85182 -283.616416) (xy 134.885568 -283.578322) (xy 134.92499 -283.546135) (xy 134.969064 -283.520689)
			(xy 135.01665 -283.502642) (xy 135.066514 -283.492462) (xy 135.117366 -283.490413) (xy 135.167887 -283.496547)
			(xy 135.216771 -283.510707) (xy 135.26275 -283.532524) (xy 135.304634 -283.561434) (xy 135.341338 -283.596689)
			(xy 135.371911 -283.637375) (xy 135.395562 -283.682438) (xy 135.411678 -283.730712) (xy 135.419842 -283.780946)
			(xy 135.420354 -283.806392) (xy 135.728451 -283.806392) (xy 135.732546 -283.755664) (xy 135.744725 -283.70625)
			(xy 135.764673 -283.65943) (xy 135.791874 -283.616416) (xy 135.825622 -283.578322) (xy 135.865044 -283.546135)
			(xy 135.909118 -283.520689) (xy 135.956704 -283.502642) (xy 136.006568 -283.492462) (xy 136.05742 -283.490413)
			(xy 136.107941 -283.496547) (xy 136.156825 -283.510707) (xy 136.202804 -283.532524) (xy 136.244688 -283.561434)
			(xy 136.281392 -283.596689) (xy 136.311965 -283.637375) (xy 136.335616 -283.682438) (xy 136.351732 -283.730712)
			(xy 136.359896 -283.780946) (xy 136.360408 -283.806392) (xy 136.359905 -283.831381) (xy 136.667222 -283.831381)
			(xy 136.667222 -283.781403) (xy 136.675041 -283.73204) (xy 136.690485 -283.684508) (xy 136.713175 -283.639976)
			(xy 136.742551 -283.599543) (xy 136.777891 -283.564203) (xy 136.818324 -283.534827) (xy 136.862856 -283.512137)
			(xy 136.910388 -283.496693) (xy 136.959751 -283.488874) (xy 137.009729 -283.488874) (xy 137.059092 -283.496693)
			(xy 137.106624 -283.512137) (xy 137.151156 -283.534827) (xy 137.191589 -283.564203) (xy 137.226929 -283.599543)
			(xy 137.256305 -283.639976) (xy 137.278995 -283.684508) (xy 137.294439 -283.73204) (xy 137.302258 -283.781403)
			(xy 137.302748 -283.806392) (xy 137.608559 -283.806392) (xy 137.612654 -283.755664) (xy 137.624833 -283.70625)
			(xy 137.644781 -283.65943) (xy 137.671982 -283.616416) (xy 137.70573 -283.578322) (xy 137.745152 -283.546135)
			(xy 137.789226 -283.520689) (xy 137.836812 -283.502642) (xy 137.886676 -283.492462) (xy 137.937528 -283.490413)
			(xy 137.988049 -283.496547) (xy 138.036933 -283.510707) (xy 138.082912 -283.532524) (xy 138.124796 -283.561434)
			(xy 138.1615 -283.596689) (xy 138.192073 -283.637375) (xy 138.215724 -283.682438) (xy 138.23184 -283.730712)
			(xy 138.240004 -283.780946) (xy 138.240516 -283.806392) (xy 138.240013 -283.831381) (xy 138.54733 -283.831381)
			(xy 138.54733 -283.781403) (xy 138.555149 -283.73204) (xy 138.570593 -283.684508) (xy 138.593283 -283.639976)
			(xy 138.622659 -283.599543) (xy 138.657999 -283.564203) (xy 138.698432 -283.534827) (xy 138.742964 -283.512137)
			(xy 138.790496 -283.496693) (xy 138.839859 -283.488874) (xy 138.889837 -283.488874) (xy 138.9392 -283.496693)
			(xy 138.986732 -283.512137) (xy 139.031264 -283.534827) (xy 139.071697 -283.564203) (xy 139.107037 -283.599543)
			(xy 139.136413 -283.639976) (xy 139.159103 -283.684508) (xy 139.174547 -283.73204) (xy 139.182366 -283.781403)
			(xy 139.182856 -283.806392) (xy 139.488413 -283.806392) (xy 139.492508 -283.755664) (xy 139.504687 -283.70625)
			(xy 139.524635 -283.65943) (xy 139.551836 -283.616416) (xy 139.585584 -283.578322) (xy 139.625006 -283.546135)
			(xy 139.66908 -283.520689) (xy 139.716666 -283.502642) (xy 139.76653 -283.492462) (xy 139.817382 -283.490413)
			(xy 139.867903 -283.496547) (xy 139.916787 -283.510707) (xy 139.962766 -283.532524) (xy 140.00465 -283.561434)
			(xy 140.041354 -283.596689) (xy 140.071927 -283.637375) (xy 140.095578 -283.682438) (xy 140.111694 -283.730712)
			(xy 140.119858 -283.780946) (xy 140.12037 -283.806392) (xy 140.119867 -283.831381) (xy 140.427184 -283.831381)
			(xy 140.427184 -283.781403) (xy 140.435003 -283.73204) (xy 140.450447 -283.684508) (xy 140.473137 -283.639976)
			(xy 140.502513 -283.599543) (xy 140.537853 -283.564203) (xy 140.578286 -283.534827) (xy 140.622818 -283.512137)
			(xy 140.67035 -283.496693) (xy 140.719713 -283.488874) (xy 140.769691 -283.488874) (xy 140.819054 -283.496693)
			(xy 140.866586 -283.512137) (xy 140.911118 -283.534827) (xy 140.951551 -283.564203) (xy 140.986891 -283.599543)
			(xy 141.016267 -283.639976) (xy 141.038957 -283.684508) (xy 141.054401 -283.73204) (xy 141.06222 -283.781403)
			(xy 141.06271 -283.806392) (xy 141.368521 -283.806392) (xy 141.372616 -283.755664) (xy 141.384795 -283.70625)
			(xy 141.404743 -283.65943) (xy 141.431944 -283.616416) (xy 141.465692 -283.578322) (xy 141.505114 -283.546135)
			(xy 141.549188 -283.520689) (xy 141.596774 -283.502642) (xy 141.646638 -283.492462) (xy 141.69749 -283.490413)
			(xy 141.748011 -283.496547) (xy 141.796895 -283.510707) (xy 141.842874 -283.532524) (xy 141.884758 -283.561434)
			(xy 141.921462 -283.596689) (xy 141.952035 -283.637375) (xy 141.975686 -283.682438) (xy 141.991802 -283.730712)
			(xy 141.999966 -283.780946) (xy 142.000478 -283.806392) (xy 142.308575 -283.806392) (xy 142.31267 -283.755664)
			(xy 142.324849 -283.70625) (xy 142.344797 -283.65943) (xy 142.371998 -283.616416) (xy 142.405746 -283.578322)
			(xy 142.445168 -283.546135) (xy 142.489242 -283.520689) (xy 142.536828 -283.502642) (xy 142.586692 -283.492462)
			(xy 142.637544 -283.490413) (xy 142.688065 -283.496547) (xy 142.736949 -283.510707) (xy 142.782928 -283.532524)
			(xy 142.824812 -283.561434) (xy 142.861516 -283.596689) (xy 142.892089 -283.637375) (xy 142.91574 -283.682438)
			(xy 142.931856 -283.730712) (xy 142.94002 -283.780946) (xy 142.940532 -283.806392) (xy 142.940029 -283.831381)
			(xy 143.247092 -283.831381) (xy 143.247092 -283.781403) (xy 143.254911 -283.73204) (xy 143.270355 -283.684508)
			(xy 143.293045 -283.639976) (xy 143.322421 -283.599543) (xy 143.357761 -283.564203) (xy 143.398194 -283.534827)
			(xy 143.442726 -283.512137) (xy 143.490258 -283.496693) (xy 143.539621 -283.488874) (xy 143.589599 -283.488874)
			(xy 143.638962 -283.496693) (xy 143.686494 -283.512137) (xy 143.731026 -283.534827) (xy 143.771459 -283.564203)
			(xy 143.806799 -283.599543) (xy 143.836175 -283.639976) (xy 143.858865 -283.684508) (xy 143.874309 -283.73204)
			(xy 143.882128 -283.781403) (xy 143.882618 -283.806392) (xy 143.882128 -283.831381) (xy 143.874309 -283.880744)
			(xy 143.858865 -283.928276) (xy 143.836175 -283.972808) (xy 143.806799 -284.013241) (xy 143.771459 -284.048581)
			(xy 143.731026 -284.077957) (xy 143.686494 -284.100647) (xy 143.638962 -284.116091) (xy 143.589599 -284.12391)
			(xy 143.539621 -284.12391) (xy 143.490258 -284.116091) (xy 143.442726 -284.100647) (xy 143.398194 -284.077957)
			(xy 143.357761 -284.048581) (xy 143.322421 -284.013241) (xy 143.293045 -283.972808) (xy 143.270355 -283.928276)
			(xy 143.254911 -283.880744) (xy 143.247092 -283.831381) (xy 142.940029 -283.831381) (xy 142.94002 -283.831838)
			(xy 142.931856 -283.882072) (xy 142.91574 -283.930346) (xy 142.892089 -283.975409) (xy 142.861516 -284.016095)
			(xy 142.824812 -284.05135) (xy 142.782928 -284.08026) (xy 142.736949 -284.102077) (xy 142.688065 -284.116237)
			(xy 142.637544 -284.122371) (xy 142.586692 -284.120322) (xy 142.536828 -284.110142) (xy 142.489242 -284.092095)
			(xy 142.445168 -284.066649) (xy 142.405746 -284.034462) (xy 142.371998 -283.996368) (xy 142.344797 -283.953354)
			(xy 142.324849 -283.906534) (xy 142.31267 -283.85712) (xy 142.308575 -283.806392) (xy 142.000478 -283.806392)
			(xy 141.999966 -283.831838) (xy 141.991802 -283.882072) (xy 141.975686 -283.930346) (xy 141.952035 -283.975409)
			(xy 141.921462 -284.016095) (xy 141.884758 -284.05135) (xy 141.842874 -284.08026) (xy 141.796895 -284.102077)
			(xy 141.748011 -284.116237) (xy 141.69749 -284.122371) (xy 141.646638 -284.120322) (xy 141.596774 -284.110142)
			(xy 141.549188 -284.092095) (xy 141.505114 -284.066649) (xy 141.465692 -284.034462) (xy 141.431944 -283.996368)
			(xy 141.404743 -283.953354) (xy 141.384795 -283.906534) (xy 141.372616 -283.85712) (xy 141.368521 -283.806392)
			(xy 141.06271 -283.806392) (xy 141.06222 -283.831381) (xy 141.054401 -283.880744) (xy 141.038957 -283.928276)
			(xy 141.016267 -283.972808) (xy 140.986891 -284.013241) (xy 140.951551 -284.048581) (xy 140.911118 -284.077957)
			(xy 140.866586 -284.100647) (xy 140.819054 -284.116091) (xy 140.769691 -284.12391) (xy 140.719713 -284.12391)
			(xy 140.67035 -284.116091) (xy 140.622818 -284.100647) (xy 140.578286 -284.077957) (xy 140.537853 -284.048581)
			(xy 140.502513 -284.013241) (xy 140.473137 -283.972808) (xy 140.450447 -283.928276) (xy 140.435003 -283.880744)
			(xy 140.427184 -283.831381) (xy 140.119867 -283.831381) (xy 140.119858 -283.831838) (xy 140.111694 -283.882072)
			(xy 140.095578 -283.930346) (xy 140.071927 -283.975409) (xy 140.041354 -284.016095) (xy 140.00465 -284.05135)
			(xy 139.962766 -284.08026) (xy 139.916787 -284.102077) (xy 139.867903 -284.116237) (xy 139.817382 -284.122371)
			(xy 139.76653 -284.120322) (xy 139.716666 -284.110142) (xy 139.66908 -284.092095) (xy 139.625006 -284.066649)
			(xy 139.585584 -284.034462) (xy 139.551836 -283.996368) (xy 139.524635 -283.953354) (xy 139.504687 -283.906534)
			(xy 139.492508 -283.85712) (xy 139.488413 -283.806392) (xy 139.182856 -283.806392) (xy 139.182366 -283.831381)
			(xy 139.174547 -283.880744) (xy 139.159103 -283.928276) (xy 139.136413 -283.972808) (xy 139.107037 -284.013241)
			(xy 139.071697 -284.048581) (xy 139.031264 -284.077957) (xy 138.986732 -284.100647) (xy 138.9392 -284.116091)
			(xy 138.889837 -284.12391) (xy 138.839859 -284.12391) (xy 138.790496 -284.116091) (xy 138.742964 -284.100647)
			(xy 138.698432 -284.077957) (xy 138.657999 -284.048581) (xy 138.622659 -284.013241) (xy 138.593283 -283.972808)
			(xy 138.570593 -283.928276) (xy 138.555149 -283.880744) (xy 138.54733 -283.831381) (xy 138.240013 -283.831381)
			(xy 138.240004 -283.831838) (xy 138.23184 -283.882072) (xy 138.215724 -283.930346) (xy 138.192073 -283.975409)
			(xy 138.1615 -284.016095) (xy 138.124796 -284.05135) (xy 138.082912 -284.08026) (xy 138.036933 -284.102077)
			(xy 137.988049 -284.116237) (xy 137.937528 -284.122371) (xy 137.886676 -284.120322) (xy 137.836812 -284.110142)
			(xy 137.789226 -284.092095) (xy 137.745152 -284.066649) (xy 137.70573 -284.034462) (xy 137.671982 -283.996368)
			(xy 137.644781 -283.953354) (xy 137.624833 -283.906534) (xy 137.612654 -283.85712) (xy 137.608559 -283.806392)
			(xy 137.302748 -283.806392) (xy 137.302258 -283.831381) (xy 137.294439 -283.880744) (xy 137.278995 -283.928276)
			(xy 137.256305 -283.972808) (xy 137.226929 -284.013241) (xy 137.191589 -284.048581) (xy 137.151156 -284.077957)
			(xy 137.106624 -284.100647) (xy 137.059092 -284.116091) (xy 137.009729 -284.12391) (xy 136.959751 -284.12391)
			(xy 136.910388 -284.116091) (xy 136.862856 -284.100647) (xy 136.818324 -284.077957) (xy 136.777891 -284.048581)
			(xy 136.742551 -284.013241) (xy 136.713175 -283.972808) (xy 136.690485 -283.928276) (xy 136.675041 -283.880744)
			(xy 136.667222 -283.831381) (xy 136.359905 -283.831381) (xy 136.359896 -283.831838) (xy 136.351732 -283.882072)
			(xy 136.335616 -283.930346) (xy 136.311965 -283.975409) (xy 136.281392 -284.016095) (xy 136.244688 -284.05135)
			(xy 136.202804 -284.08026) (xy 136.156825 -284.102077) (xy 136.107941 -284.116237) (xy 136.05742 -284.122371)
			(xy 136.006568 -284.120322) (xy 135.956704 -284.110142) (xy 135.909118 -284.092095) (xy 135.865044 -284.066649)
			(xy 135.825622 -284.034462) (xy 135.791874 -283.996368) (xy 135.764673 -283.953354) (xy 135.744725 -283.906534)
			(xy 135.732546 -283.85712) (xy 135.728451 -283.806392) (xy 135.420354 -283.806392) (xy 135.419842 -283.831838)
			(xy 135.411678 -283.882072) (xy 135.395562 -283.930346) (xy 135.371911 -283.975409) (xy 135.341338 -284.016095)
			(xy 135.304634 -284.05135) (xy 135.26275 -284.08026) (xy 135.216771 -284.102077) (xy 135.167887 -284.116237)
			(xy 135.117366 -284.122371) (xy 135.066514 -284.120322) (xy 135.01665 -284.110142) (xy 134.969064 -284.092095)
			(xy 134.92499 -284.066649) (xy 134.885568 -284.034462) (xy 134.85182 -283.996368) (xy 134.824619 -283.953354)
			(xy 134.804671 -283.906534) (xy 134.792492 -283.85712) (xy 134.788397 -283.806392) (xy 134.48284 -283.806392)
			(xy 134.48235 -283.831381) (xy 134.474531 -283.880744) (xy 134.459087 -283.928276) (xy 134.436397 -283.972808)
			(xy 134.407021 -284.013241) (xy 134.371681 -284.048581) (xy 134.331248 -284.077957) (xy 134.286716 -284.100647)
			(xy 134.239184 -284.116091) (xy 134.189821 -284.12391) (xy 134.139843 -284.12391) (xy 134.09048 -284.116091)
			(xy 134.042948 -284.100647) (xy 133.998416 -284.077957) (xy 133.957983 -284.048581) (xy 133.922643 -284.013241)
			(xy 133.893267 -283.972808) (xy 133.870577 -283.928276) (xy 133.855133 -283.880744) (xy 133.847314 -283.831381)
			(xy 133.539997 -283.831381) (xy 133.539988 -283.831838) (xy 133.531824 -283.882072) (xy 133.515708 -283.930346)
			(xy 133.492057 -283.975409) (xy 133.461484 -284.016095) (xy 133.42478 -284.05135) (xy 133.382896 -284.08026)
			(xy 133.336917 -284.102077) (xy 133.288033 -284.116237) (xy 133.237512 -284.122371) (xy 133.18666 -284.120322)
			(xy 133.136796 -284.110142) (xy 133.08921 -284.092095) (xy 133.045136 -284.066649) (xy 133.005714 -284.034462)
			(xy 132.971966 -283.996368) (xy 132.944765 -283.953354) (xy 132.924817 -283.906534) (xy 132.912638 -283.85712)
			(xy 132.908543 -283.806392) (xy 132.602732 -283.806392) (xy 132.602242 -283.831381) (xy 132.594423 -283.880744)
			(xy 132.578979 -283.928276) (xy 132.556289 -283.972808) (xy 132.526913 -284.013241) (xy 132.491573 -284.048581)
			(xy 132.45114 -284.077957) (xy 132.406608 -284.100647) (xy 132.359076 -284.116091) (xy 132.309713 -284.12391)
			(xy 132.259735 -284.12391) (xy 132.210372 -284.116091) (xy 132.16284 -284.100647) (xy 132.118308 -284.077957)
			(xy 132.077875 -284.048581) (xy 132.042535 -284.013241) (xy 132.013159 -283.972808) (xy 131.990469 -283.928276)
			(xy 131.975025 -283.880744) (xy 131.967206 -283.831381) (xy 131.659889 -283.831381) (xy 131.65988 -283.831838)
			(xy 131.651716 -283.882072) (xy 131.6356 -283.930346) (xy 131.611949 -283.975409) (xy 131.581376 -284.016095)
			(xy 131.544672 -284.05135) (xy 131.502788 -284.08026) (xy 131.456809 -284.102077) (xy 131.407925 -284.116237)
			(xy 131.357404 -284.122371) (xy 131.306552 -284.120322) (xy 131.256688 -284.110142) (xy 131.209102 -284.092095)
			(xy 131.165028 -284.066649) (xy 131.125606 -284.034462) (xy 131.091858 -283.996368) (xy 131.064657 -283.953354)
			(xy 131.044709 -283.906534) (xy 131.03253 -283.85712) (xy 131.028435 -283.806392) (xy 130.722878 -283.806392)
			(xy 130.722388 -283.831381) (xy 130.714569 -283.880744) (xy 130.699125 -283.928276) (xy 130.676435 -283.972808)
			(xy 130.647059 -284.013241) (xy 130.611719 -284.048581) (xy 130.571286 -284.077957) (xy 130.526754 -284.100647)
			(xy 130.479222 -284.116091) (xy 130.429859 -284.12391) (xy 130.379881 -284.12391) (xy 130.330518 -284.116091)
			(xy 130.282986 -284.100647) (xy 130.238454 -284.077957) (xy 130.198021 -284.048581) (xy 130.162681 -284.013241)
			(xy 130.133305 -283.972808) (xy 130.110615 -283.928276) (xy 130.095171 -283.880744) (xy 130.087352 -283.831381)
			(xy 129.780035 -283.831381) (xy 129.780026 -283.831838) (xy 129.771862 -283.882072) (xy 129.755746 -283.930346)
			(xy 129.732095 -283.975409) (xy 129.701522 -284.016095) (xy 129.664818 -284.05135) (xy 129.622934 -284.08026)
			(xy 129.576955 -284.102077) (xy 129.528071 -284.116237) (xy 129.47755 -284.122371) (xy 129.426698 -284.120322)
			(xy 129.376834 -284.110142) (xy 129.329248 -284.092095) (xy 129.285174 -284.066649) (xy 129.245752 -284.034462)
			(xy 129.212004 -283.996368) (xy 129.184803 -283.953354) (xy 129.164855 -283.906534) (xy 129.152676 -283.85712)
			(xy 129.148581 -283.806392) (xy 128.840484 -283.806392) (xy 128.839972 -283.831838) (xy 128.831808 -283.882072)
			(xy 128.815692 -283.930346) (xy 128.792041 -283.975409) (xy 128.761468 -284.016095) (xy 128.724764 -284.05135)
			(xy 128.68288 -284.08026) (xy 128.636901 -284.102077) (xy 128.588017 -284.116237) (xy 128.537496 -284.122371)
			(xy 128.486644 -284.120322) (xy 128.43678 -284.110142) (xy 128.389194 -284.092095) (xy 128.34512 -284.066649)
			(xy 128.305698 -284.034462) (xy 128.27195 -283.996368) (xy 128.244749 -283.953354) (xy 128.224801 -283.906534)
			(xy 128.212622 -283.85712) (xy 128.208527 -283.806392) (xy 127.902716 -283.806392) (xy 127.902226 -283.831382)
			(xy 127.894409 -283.880746) (xy 127.878966 -283.92828) (xy 127.856276 -283.972813) (xy 127.8269 -284.013248)
			(xy 127.79156 -284.04859) (xy 127.751127 -284.077968) (xy 127.706595 -284.100659) (xy 127.659062 -284.116105)
			(xy 127.609698 -284.123925) (xy 127.584708 -284.1244) (xy 127.584454 -284.1244) (xy 127.561327 -284.123979)
			(xy 127.515559 -284.117281) (xy 127.471238 -284.104049) (xy 127.450088 -284.094682) (xy 127.442722 -284.091126)
			(xy 127.432816 -284.0863) (xy 127.42418 -284.08503) (xy 127.415529 -284.084202) (xy 127.398517 -284.087695)
			(xy 127.390906 -284.091888) (xy 127.31877 -284.13583) (xy 127.311514 -284.14065) (xy 127.300527 -284.154153)
			(xy 127.294707 -284.17056) (xy 127.294386 -284.179264) (xy 127.294386 -284.31109) (xy 127.295656 -284.321758)
			(xy 127.297688 -284.331664) (xy 127.298958 -284.338014) (xy 127.308864 -284.358334) (xy 127.310843 -284.362317)
			(xy 127.315947 -284.369601) (xy 127.319024 -284.372812) (xy 127.321564 -284.374844) (xy 127.34206 -284.393125)
			(xy 127.377052 -284.435451) (xy 127.404245 -284.483162) (xy 127.422831 -284.534838) (xy 127.432255 -284.58894)
			(xy 127.432816 -284.616398) (xy 127.738627 -284.616398) (xy 127.742722 -284.56567) (xy 127.754901 -284.516256)
			(xy 127.774849 -284.469436) (xy 127.80205 -284.426422) (xy 127.835798 -284.388328) (xy 127.87522 -284.356141)
			(xy 127.919294 -284.330695) (xy 127.96688 -284.312648) (xy 128.016744 -284.302468) (xy 128.067596 -284.300419)
			(xy 128.118117 -284.306553) (xy 128.167001 -284.320713) (xy 128.21298 -284.34253) (xy 128.254864 -284.37144)
			(xy 128.291568 -284.406695) (xy 128.322141 -284.447381) (xy 128.345792 -284.492444) (xy 128.361908 -284.540718)
			(xy 128.370072 -284.590952) (xy 128.370584 -284.616398) (xy 128.370081 -284.641387) (xy 128.677144 -284.641387)
			(xy 128.677144 -284.591409) (xy 128.684963 -284.542046) (xy 128.700407 -284.494514) (xy 128.723097 -284.449982)
			(xy 128.752473 -284.409549) (xy 128.787813 -284.374209) (xy 128.828246 -284.344833) (xy 128.872778 -284.322143)
			(xy 128.92031 -284.306699) (xy 128.969673 -284.29888) (xy 129.019651 -284.29888) (xy 129.069014 -284.306699)
			(xy 129.116546 -284.322143) (xy 129.161078 -284.344833) (xy 129.201511 -284.374209) (xy 129.236851 -284.409549)
			(xy 129.266227 -284.449982) (xy 129.288917 -284.494514) (xy 129.304361 -284.542046) (xy 129.31218 -284.591409)
			(xy 129.31267 -284.616398) (xy 129.618481 -284.616398) (xy 129.622576 -284.56567) (xy 129.634755 -284.516256)
			(xy 129.654703 -284.469436) (xy 129.681904 -284.426422) (xy 129.715652 -284.388328) (xy 129.755074 -284.356141)
			(xy 129.799148 -284.330695) (xy 129.846734 -284.312648) (xy 129.896598 -284.302468) (xy 129.94745 -284.300419)
			(xy 129.997971 -284.306553) (xy 130.046855 -284.320713) (xy 130.092834 -284.34253) (xy 130.134718 -284.37144)
			(xy 130.171422 -284.406695) (xy 130.201995 -284.447381) (xy 130.225646 -284.492444) (xy 130.241762 -284.540718)
			(xy 130.249926 -284.590952) (xy 130.250438 -284.616398) (xy 130.249935 -284.641387) (xy 130.557252 -284.641387)
			(xy 130.557252 -284.591409) (xy 130.565071 -284.542046) (xy 130.580515 -284.494514) (xy 130.603205 -284.449982)
			(xy 130.632581 -284.409549) (xy 130.667921 -284.374209) (xy 130.708354 -284.344833) (xy 130.752886 -284.322143)
			(xy 130.800418 -284.306699) (xy 130.849781 -284.29888) (xy 130.899759 -284.29888) (xy 130.949122 -284.306699)
			(xy 130.996654 -284.322143) (xy 131.041186 -284.344833) (xy 131.081619 -284.374209) (xy 131.116959 -284.409549)
			(xy 131.146335 -284.449982) (xy 131.169025 -284.494514) (xy 131.184469 -284.542046) (xy 131.192288 -284.591409)
			(xy 131.192778 -284.616398) (xy 131.498589 -284.616398) (xy 131.502684 -284.56567) (xy 131.514863 -284.516256)
			(xy 131.534811 -284.469436) (xy 131.562012 -284.426422) (xy 131.59576 -284.388328) (xy 131.635182 -284.356141)
			(xy 131.679256 -284.330695) (xy 131.726842 -284.312648) (xy 131.776706 -284.302468) (xy 131.827558 -284.300419)
			(xy 131.878079 -284.306553) (xy 131.926963 -284.320713) (xy 131.972942 -284.34253) (xy 132.014826 -284.37144)
			(xy 132.05153 -284.406695) (xy 132.082103 -284.447381) (xy 132.105754 -284.492444) (xy 132.12187 -284.540718)
			(xy 132.130034 -284.590952) (xy 132.130546 -284.616398) (xy 132.438643 -284.616398) (xy 132.442738 -284.56567)
			(xy 132.454917 -284.516256) (xy 132.474865 -284.469436) (xy 132.502066 -284.426422) (xy 132.535814 -284.388328)
			(xy 132.575236 -284.356141) (xy 132.61931 -284.330695) (xy 132.666896 -284.312648) (xy 132.71676 -284.302468)
			(xy 132.767612 -284.300419) (xy 132.818133 -284.306553) (xy 132.867017 -284.320713) (xy 132.912996 -284.34253)
			(xy 132.95488 -284.37144) (xy 132.991584 -284.406695) (xy 133.022157 -284.447381) (xy 133.045808 -284.492444)
			(xy 133.061924 -284.540718) (xy 133.070088 -284.590952) (xy 133.0706 -284.616398) (xy 133.070097 -284.641387)
			(xy 133.37716 -284.641387) (xy 133.37716 -284.591409) (xy 133.384979 -284.542046) (xy 133.400423 -284.494514)
			(xy 133.423113 -284.449982) (xy 133.452489 -284.409549) (xy 133.487829 -284.374209) (xy 133.528262 -284.344833)
			(xy 133.572794 -284.322143) (xy 133.620326 -284.306699) (xy 133.669689 -284.29888) (xy 133.719667 -284.29888)
			(xy 133.76903 -284.306699) (xy 133.816562 -284.322143) (xy 133.861094 -284.344833) (xy 133.901527 -284.374209)
			(xy 133.936867 -284.409549) (xy 133.966243 -284.449982) (xy 133.988933 -284.494514) (xy 134.004377 -284.542046)
			(xy 134.012196 -284.591409) (xy 134.012686 -284.616398) (xy 134.318497 -284.616398) (xy 134.322592 -284.56567)
			(xy 134.334771 -284.516256) (xy 134.354719 -284.469436) (xy 134.38192 -284.426422) (xy 134.415668 -284.388328)
			(xy 134.45509 -284.356141) (xy 134.499164 -284.330695) (xy 134.54675 -284.312648) (xy 134.596614 -284.302468)
			(xy 134.647466 -284.300419) (xy 134.697987 -284.306553) (xy 134.746871 -284.320713) (xy 134.79285 -284.34253)
			(xy 134.834734 -284.37144) (xy 134.871438 -284.406695) (xy 134.902011 -284.447381) (xy 134.925662 -284.492444)
			(xy 134.941778 -284.540718) (xy 134.949942 -284.590952) (xy 134.950454 -284.616398) (xy 134.949951 -284.641387)
			(xy 135.257268 -284.641387) (xy 135.257268 -284.591409) (xy 135.265087 -284.542046) (xy 135.280531 -284.494514)
			(xy 135.303221 -284.449982) (xy 135.332597 -284.409549) (xy 135.367937 -284.374209) (xy 135.40837 -284.344833)
			(xy 135.452902 -284.322143) (xy 135.500434 -284.306699) (xy 135.549797 -284.29888) (xy 135.599775 -284.29888)
			(xy 135.649138 -284.306699) (xy 135.69667 -284.322143) (xy 135.741202 -284.344833) (xy 135.781635 -284.374209)
			(xy 135.816975 -284.409549) (xy 135.846351 -284.449982) (xy 135.869041 -284.494514) (xy 135.884485 -284.542046)
			(xy 135.892304 -284.591409) (xy 135.892794 -284.616398) (xy 136.198605 -284.616398) (xy 136.2027 -284.56567)
			(xy 136.214879 -284.516256) (xy 136.234827 -284.469436) (xy 136.262028 -284.426422) (xy 136.295776 -284.388328)
			(xy 136.335198 -284.356141) (xy 136.379272 -284.330695) (xy 136.426858 -284.312648) (xy 136.476722 -284.302468)
			(xy 136.527574 -284.300419) (xy 136.578095 -284.306553) (xy 136.626979 -284.320713) (xy 136.672958 -284.34253)
			(xy 136.714842 -284.37144) (xy 136.751546 -284.406695) (xy 136.782119 -284.447381) (xy 136.80577 -284.492444)
			(xy 136.821886 -284.540718) (xy 136.83005 -284.590952) (xy 136.830562 -284.616398) (xy 136.830059 -284.641387)
			(xy 137.137122 -284.641387) (xy 137.137122 -284.591409) (xy 137.144941 -284.542046) (xy 137.160385 -284.494514)
			(xy 137.183075 -284.449982) (xy 137.212451 -284.409549) (xy 137.247791 -284.374209) (xy 137.288224 -284.344833)
			(xy 137.332756 -284.322143) (xy 137.380288 -284.306699) (xy 137.429651 -284.29888) (xy 137.479629 -284.29888)
			(xy 137.528992 -284.306699) (xy 137.576524 -284.322143) (xy 137.621056 -284.344833) (xy 137.661489 -284.374209)
			(xy 137.696829 -284.409549) (xy 137.726205 -284.449982) (xy 137.748895 -284.494514) (xy 137.764339 -284.542046)
			(xy 137.772158 -284.591409) (xy 137.772648 -284.616398) (xy 138.078459 -284.616398) (xy 138.082554 -284.56567)
			(xy 138.094733 -284.516256) (xy 138.114681 -284.469436) (xy 138.141882 -284.426422) (xy 138.17563 -284.388328)
			(xy 138.215052 -284.356141) (xy 138.259126 -284.330695) (xy 138.306712 -284.312648) (xy 138.356576 -284.302468)
			(xy 138.407428 -284.300419) (xy 138.457949 -284.306553) (xy 138.506833 -284.320713) (xy 138.552812 -284.34253)
			(xy 138.594696 -284.37144) (xy 138.6314 -284.406695) (xy 138.661973 -284.447381) (xy 138.685624 -284.492444)
			(xy 138.70174 -284.540718) (xy 138.709904 -284.590952) (xy 138.710416 -284.616398) (xy 139.018513 -284.616398)
			(xy 139.022608 -284.56567) (xy 139.034787 -284.516256) (xy 139.054735 -284.469436) (xy 139.081936 -284.426422)
			(xy 139.115684 -284.388328) (xy 139.155106 -284.356141) (xy 139.19918 -284.330695) (xy 139.246766 -284.312648)
			(xy 139.29663 -284.302468) (xy 139.347482 -284.300419) (xy 139.398003 -284.306553) (xy 139.446887 -284.320713)
			(xy 139.492866 -284.34253) (xy 139.53475 -284.37144) (xy 139.571454 -284.406695) (xy 139.602027 -284.447381)
			(xy 139.625678 -284.492444) (xy 139.641794 -284.540718) (xy 139.649958 -284.590952) (xy 139.65047 -284.616398)
			(xy 139.649967 -284.641387) (xy 139.957284 -284.641387) (xy 139.957284 -284.591409) (xy 139.965103 -284.542046)
			(xy 139.980547 -284.494514) (xy 140.003237 -284.449982) (xy 140.032613 -284.409549) (xy 140.067953 -284.374209)
			(xy 140.108386 -284.344833) (xy 140.152918 -284.322143) (xy 140.20045 -284.306699) (xy 140.249813 -284.29888)
			(xy 140.299791 -284.29888) (xy 140.349154 -284.306699) (xy 140.396686 -284.322143) (xy 140.441218 -284.344833)
			(xy 140.481651 -284.374209) (xy 140.516991 -284.409549) (xy 140.546367 -284.449982) (xy 140.569057 -284.494514)
			(xy 140.584501 -284.542046) (xy 140.59232 -284.591409) (xy 140.59281 -284.616398) (xy 140.898621 -284.616398)
			(xy 140.902716 -284.56567) (xy 140.914895 -284.516256) (xy 140.934843 -284.469436) (xy 140.962044 -284.426422)
			(xy 140.995792 -284.388328) (xy 141.035214 -284.356141) (xy 141.079288 -284.330695) (xy 141.126874 -284.312648)
			(xy 141.176738 -284.302468) (xy 141.22759 -284.300419) (xy 141.278111 -284.306553) (xy 141.326995 -284.320713)
			(xy 141.372974 -284.34253) (xy 141.414858 -284.37144) (xy 141.451562 -284.406695) (xy 141.482135 -284.447381)
			(xy 141.505786 -284.492444) (xy 141.521902 -284.540718) (xy 141.530066 -284.590952) (xy 141.530578 -284.616398)
			(xy 141.530075 -284.641387) (xy 141.837138 -284.641387) (xy 141.837138 -284.591409) (xy 141.844957 -284.542046)
			(xy 141.860401 -284.494514) (xy 141.883091 -284.449982) (xy 141.912467 -284.409549) (xy 141.947807 -284.374209)
			(xy 141.98824 -284.344833) (xy 142.032772 -284.322143) (xy 142.080304 -284.306699) (xy 142.129667 -284.29888)
			(xy 142.179645 -284.29888) (xy 142.229008 -284.306699) (xy 142.27654 -284.322143) (xy 142.321072 -284.344833)
			(xy 142.361505 -284.374209) (xy 142.396845 -284.409549) (xy 142.426221 -284.449982) (xy 142.448911 -284.494514)
			(xy 142.464355 -284.542046) (xy 142.472174 -284.591409) (xy 142.472664 -284.616398) (xy 142.778475 -284.616398)
			(xy 142.78257 -284.56567) (xy 142.794749 -284.516256) (xy 142.814697 -284.469436) (xy 142.841898 -284.426422)
			(xy 142.875646 -284.388328) (xy 142.915068 -284.356141) (xy 142.959142 -284.330695) (xy 143.006728 -284.312648)
			(xy 143.056592 -284.302468) (xy 143.107444 -284.300419) (xy 143.157965 -284.306553) (xy 143.206849 -284.320713)
			(xy 143.252828 -284.34253) (xy 143.294712 -284.37144) (xy 143.331416 -284.406695) (xy 143.361989 -284.447381)
			(xy 143.38564 -284.492444) (xy 143.401756 -284.540718) (xy 143.40992 -284.590952) (xy 143.410432 -284.616398)
			(xy 143.409929 -284.641387) (xy 143.717246 -284.641387) (xy 143.717246 -284.591409) (xy 143.725065 -284.542046)
			(xy 143.740509 -284.494514) (xy 143.763199 -284.449982) (xy 143.792575 -284.409549) (xy 143.827915 -284.374209)
			(xy 143.868348 -284.344833) (xy 143.91288 -284.322143) (xy 143.960412 -284.306699) (xy 144.009775 -284.29888)
			(xy 144.059753 -284.29888) (xy 144.109116 -284.306699) (xy 144.156648 -284.322143) (xy 144.20118 -284.344833)
			(xy 144.241613 -284.374209) (xy 144.276953 -284.409549) (xy 144.306329 -284.449982) (xy 144.329019 -284.494514)
			(xy 144.344463 -284.542046) (xy 144.352282 -284.591409) (xy 144.352772 -284.616398) (xy 144.352282 -284.641387)
			(xy 144.344463 -284.69075) (xy 144.329019 -284.738282) (xy 144.306329 -284.782814) (xy 144.276953 -284.823247)
			(xy 144.241613 -284.858587) (xy 144.20118 -284.887963) (xy 144.156648 -284.910653) (xy 144.109116 -284.926097)
			(xy 144.059753 -284.933916) (xy 144.009775 -284.933916) (xy 143.960412 -284.926097) (xy 143.91288 -284.910653)
			(xy 143.868348 -284.887963) (xy 143.827915 -284.858587) (xy 143.792575 -284.823247) (xy 143.763199 -284.782814)
			(xy 143.740509 -284.738282) (xy 143.725065 -284.69075) (xy 143.717246 -284.641387) (xy 143.409929 -284.641387)
			(xy 143.40992 -284.641844) (xy 143.401756 -284.692078) (xy 143.38564 -284.740352) (xy 143.361989 -284.785415)
			(xy 143.331416 -284.826101) (xy 143.294712 -284.861356) (xy 143.252828 -284.890266) (xy 143.206849 -284.912083)
			(xy 143.157965 -284.926243) (xy 143.107444 -284.932377) (xy 143.056592 -284.930328) (xy 143.006728 -284.920148)
			(xy 142.959142 -284.902101) (xy 142.915068 -284.876655) (xy 142.875646 -284.844468) (xy 142.841898 -284.806374)
			(xy 142.814697 -284.76336) (xy 142.794749 -284.71654) (xy 142.78257 -284.667126) (xy 142.778475 -284.616398)
			(xy 142.472664 -284.616398) (xy 142.472174 -284.641387) (xy 142.464355 -284.69075) (xy 142.448911 -284.738282)
			(xy 142.426221 -284.782814) (xy 142.396845 -284.823247) (xy 142.361505 -284.858587) (xy 142.321072 -284.887963)
			(xy 142.27654 -284.910653) (xy 142.229008 -284.926097) (xy 142.179645 -284.933916) (xy 142.129667 -284.933916)
			(xy 142.080304 -284.926097) (xy 142.032772 -284.910653) (xy 141.98824 -284.887963) (xy 141.947807 -284.858587)
			(xy 141.912467 -284.823247) (xy 141.883091 -284.782814) (xy 141.860401 -284.738282) (xy 141.844957 -284.69075)
			(xy 141.837138 -284.641387) (xy 141.530075 -284.641387) (xy 141.530066 -284.641844) (xy 141.521902 -284.692078)
			(xy 141.505786 -284.740352) (xy 141.482135 -284.785415) (xy 141.451562 -284.826101) (xy 141.414858 -284.861356)
			(xy 141.372974 -284.890266) (xy 141.326995 -284.912083) (xy 141.278111 -284.926243) (xy 141.22759 -284.932377)
			(xy 141.176738 -284.930328) (xy 141.126874 -284.920148) (xy 141.079288 -284.902101) (xy 141.035214 -284.876655)
			(xy 140.995792 -284.844468) (xy 140.962044 -284.806374) (xy 140.934843 -284.76336) (xy 140.914895 -284.71654)
			(xy 140.902716 -284.667126) (xy 140.898621 -284.616398) (xy 140.59281 -284.616398) (xy 140.59232 -284.641387)
			(xy 140.584501 -284.69075) (xy 140.569057 -284.738282) (xy 140.546367 -284.782814) (xy 140.516991 -284.823247)
			(xy 140.481651 -284.858587) (xy 140.441218 -284.887963) (xy 140.396686 -284.910653) (xy 140.349154 -284.926097)
			(xy 140.299791 -284.933916) (xy 140.249813 -284.933916) (xy 140.20045 -284.926097) (xy 140.152918 -284.910653)
			(xy 140.108386 -284.887963) (xy 140.067953 -284.858587) (xy 140.032613 -284.823247) (xy 140.003237 -284.782814)
			(xy 139.980547 -284.738282) (xy 139.965103 -284.69075) (xy 139.957284 -284.641387) (xy 139.649967 -284.641387)
			(xy 139.649958 -284.641844) (xy 139.641794 -284.692078) (xy 139.625678 -284.740352) (xy 139.602027 -284.785415)
			(xy 139.571454 -284.826101) (xy 139.53475 -284.861356) (xy 139.492866 -284.890266) (xy 139.446887 -284.912083)
			(xy 139.398003 -284.926243) (xy 139.347482 -284.932377) (xy 139.29663 -284.930328) (xy 139.246766 -284.920148)
			(xy 139.19918 -284.902101) (xy 139.155106 -284.876655) (xy 139.115684 -284.844468) (xy 139.081936 -284.806374)
			(xy 139.054735 -284.76336) (xy 139.034787 -284.71654) (xy 139.022608 -284.667126) (xy 139.018513 -284.616398)
			(xy 138.710416 -284.616398) (xy 138.709904 -284.641844) (xy 138.70174 -284.692078) (xy 138.685624 -284.740352)
			(xy 138.661973 -284.785415) (xy 138.6314 -284.826101) (xy 138.594696 -284.861356) (xy 138.552812 -284.890266)
			(xy 138.506833 -284.912083) (xy 138.457949 -284.926243) (xy 138.407428 -284.932377) (xy 138.356576 -284.930328)
			(xy 138.306712 -284.920148) (xy 138.259126 -284.902101) (xy 138.215052 -284.876655) (xy 138.17563 -284.844468)
			(xy 138.141882 -284.806374) (xy 138.114681 -284.76336) (xy 138.094733 -284.71654) (xy 138.082554 -284.667126)
			(xy 138.078459 -284.616398) (xy 137.772648 -284.616398) (xy 137.772158 -284.641387) (xy 137.764339 -284.69075)
			(xy 137.748895 -284.738282) (xy 137.726205 -284.782814) (xy 137.696829 -284.823247) (xy 137.661489 -284.858587)
			(xy 137.621056 -284.887963) (xy 137.576524 -284.910653) (xy 137.528992 -284.926097) (xy 137.479629 -284.933916)
			(xy 137.429651 -284.933916) (xy 137.380288 -284.926097) (xy 137.332756 -284.910653) (xy 137.288224 -284.887963)
			(xy 137.247791 -284.858587) (xy 137.212451 -284.823247) (xy 137.183075 -284.782814) (xy 137.160385 -284.738282)
			(xy 137.144941 -284.69075) (xy 137.137122 -284.641387) (xy 136.830059 -284.641387) (xy 136.83005 -284.641844)
			(xy 136.821886 -284.692078) (xy 136.80577 -284.740352) (xy 136.782119 -284.785415) (xy 136.751546 -284.826101)
			(xy 136.714842 -284.861356) (xy 136.672958 -284.890266) (xy 136.626979 -284.912083) (xy 136.578095 -284.926243)
			(xy 136.527574 -284.932377) (xy 136.476722 -284.930328) (xy 136.426858 -284.920148) (xy 136.379272 -284.902101)
			(xy 136.335198 -284.876655) (xy 136.295776 -284.844468) (xy 136.262028 -284.806374) (xy 136.234827 -284.76336)
			(xy 136.214879 -284.71654) (xy 136.2027 -284.667126) (xy 136.198605 -284.616398) (xy 135.892794 -284.616398)
			(xy 135.892304 -284.641387) (xy 135.884485 -284.69075) (xy 135.869041 -284.738282) (xy 135.846351 -284.782814)
			(xy 135.816975 -284.823247) (xy 135.781635 -284.858587) (xy 135.741202 -284.887963) (xy 135.69667 -284.910653)
			(xy 135.649138 -284.926097) (xy 135.599775 -284.933916) (xy 135.549797 -284.933916) (xy 135.500434 -284.926097)
			(xy 135.452902 -284.910653) (xy 135.40837 -284.887963) (xy 135.367937 -284.858587) (xy 135.332597 -284.823247)
			(xy 135.303221 -284.782814) (xy 135.280531 -284.738282) (xy 135.265087 -284.69075) (xy 135.257268 -284.641387)
			(xy 134.949951 -284.641387) (xy 134.949942 -284.641844) (xy 134.941778 -284.692078) (xy 134.925662 -284.740352)
			(xy 134.902011 -284.785415) (xy 134.871438 -284.826101) (xy 134.834734 -284.861356) (xy 134.79285 -284.890266)
			(xy 134.746871 -284.912083) (xy 134.697987 -284.926243) (xy 134.647466 -284.932377) (xy 134.596614 -284.930328)
			(xy 134.54675 -284.920148) (xy 134.499164 -284.902101) (xy 134.45509 -284.876655) (xy 134.415668 -284.844468)
			(xy 134.38192 -284.806374) (xy 134.354719 -284.76336) (xy 134.334771 -284.71654) (xy 134.322592 -284.667126)
			(xy 134.318497 -284.616398) (xy 134.012686 -284.616398) (xy 134.012196 -284.641387) (xy 134.004377 -284.69075)
			(xy 133.988933 -284.738282) (xy 133.966243 -284.782814) (xy 133.936867 -284.823247) (xy 133.901527 -284.858587)
			(xy 133.861094 -284.887963) (xy 133.816562 -284.910653) (xy 133.76903 -284.926097) (xy 133.719667 -284.933916)
			(xy 133.669689 -284.933916) (xy 133.620326 -284.926097) (xy 133.572794 -284.910653) (xy 133.528262 -284.887963)
			(xy 133.487829 -284.858587) (xy 133.452489 -284.823247) (xy 133.423113 -284.782814) (xy 133.400423 -284.738282)
			(xy 133.384979 -284.69075) (xy 133.37716 -284.641387) (xy 133.070097 -284.641387) (xy 133.070088 -284.641844)
			(xy 133.061924 -284.692078) (xy 133.045808 -284.740352) (xy 133.022157 -284.785415) (xy 132.991584 -284.826101)
			(xy 132.95488 -284.861356) (xy 132.912996 -284.890266) (xy 132.867017 -284.912083) (xy 132.818133 -284.926243)
			(xy 132.767612 -284.932377) (xy 132.71676 -284.930328) (xy 132.666896 -284.920148) (xy 132.61931 -284.902101)
			(xy 132.575236 -284.876655) (xy 132.535814 -284.844468) (xy 132.502066 -284.806374) (xy 132.474865 -284.76336)
			(xy 132.454917 -284.71654) (xy 132.442738 -284.667126) (xy 132.438643 -284.616398) (xy 132.130546 -284.616398)
			(xy 132.130034 -284.641844) (xy 132.12187 -284.692078) (xy 132.105754 -284.740352) (xy 132.082103 -284.785415)
			(xy 132.05153 -284.826101) (xy 132.014826 -284.861356) (xy 131.972942 -284.890266) (xy 131.926963 -284.912083)
			(xy 131.878079 -284.926243) (xy 131.827558 -284.932377) (xy 131.776706 -284.930328) (xy 131.726842 -284.920148)
			(xy 131.679256 -284.902101) (xy 131.635182 -284.876655) (xy 131.59576 -284.844468) (xy 131.562012 -284.806374)
			(xy 131.534811 -284.76336) (xy 131.514863 -284.71654) (xy 131.502684 -284.667126) (xy 131.498589 -284.616398)
			(xy 131.192778 -284.616398) (xy 131.192288 -284.641387) (xy 131.184469 -284.69075) (xy 131.169025 -284.738282)
			(xy 131.146335 -284.782814) (xy 131.116959 -284.823247) (xy 131.081619 -284.858587) (xy 131.041186 -284.887963)
			(xy 130.996654 -284.910653) (xy 130.949122 -284.926097) (xy 130.899759 -284.933916) (xy 130.849781 -284.933916)
			(xy 130.800418 -284.926097) (xy 130.752886 -284.910653) (xy 130.708354 -284.887963) (xy 130.667921 -284.858587)
			(xy 130.632581 -284.823247) (xy 130.603205 -284.782814) (xy 130.580515 -284.738282) (xy 130.565071 -284.69075)
			(xy 130.557252 -284.641387) (xy 130.249935 -284.641387) (xy 130.249926 -284.641844) (xy 130.241762 -284.692078)
			(xy 130.225646 -284.740352) (xy 130.201995 -284.785415) (xy 130.171422 -284.826101) (xy 130.134718 -284.861356)
			(xy 130.092834 -284.890266) (xy 130.046855 -284.912083) (xy 129.997971 -284.926243) (xy 129.94745 -284.932377)
			(xy 129.896598 -284.930328) (xy 129.846734 -284.920148) (xy 129.799148 -284.902101) (xy 129.755074 -284.876655)
			(xy 129.715652 -284.844468) (xy 129.681904 -284.806374) (xy 129.654703 -284.76336) (xy 129.634755 -284.71654)
			(xy 129.622576 -284.667126) (xy 129.618481 -284.616398) (xy 129.31267 -284.616398) (xy 129.31218 -284.641387)
			(xy 129.304361 -284.69075) (xy 129.288917 -284.738282) (xy 129.266227 -284.782814) (xy 129.236851 -284.823247)
			(xy 129.201511 -284.858587) (xy 129.161078 -284.887963) (xy 129.116546 -284.910653) (xy 129.069014 -284.926097)
			(xy 129.019651 -284.933916) (xy 128.969673 -284.933916) (xy 128.92031 -284.926097) (xy 128.872778 -284.910653)
			(xy 128.828246 -284.887963) (xy 128.787813 -284.858587) (xy 128.752473 -284.823247) (xy 128.723097 -284.782814)
			(xy 128.700407 -284.738282) (xy 128.684963 -284.69075) (xy 128.677144 -284.641387) (xy 128.370081 -284.641387)
			(xy 128.370072 -284.641844) (xy 128.361908 -284.692078) (xy 128.345792 -284.740352) (xy 128.322141 -284.785415)
			(xy 128.291568 -284.826101) (xy 128.254864 -284.861356) (xy 128.21298 -284.890266) (xy 128.167001 -284.912083)
			(xy 128.118117 -284.926243) (xy 128.067596 -284.932377) (xy 128.016744 -284.930328) (xy 127.96688 -284.920148)
			(xy 127.919294 -284.902101) (xy 127.87522 -284.876655) (xy 127.835798 -284.844468) (xy 127.80205 -284.806374)
			(xy 127.774849 -284.76336) (xy 127.754901 -284.71654) (xy 127.742722 -284.667126) (xy 127.738627 -284.616398)
			(xy 127.432816 -284.616398) (xy 127.43225 -284.643732) (xy 127.422912 -284.697596) (xy 127.404508 -284.749073)
			(xy 127.377581 -284.796649) (xy 127.342923 -284.838925) (xy 127.32258 -284.85719) (xy 127.321056 -284.85846)
			(xy 127.317754 -284.861762) (xy 127.31495 -284.864717) (xy 127.310222 -284.871349) (xy 127.308356 -284.87497)
			(xy 127.29845 -284.896052) (xy 127.296926 -284.90037) (xy 127.295779 -284.904142) (xy 127.294501 -284.911923)
			(xy 127.294386 -284.915864) (xy 127.294386 -285.426404) (xy 128.208527 -285.426404) (xy 128.212622 -285.375676)
			(xy 128.224801 -285.326262) (xy 128.244749 -285.279442) (xy 128.27195 -285.236428) (xy 128.305698 -285.198334)
			(xy 128.34512 -285.166147) (xy 128.389194 -285.140701) (xy 128.43678 -285.122654) (xy 128.486644 -285.112474)
			(xy 128.537496 -285.110425) (xy 128.588017 -285.116559) (xy 128.636901 -285.130719) (xy 128.68288 -285.152536)
			(xy 128.724764 -285.181446) (xy 128.761468 -285.216701) (xy 128.792041 -285.257387) (xy 128.815692 -285.30245)
			(xy 128.831808 -285.350724) (xy 128.839972 -285.400958) (xy 128.840484 -285.426404) (xy 129.148581 -285.426404)
			(xy 129.152676 -285.375676) (xy 129.164855 -285.326262) (xy 129.184803 -285.279442) (xy 129.212004 -285.236428)
			(xy 129.245752 -285.198334) (xy 129.285174 -285.166147) (xy 129.329248 -285.140701) (xy 129.376834 -285.122654)
			(xy 129.426698 -285.112474) (xy 129.47755 -285.110425) (xy 129.528071 -285.116559) (xy 129.576955 -285.130719)
			(xy 129.622934 -285.152536) (xy 129.664818 -285.181446) (xy 129.701522 -285.216701) (xy 129.732095 -285.257387)
			(xy 129.755746 -285.30245) (xy 129.771862 -285.350724) (xy 129.780026 -285.400958) (xy 129.780538 -285.426404)
			(xy 131.028435 -285.426404) (xy 131.03253 -285.375676) (xy 131.044709 -285.326262) (xy 131.064657 -285.279442)
			(xy 131.091858 -285.236428) (xy 131.125606 -285.198334) (xy 131.165028 -285.166147) (xy 131.209102 -285.140701)
			(xy 131.256688 -285.122654) (xy 131.306552 -285.112474) (xy 131.357404 -285.110425) (xy 131.407925 -285.116559)
			(xy 131.456809 -285.130719) (xy 131.502788 -285.152536) (xy 131.544672 -285.181446) (xy 131.581376 -285.216701)
			(xy 131.611949 -285.257387) (xy 131.6356 -285.30245) (xy 131.651716 -285.350724) (xy 131.65988 -285.400958)
			(xy 131.660392 -285.426404) (xy 131.659889 -285.451393) (xy 131.967206 -285.451393) (xy 131.967206 -285.401415)
			(xy 131.975025 -285.352052) (xy 131.990469 -285.30452) (xy 132.013159 -285.259988) (xy 132.042535 -285.219555)
			(xy 132.077875 -285.184215) (xy 132.118308 -285.154839) (xy 132.16284 -285.132149) (xy 132.210372 -285.116705)
			(xy 132.259735 -285.108886) (xy 132.309713 -285.108886) (xy 132.359076 -285.116705) (xy 132.406608 -285.132149)
			(xy 132.45114 -285.154839) (xy 132.491573 -285.184215) (xy 132.526913 -285.219555) (xy 132.556289 -285.259988)
			(xy 132.578979 -285.30452) (xy 132.594423 -285.352052) (xy 132.602242 -285.401415) (xy 132.602732 -285.426404)
			(xy 132.908543 -285.426404) (xy 132.912638 -285.375676) (xy 132.924817 -285.326262) (xy 132.944765 -285.279442)
			(xy 132.971966 -285.236428) (xy 133.005714 -285.198334) (xy 133.045136 -285.166147) (xy 133.08921 -285.140701)
			(xy 133.136796 -285.122654) (xy 133.18666 -285.112474) (xy 133.237512 -285.110425) (xy 133.288033 -285.116559)
			(xy 133.336917 -285.130719) (xy 133.382896 -285.152536) (xy 133.42478 -285.181446) (xy 133.461484 -285.216701)
			(xy 133.492057 -285.257387) (xy 133.515708 -285.30245) (xy 133.531824 -285.350724) (xy 133.539988 -285.400958)
			(xy 133.5405 -285.426404) (xy 133.539997 -285.451393) (xy 133.847314 -285.451393) (xy 133.847314 -285.401415)
			(xy 133.855133 -285.352052) (xy 133.870577 -285.30452) (xy 133.893267 -285.259988) (xy 133.922643 -285.219555)
			(xy 133.957983 -285.184215) (xy 133.998416 -285.154839) (xy 134.042948 -285.132149) (xy 134.09048 -285.116705)
			(xy 134.139843 -285.108886) (xy 134.189821 -285.108886) (xy 134.239184 -285.116705) (xy 134.286716 -285.132149)
			(xy 134.331248 -285.154839) (xy 134.371681 -285.184215) (xy 134.407021 -285.219555) (xy 134.436397 -285.259988)
			(xy 134.459087 -285.30452) (xy 134.474531 -285.352052) (xy 134.48235 -285.401415) (xy 134.48284 -285.426404)
			(xy 134.788397 -285.426404) (xy 134.792492 -285.375676) (xy 134.804671 -285.326262) (xy 134.824619 -285.279442)
			(xy 134.85182 -285.236428) (xy 134.885568 -285.198334) (xy 134.92499 -285.166147) (xy 134.969064 -285.140701)
			(xy 135.01665 -285.122654) (xy 135.066514 -285.112474) (xy 135.117366 -285.110425) (xy 135.167887 -285.116559)
			(xy 135.216771 -285.130719) (xy 135.26275 -285.152536) (xy 135.304634 -285.181446) (xy 135.341338 -285.216701)
			(xy 135.371911 -285.257387) (xy 135.395562 -285.30245) (xy 135.411678 -285.350724) (xy 135.419842 -285.400958)
			(xy 135.420354 -285.426404) (xy 135.728451 -285.426404) (xy 135.732546 -285.375676) (xy 135.744725 -285.326262)
			(xy 135.764673 -285.279442) (xy 135.791874 -285.236428) (xy 135.825622 -285.198334) (xy 135.865044 -285.166147)
			(xy 135.909118 -285.140701) (xy 135.956704 -285.122654) (xy 136.006568 -285.112474) (xy 136.05742 -285.110425)
			(xy 136.107941 -285.116559) (xy 136.156825 -285.130719) (xy 136.202804 -285.152536) (xy 136.244688 -285.181446)
			(xy 136.281392 -285.216701) (xy 136.311965 -285.257387) (xy 136.335616 -285.30245) (xy 136.351732 -285.350724)
			(xy 136.359896 -285.400958) (xy 136.360408 -285.426404) (xy 137.608559 -285.426404) (xy 137.612654 -285.375676)
			(xy 137.624833 -285.326262) (xy 137.644781 -285.279442) (xy 137.671982 -285.236428) (xy 137.70573 -285.198334)
			(xy 137.745152 -285.166147) (xy 137.789226 -285.140701) (xy 137.836812 -285.122654) (xy 137.886676 -285.112474)
			(xy 137.937528 -285.110425) (xy 137.988049 -285.116559) (xy 138.036933 -285.130719) (xy 138.082912 -285.152536)
			(xy 138.124796 -285.181446) (xy 138.1615 -285.216701) (xy 138.192073 -285.257387) (xy 138.215724 -285.30245)
			(xy 138.23184 -285.350724) (xy 138.240004 -285.400958) (xy 138.240516 -285.426404) (xy 138.240013 -285.451393)
			(xy 138.54733 -285.451393) (xy 138.54733 -285.401415) (xy 138.555149 -285.352052) (xy 138.570593 -285.30452)
			(xy 138.593283 -285.259988) (xy 138.622659 -285.219555) (xy 138.657999 -285.184215) (xy 138.698432 -285.154839)
			(xy 138.742964 -285.132149) (xy 138.790496 -285.116705) (xy 138.839859 -285.108886) (xy 138.889837 -285.108886)
			(xy 138.9392 -285.116705) (xy 138.986732 -285.132149) (xy 139.031264 -285.154839) (xy 139.071697 -285.184215)
			(xy 139.107037 -285.219555) (xy 139.136413 -285.259988) (xy 139.159103 -285.30452) (xy 139.174547 -285.352052)
			(xy 139.182366 -285.401415) (xy 139.182856 -285.426404) (xy 139.488413 -285.426404) (xy 139.492508 -285.375676)
			(xy 139.504687 -285.326262) (xy 139.524635 -285.279442) (xy 139.551836 -285.236428) (xy 139.585584 -285.198334)
			(xy 139.625006 -285.166147) (xy 139.66908 -285.140701) (xy 139.716666 -285.122654) (xy 139.76653 -285.112474)
			(xy 139.817382 -285.110425) (xy 139.867903 -285.116559) (xy 139.916787 -285.130719) (xy 139.962766 -285.152536)
			(xy 140.00465 -285.181446) (xy 140.041354 -285.216701) (xy 140.071927 -285.257387) (xy 140.095578 -285.30245)
			(xy 140.111694 -285.350724) (xy 140.119858 -285.400958) (xy 140.12037 -285.426404) (xy 140.119867 -285.451393)
			(xy 140.427184 -285.451393) (xy 140.427184 -285.401415) (xy 140.435003 -285.352052) (xy 140.450447 -285.30452)
			(xy 140.473137 -285.259988) (xy 140.502513 -285.219555) (xy 140.537853 -285.184215) (xy 140.578286 -285.154839)
			(xy 140.622818 -285.132149) (xy 140.67035 -285.116705) (xy 140.719713 -285.108886) (xy 140.769691 -285.108886)
			(xy 140.819054 -285.116705) (xy 140.866586 -285.132149) (xy 140.911118 -285.154839) (xy 140.951551 -285.184215)
			(xy 140.986891 -285.219555) (xy 141.016267 -285.259988) (xy 141.038957 -285.30452) (xy 141.054401 -285.352052)
			(xy 141.06222 -285.401415) (xy 141.06271 -285.426404) (xy 141.368521 -285.426404) (xy 141.372616 -285.375676)
			(xy 141.384795 -285.326262) (xy 141.404743 -285.279442) (xy 141.431944 -285.236428) (xy 141.465692 -285.198334)
			(xy 141.505114 -285.166147) (xy 141.549188 -285.140701) (xy 141.596774 -285.122654) (xy 141.646638 -285.112474)
			(xy 141.69749 -285.110425) (xy 141.748011 -285.116559) (xy 141.796895 -285.130719) (xy 141.842874 -285.152536)
			(xy 141.884758 -285.181446) (xy 141.921462 -285.216701) (xy 141.952035 -285.257387) (xy 141.975686 -285.30245)
			(xy 141.991802 -285.350724) (xy 141.999966 -285.400958) (xy 142.000478 -285.426404) (xy 142.308575 -285.426404)
			(xy 142.31267 -285.375676) (xy 142.324849 -285.326262) (xy 142.344797 -285.279442) (xy 142.371998 -285.236428)
			(xy 142.405746 -285.198334) (xy 142.445168 -285.166147) (xy 142.489242 -285.140701) (xy 142.536828 -285.122654)
			(xy 142.586692 -285.112474) (xy 142.637544 -285.110425) (xy 142.688065 -285.116559) (xy 142.736949 -285.130719)
			(xy 142.782928 -285.152536) (xy 142.824812 -285.181446) (xy 142.861516 -285.216701) (xy 142.892089 -285.257387)
			(xy 142.91574 -285.30245) (xy 142.931856 -285.350724) (xy 142.94002 -285.400958) (xy 142.940532 -285.426404)
			(xy 142.94002 -285.45185) (xy 142.931856 -285.502084) (xy 142.91574 -285.550358) (xy 142.892089 -285.595421)
			(xy 142.861516 -285.636107) (xy 142.824812 -285.671362) (xy 142.782928 -285.700272) (xy 142.736949 -285.722089)
			(xy 142.688065 -285.736249) (xy 142.637544 -285.742383) (xy 142.586692 -285.740334) (xy 142.536828 -285.730154)
			(xy 142.489242 -285.712107) (xy 142.445168 -285.686661) (xy 142.405746 -285.654474) (xy 142.371998 -285.61638)
			(xy 142.344797 -285.573366) (xy 142.324849 -285.526546) (xy 142.31267 -285.477132) (xy 142.308575 -285.426404)
			(xy 142.000478 -285.426404) (xy 141.999966 -285.45185) (xy 141.991802 -285.502084) (xy 141.975686 -285.550358)
			(xy 141.952035 -285.595421) (xy 141.921462 -285.636107) (xy 141.884758 -285.671362) (xy 141.842874 -285.700272)
			(xy 141.796895 -285.722089) (xy 141.748011 -285.736249) (xy 141.69749 -285.742383) (xy 141.646638 -285.740334)
			(xy 141.596774 -285.730154) (xy 141.549188 -285.712107) (xy 141.505114 -285.686661) (xy 141.465692 -285.654474)
			(xy 141.431944 -285.61638) (xy 141.404743 -285.573366) (xy 141.384795 -285.526546) (xy 141.372616 -285.477132)
			(xy 141.368521 -285.426404) (xy 141.06271 -285.426404) (xy 141.06222 -285.451393) (xy 141.054401 -285.500756)
			(xy 141.038957 -285.548288) (xy 141.016267 -285.59282) (xy 140.986891 -285.633253) (xy 140.951551 -285.668593)
			(xy 140.911118 -285.697969) (xy 140.866586 -285.720659) (xy 140.819054 -285.736103) (xy 140.769691 -285.743922)
			(xy 140.719713 -285.743922) (xy 140.67035 -285.736103) (xy 140.622818 -285.720659) (xy 140.578286 -285.697969)
			(xy 140.537853 -285.668593) (xy 140.502513 -285.633253) (xy 140.473137 -285.59282) (xy 140.450447 -285.548288)
			(xy 140.435003 -285.500756) (xy 140.427184 -285.451393) (xy 140.119867 -285.451393) (xy 140.119858 -285.45185)
			(xy 140.111694 -285.502084) (xy 140.095578 -285.550358) (xy 140.071927 -285.595421) (xy 140.041354 -285.636107)
			(xy 140.00465 -285.671362) (xy 139.962766 -285.700272) (xy 139.916787 -285.722089) (xy 139.867903 -285.736249)
			(xy 139.817382 -285.742383) (xy 139.76653 -285.740334) (xy 139.716666 -285.730154) (xy 139.66908 -285.712107)
			(xy 139.625006 -285.686661) (xy 139.585584 -285.654474) (xy 139.551836 -285.61638) (xy 139.524635 -285.573366)
			(xy 139.504687 -285.526546) (xy 139.492508 -285.477132) (xy 139.488413 -285.426404) (xy 139.182856 -285.426404)
			(xy 139.182366 -285.451393) (xy 139.174547 -285.500756) (xy 139.159103 -285.548288) (xy 139.136413 -285.59282)
			(xy 139.107037 -285.633253) (xy 139.071697 -285.668593) (xy 139.031264 -285.697969) (xy 138.986732 -285.720659)
			(xy 138.9392 -285.736103) (xy 138.889837 -285.743922) (xy 138.839859 -285.743922) (xy 138.790496 -285.736103)
			(xy 138.742964 -285.720659) (xy 138.698432 -285.697969) (xy 138.657999 -285.668593) (xy 138.622659 -285.633253)
			(xy 138.593283 -285.59282) (xy 138.570593 -285.548288) (xy 138.555149 -285.500756) (xy 138.54733 -285.451393)
			(xy 138.240013 -285.451393) (xy 138.240004 -285.45185) (xy 138.23184 -285.502084) (xy 138.215724 -285.550358)
			(xy 138.192073 -285.595421) (xy 138.1615 -285.636107) (xy 138.124796 -285.671362) (xy 138.082912 -285.700272)
			(xy 138.036933 -285.722089) (xy 137.988049 -285.736249) (xy 137.937528 -285.742383) (xy 137.886676 -285.740334)
			(xy 137.836812 -285.730154) (xy 137.789226 -285.712107) (xy 137.745152 -285.686661) (xy 137.70573 -285.654474)
			(xy 137.671982 -285.61638) (xy 137.644781 -285.573366) (xy 137.624833 -285.526546) (xy 137.612654 -285.477132)
			(xy 137.608559 -285.426404) (xy 136.360408 -285.426404) (xy 136.359896 -285.45185) (xy 136.351732 -285.502084)
			(xy 136.335616 -285.550358) (xy 136.311965 -285.595421) (xy 136.281392 -285.636107) (xy 136.244688 -285.671362)
			(xy 136.202804 -285.700272) (xy 136.156825 -285.722089) (xy 136.107941 -285.736249) (xy 136.05742 -285.742383)
			(xy 136.006568 -285.740334) (xy 135.956704 -285.730154) (xy 135.909118 -285.712107) (xy 135.865044 -285.686661)
			(xy 135.825622 -285.654474) (xy 135.791874 -285.61638) (xy 135.764673 -285.573366) (xy 135.744725 -285.526546)
			(xy 135.732546 -285.477132) (xy 135.728451 -285.426404) (xy 135.420354 -285.426404) (xy 135.419842 -285.45185)
			(xy 135.411678 -285.502084) (xy 135.395562 -285.550358) (xy 135.371911 -285.595421) (xy 135.341338 -285.636107)
			(xy 135.304634 -285.671362) (xy 135.26275 -285.700272) (xy 135.216771 -285.722089) (xy 135.167887 -285.736249)
			(xy 135.117366 -285.742383) (xy 135.066514 -285.740334) (xy 135.01665 -285.730154) (xy 134.969064 -285.712107)
			(xy 134.92499 -285.686661) (xy 134.885568 -285.654474) (xy 134.85182 -285.61638) (xy 134.824619 -285.573366)
			(xy 134.804671 -285.526546) (xy 134.792492 -285.477132) (xy 134.788397 -285.426404) (xy 134.48284 -285.426404)
			(xy 134.48235 -285.451393) (xy 134.474531 -285.500756) (xy 134.459087 -285.548288) (xy 134.436397 -285.59282)
			(xy 134.407021 -285.633253) (xy 134.371681 -285.668593) (xy 134.331248 -285.697969) (xy 134.286716 -285.720659)
			(xy 134.239184 -285.736103) (xy 134.189821 -285.743922) (xy 134.139843 -285.743922) (xy 134.09048 -285.736103)
			(xy 134.042948 -285.720659) (xy 133.998416 -285.697969) (xy 133.957983 -285.668593) (xy 133.922643 -285.633253)
			(xy 133.893267 -285.59282) (xy 133.870577 -285.548288) (xy 133.855133 -285.500756) (xy 133.847314 -285.451393)
			(xy 133.539997 -285.451393) (xy 133.539988 -285.45185) (xy 133.531824 -285.502084) (xy 133.515708 -285.550358)
			(xy 133.492057 -285.595421) (xy 133.461484 -285.636107) (xy 133.42478 -285.671362) (xy 133.382896 -285.700272)
			(xy 133.336917 -285.722089) (xy 133.288033 -285.736249) (xy 133.237512 -285.742383) (xy 133.18666 -285.740334)
			(xy 133.136796 -285.730154) (xy 133.08921 -285.712107) (xy 133.045136 -285.686661) (xy 133.005714 -285.654474)
			(xy 132.971966 -285.61638) (xy 132.944765 -285.573366) (xy 132.924817 -285.526546) (xy 132.912638 -285.477132)
			(xy 132.908543 -285.426404) (xy 132.602732 -285.426404) (xy 132.602242 -285.451393) (xy 132.594423 -285.500756)
			(xy 132.578979 -285.548288) (xy 132.556289 -285.59282) (xy 132.526913 -285.633253) (xy 132.491573 -285.668593)
			(xy 132.45114 -285.697969) (xy 132.406608 -285.720659) (xy 132.359076 -285.736103) (xy 132.309713 -285.743922)
			(xy 132.259735 -285.743922) (xy 132.210372 -285.736103) (xy 132.16284 -285.720659) (xy 132.118308 -285.697969)
			(xy 132.077875 -285.668593) (xy 132.042535 -285.633253) (xy 132.013159 -285.59282) (xy 131.990469 -285.548288)
			(xy 131.975025 -285.500756) (xy 131.967206 -285.451393) (xy 131.659889 -285.451393) (xy 131.65988 -285.45185)
			(xy 131.651716 -285.502084) (xy 131.6356 -285.550358) (xy 131.611949 -285.595421) (xy 131.581376 -285.636107)
			(xy 131.544672 -285.671362) (xy 131.502788 -285.700272) (xy 131.456809 -285.722089) (xy 131.407925 -285.736249)
			(xy 131.357404 -285.742383) (xy 131.306552 -285.740334) (xy 131.256688 -285.730154) (xy 131.209102 -285.712107)
			(xy 131.165028 -285.686661) (xy 131.125606 -285.654474) (xy 131.091858 -285.61638) (xy 131.064657 -285.573366)
			(xy 131.044709 -285.526546) (xy 131.03253 -285.477132) (xy 131.028435 -285.426404) (xy 129.780538 -285.426404)
			(xy 129.780026 -285.45185) (xy 129.771862 -285.502084) (xy 129.755746 -285.550358) (xy 129.732095 -285.595421)
			(xy 129.701522 -285.636107) (xy 129.664818 -285.671362) (xy 129.622934 -285.700272) (xy 129.576955 -285.722089)
			(xy 129.528071 -285.736249) (xy 129.47755 -285.742383) (xy 129.426698 -285.740334) (xy 129.376834 -285.730154)
			(xy 129.329248 -285.712107) (xy 129.285174 -285.686661) (xy 129.245752 -285.654474) (xy 129.212004 -285.61638)
			(xy 129.184803 -285.573366) (xy 129.164855 -285.526546) (xy 129.152676 -285.477132) (xy 129.148581 -285.426404)
			(xy 128.840484 -285.426404) (xy 128.839972 -285.45185) (xy 128.831808 -285.502084) (xy 128.815692 -285.550358)
			(xy 128.792041 -285.595421) (xy 128.761468 -285.636107) (xy 128.724764 -285.671362) (xy 128.68288 -285.700272)
			(xy 128.636901 -285.722089) (xy 128.588017 -285.736249) (xy 128.537496 -285.742383) (xy 128.486644 -285.740334)
			(xy 128.43678 -285.730154) (xy 128.389194 -285.712107) (xy 128.34512 -285.686661) (xy 128.305698 -285.654474)
			(xy 128.27195 -285.61638) (xy 128.244749 -285.573366) (xy 128.224801 -285.526546) (xy 128.212622 -285.477132)
			(xy 128.208527 -285.426404) (xy 127.294386 -285.426404) (xy 127.294386 -285.931102) (xy 127.295656 -285.94177)
			(xy 127.297688 -285.951676) (xy 127.298958 -285.958026) (xy 127.308864 -285.978346) (xy 127.310843 -285.982329)
			(xy 127.315949 -285.989611) (xy 127.319024 -285.992824) (xy 127.321564 -285.994856) (xy 127.34206 -286.013137)
			(xy 127.377049 -286.055463) (xy 127.404241 -286.103175) (xy 127.422825 -286.15485) (xy 127.432247 -286.208952)
			(xy 127.432816 -286.23641) (xy 127.738627 -286.23641) (xy 127.742722 -286.185682) (xy 127.754901 -286.136268)
			(xy 127.774849 -286.089448) (xy 127.80205 -286.046434) (xy 127.835798 -286.00834) (xy 127.87522 -285.976153)
			(xy 127.919294 -285.950707) (xy 127.96688 -285.93266) (xy 128.016744 -285.92248) (xy 128.067596 -285.920431)
			(xy 128.118117 -285.926565) (xy 128.167001 -285.940725) (xy 128.21298 -285.962542) (xy 128.254864 -285.991452)
			(xy 128.291568 -286.026707) (xy 128.322141 -286.067393) (xy 128.345792 -286.112456) (xy 128.361908 -286.16073)
			(xy 128.370072 -286.210964) (xy 128.370584 -286.23641) (xy 128.370081 -286.261399) (xy 128.677144 -286.261399)
			(xy 128.677144 -286.211421) (xy 128.684963 -286.162058) (xy 128.700407 -286.114526) (xy 128.723097 -286.069994)
			(xy 128.752473 -286.029561) (xy 128.787813 -285.994221) (xy 128.828246 -285.964845) (xy 128.872778 -285.942155)
			(xy 128.92031 -285.926711) (xy 128.969673 -285.918892) (xy 129.019651 -285.918892) (xy 129.069014 -285.926711)
			(xy 129.116546 -285.942155) (xy 129.161078 -285.964845) (xy 129.201511 -285.994221) (xy 129.236851 -286.029561)
			(xy 129.266227 -286.069994) (xy 129.288917 -286.114526) (xy 129.304361 -286.162058) (xy 129.31218 -286.211421)
			(xy 129.31267 -286.23641) (xy 129.618481 -286.23641) (xy 129.622576 -286.185682) (xy 129.634755 -286.136268)
			(xy 129.654703 -286.089448) (xy 129.681904 -286.046434) (xy 129.715652 -286.00834) (xy 129.755074 -285.976153)
			(xy 129.799148 -285.950707) (xy 129.846734 -285.93266) (xy 129.896598 -285.92248) (xy 129.94745 -285.920431)
			(xy 129.997971 -285.926565) (xy 130.046855 -285.940725) (xy 130.092834 -285.962542) (xy 130.134718 -285.991452)
			(xy 130.171422 -286.026707) (xy 130.201995 -286.067393) (xy 130.225646 -286.112456) (xy 130.241762 -286.16073)
			(xy 130.249926 -286.210964) (xy 130.250438 -286.23641) (xy 130.249935 -286.261399) (xy 130.557252 -286.261399)
			(xy 130.557252 -286.211421) (xy 130.565071 -286.162058) (xy 130.580515 -286.114526) (xy 130.603205 -286.069994)
			(xy 130.632581 -286.029561) (xy 130.667921 -285.994221) (xy 130.708354 -285.964845) (xy 130.752886 -285.942155)
			(xy 130.800418 -285.926711) (xy 130.849781 -285.918892) (xy 130.899759 -285.918892) (xy 130.949122 -285.926711)
			(xy 130.996654 -285.942155) (xy 131.041186 -285.964845) (xy 131.081619 -285.994221) (xy 131.116959 -286.029561)
			(xy 131.146335 -286.069994) (xy 131.169025 -286.114526) (xy 131.184469 -286.162058) (xy 131.192288 -286.211421)
			(xy 131.192778 -286.23641) (xy 131.498589 -286.23641) (xy 131.502684 -286.185682) (xy 131.514863 -286.136268)
			(xy 131.534811 -286.089448) (xy 131.562012 -286.046434) (xy 131.59576 -286.00834) (xy 131.635182 -285.976153)
			(xy 131.679256 -285.950707) (xy 131.726842 -285.93266) (xy 131.776706 -285.92248) (xy 131.827558 -285.920431)
			(xy 131.878079 -285.926565) (xy 131.926963 -285.940725) (xy 131.972942 -285.962542) (xy 132.014826 -285.991452)
			(xy 132.05153 -286.026707) (xy 132.082103 -286.067393) (xy 132.105754 -286.112456) (xy 132.12187 -286.16073)
			(xy 132.130034 -286.210964) (xy 132.130546 -286.23641) (xy 132.438643 -286.23641) (xy 132.442738 -286.185682)
			(xy 132.454917 -286.136268) (xy 132.474865 -286.089448) (xy 132.502066 -286.046434) (xy 132.535814 -286.00834)
			(xy 132.575236 -285.976153) (xy 132.61931 -285.950707) (xy 132.666896 -285.93266) (xy 132.71676 -285.92248)
			(xy 132.767612 -285.920431) (xy 132.818133 -285.926565) (xy 132.867017 -285.940725) (xy 132.912996 -285.962542)
			(xy 132.95488 -285.991452) (xy 132.991584 -286.026707) (xy 133.022157 -286.067393) (xy 133.045808 -286.112456)
			(xy 133.061924 -286.16073) (xy 133.070088 -286.210964) (xy 133.0706 -286.23641) (xy 133.070097 -286.261399)
			(xy 133.37716 -286.261399) (xy 133.37716 -286.211421) (xy 133.384979 -286.162058) (xy 133.400423 -286.114526)
			(xy 133.423113 -286.069994) (xy 133.452489 -286.029561) (xy 133.487829 -285.994221) (xy 133.528262 -285.964845)
			(xy 133.572794 -285.942155) (xy 133.620326 -285.926711) (xy 133.669689 -285.918892) (xy 133.719667 -285.918892)
			(xy 133.76903 -285.926711) (xy 133.816562 -285.942155) (xy 133.861094 -285.964845) (xy 133.901527 -285.994221)
			(xy 133.936867 -286.029561) (xy 133.966243 -286.069994) (xy 133.988933 -286.114526) (xy 134.004377 -286.162058)
			(xy 134.012196 -286.211421) (xy 134.012686 -286.23641) (xy 134.318497 -286.23641) (xy 134.322592 -286.185682)
			(xy 134.334771 -286.136268) (xy 134.354719 -286.089448) (xy 134.38192 -286.046434) (xy 134.415668 -286.00834)
			(xy 134.45509 -285.976153) (xy 134.499164 -285.950707) (xy 134.54675 -285.93266) (xy 134.596614 -285.92248)
			(xy 134.647466 -285.920431) (xy 134.697987 -285.926565) (xy 134.746871 -285.940725) (xy 134.79285 -285.962542)
			(xy 134.834734 -285.991452) (xy 134.871438 -286.026707) (xy 134.902011 -286.067393) (xy 134.925662 -286.112456)
			(xy 134.941778 -286.16073) (xy 134.949942 -286.210964) (xy 134.950454 -286.23641) (xy 134.949951 -286.261399)
			(xy 135.257268 -286.261399) (xy 135.257268 -286.211421) (xy 135.265087 -286.162058) (xy 135.280531 -286.114526)
			(xy 135.303221 -286.069994) (xy 135.332597 -286.029561) (xy 135.367937 -285.994221) (xy 135.40837 -285.964845)
			(xy 135.452902 -285.942155) (xy 135.500434 -285.926711) (xy 135.549797 -285.918892) (xy 135.599775 -285.918892)
			(xy 135.649138 -285.926711) (xy 135.69667 -285.942155) (xy 135.741202 -285.964845) (xy 135.781635 -285.994221)
			(xy 135.816975 -286.029561) (xy 135.846351 -286.069994) (xy 135.869041 -286.114526) (xy 135.884485 -286.162058)
			(xy 135.892304 -286.211421) (xy 135.892794 -286.23641) (xy 136.198605 -286.23641) (xy 136.2027 -286.185682)
			(xy 136.214879 -286.136268) (xy 136.234827 -286.089448) (xy 136.262028 -286.046434) (xy 136.295776 -286.00834)
			(xy 136.335198 -285.976153) (xy 136.379272 -285.950707) (xy 136.426858 -285.93266) (xy 136.476722 -285.92248)
			(xy 136.527574 -285.920431) (xy 136.578095 -285.926565) (xy 136.626979 -285.940725) (xy 136.672958 -285.962542)
			(xy 136.714842 -285.991452) (xy 136.751546 -286.026707) (xy 136.782119 -286.067393) (xy 136.80577 -286.112456)
			(xy 136.821886 -286.16073) (xy 136.83005 -286.210964) (xy 136.830562 -286.23641) (xy 136.830059 -286.261399)
			(xy 137.137122 -286.261399) (xy 137.137122 -286.211421) (xy 137.144941 -286.162058) (xy 137.160385 -286.114526)
			(xy 137.183075 -286.069994) (xy 137.212451 -286.029561) (xy 137.247791 -285.994221) (xy 137.288224 -285.964845)
			(xy 137.332756 -285.942155) (xy 137.380288 -285.926711) (xy 137.429651 -285.918892) (xy 137.479629 -285.918892)
			(xy 137.528992 -285.926711) (xy 137.576524 -285.942155) (xy 137.621056 -285.964845) (xy 137.661489 -285.994221)
			(xy 137.696829 -286.029561) (xy 137.726205 -286.069994) (xy 137.748895 -286.114526) (xy 137.764339 -286.162058)
			(xy 137.772158 -286.211421) (xy 137.772648 -286.23641) (xy 138.078459 -286.23641) (xy 138.082554 -286.185682)
			(xy 138.094733 -286.136268) (xy 138.114681 -286.089448) (xy 138.141882 -286.046434) (xy 138.17563 -286.00834)
			(xy 138.215052 -285.976153) (xy 138.259126 -285.950707) (xy 138.306712 -285.93266) (xy 138.356576 -285.92248)
			(xy 138.407428 -285.920431) (xy 138.457949 -285.926565) (xy 138.506833 -285.940725) (xy 138.552812 -285.962542)
			(xy 138.594696 -285.991452) (xy 138.6314 -286.026707) (xy 138.661973 -286.067393) (xy 138.685624 -286.112456)
			(xy 138.70174 -286.16073) (xy 138.709904 -286.210964) (xy 138.710416 -286.23641) (xy 139.018513 -286.23641)
			(xy 139.022608 -286.185682) (xy 139.034787 -286.136268) (xy 139.054735 -286.089448) (xy 139.081936 -286.046434)
			(xy 139.115684 -286.00834) (xy 139.155106 -285.976153) (xy 139.19918 -285.950707) (xy 139.246766 -285.93266)
			(xy 139.29663 -285.92248) (xy 139.347482 -285.920431) (xy 139.398003 -285.926565) (xy 139.446887 -285.940725)
			(xy 139.492866 -285.962542) (xy 139.53475 -285.991452) (xy 139.571454 -286.026707) (xy 139.602027 -286.067393)
			(xy 139.625678 -286.112456) (xy 139.641794 -286.16073) (xy 139.649958 -286.210964) (xy 139.65047 -286.23641)
			(xy 139.649967 -286.261399) (xy 139.957284 -286.261399) (xy 139.957284 -286.211421) (xy 139.965103 -286.162058)
			(xy 139.980547 -286.114526) (xy 140.003237 -286.069994) (xy 140.032613 -286.029561) (xy 140.067953 -285.994221)
			(xy 140.108386 -285.964845) (xy 140.152918 -285.942155) (xy 140.20045 -285.926711) (xy 140.249813 -285.918892)
			(xy 140.299791 -285.918892) (xy 140.349154 -285.926711) (xy 140.396686 -285.942155) (xy 140.441218 -285.964845)
			(xy 140.481651 -285.994221) (xy 140.516991 -286.029561) (xy 140.546367 -286.069994) (xy 140.569057 -286.114526)
			(xy 140.584501 -286.162058) (xy 140.59232 -286.211421) (xy 140.59281 -286.23641) (xy 140.898621 -286.23641)
			(xy 140.902716 -286.185682) (xy 140.914895 -286.136268) (xy 140.934843 -286.089448) (xy 140.962044 -286.046434)
			(xy 140.995792 -286.00834) (xy 141.035214 -285.976153) (xy 141.079288 -285.950707) (xy 141.126874 -285.93266)
			(xy 141.176738 -285.92248) (xy 141.22759 -285.920431) (xy 141.278111 -285.926565) (xy 141.326995 -285.940725)
			(xy 141.372974 -285.962542) (xy 141.414858 -285.991452) (xy 141.451562 -286.026707) (xy 141.482135 -286.067393)
			(xy 141.505786 -286.112456) (xy 141.521902 -286.16073) (xy 141.530066 -286.210964) (xy 141.530578 -286.23641)
			(xy 141.530075 -286.261399) (xy 141.837138 -286.261399) (xy 141.837138 -286.211421) (xy 141.844957 -286.162058)
			(xy 141.860401 -286.114526) (xy 141.883091 -286.069994) (xy 141.912467 -286.029561) (xy 141.947807 -285.994221)
			(xy 141.98824 -285.964845) (xy 142.032772 -285.942155) (xy 142.080304 -285.926711) (xy 142.129667 -285.918892)
			(xy 142.179645 -285.918892) (xy 142.229008 -285.926711) (xy 142.27654 -285.942155) (xy 142.321072 -285.964845)
			(xy 142.361505 -285.994221) (xy 142.396845 -286.029561) (xy 142.426221 -286.069994) (xy 142.448911 -286.114526)
			(xy 142.464355 -286.162058) (xy 142.472174 -286.211421) (xy 142.472664 -286.23641) (xy 142.778475 -286.23641)
			(xy 142.78257 -286.185682) (xy 142.794749 -286.136268) (xy 142.814697 -286.089448) (xy 142.841898 -286.046434)
			(xy 142.875646 -286.00834) (xy 142.915068 -285.976153) (xy 142.959142 -285.950707) (xy 143.006728 -285.93266)
			(xy 143.056592 -285.92248) (xy 143.107444 -285.920431) (xy 143.157965 -285.926565) (xy 143.206849 -285.940725)
			(xy 143.252828 -285.962542) (xy 143.294712 -285.991452) (xy 143.331416 -286.026707) (xy 143.361989 -286.067393)
			(xy 143.38564 -286.112456) (xy 143.401756 -286.16073) (xy 143.40992 -286.210964) (xy 143.410432 -286.23641)
			(xy 143.409929 -286.261399) (xy 143.717246 -286.261399) (xy 143.717246 -286.211421) (xy 143.725065 -286.162058)
			(xy 143.740509 -286.114526) (xy 143.763199 -286.069994) (xy 143.792575 -286.029561) (xy 143.827915 -285.994221)
			(xy 143.868348 -285.964845) (xy 143.91288 -285.942155) (xy 143.960412 -285.926711) (xy 144.009775 -285.918892)
			(xy 144.059753 -285.918892) (xy 144.109116 -285.926711) (xy 144.156648 -285.942155) (xy 144.20118 -285.964845)
			(xy 144.241613 -285.994221) (xy 144.276953 -286.029561) (xy 144.306329 -286.069994) (xy 144.329019 -286.114526)
			(xy 144.344463 -286.162058) (xy 144.352282 -286.211421) (xy 144.352772 -286.23641) (xy 144.352282 -286.261399)
			(xy 144.344463 -286.310762) (xy 144.329019 -286.358294) (xy 144.306329 -286.402826) (xy 144.276953 -286.443259)
			(xy 144.241613 -286.478599) (xy 144.20118 -286.507975) (xy 144.156648 -286.530665) (xy 144.109116 -286.546109)
			(xy 144.059753 -286.553928) (xy 144.009775 -286.553928) (xy 143.960412 -286.546109) (xy 143.91288 -286.530665)
			(xy 143.868348 -286.507975) (xy 143.827915 -286.478599) (xy 143.792575 -286.443259) (xy 143.763199 -286.402826)
			(xy 143.740509 -286.358294) (xy 143.725065 -286.310762) (xy 143.717246 -286.261399) (xy 143.409929 -286.261399)
			(xy 143.40992 -286.261856) (xy 143.401756 -286.31209) (xy 143.38564 -286.360364) (xy 143.361989 -286.405427)
			(xy 143.331416 -286.446113) (xy 143.294712 -286.481368) (xy 143.252828 -286.510278) (xy 143.206849 -286.532095)
			(xy 143.157965 -286.546255) (xy 143.107444 -286.552389) (xy 143.056592 -286.55034) (xy 143.006728 -286.54016)
			(xy 142.959142 -286.522113) (xy 142.915068 -286.496667) (xy 142.875646 -286.46448) (xy 142.841898 -286.426386)
			(xy 142.814697 -286.383372) (xy 142.794749 -286.336552) (xy 142.78257 -286.287138) (xy 142.778475 -286.23641)
			(xy 142.472664 -286.23641) (xy 142.472174 -286.261399) (xy 142.464355 -286.310762) (xy 142.448911 -286.358294)
			(xy 142.426221 -286.402826) (xy 142.396845 -286.443259) (xy 142.361505 -286.478599) (xy 142.321072 -286.507975)
			(xy 142.27654 -286.530665) (xy 142.229008 -286.546109) (xy 142.179645 -286.553928) (xy 142.129667 -286.553928)
			(xy 142.080304 -286.546109) (xy 142.032772 -286.530665) (xy 141.98824 -286.507975) (xy 141.947807 -286.478599)
			(xy 141.912467 -286.443259) (xy 141.883091 -286.402826) (xy 141.860401 -286.358294) (xy 141.844957 -286.310762)
			(xy 141.837138 -286.261399) (xy 141.530075 -286.261399) (xy 141.530066 -286.261856) (xy 141.521902 -286.31209)
			(xy 141.505786 -286.360364) (xy 141.482135 -286.405427) (xy 141.451562 -286.446113) (xy 141.414858 -286.481368)
			(xy 141.372974 -286.510278) (xy 141.326995 -286.532095) (xy 141.278111 -286.546255) (xy 141.22759 -286.552389)
			(xy 141.176738 -286.55034) (xy 141.126874 -286.54016) (xy 141.079288 -286.522113) (xy 141.035214 -286.496667)
			(xy 140.995792 -286.46448) (xy 140.962044 -286.426386) (xy 140.934843 -286.383372) (xy 140.914895 -286.336552)
			(xy 140.902716 -286.287138) (xy 140.898621 -286.23641) (xy 140.59281 -286.23641) (xy 140.59232 -286.261399)
			(xy 140.584501 -286.310762) (xy 140.569057 -286.358294) (xy 140.546367 -286.402826) (xy 140.516991 -286.443259)
			(xy 140.481651 -286.478599) (xy 140.441218 -286.507975) (xy 140.396686 -286.530665) (xy 140.349154 -286.546109)
			(xy 140.299791 -286.553928) (xy 140.249813 -286.553928) (xy 140.20045 -286.546109) (xy 140.152918 -286.530665)
			(xy 140.108386 -286.507975) (xy 140.067953 -286.478599) (xy 140.032613 -286.443259) (xy 140.003237 -286.402826)
			(xy 139.980547 -286.358294) (xy 139.965103 -286.310762) (xy 139.957284 -286.261399) (xy 139.649967 -286.261399)
			(xy 139.649958 -286.261856) (xy 139.641794 -286.31209) (xy 139.625678 -286.360364) (xy 139.602027 -286.405427)
			(xy 139.571454 -286.446113) (xy 139.53475 -286.481368) (xy 139.492866 -286.510278) (xy 139.446887 -286.532095)
			(xy 139.398003 -286.546255) (xy 139.347482 -286.552389) (xy 139.29663 -286.55034) (xy 139.246766 -286.54016)
			(xy 139.19918 -286.522113) (xy 139.155106 -286.496667) (xy 139.115684 -286.46448) (xy 139.081936 -286.426386)
			(xy 139.054735 -286.383372) (xy 139.034787 -286.336552) (xy 139.022608 -286.287138) (xy 139.018513 -286.23641)
			(xy 138.710416 -286.23641) (xy 138.709904 -286.261856) (xy 138.70174 -286.31209) (xy 138.685624 -286.360364)
			(xy 138.661973 -286.405427) (xy 138.6314 -286.446113) (xy 138.594696 -286.481368) (xy 138.552812 -286.510278)
			(xy 138.506833 -286.532095) (xy 138.457949 -286.546255) (xy 138.407428 -286.552389) (xy 138.356576 -286.55034)
			(xy 138.306712 -286.54016) (xy 138.259126 -286.522113) (xy 138.215052 -286.496667) (xy 138.17563 -286.46448)
			(xy 138.141882 -286.426386) (xy 138.114681 -286.383372) (xy 138.094733 -286.336552) (xy 138.082554 -286.287138)
			(xy 138.078459 -286.23641) (xy 137.772648 -286.23641) (xy 137.772158 -286.261399) (xy 137.764339 -286.310762)
			(xy 137.748895 -286.358294) (xy 137.726205 -286.402826) (xy 137.696829 -286.443259) (xy 137.661489 -286.478599)
			(xy 137.621056 -286.507975) (xy 137.576524 -286.530665) (xy 137.528992 -286.546109) (xy 137.479629 -286.553928)
			(xy 137.429651 -286.553928) (xy 137.380288 -286.546109) (xy 137.332756 -286.530665) (xy 137.288224 -286.507975)
			(xy 137.247791 -286.478599) (xy 137.212451 -286.443259) (xy 137.183075 -286.402826) (xy 137.160385 -286.358294)
			(xy 137.144941 -286.310762) (xy 137.137122 -286.261399) (xy 136.830059 -286.261399) (xy 136.83005 -286.261856)
			(xy 136.821886 -286.31209) (xy 136.80577 -286.360364) (xy 136.782119 -286.405427) (xy 136.751546 -286.446113)
			(xy 136.714842 -286.481368) (xy 136.672958 -286.510278) (xy 136.626979 -286.532095) (xy 136.578095 -286.546255)
			(xy 136.527574 -286.552389) (xy 136.476722 -286.55034) (xy 136.426858 -286.54016) (xy 136.379272 -286.522113)
			(xy 136.335198 -286.496667) (xy 136.295776 -286.46448) (xy 136.262028 -286.426386) (xy 136.234827 -286.383372)
			(xy 136.214879 -286.336552) (xy 136.2027 -286.287138) (xy 136.198605 -286.23641) (xy 135.892794 -286.23641)
			(xy 135.892304 -286.261399) (xy 135.884485 -286.310762) (xy 135.869041 -286.358294) (xy 135.846351 -286.402826)
			(xy 135.816975 -286.443259) (xy 135.781635 -286.478599) (xy 135.741202 -286.507975) (xy 135.69667 -286.530665)
			(xy 135.649138 -286.546109) (xy 135.599775 -286.553928) (xy 135.549797 -286.553928) (xy 135.500434 -286.546109)
			(xy 135.452902 -286.530665) (xy 135.40837 -286.507975) (xy 135.367937 -286.478599) (xy 135.332597 -286.443259)
			(xy 135.303221 -286.402826) (xy 135.280531 -286.358294) (xy 135.265087 -286.310762) (xy 135.257268 -286.261399)
			(xy 134.949951 -286.261399) (xy 134.949942 -286.261856) (xy 134.941778 -286.31209) (xy 134.925662 -286.360364)
			(xy 134.902011 -286.405427) (xy 134.871438 -286.446113) (xy 134.834734 -286.481368) (xy 134.79285 -286.510278)
			(xy 134.746871 -286.532095) (xy 134.697987 -286.546255) (xy 134.647466 -286.552389) (xy 134.596614 -286.55034)
			(xy 134.54675 -286.54016) (xy 134.499164 -286.522113) (xy 134.45509 -286.496667) (xy 134.415668 -286.46448)
			(xy 134.38192 -286.426386) (xy 134.354719 -286.383372) (xy 134.334771 -286.336552) (xy 134.322592 -286.287138)
			(xy 134.318497 -286.23641) (xy 134.012686 -286.23641) (xy 134.012196 -286.261399) (xy 134.004377 -286.310762)
			(xy 133.988933 -286.358294) (xy 133.966243 -286.402826) (xy 133.936867 -286.443259) (xy 133.901527 -286.478599)
			(xy 133.861094 -286.507975) (xy 133.816562 -286.530665) (xy 133.76903 -286.546109) (xy 133.719667 -286.553928)
			(xy 133.669689 -286.553928) (xy 133.620326 -286.546109) (xy 133.572794 -286.530665) (xy 133.528262 -286.507975)
			(xy 133.487829 -286.478599) (xy 133.452489 -286.443259) (xy 133.423113 -286.402826) (xy 133.400423 -286.358294)
			(xy 133.384979 -286.310762) (xy 133.37716 -286.261399) (xy 133.070097 -286.261399) (xy 133.070088 -286.261856)
			(xy 133.061924 -286.31209) (xy 133.045808 -286.360364) (xy 133.022157 -286.405427) (xy 132.991584 -286.446113)
			(xy 132.95488 -286.481368) (xy 132.912996 -286.510278) (xy 132.867017 -286.532095) (xy 132.818133 -286.546255)
			(xy 132.767612 -286.552389) (xy 132.71676 -286.55034) (xy 132.666896 -286.54016) (xy 132.61931 -286.522113)
			(xy 132.575236 -286.496667) (xy 132.535814 -286.46448) (xy 132.502066 -286.426386) (xy 132.474865 -286.383372)
			(xy 132.454917 -286.336552) (xy 132.442738 -286.287138) (xy 132.438643 -286.23641) (xy 132.130546 -286.23641)
			(xy 132.130034 -286.261856) (xy 132.12187 -286.31209) (xy 132.105754 -286.360364) (xy 132.082103 -286.405427)
			(xy 132.05153 -286.446113) (xy 132.014826 -286.481368) (xy 131.972942 -286.510278) (xy 131.926963 -286.532095)
			(xy 131.878079 -286.546255) (xy 131.827558 -286.552389) (xy 131.776706 -286.55034) (xy 131.726842 -286.54016)
			(xy 131.679256 -286.522113) (xy 131.635182 -286.496667) (xy 131.59576 -286.46448) (xy 131.562012 -286.426386)
			(xy 131.534811 -286.383372) (xy 131.514863 -286.336552) (xy 131.502684 -286.287138) (xy 131.498589 -286.23641)
			(xy 131.192778 -286.23641) (xy 131.192288 -286.261399) (xy 131.184469 -286.310762) (xy 131.169025 -286.358294)
			(xy 131.146335 -286.402826) (xy 131.116959 -286.443259) (xy 131.081619 -286.478599) (xy 131.041186 -286.507975)
			(xy 130.996654 -286.530665) (xy 130.949122 -286.546109) (xy 130.899759 -286.553928) (xy 130.849781 -286.553928)
			(xy 130.800418 -286.546109) (xy 130.752886 -286.530665) (xy 130.708354 -286.507975) (xy 130.667921 -286.478599)
			(xy 130.632581 -286.443259) (xy 130.603205 -286.402826) (xy 130.580515 -286.358294) (xy 130.565071 -286.310762)
			(xy 130.557252 -286.261399) (xy 130.249935 -286.261399) (xy 130.249926 -286.261856) (xy 130.241762 -286.31209)
			(xy 130.225646 -286.360364) (xy 130.201995 -286.405427) (xy 130.171422 -286.446113) (xy 130.134718 -286.481368)
			(xy 130.092834 -286.510278) (xy 130.046855 -286.532095) (xy 129.997971 -286.546255) (xy 129.94745 -286.552389)
			(xy 129.896598 -286.55034) (xy 129.846734 -286.54016) (xy 129.799148 -286.522113) (xy 129.755074 -286.496667)
			(xy 129.715652 -286.46448) (xy 129.681904 -286.426386) (xy 129.654703 -286.383372) (xy 129.634755 -286.336552)
			(xy 129.622576 -286.287138) (xy 129.618481 -286.23641) (xy 129.31267 -286.23641) (xy 129.31218 -286.261399)
			(xy 129.304361 -286.310762) (xy 129.288917 -286.358294) (xy 129.266227 -286.402826) (xy 129.236851 -286.443259)
			(xy 129.201511 -286.478599) (xy 129.161078 -286.507975) (xy 129.116546 -286.530665) (xy 129.069014 -286.546109)
			(xy 129.019651 -286.553928) (xy 128.969673 -286.553928) (xy 128.92031 -286.546109) (xy 128.872778 -286.530665)
			(xy 128.828246 -286.507975) (xy 128.787813 -286.478599) (xy 128.752473 -286.443259) (xy 128.723097 -286.402826)
			(xy 128.700407 -286.358294) (xy 128.684963 -286.310762) (xy 128.677144 -286.261399) (xy 128.370081 -286.261399)
			(xy 128.370072 -286.261856) (xy 128.361908 -286.31209) (xy 128.345792 -286.360364) (xy 128.322141 -286.405427)
			(xy 128.291568 -286.446113) (xy 128.254864 -286.481368) (xy 128.21298 -286.510278) (xy 128.167001 -286.532095)
			(xy 128.118117 -286.546255) (xy 128.067596 -286.552389) (xy 128.016744 -286.55034) (xy 127.96688 -286.54016)
			(xy 127.919294 -286.522113) (xy 127.87522 -286.496667) (xy 127.835798 -286.46448) (xy 127.80205 -286.426386)
			(xy 127.774849 -286.383372) (xy 127.754901 -286.336552) (xy 127.742722 -286.287138) (xy 127.738627 -286.23641)
			(xy 127.432816 -286.23641) (xy 127.432249 -286.263743) (xy 127.422909 -286.317606) (xy 127.404504 -286.369082)
			(xy 127.377576 -286.416656) (xy 127.342917 -286.458931) (xy 127.32258 -286.477202) (xy 127.321056 -286.478472)
			(xy 127.317754 -286.481774) (xy 127.314951 -286.48473) (xy 127.310225 -286.491363) (xy 127.308356 -286.494982)
			(xy 127.29845 -286.516064) (xy 127.296926 -286.520382) (xy 127.29578 -286.524154) (xy 127.294504 -286.531935)
			(xy 127.294386 -286.535876) (xy 127.294386 -286.667956) (xy 127.295148 -286.676338) (xy 127.296672 -286.684466)
			(xy 127.297922 -286.689709) (xy 127.302276 -286.699567) (xy 127.305308 -286.704024) (xy 127.31115 -286.712152)
			(xy 127.391414 -286.761174) (xy 127.399478 -286.76501) (xy 127.41715 -286.767472) (xy 127.425958 -286.766)
			(xy 127.439928 -286.762698) (xy 127.445262 -286.760158) (xy 127.446024 -286.759904) (xy 127.467052 -286.750177)
			(xy 127.511237 -286.736245) (xy 127.556979 -286.728889) (xy 127.580136 -286.728154) (xy 127.590042 -286.728154)
			(xy 127.614755 -286.729039) (xy 127.663472 -286.737513) (xy 127.71029 -286.753426) (xy 127.75408 -286.776394)
			(xy 127.793788 -286.805864) (xy 127.828455 -286.841125) (xy 127.857246 -286.881328) (xy 127.879466 -286.925502)
			(xy 127.894581 -286.972584) (xy 127.902226 -287.021438) (xy 127.902716 -287.046162) (xy 128.208527 -287.046162)
			(xy 128.212622 -286.995434) (xy 128.224801 -286.94602) (xy 128.244749 -286.8992) (xy 128.27195 -286.856186)
			(xy 128.305698 -286.818092) (xy 128.34512 -286.785905) (xy 128.389194 -286.760459) (xy 128.43678 -286.742412)
			(xy 128.486644 -286.732232) (xy 128.537496 -286.730183) (xy 128.588017 -286.736317) (xy 128.636901 -286.750477)
			(xy 128.68288 -286.772294) (xy 128.724764 -286.801204) (xy 128.761468 -286.836459) (xy 128.792041 -286.877145)
			(xy 128.815692 -286.922208) (xy 128.831808 -286.970482) (xy 128.839972 -287.020716) (xy 128.840484 -287.046162)
			(xy 129.148581 -287.046162) (xy 129.152676 -286.995434) (xy 129.164855 -286.94602) (xy 129.184803 -286.8992)
			(xy 129.212004 -286.856186) (xy 129.245752 -286.818092) (xy 129.285174 -286.785905) (xy 129.329248 -286.760459)
			(xy 129.376834 -286.742412) (xy 129.426698 -286.732232) (xy 129.47755 -286.730183) (xy 129.528071 -286.736317)
			(xy 129.576955 -286.750477) (xy 129.622934 -286.772294) (xy 129.664818 -286.801204) (xy 129.701522 -286.836459)
			(xy 129.732095 -286.877145) (xy 129.755746 -286.922208) (xy 129.771862 -286.970482) (xy 129.780026 -287.020716)
			(xy 129.780538 -287.046162) (xy 129.78003 -287.071405) (xy 130.087352 -287.071405) (xy 130.087352 -287.021427)
			(xy 130.095171 -286.972064) (xy 130.110615 -286.924532) (xy 130.133305 -286.88) (xy 130.162681 -286.839567)
			(xy 130.198021 -286.804227) (xy 130.238454 -286.774851) (xy 130.282986 -286.752161) (xy 130.330518 -286.736717)
			(xy 130.379881 -286.728898) (xy 130.429859 -286.728898) (xy 130.479222 -286.736717) (xy 130.526754 -286.752161)
			(xy 130.571286 -286.774851) (xy 130.611719 -286.804227) (xy 130.647059 -286.839567) (xy 130.676435 -286.88)
			(xy 130.699125 -286.924532) (xy 130.714569 -286.972064) (xy 130.722388 -287.021427) (xy 130.722873 -287.046162)
			(xy 131.028435 -287.046162) (xy 131.03253 -286.995434) (xy 131.044709 -286.94602) (xy 131.064657 -286.8992)
			(xy 131.091858 -286.856186) (xy 131.125606 -286.818092) (xy 131.165028 -286.785905) (xy 131.209102 -286.760459)
			(xy 131.256688 -286.742412) (xy 131.306552 -286.732232) (xy 131.357404 -286.730183) (xy 131.407925 -286.736317)
			(xy 131.456809 -286.750477) (xy 131.502788 -286.772294) (xy 131.544672 -286.801204) (xy 131.581376 -286.836459)
			(xy 131.611949 -286.877145) (xy 131.6356 -286.922208) (xy 131.651716 -286.970482) (xy 131.65988 -287.020716)
			(xy 131.660392 -287.046162) (xy 131.659889 -287.071151) (xy 131.967206 -287.071151) (xy 131.967206 -287.021173)
			(xy 131.975025 -286.97181) (xy 131.990469 -286.924278) (xy 132.013159 -286.879746) (xy 132.042535 -286.839313)
			(xy 132.077875 -286.803973) (xy 132.118308 -286.774597) (xy 132.16284 -286.751907) (xy 132.210372 -286.736463)
			(xy 132.259735 -286.728644) (xy 132.309713 -286.728644) (xy 132.359076 -286.736463) (xy 132.406608 -286.751907)
			(xy 132.45114 -286.774597) (xy 132.491573 -286.803973) (xy 132.526913 -286.839313) (xy 132.556289 -286.879746)
			(xy 132.578979 -286.924278) (xy 132.594423 -286.97181) (xy 132.602242 -287.021173) (xy 132.602732 -287.046162)
			(xy 132.908543 -287.046162) (xy 132.912638 -286.995434) (xy 132.924817 -286.94602) (xy 132.944765 -286.8992)
			(xy 132.971966 -286.856186) (xy 133.005714 -286.818092) (xy 133.045136 -286.785905) (xy 133.08921 -286.760459)
			(xy 133.136796 -286.742412) (xy 133.18666 -286.732232) (xy 133.237512 -286.730183) (xy 133.288033 -286.736317)
			(xy 133.336917 -286.750477) (xy 133.382896 -286.772294) (xy 133.42478 -286.801204) (xy 133.461484 -286.836459)
			(xy 133.492057 -286.877145) (xy 133.515708 -286.922208) (xy 133.531824 -286.970482) (xy 133.539988 -287.020716)
			(xy 133.5405 -287.046162) (xy 133.539992 -287.071405) (xy 133.847314 -287.071405) (xy 133.847314 -287.021427)
			(xy 133.855133 -286.972064) (xy 133.870577 -286.924532) (xy 133.893267 -286.88) (xy 133.922643 -286.839567)
			(xy 133.957983 -286.804227) (xy 133.998416 -286.774851) (xy 134.042948 -286.752161) (xy 134.09048 -286.736717)
			(xy 134.139843 -286.728898) (xy 134.189821 -286.728898) (xy 134.239184 -286.736717) (xy 134.286716 -286.752161)
			(xy 134.331248 -286.774851) (xy 134.371681 -286.804227) (xy 134.407021 -286.839567) (xy 134.436397 -286.88)
			(xy 134.459087 -286.924532) (xy 134.474531 -286.972064) (xy 134.48235 -287.021427) (xy 134.482835 -287.046162)
			(xy 134.788397 -287.046162) (xy 134.792492 -286.995434) (xy 134.804671 -286.94602) (xy 134.824619 -286.8992)
			(xy 134.85182 -286.856186) (xy 134.885568 -286.818092) (xy 134.92499 -286.785905) (xy 134.969064 -286.760459)
			(xy 135.01665 -286.742412) (xy 135.066514 -286.732232) (xy 135.117366 -286.730183) (xy 135.167887 -286.736317)
			(xy 135.216771 -286.750477) (xy 135.26275 -286.772294) (xy 135.304634 -286.801204) (xy 135.341338 -286.836459)
			(xy 135.371911 -286.877145) (xy 135.395562 -286.922208) (xy 135.411678 -286.970482) (xy 135.419842 -287.020716)
			(xy 135.420354 -287.046162) (xy 135.728451 -287.046162) (xy 135.732546 -286.995434) (xy 135.744725 -286.94602)
			(xy 135.764673 -286.8992) (xy 135.791874 -286.856186) (xy 135.825622 -286.818092) (xy 135.865044 -286.785905)
			(xy 135.909118 -286.760459) (xy 135.956704 -286.742412) (xy 136.006568 -286.732232) (xy 136.05742 -286.730183)
			(xy 136.107941 -286.736317) (xy 136.156825 -286.750477) (xy 136.202804 -286.772294) (xy 136.244688 -286.801204)
			(xy 136.281392 -286.836459) (xy 136.311965 -286.877145) (xy 136.335616 -286.922208) (xy 136.351732 -286.970482)
			(xy 136.359896 -287.020716) (xy 136.360408 -287.046162) (xy 136.359905 -287.071151) (xy 136.667222 -287.071151)
			(xy 136.667222 -287.021173) (xy 136.675041 -286.97181) (xy 136.690485 -286.924278) (xy 136.713175 -286.879746)
			(xy 136.742551 -286.839313) (xy 136.777891 -286.803973) (xy 136.818324 -286.774597) (xy 136.862856 -286.751907)
			(xy 136.910388 -286.736463) (xy 136.959751 -286.728644) (xy 137.009729 -286.728644) (xy 137.059092 -286.736463)
			(xy 137.106624 -286.751907) (xy 137.151156 -286.774597) (xy 137.191589 -286.803973) (xy 137.226929 -286.839313)
			(xy 137.256305 -286.879746) (xy 137.278995 -286.924278) (xy 137.294439 -286.97181) (xy 137.302258 -287.021173)
			(xy 137.302748 -287.046162) (xy 137.608559 -287.046162) (xy 137.612654 -286.995434) (xy 137.624833 -286.94602)
			(xy 137.644781 -286.8992) (xy 137.671982 -286.856186) (xy 137.70573 -286.818092) (xy 137.745152 -286.785905)
			(xy 137.789226 -286.760459) (xy 137.836812 -286.742412) (xy 137.886676 -286.732232) (xy 137.937528 -286.730183)
			(xy 137.988049 -286.736317) (xy 138.036933 -286.750477) (xy 138.082912 -286.772294) (xy 138.124796 -286.801204)
			(xy 138.1615 -286.836459) (xy 138.192073 -286.877145) (xy 138.215724 -286.922208) (xy 138.23184 -286.970482)
			(xy 138.240004 -287.020716) (xy 138.240516 -287.046162) (xy 138.240008 -287.071405) (xy 138.54733 -287.071405)
			(xy 138.54733 -287.021427) (xy 138.555149 -286.972064) (xy 138.570593 -286.924532) (xy 138.593283 -286.88)
			(xy 138.622659 -286.839567) (xy 138.657999 -286.804227) (xy 138.698432 -286.774851) (xy 138.742964 -286.752161)
			(xy 138.790496 -286.736717) (xy 138.839859 -286.728898) (xy 138.889837 -286.728898) (xy 138.9392 -286.736717)
			(xy 138.986732 -286.752161) (xy 139.031264 -286.774851) (xy 139.071697 -286.804227) (xy 139.107037 -286.839567)
			(xy 139.136413 -286.88) (xy 139.159103 -286.924532) (xy 139.174547 -286.972064) (xy 139.182366 -287.021427)
			(xy 139.182851 -287.046162) (xy 139.488413 -287.046162) (xy 139.492508 -286.995434) (xy 139.504687 -286.94602)
			(xy 139.524635 -286.8992) (xy 139.551836 -286.856186) (xy 139.585584 -286.818092) (xy 139.625006 -286.785905)
			(xy 139.66908 -286.760459) (xy 139.716666 -286.742412) (xy 139.76653 -286.732232) (xy 139.817382 -286.730183)
			(xy 139.867903 -286.736317) (xy 139.916787 -286.750477) (xy 139.962766 -286.772294) (xy 140.00465 -286.801204)
			(xy 140.041354 -286.836459) (xy 140.071927 -286.877145) (xy 140.095578 -286.922208) (xy 140.111694 -286.970482)
			(xy 140.119858 -287.020716) (xy 140.12037 -287.046162) (xy 140.119867 -287.071151) (xy 140.427184 -287.071151)
			(xy 140.427184 -287.021173) (xy 140.435003 -286.97181) (xy 140.450447 -286.924278) (xy 140.473137 -286.879746)
			(xy 140.502513 -286.839313) (xy 140.537853 -286.803973) (xy 140.578286 -286.774597) (xy 140.622818 -286.751907)
			(xy 140.67035 -286.736463) (xy 140.719713 -286.728644) (xy 140.769691 -286.728644) (xy 140.819054 -286.736463)
			(xy 140.866586 -286.751907) (xy 140.911118 -286.774597) (xy 140.951551 -286.803973) (xy 140.986891 -286.839313)
			(xy 141.016267 -286.879746) (xy 141.038957 -286.924278) (xy 141.054401 -286.97181) (xy 141.06222 -287.021173)
			(xy 141.06271 -287.046162) (xy 141.368521 -287.046162) (xy 141.372616 -286.995434) (xy 141.384795 -286.94602)
			(xy 141.404743 -286.8992) (xy 141.431944 -286.856186) (xy 141.465692 -286.818092) (xy 141.505114 -286.785905)
			(xy 141.549188 -286.760459) (xy 141.596774 -286.742412) (xy 141.646638 -286.732232) (xy 141.69749 -286.730183)
			(xy 141.748011 -286.736317) (xy 141.796895 -286.750477) (xy 141.842874 -286.772294) (xy 141.884758 -286.801204)
			(xy 141.921462 -286.836459) (xy 141.952035 -286.877145) (xy 141.975686 -286.922208) (xy 141.991802 -286.970482)
			(xy 141.999966 -287.020716) (xy 142.000478 -287.046162) (xy 142.308575 -287.046162) (xy 142.31267 -286.995434)
			(xy 142.324849 -286.94602) (xy 142.344797 -286.8992) (xy 142.371998 -286.856186) (xy 142.405746 -286.818092)
			(xy 142.445168 -286.785905) (xy 142.489242 -286.760459) (xy 142.536828 -286.742412) (xy 142.586692 -286.732232)
			(xy 142.637544 -286.730183) (xy 142.688065 -286.736317) (xy 142.736949 -286.750477) (xy 142.782928 -286.772294)
			(xy 142.824812 -286.801204) (xy 142.861516 -286.836459) (xy 142.892089 -286.877145) (xy 142.91574 -286.922208)
			(xy 142.931856 -286.970482) (xy 142.94002 -287.020716) (xy 142.940532 -287.046162) (xy 142.940029 -287.071151)
			(xy 143.247092 -287.071151) (xy 143.247092 -287.021173) (xy 143.254911 -286.97181) (xy 143.270355 -286.924278)
			(xy 143.293045 -286.879746) (xy 143.322421 -286.839313) (xy 143.357761 -286.803973) (xy 143.398194 -286.774597)
			(xy 143.442726 -286.751907) (xy 143.490258 -286.736463) (xy 143.539621 -286.728644) (xy 143.589599 -286.728644)
			(xy 143.638962 -286.736463) (xy 143.686494 -286.751907) (xy 143.731026 -286.774597) (xy 143.771459 -286.803973)
			(xy 143.806799 -286.839313) (xy 143.836175 -286.879746) (xy 143.858865 -286.924278) (xy 143.874309 -286.97181)
			(xy 143.882128 -287.021173) (xy 143.882618 -287.046162) (xy 143.882128 -287.071151) (xy 143.874309 -287.120514)
			(xy 143.858865 -287.168046) (xy 143.836175 -287.212578) (xy 143.806799 -287.253011) (xy 143.771459 -287.288351)
			(xy 143.731026 -287.317727) (xy 143.686494 -287.340417) (xy 143.638962 -287.355861) (xy 143.589599 -287.36368)
			(xy 143.539621 -287.36368) (xy 143.490258 -287.355861) (xy 143.442726 -287.340417) (xy 143.398194 -287.317727)
			(xy 143.357761 -287.288351) (xy 143.322421 -287.253011) (xy 143.293045 -287.212578) (xy 143.270355 -287.168046)
			(xy 143.254911 -287.120514) (xy 143.247092 -287.071151) (xy 142.940029 -287.071151) (xy 142.94002 -287.071608)
			(xy 142.931856 -287.121842) (xy 142.91574 -287.170116) (xy 142.892089 -287.215179) (xy 142.861516 -287.255865)
			(xy 142.824812 -287.29112) (xy 142.782928 -287.32003) (xy 142.736949 -287.341847) (xy 142.688065 -287.356007)
			(xy 142.637544 -287.362141) (xy 142.586692 -287.360092) (xy 142.536828 -287.349912) (xy 142.489242 -287.331865)
			(xy 142.445168 -287.306419) (xy 142.405746 -287.274232) (xy 142.371998 -287.236138) (xy 142.344797 -287.193124)
			(xy 142.324849 -287.146304) (xy 142.31267 -287.09689) (xy 142.308575 -287.046162) (xy 142.000478 -287.046162)
			(xy 141.999966 -287.071608) (xy 141.991802 -287.121842) (xy 141.975686 -287.170116) (xy 141.952035 -287.215179)
			(xy 141.921462 -287.255865) (xy 141.884758 -287.29112) (xy 141.842874 -287.32003) (xy 141.796895 -287.341847)
			(xy 141.748011 -287.356007) (xy 141.69749 -287.362141) (xy 141.646638 -287.360092) (xy 141.596774 -287.349912)
			(xy 141.549188 -287.331865) (xy 141.505114 -287.306419) (xy 141.465692 -287.274232) (xy 141.431944 -287.236138)
			(xy 141.404743 -287.193124) (xy 141.384795 -287.146304) (xy 141.372616 -287.09689) (xy 141.368521 -287.046162)
			(xy 141.06271 -287.046162) (xy 141.06222 -287.071151) (xy 141.054401 -287.120514) (xy 141.038957 -287.168046)
			(xy 141.016267 -287.212578) (xy 140.986891 -287.253011) (xy 140.951551 -287.288351) (xy 140.911118 -287.317727)
			(xy 140.866586 -287.340417) (xy 140.819054 -287.355861) (xy 140.769691 -287.36368) (xy 140.719713 -287.36368)
			(xy 140.67035 -287.355861) (xy 140.622818 -287.340417) (xy 140.578286 -287.317727) (xy 140.537853 -287.288351)
			(xy 140.502513 -287.253011) (xy 140.473137 -287.212578) (xy 140.450447 -287.168046) (xy 140.435003 -287.120514)
			(xy 140.427184 -287.071151) (xy 140.119867 -287.071151) (xy 140.119858 -287.071608) (xy 140.111694 -287.121842)
			(xy 140.095578 -287.170116) (xy 140.071927 -287.215179) (xy 140.041354 -287.255865) (xy 140.00465 -287.29112)
			(xy 139.962766 -287.32003) (xy 139.916787 -287.341847) (xy 139.867903 -287.356007) (xy 139.817382 -287.362141)
			(xy 139.76653 -287.360092) (xy 139.716666 -287.349912) (xy 139.66908 -287.331865) (xy 139.625006 -287.306419)
			(xy 139.585584 -287.274232) (xy 139.551836 -287.236138) (xy 139.524635 -287.193124) (xy 139.504687 -287.146304)
			(xy 139.492508 -287.09689) (xy 139.488413 -287.046162) (xy 139.182851 -287.046162) (xy 139.182856 -287.046416)
			(xy 139.182366 -287.071405) (xy 139.174547 -287.120768) (xy 139.159103 -287.1683) (xy 139.136413 -287.212832)
			(xy 139.107037 -287.253265) (xy 139.071697 -287.288605) (xy 139.031264 -287.317981) (xy 138.986732 -287.340671)
			(xy 138.9392 -287.356115) (xy 138.889837 -287.363934) (xy 138.839859 -287.363934) (xy 138.790496 -287.356115)
			(xy 138.742964 -287.340671) (xy 138.698432 -287.317981) (xy 138.657999 -287.288605) (xy 138.622659 -287.253265)
			(xy 138.593283 -287.212832) (xy 138.570593 -287.1683) (xy 138.555149 -287.120768) (xy 138.54733 -287.071405)
			(xy 138.240008 -287.071405) (xy 138.240004 -287.071608) (xy 138.23184 -287.121842) (xy 138.215724 -287.170116)
			(xy 138.192073 -287.215179) (xy 138.1615 -287.255865) (xy 138.124796 -287.29112) (xy 138.082912 -287.32003)
			(xy 138.036933 -287.341847) (xy 137.988049 -287.356007) (xy 137.937528 -287.362141) (xy 137.886676 -287.360092)
			(xy 137.836812 -287.349912) (xy 137.789226 -287.331865) (xy 137.745152 -287.306419) (xy 137.70573 -287.274232)
			(xy 137.671982 -287.236138) (xy 137.644781 -287.193124) (xy 137.624833 -287.146304) (xy 137.612654 -287.09689)
			(xy 137.608559 -287.046162) (xy 137.302748 -287.046162) (xy 137.302258 -287.071151) (xy 137.294439 -287.120514)
			(xy 137.278995 -287.168046) (xy 137.256305 -287.212578) (xy 137.226929 -287.253011) (xy 137.191589 -287.288351)
			(xy 137.151156 -287.317727) (xy 137.106624 -287.340417) (xy 137.059092 -287.355861) (xy 137.009729 -287.36368)
			(xy 136.959751 -287.36368) (xy 136.910388 -287.355861) (xy 136.862856 -287.340417) (xy 136.818324 -287.317727)
			(xy 136.777891 -287.288351) (xy 136.742551 -287.253011) (xy 136.713175 -287.212578) (xy 136.690485 -287.168046)
			(xy 136.675041 -287.120514) (xy 136.667222 -287.071151) (xy 136.359905 -287.071151) (xy 136.359896 -287.071608)
			(xy 136.351732 -287.121842) (xy 136.335616 -287.170116) (xy 136.311965 -287.215179) (xy 136.281392 -287.255865)
			(xy 136.244688 -287.29112) (xy 136.202804 -287.32003) (xy 136.156825 -287.341847) (xy 136.107941 -287.356007)
			(xy 136.05742 -287.362141) (xy 136.006568 -287.360092) (xy 135.956704 -287.349912) (xy 135.909118 -287.331865)
			(xy 135.865044 -287.306419) (xy 135.825622 -287.274232) (xy 135.791874 -287.236138) (xy 135.764673 -287.193124)
			(xy 135.744725 -287.146304) (xy 135.732546 -287.09689) (xy 135.728451 -287.046162) (xy 135.420354 -287.046162)
			(xy 135.419842 -287.071608) (xy 135.411678 -287.121842) (xy 135.395562 -287.170116) (xy 135.371911 -287.215179)
			(xy 135.341338 -287.255865) (xy 135.304634 -287.29112) (xy 135.26275 -287.32003) (xy 135.216771 -287.341847)
			(xy 135.167887 -287.356007) (xy 135.117366 -287.362141) (xy 135.066514 -287.360092) (xy 135.01665 -287.349912)
			(xy 134.969064 -287.331865) (xy 134.92499 -287.306419) (xy 134.885568 -287.274232) (xy 134.85182 -287.236138)
			(xy 134.824619 -287.193124) (xy 134.804671 -287.146304) (xy 134.792492 -287.09689) (xy 134.788397 -287.046162)
			(xy 134.482835 -287.046162) (xy 134.48284 -287.046416) (xy 134.48235 -287.071405) (xy 134.474531 -287.120768)
			(xy 134.459087 -287.1683) (xy 134.436397 -287.212832) (xy 134.407021 -287.253265) (xy 134.371681 -287.288605)
			(xy 134.331248 -287.317981) (xy 134.286716 -287.340671) (xy 134.239184 -287.356115) (xy 134.189821 -287.363934)
			(xy 134.139843 -287.363934) (xy 134.09048 -287.356115) (xy 134.042948 -287.340671) (xy 133.998416 -287.317981)
			(xy 133.957983 -287.288605) (xy 133.922643 -287.253265) (xy 133.893267 -287.212832) (xy 133.870577 -287.1683)
			(xy 133.855133 -287.120768) (xy 133.847314 -287.071405) (xy 133.539992 -287.071405) (xy 133.539988 -287.071608)
			(xy 133.531824 -287.121842) (xy 133.515708 -287.170116) (xy 133.492057 -287.215179) (xy 133.461484 -287.255865)
			(xy 133.42478 -287.29112) (xy 133.382896 -287.32003) (xy 133.336917 -287.341847) (xy 133.288033 -287.356007)
			(xy 133.237512 -287.362141) (xy 133.18666 -287.360092) (xy 133.136796 -287.349912) (xy 133.08921 -287.331865)
			(xy 133.045136 -287.306419) (xy 133.005714 -287.274232) (xy 132.971966 -287.236138) (xy 132.944765 -287.193124)
			(xy 132.924817 -287.146304) (xy 132.912638 -287.09689) (xy 132.908543 -287.046162) (xy 132.602732 -287.046162)
			(xy 132.602242 -287.071151) (xy 132.594423 -287.120514) (xy 132.578979 -287.168046) (xy 132.556289 -287.212578)
			(xy 132.526913 -287.253011) (xy 132.491573 -287.288351) (xy 132.45114 -287.317727) (xy 132.406608 -287.340417)
			(xy 132.359076 -287.355861) (xy 132.309713 -287.36368) (xy 132.259735 -287.36368) (xy 132.210372 -287.355861)
			(xy 132.16284 -287.340417) (xy 132.118308 -287.317727) (xy 132.077875 -287.288351) (xy 132.042535 -287.253011)
			(xy 132.013159 -287.212578) (xy 131.990469 -287.168046) (xy 131.975025 -287.120514) (xy 131.967206 -287.071151)
			(xy 131.659889 -287.071151) (xy 131.65988 -287.071608) (xy 131.651716 -287.121842) (xy 131.6356 -287.170116)
			(xy 131.611949 -287.215179) (xy 131.581376 -287.255865) (xy 131.544672 -287.29112) (xy 131.502788 -287.32003)
			(xy 131.456809 -287.341847) (xy 131.407925 -287.356007) (xy 131.357404 -287.362141) (xy 131.306552 -287.360092)
			(xy 131.256688 -287.349912) (xy 131.209102 -287.331865) (xy 131.165028 -287.306419) (xy 131.125606 -287.274232)
			(xy 131.091858 -287.236138) (xy 131.064657 -287.193124) (xy 131.044709 -287.146304) (xy 131.03253 -287.09689)
			(xy 131.028435 -287.046162) (xy 130.722873 -287.046162) (xy 130.722878 -287.046416) (xy 130.722388 -287.071405)
			(xy 130.714569 -287.120768) (xy 130.699125 -287.1683) (xy 130.676435 -287.212832) (xy 130.647059 -287.253265)
			(xy 130.611719 -287.288605) (xy 130.571286 -287.317981) (xy 130.526754 -287.340671) (xy 130.479222 -287.356115)
			(xy 130.429859 -287.363934) (xy 130.379881 -287.363934) (xy 130.330518 -287.356115) (xy 130.282986 -287.340671)
			(xy 130.238454 -287.317981) (xy 130.198021 -287.288605) (xy 130.162681 -287.253265) (xy 130.133305 -287.212832)
			(xy 130.110615 -287.1683) (xy 130.095171 -287.120768) (xy 130.087352 -287.071405) (xy 129.78003 -287.071405)
			(xy 129.780026 -287.071608) (xy 129.771862 -287.121842) (xy 129.755746 -287.170116) (xy 129.732095 -287.215179)
			(xy 129.701522 -287.255865) (xy 129.664818 -287.29112) (xy 129.622934 -287.32003) (xy 129.576955 -287.341847)
			(xy 129.528071 -287.356007) (xy 129.47755 -287.362141) (xy 129.426698 -287.360092) (xy 129.376834 -287.349912)
			(xy 129.329248 -287.331865) (xy 129.285174 -287.306419) (xy 129.245752 -287.274232) (xy 129.212004 -287.236138)
			(xy 129.184803 -287.193124) (xy 129.164855 -287.146304) (xy 129.152676 -287.09689) (xy 129.148581 -287.046162)
			(xy 128.840484 -287.046162) (xy 128.839972 -287.071608) (xy 128.831808 -287.121842) (xy 128.815692 -287.170116)
			(xy 128.792041 -287.215179) (xy 128.761468 -287.255865) (xy 128.724764 -287.29112) (xy 128.68288 -287.32003)
			(xy 128.636901 -287.341847) (xy 128.588017 -287.356007) (xy 128.537496 -287.362141) (xy 128.486644 -287.360092)
			(xy 128.43678 -287.349912) (xy 128.389194 -287.331865) (xy 128.34512 -287.306419) (xy 128.305698 -287.274232)
			(xy 128.27195 -287.236138) (xy 128.244749 -287.193124) (xy 128.224801 -287.146304) (xy 128.212622 -287.09689)
			(xy 128.208527 -287.046162) (xy 127.902716 -287.046162) (xy 127.902254 -287.071155) (xy 127.89444 -287.120528)
			(xy 127.878998 -287.168069) (xy 127.856309 -287.21261) (xy 127.826931 -287.253052) (xy 127.791587 -287.288401)
			(xy 127.751149 -287.317785) (xy 127.706612 -287.340481) (xy 127.659072 -287.355929) (xy 127.609701 -287.363751)
			(xy 127.584708 -287.36417) (xy 127.584454 -287.36417) (xy 127.561327 -287.363749) (xy 127.515559 -287.357053)
			(xy 127.471236 -287.343823) (xy 127.450088 -287.334452) (xy 127.442722 -287.330896) (xy 127.432816 -287.32607)
			(xy 127.42418 -287.3248) (xy 127.415529 -287.323971) (xy 127.398516 -287.327463) (xy 127.390906 -287.331658)
			(xy 127.31877 -287.3756) (xy 127.311522 -287.380424) (xy 127.300553 -287.393929) (xy 127.294756 -287.410334)
			(xy 127.294386 -287.419034) (xy 127.294386 -287.551114) (xy 127.295656 -287.561782) (xy 127.297688 -287.571688)
			(xy 127.298958 -287.578038) (xy 127.308864 -287.598358) (xy 127.310844 -287.60234) (xy 127.315951 -287.609621)
			(xy 127.319024 -287.612836) (xy 127.321564 -287.614868) (xy 127.342059 -287.633149) (xy 127.377047 -287.675476)
			(xy 127.404237 -287.723187) (xy 127.422819 -287.774863) (xy 127.432239 -287.828964) (xy 127.432816 -287.856422)
			(xy 127.738627 -287.856422) (xy 127.742722 -287.805694) (xy 127.754901 -287.75628) (xy 127.774849 -287.70946)
			(xy 127.80205 -287.666446) (xy 127.835798 -287.628352) (xy 127.87522 -287.596165) (xy 127.919294 -287.570719)
			(xy 127.96688 -287.552672) (xy 128.016744 -287.542492) (xy 128.067596 -287.540443) (xy 128.118117 -287.546577)
			(xy 128.167001 -287.560737) (xy 128.21298 -287.582554) (xy 128.254864 -287.611464) (xy 128.291568 -287.646719)
			(xy 128.322141 -287.687405) (xy 128.345792 -287.732468) (xy 128.361908 -287.780742) (xy 128.370072 -287.830976)
			(xy 128.370584 -287.856422) (xy 128.370081 -287.881411) (xy 128.677144 -287.881411) (xy 128.677144 -287.831433)
			(xy 128.684963 -287.78207) (xy 128.700407 -287.734538) (xy 128.723097 -287.690006) (xy 128.752473 -287.649573)
			(xy 128.787813 -287.614233) (xy 128.828246 -287.584857) (xy 128.872778 -287.562167) (xy 128.92031 -287.546723)
			(xy 128.969673 -287.538904) (xy 129.019651 -287.538904) (xy 129.069014 -287.546723) (xy 129.116546 -287.562167)
			(xy 129.161078 -287.584857) (xy 129.201511 -287.614233) (xy 129.236851 -287.649573) (xy 129.266227 -287.690006)
			(xy 129.288917 -287.734538) (xy 129.304361 -287.78207) (xy 129.31218 -287.831433) (xy 129.31267 -287.856422)
			(xy 129.618481 -287.856422) (xy 129.622576 -287.805694) (xy 129.634755 -287.75628) (xy 129.654703 -287.70946)
			(xy 129.681904 -287.666446) (xy 129.715652 -287.628352) (xy 129.755074 -287.596165) (xy 129.799148 -287.570719)
			(xy 129.846734 -287.552672) (xy 129.896598 -287.542492) (xy 129.94745 -287.540443) (xy 129.997971 -287.546577)
			(xy 130.046855 -287.560737) (xy 130.092834 -287.582554) (xy 130.134718 -287.611464) (xy 130.171422 -287.646719)
			(xy 130.201995 -287.687405) (xy 130.225646 -287.732468) (xy 130.241762 -287.780742) (xy 130.249926 -287.830976)
			(xy 130.250438 -287.856422) (xy 131.498589 -287.856422) (xy 131.502684 -287.805694) (xy 131.514863 -287.75628)
			(xy 131.534811 -287.70946) (xy 131.562012 -287.666446) (xy 131.59576 -287.628352) (xy 131.635182 -287.596165)
			(xy 131.679256 -287.570719) (xy 131.726842 -287.552672) (xy 131.776706 -287.542492) (xy 131.827558 -287.540443)
			(xy 131.878079 -287.546577) (xy 131.926963 -287.560737) (xy 131.972942 -287.582554) (xy 132.014826 -287.611464)
			(xy 132.05153 -287.646719) (xy 132.082103 -287.687405) (xy 132.105754 -287.732468) (xy 132.12187 -287.780742)
			(xy 132.130034 -287.830976) (xy 132.130546 -287.856422) (xy 132.438643 -287.856422) (xy 132.442738 -287.805694)
			(xy 132.454917 -287.75628) (xy 132.474865 -287.70946) (xy 132.502066 -287.666446) (xy 132.535814 -287.628352)
			(xy 132.575236 -287.596165) (xy 132.61931 -287.570719) (xy 132.666896 -287.552672) (xy 132.71676 -287.542492)
			(xy 132.767612 -287.540443) (xy 132.818133 -287.546577) (xy 132.867017 -287.560737) (xy 132.912996 -287.582554)
			(xy 132.95488 -287.611464) (xy 132.991584 -287.646719) (xy 133.022157 -287.687405) (xy 133.045808 -287.732468)
			(xy 133.061924 -287.780742) (xy 133.070088 -287.830976) (xy 133.0706 -287.856422) (xy 133.070097 -287.881411)
			(xy 133.37716 -287.881411) (xy 133.37716 -287.831433) (xy 133.384979 -287.78207) (xy 133.400423 -287.734538)
			(xy 133.423113 -287.690006) (xy 133.452489 -287.649573) (xy 133.487829 -287.614233) (xy 133.528262 -287.584857)
			(xy 133.572794 -287.562167) (xy 133.620326 -287.546723) (xy 133.669689 -287.538904) (xy 133.719667 -287.538904)
			(xy 133.76903 -287.546723) (xy 133.816562 -287.562167) (xy 133.861094 -287.584857) (xy 133.901527 -287.614233)
			(xy 133.936867 -287.649573) (xy 133.966243 -287.690006) (xy 133.988933 -287.734538) (xy 134.004377 -287.78207)
			(xy 134.012196 -287.831433) (xy 134.012686 -287.856422) (xy 134.318497 -287.856422) (xy 134.322592 -287.805694)
			(xy 134.334771 -287.75628) (xy 134.354719 -287.70946) (xy 134.38192 -287.666446) (xy 134.415668 -287.628352)
			(xy 134.45509 -287.596165) (xy 134.499164 -287.570719) (xy 134.54675 -287.552672) (xy 134.596614 -287.542492)
			(xy 134.647466 -287.540443) (xy 134.697987 -287.546577) (xy 134.746871 -287.560737) (xy 134.79285 -287.582554)
			(xy 134.834734 -287.611464) (xy 134.871438 -287.646719) (xy 134.902011 -287.687405) (xy 134.925662 -287.732468)
			(xy 134.941778 -287.780742) (xy 134.949942 -287.830976) (xy 134.950454 -287.856422) (xy 134.949951 -287.881411)
			(xy 135.257268 -287.881411) (xy 135.257268 -287.831433) (xy 135.265087 -287.78207) (xy 135.280531 -287.734538)
			(xy 135.303221 -287.690006) (xy 135.332597 -287.649573) (xy 135.367937 -287.614233) (xy 135.40837 -287.584857)
			(xy 135.452902 -287.562167) (xy 135.500434 -287.546723) (xy 135.549797 -287.538904) (xy 135.599775 -287.538904)
			(xy 135.649138 -287.546723) (xy 135.69667 -287.562167) (xy 135.741202 -287.584857) (xy 135.781635 -287.614233)
			(xy 135.816975 -287.649573) (xy 135.846351 -287.690006) (xy 135.869041 -287.734538) (xy 135.884485 -287.78207)
			(xy 135.892304 -287.831433) (xy 135.892794 -287.856422) (xy 136.198605 -287.856422) (xy 136.2027 -287.805694)
			(xy 136.214879 -287.75628) (xy 136.234827 -287.70946) (xy 136.262028 -287.666446) (xy 136.295776 -287.628352)
			(xy 136.335198 -287.596165) (xy 136.379272 -287.570719) (xy 136.426858 -287.552672) (xy 136.476722 -287.542492)
			(xy 136.527574 -287.540443) (xy 136.578095 -287.546577) (xy 136.626979 -287.560737) (xy 136.672958 -287.582554)
			(xy 136.714842 -287.611464) (xy 136.751546 -287.646719) (xy 136.782119 -287.687405) (xy 136.80577 -287.732468)
			(xy 136.821886 -287.780742) (xy 136.83005 -287.830976) (xy 136.830562 -287.856422) (xy 138.078459 -287.856422)
			(xy 138.082554 -287.805694) (xy 138.094733 -287.75628) (xy 138.114681 -287.70946) (xy 138.141882 -287.666446)
			(xy 138.17563 -287.628352) (xy 138.215052 -287.596165) (xy 138.259126 -287.570719) (xy 138.306712 -287.552672)
			(xy 138.356576 -287.542492) (xy 138.407428 -287.540443) (xy 138.457949 -287.546577) (xy 138.506833 -287.560737)
			(xy 138.552812 -287.582554) (xy 138.594696 -287.611464) (xy 138.6314 -287.646719) (xy 138.661973 -287.687405)
			(xy 138.685624 -287.732468) (xy 138.70174 -287.780742) (xy 138.709904 -287.830976) (xy 138.710416 -287.856422)
			(xy 139.018513 -287.856422) (xy 139.022608 -287.805694) (xy 139.034787 -287.75628) (xy 139.054735 -287.70946)
			(xy 139.081936 -287.666446) (xy 139.115684 -287.628352) (xy 139.155106 -287.596165) (xy 139.19918 -287.570719)
			(xy 139.246766 -287.552672) (xy 139.29663 -287.542492) (xy 139.347482 -287.540443) (xy 139.398003 -287.546577)
			(xy 139.446887 -287.560737) (xy 139.492866 -287.582554) (xy 139.53475 -287.611464) (xy 139.571454 -287.646719)
			(xy 139.602027 -287.687405) (xy 139.625678 -287.732468) (xy 139.641794 -287.780742) (xy 139.649958 -287.830976)
			(xy 139.65047 -287.856422) (xy 139.649967 -287.881411) (xy 139.957284 -287.881411) (xy 139.957284 -287.831433)
			(xy 139.965103 -287.78207) (xy 139.980547 -287.734538) (xy 140.003237 -287.690006) (xy 140.032613 -287.649573)
			(xy 140.067953 -287.614233) (xy 140.108386 -287.584857) (xy 140.152918 -287.562167) (xy 140.20045 -287.546723)
			(xy 140.249813 -287.538904) (xy 140.299791 -287.538904) (xy 140.349154 -287.546723) (xy 140.396686 -287.562167)
			(xy 140.441218 -287.584857) (xy 140.481651 -287.614233) (xy 140.516991 -287.649573) (xy 140.546367 -287.690006)
			(xy 140.569057 -287.734538) (xy 140.584501 -287.78207) (xy 140.59232 -287.831433) (xy 140.59281 -287.856422)
			(xy 140.898621 -287.856422) (xy 140.902716 -287.805694) (xy 140.914895 -287.75628) (xy 140.934843 -287.70946)
			(xy 140.962044 -287.666446) (xy 140.995792 -287.628352) (xy 141.035214 -287.596165) (xy 141.079288 -287.570719)
			(xy 141.126874 -287.552672) (xy 141.176738 -287.542492) (xy 141.22759 -287.540443) (xy 141.278111 -287.546577)
			(xy 141.326995 -287.560737) (xy 141.372974 -287.582554) (xy 141.414858 -287.611464) (xy 141.451562 -287.646719)
			(xy 141.482135 -287.687405) (xy 141.505786 -287.732468) (xy 141.521902 -287.780742) (xy 141.530066 -287.830976)
			(xy 141.530578 -287.856422) (xy 141.530075 -287.881411) (xy 141.837138 -287.881411) (xy 141.837138 -287.831433)
			(xy 141.844957 -287.78207) (xy 141.860401 -287.734538) (xy 141.883091 -287.690006) (xy 141.912467 -287.649573)
			(xy 141.947807 -287.614233) (xy 141.98824 -287.584857) (xy 142.032772 -287.562167) (xy 142.080304 -287.546723)
			(xy 142.129667 -287.538904) (xy 142.179645 -287.538904) (xy 142.229008 -287.546723) (xy 142.27654 -287.562167)
			(xy 142.321072 -287.584857) (xy 142.361505 -287.614233) (xy 142.396845 -287.649573) (xy 142.426221 -287.690006)
			(xy 142.448911 -287.734538) (xy 142.464355 -287.78207) (xy 142.472174 -287.831433) (xy 142.472664 -287.856422)
			(xy 142.778475 -287.856422) (xy 142.78257 -287.805694) (xy 142.794749 -287.75628) (xy 142.814697 -287.70946)
			(xy 142.841898 -287.666446) (xy 142.875646 -287.628352) (xy 142.915068 -287.596165) (xy 142.959142 -287.570719)
			(xy 143.006728 -287.552672) (xy 143.056592 -287.542492) (xy 143.107444 -287.540443) (xy 143.157965 -287.546577)
			(xy 143.206849 -287.560737) (xy 143.252828 -287.582554) (xy 143.294712 -287.611464) (xy 143.331416 -287.646719)
			(xy 143.361989 -287.687405) (xy 143.38564 -287.732468) (xy 143.401756 -287.780742) (xy 143.40992 -287.830976)
			(xy 143.410432 -287.856422) (xy 143.40992 -287.881868) (xy 143.401756 -287.932102) (xy 143.38564 -287.980376)
			(xy 143.361989 -288.025439) (xy 143.331416 -288.066125) (xy 143.294712 -288.10138) (xy 143.252828 -288.13029)
			(xy 143.206849 -288.152107) (xy 143.157965 -288.166267) (xy 143.107444 -288.172401) (xy 143.056592 -288.170352)
			(xy 143.006728 -288.160172) (xy 142.959142 -288.142125) (xy 142.915068 -288.116679) (xy 142.875646 -288.084492)
			(xy 142.841898 -288.046398) (xy 142.814697 -288.003384) (xy 142.794749 -287.956564) (xy 142.78257 -287.90715)
			(xy 142.778475 -287.856422) (xy 142.472664 -287.856422) (xy 142.472174 -287.881411) (xy 142.464355 -287.930774)
			(xy 142.448911 -287.978306) (xy 142.426221 -288.022838) (xy 142.396845 -288.063271) (xy 142.361505 -288.098611)
			(xy 142.321072 -288.127987) (xy 142.27654 -288.150677) (xy 142.229008 -288.166121) (xy 142.179645 -288.17394)
			(xy 142.129667 -288.17394) (xy 142.080304 -288.166121) (xy 142.032772 -288.150677) (xy 141.98824 -288.127987)
			(xy 141.947807 -288.098611) (xy 141.912467 -288.063271) (xy 141.883091 -288.022838) (xy 141.860401 -287.978306)
			(xy 141.844957 -287.930774) (xy 141.837138 -287.881411) (xy 141.530075 -287.881411) (xy 141.530066 -287.881868)
			(xy 141.521902 -287.932102) (xy 141.505786 -287.980376) (xy 141.482135 -288.025439) (xy 141.451562 -288.066125)
			(xy 141.414858 -288.10138) (xy 141.372974 -288.13029) (xy 141.326995 -288.152107) (xy 141.278111 -288.166267)
			(xy 141.22759 -288.172401) (xy 141.176738 -288.170352) (xy 141.126874 -288.160172) (xy 141.079288 -288.142125)
			(xy 141.035214 -288.116679) (xy 140.995792 -288.084492) (xy 140.962044 -288.046398) (xy 140.934843 -288.003384)
			(xy 140.914895 -287.956564) (xy 140.902716 -287.90715) (xy 140.898621 -287.856422) (xy 140.59281 -287.856422)
			(xy 140.59232 -287.881411) (xy 140.584501 -287.930774) (xy 140.569057 -287.978306) (xy 140.546367 -288.022838)
			(xy 140.516991 -288.063271) (xy 140.481651 -288.098611) (xy 140.441218 -288.127987) (xy 140.396686 -288.150677)
			(xy 140.349154 -288.166121) (xy 140.299791 -288.17394) (xy 140.249813 -288.17394) (xy 140.20045 -288.166121)
			(xy 140.152918 -288.150677) (xy 140.108386 -288.127987) (xy 140.067953 -288.098611) (xy 140.032613 -288.063271)
			(xy 140.003237 -288.022838) (xy 139.980547 -287.978306) (xy 139.965103 -287.930774) (xy 139.957284 -287.881411)
			(xy 139.649967 -287.881411) (xy 139.649958 -287.881868) (xy 139.641794 -287.932102) (xy 139.625678 -287.980376)
			(xy 139.602027 -288.025439) (xy 139.571454 -288.066125) (xy 139.53475 -288.10138) (xy 139.492866 -288.13029)
			(xy 139.446887 -288.152107) (xy 139.398003 -288.166267) (xy 139.347482 -288.172401) (xy 139.29663 -288.170352)
			(xy 139.246766 -288.160172) (xy 139.19918 -288.142125) (xy 139.155106 -288.116679) (xy 139.115684 -288.084492)
			(xy 139.081936 -288.046398) (xy 139.054735 -288.003384) (xy 139.034787 -287.956564) (xy 139.022608 -287.90715)
			(xy 139.018513 -287.856422) (xy 138.710416 -287.856422) (xy 138.709904 -287.881868) (xy 138.70174 -287.932102)
			(xy 138.685624 -287.980376) (xy 138.661973 -288.025439) (xy 138.6314 -288.066125) (xy 138.594696 -288.10138)
			(xy 138.552812 -288.13029) (xy 138.506833 -288.152107) (xy 138.457949 -288.166267) (xy 138.407428 -288.172401)
			(xy 138.356576 -288.170352) (xy 138.306712 -288.160172) (xy 138.259126 -288.142125) (xy 138.215052 -288.116679)
			(xy 138.17563 -288.084492) (xy 138.141882 -288.046398) (xy 138.114681 -288.003384) (xy 138.094733 -287.956564)
			(xy 138.082554 -287.90715) (xy 138.078459 -287.856422) (xy 136.830562 -287.856422) (xy 136.83005 -287.881868)
			(xy 136.821886 -287.932102) (xy 136.80577 -287.980376) (xy 136.782119 -288.025439) (xy 136.751546 -288.066125)
			(xy 136.714842 -288.10138) (xy 136.672958 -288.13029) (xy 136.626979 -288.152107) (xy 136.578095 -288.166267)
			(xy 136.527574 -288.172401) (xy 136.476722 -288.170352) (xy 136.426858 -288.160172) (xy 136.379272 -288.142125)
			(xy 136.335198 -288.116679) (xy 136.295776 -288.084492) (xy 136.262028 -288.046398) (xy 136.234827 -288.003384)
			(xy 136.214879 -287.956564) (xy 136.2027 -287.90715) (xy 136.198605 -287.856422) (xy 135.892794 -287.856422)
			(xy 135.892304 -287.881411) (xy 135.884485 -287.930774) (xy 135.869041 -287.978306) (xy 135.846351 -288.022838)
			(xy 135.816975 -288.063271) (xy 135.781635 -288.098611) (xy 135.741202 -288.127987) (xy 135.69667 -288.150677)
			(xy 135.649138 -288.166121) (xy 135.599775 -288.17394) (xy 135.549797 -288.17394) (xy 135.500434 -288.166121)
			(xy 135.452902 -288.150677) (xy 135.40837 -288.127987) (xy 135.367937 -288.098611) (xy 135.332597 -288.063271)
			(xy 135.303221 -288.022838) (xy 135.280531 -287.978306) (xy 135.265087 -287.930774) (xy 135.257268 -287.881411)
			(xy 134.949951 -287.881411) (xy 134.949942 -287.881868) (xy 134.941778 -287.932102) (xy 134.925662 -287.980376)
			(xy 134.902011 -288.025439) (xy 134.871438 -288.066125) (xy 134.834734 -288.10138) (xy 134.79285 -288.13029)
			(xy 134.746871 -288.152107) (xy 134.697987 -288.166267) (xy 134.647466 -288.172401) (xy 134.596614 -288.170352)
			(xy 134.54675 -288.160172) (xy 134.499164 -288.142125) (xy 134.45509 -288.116679) (xy 134.415668 -288.084492)
			(xy 134.38192 -288.046398) (xy 134.354719 -288.003384) (xy 134.334771 -287.956564) (xy 134.322592 -287.90715)
			(xy 134.318497 -287.856422) (xy 134.012686 -287.856422) (xy 134.012196 -287.881411) (xy 134.004377 -287.930774)
			(xy 133.988933 -287.978306) (xy 133.966243 -288.022838) (xy 133.936867 -288.063271) (xy 133.901527 -288.098611)
			(xy 133.861094 -288.127987) (xy 133.816562 -288.150677) (xy 133.76903 -288.166121) (xy 133.719667 -288.17394)
			(xy 133.669689 -288.17394) (xy 133.620326 -288.166121) (xy 133.572794 -288.150677) (xy 133.528262 -288.127987)
			(xy 133.487829 -288.098611) (xy 133.452489 -288.063271) (xy 133.423113 -288.022838) (xy 133.400423 -287.978306)
			(xy 133.384979 -287.930774) (xy 133.37716 -287.881411) (xy 133.070097 -287.881411) (xy 133.070088 -287.881868)
			(xy 133.061924 -287.932102) (xy 133.045808 -287.980376) (xy 133.022157 -288.025439) (xy 132.991584 -288.066125)
			(xy 132.95488 -288.10138) (xy 132.912996 -288.13029) (xy 132.867017 -288.152107) (xy 132.818133 -288.166267)
			(xy 132.767612 -288.172401) (xy 132.71676 -288.170352) (xy 132.666896 -288.160172) (xy 132.61931 -288.142125)
			(xy 132.575236 -288.116679) (xy 132.535814 -288.084492) (xy 132.502066 -288.046398) (xy 132.474865 -288.003384)
			(xy 132.454917 -287.956564) (xy 132.442738 -287.90715) (xy 132.438643 -287.856422) (xy 132.130546 -287.856422)
			(xy 132.130034 -287.881868) (xy 132.12187 -287.932102) (xy 132.105754 -287.980376) (xy 132.082103 -288.025439)
			(xy 132.05153 -288.066125) (xy 132.014826 -288.10138) (xy 131.972942 -288.13029) (xy 131.926963 -288.152107)
			(xy 131.878079 -288.166267) (xy 131.827558 -288.172401) (xy 131.776706 -288.170352) (xy 131.726842 -288.160172)
			(xy 131.679256 -288.142125) (xy 131.635182 -288.116679) (xy 131.59576 -288.084492) (xy 131.562012 -288.046398)
			(xy 131.534811 -288.003384) (xy 131.514863 -287.956564) (xy 131.502684 -287.90715) (xy 131.498589 -287.856422)
			(xy 130.250438 -287.856422) (xy 130.249926 -287.881868) (xy 130.241762 -287.932102) (xy 130.225646 -287.980376)
			(xy 130.201995 -288.025439) (xy 130.171422 -288.066125) (xy 130.134718 -288.10138) (xy 130.092834 -288.13029)
			(xy 130.046855 -288.152107) (xy 129.997971 -288.166267) (xy 129.94745 -288.172401) (xy 129.896598 -288.170352)
			(xy 129.846734 -288.160172) (xy 129.799148 -288.142125) (xy 129.755074 -288.116679) (xy 129.715652 -288.084492)
			(xy 129.681904 -288.046398) (xy 129.654703 -288.003384) (xy 129.634755 -287.956564) (xy 129.622576 -287.90715)
			(xy 129.618481 -287.856422) (xy 129.31267 -287.856422) (xy 129.31218 -287.881411) (xy 129.304361 -287.930774)
			(xy 129.288917 -287.978306) (xy 129.266227 -288.022838) (xy 129.236851 -288.063271) (xy 129.201511 -288.098611)
			(xy 129.161078 -288.127987) (xy 129.116546 -288.150677) (xy 129.069014 -288.166121) (xy 129.019651 -288.17394)
			(xy 128.969673 -288.17394) (xy 128.92031 -288.166121) (xy 128.872778 -288.150677) (xy 128.828246 -288.127987)
			(xy 128.787813 -288.098611) (xy 128.752473 -288.063271) (xy 128.723097 -288.022838) (xy 128.700407 -287.978306)
			(xy 128.684963 -287.930774) (xy 128.677144 -287.881411) (xy 128.370081 -287.881411) (xy 128.370072 -287.881868)
			(xy 128.361908 -287.932102) (xy 128.345792 -287.980376) (xy 128.322141 -288.025439) (xy 128.291568 -288.066125)
			(xy 128.254864 -288.10138) (xy 128.21298 -288.13029) (xy 128.167001 -288.152107) (xy 128.118117 -288.166267)
			(xy 128.067596 -288.172401) (xy 128.016744 -288.170352) (xy 127.96688 -288.160172) (xy 127.919294 -288.142125)
			(xy 127.87522 -288.116679) (xy 127.835798 -288.084492) (xy 127.80205 -288.046398) (xy 127.774849 -288.003384)
			(xy 127.754901 -287.956564) (xy 127.742722 -287.90715) (xy 127.738627 -287.856422) (xy 127.432816 -287.856422)
			(xy 127.432248 -287.883755) (xy 127.422906 -287.937617) (xy 127.4045 -287.989091) (xy 127.377571 -288.036664)
			(xy 127.342911 -288.078937) (xy 127.32258 -288.097214) (xy 127.321056 -288.098484) (xy 127.317754 -288.101786)
			(xy 127.314952 -288.104742) (xy 127.310226 -288.111376) (xy 127.308356 -288.114994) (xy 127.29845 -288.136076)
			(xy 127.296926 -288.140394) (xy 127.29578 -288.144167) (xy 127.294506 -288.151947) (xy 127.294386 -288.155888)
			(xy 127.294386 -288.666174) (xy 128.208527 -288.666174) (xy 128.212622 -288.615446) (xy 128.224801 -288.566032)
			(xy 128.244749 -288.519212) (xy 128.27195 -288.476198) (xy 128.305698 -288.438104) (xy 128.34512 -288.405917)
			(xy 128.389194 -288.380471) (xy 128.43678 -288.362424) (xy 128.486644 -288.352244) (xy 128.537496 -288.350195)
			(xy 128.588017 -288.356329) (xy 128.636901 -288.370489) (xy 128.68288 -288.392306) (xy 128.724764 -288.421216)
			(xy 128.761468 -288.456471) (xy 128.792041 -288.497157) (xy 128.815692 -288.54222) (xy 128.831808 -288.590494)
			(xy 128.839972 -288.640728) (xy 128.840484 -288.666174) (xy 129.148581 -288.666174) (xy 129.152676 -288.615446)
			(xy 129.164855 -288.566032) (xy 129.184803 -288.519212) (xy 129.212004 -288.476198) (xy 129.245752 -288.438104)
			(xy 129.285174 -288.405917) (xy 129.329248 -288.380471) (xy 129.376834 -288.362424) (xy 129.426698 -288.352244)
			(xy 129.47755 -288.350195) (xy 129.528071 -288.356329) (xy 129.576955 -288.370489) (xy 129.622934 -288.392306)
			(xy 129.664818 -288.421216) (xy 129.701522 -288.456471) (xy 129.732095 -288.497157) (xy 129.755746 -288.54222)
			(xy 129.771862 -288.590494) (xy 129.780026 -288.640728) (xy 129.780538 -288.666174) (xy 129.780035 -288.691163)
			(xy 130.087352 -288.691163) (xy 130.087352 -288.641185) (xy 130.095171 -288.591822) (xy 130.110615 -288.54429)
			(xy 130.133305 -288.499758) (xy 130.162681 -288.459325) (xy 130.198021 -288.423985) (xy 130.238454 -288.394609)
			(xy 130.282986 -288.371919) (xy 130.330518 -288.356475) (xy 130.379881 -288.348656) (xy 130.429859 -288.348656)
			(xy 130.479222 -288.356475) (xy 130.526754 -288.371919) (xy 130.571286 -288.394609) (xy 130.611719 -288.423985)
			(xy 130.647059 -288.459325) (xy 130.676435 -288.499758) (xy 130.699125 -288.54429) (xy 130.714569 -288.591822)
			(xy 130.722388 -288.641185) (xy 130.722878 -288.666174) (xy 131.028435 -288.666174) (xy 131.03253 -288.615446)
			(xy 131.044709 -288.566032) (xy 131.064657 -288.519212) (xy 131.091858 -288.476198) (xy 131.125606 -288.438104)
			(xy 131.165028 -288.405917) (xy 131.209102 -288.380471) (xy 131.256688 -288.362424) (xy 131.306552 -288.352244)
			(xy 131.357404 -288.350195) (xy 131.407925 -288.356329) (xy 131.456809 -288.370489) (xy 131.502788 -288.392306)
			(xy 131.544672 -288.421216) (xy 131.581376 -288.456471) (xy 131.611949 -288.497157) (xy 131.6356 -288.54222)
			(xy 131.651716 -288.590494) (xy 131.65988 -288.640728) (xy 131.660392 -288.666174) (xy 131.659889 -288.691163)
			(xy 131.967206 -288.691163) (xy 131.967206 -288.641185) (xy 131.975025 -288.591822) (xy 131.990469 -288.54429)
			(xy 132.013159 -288.499758) (xy 132.042535 -288.459325) (xy 132.077875 -288.423985) (xy 132.118308 -288.394609)
			(xy 132.16284 -288.371919) (xy 132.210372 -288.356475) (xy 132.259735 -288.348656) (xy 132.309713 -288.348656)
			(xy 132.359076 -288.356475) (xy 132.406608 -288.371919) (xy 132.45114 -288.394609) (xy 132.491573 -288.423985)
			(xy 132.526913 -288.459325) (xy 132.556289 -288.499758) (xy 132.578979 -288.54429) (xy 132.594423 -288.591822)
			(xy 132.602242 -288.641185) (xy 132.602732 -288.666174) (xy 132.908543 -288.666174) (xy 132.912638 -288.615446)
			(xy 132.924817 -288.566032) (xy 132.944765 -288.519212) (xy 132.971966 -288.476198) (xy 133.005714 -288.438104)
			(xy 133.045136 -288.405917) (xy 133.08921 -288.380471) (xy 133.136796 -288.362424) (xy 133.18666 -288.352244)
			(xy 133.237512 -288.350195) (xy 133.288033 -288.356329) (xy 133.336917 -288.370489) (xy 133.382896 -288.392306)
			(xy 133.42478 -288.421216) (xy 133.461484 -288.456471) (xy 133.492057 -288.497157) (xy 133.515708 -288.54222)
			(xy 133.531824 -288.590494) (xy 133.539988 -288.640728) (xy 133.5405 -288.666174) (xy 133.539997 -288.691163)
			(xy 133.847314 -288.691163) (xy 133.847314 -288.641185) (xy 133.855133 -288.591822) (xy 133.870577 -288.54429)
			(xy 133.893267 -288.499758) (xy 133.922643 -288.459325) (xy 133.957983 -288.423985) (xy 133.998416 -288.394609)
			(xy 134.042948 -288.371919) (xy 134.09048 -288.356475) (xy 134.139843 -288.348656) (xy 134.189821 -288.348656)
			(xy 134.239184 -288.356475) (xy 134.286716 -288.371919) (xy 134.331248 -288.394609) (xy 134.371681 -288.423985)
			(xy 134.407021 -288.459325) (xy 134.436397 -288.499758) (xy 134.459087 -288.54429) (xy 134.474531 -288.591822)
			(xy 134.48235 -288.641185) (xy 134.48284 -288.666174) (xy 134.788397 -288.666174) (xy 134.792492 -288.615446)
			(xy 134.804671 -288.566032) (xy 134.824619 -288.519212) (xy 134.85182 -288.476198) (xy 134.885568 -288.438104)
			(xy 134.92499 -288.405917) (xy 134.969064 -288.380471) (xy 135.01665 -288.362424) (xy 135.066514 -288.352244)
			(xy 135.117366 -288.350195) (xy 135.167887 -288.356329) (xy 135.216771 -288.370489) (xy 135.26275 -288.392306)
			(xy 135.304634 -288.421216) (xy 135.341338 -288.456471) (xy 135.371911 -288.497157) (xy 135.395562 -288.54222)
			(xy 135.411678 -288.590494) (xy 135.419842 -288.640728) (xy 135.420354 -288.666174) (xy 135.728451 -288.666174)
			(xy 135.732546 -288.615446) (xy 135.744725 -288.566032) (xy 135.764673 -288.519212) (xy 135.791874 -288.476198)
			(xy 135.825622 -288.438104) (xy 135.865044 -288.405917) (xy 135.909118 -288.380471) (xy 135.956704 -288.362424)
			(xy 136.006568 -288.352244) (xy 136.05742 -288.350195) (xy 136.107941 -288.356329) (xy 136.156825 -288.370489)
			(xy 136.202804 -288.392306) (xy 136.244688 -288.421216) (xy 136.281392 -288.456471) (xy 136.311965 -288.497157)
			(xy 136.335616 -288.54222) (xy 136.351732 -288.590494) (xy 136.359896 -288.640728) (xy 136.360408 -288.666174)
			(xy 136.359905 -288.691163) (xy 136.667222 -288.691163) (xy 136.667222 -288.641185) (xy 136.675041 -288.591822)
			(xy 136.690485 -288.54429) (xy 136.713175 -288.499758) (xy 136.742551 -288.459325) (xy 136.777891 -288.423985)
			(xy 136.818324 -288.394609) (xy 136.862856 -288.371919) (xy 136.910388 -288.356475) (xy 136.959751 -288.348656)
			(xy 137.009729 -288.348656) (xy 137.059092 -288.356475) (xy 137.106624 -288.371919) (xy 137.151156 -288.394609)
			(xy 137.191589 -288.423985) (xy 137.226929 -288.459325) (xy 137.256305 -288.499758) (xy 137.278995 -288.54429)
			(xy 137.294439 -288.591822) (xy 137.302258 -288.641185) (xy 137.302748 -288.666174) (xy 137.608559 -288.666174)
			(xy 137.612654 -288.615446) (xy 137.624833 -288.566032) (xy 137.644781 -288.519212) (xy 137.671982 -288.476198)
			(xy 137.70573 -288.438104) (xy 137.745152 -288.405917) (xy 137.789226 -288.380471) (xy 137.836812 -288.362424)
			(xy 137.886676 -288.352244) (xy 137.937528 -288.350195) (xy 137.988049 -288.356329) (xy 138.036933 -288.370489)
			(xy 138.082912 -288.392306) (xy 138.124796 -288.421216) (xy 138.1615 -288.456471) (xy 138.192073 -288.497157)
			(xy 138.215724 -288.54222) (xy 138.23184 -288.590494) (xy 138.240004 -288.640728) (xy 138.240516 -288.666174)
			(xy 138.240013 -288.691163) (xy 138.54733 -288.691163) (xy 138.54733 -288.641185) (xy 138.555149 -288.591822)
			(xy 138.570593 -288.54429) (xy 138.593283 -288.499758) (xy 138.622659 -288.459325) (xy 138.657999 -288.423985)
			(xy 138.698432 -288.394609) (xy 138.742964 -288.371919) (xy 138.790496 -288.356475) (xy 138.839859 -288.348656)
			(xy 138.889837 -288.348656) (xy 138.9392 -288.356475) (xy 138.986732 -288.371919) (xy 139.031264 -288.394609)
			(xy 139.071697 -288.423985) (xy 139.107037 -288.459325) (xy 139.136413 -288.499758) (xy 139.159103 -288.54429)
			(xy 139.174547 -288.591822) (xy 139.182366 -288.641185) (xy 139.182856 -288.666174) (xy 139.488413 -288.666174)
			(xy 139.492508 -288.615446) (xy 139.504687 -288.566032) (xy 139.524635 -288.519212) (xy 139.551836 -288.476198)
			(xy 139.585584 -288.438104) (xy 139.625006 -288.405917) (xy 139.66908 -288.380471) (xy 139.716666 -288.362424)
			(xy 139.76653 -288.352244) (xy 139.817382 -288.350195) (xy 139.867903 -288.356329) (xy 139.916787 -288.370489)
			(xy 139.962766 -288.392306) (xy 140.00465 -288.421216) (xy 140.041354 -288.456471) (xy 140.071927 -288.497157)
			(xy 140.095578 -288.54222) (xy 140.111694 -288.590494) (xy 140.119858 -288.640728) (xy 140.12037 -288.666174)
			(xy 140.119867 -288.691163) (xy 140.427184 -288.691163) (xy 140.427184 -288.641185) (xy 140.435003 -288.591822)
			(xy 140.450447 -288.54429) (xy 140.473137 -288.499758) (xy 140.502513 -288.459325) (xy 140.537853 -288.423985)
			(xy 140.578286 -288.394609) (xy 140.622818 -288.371919) (xy 140.67035 -288.356475) (xy 140.719713 -288.348656)
			(xy 140.769691 -288.348656) (xy 140.819054 -288.356475) (xy 140.866586 -288.371919) (xy 140.911118 -288.394609)
			(xy 140.951551 -288.423985) (xy 140.986891 -288.459325) (xy 141.016267 -288.499758) (xy 141.038957 -288.54429)
			(xy 141.054401 -288.591822) (xy 141.06222 -288.641185) (xy 141.06271 -288.666174) (xy 141.368521 -288.666174)
			(xy 141.372616 -288.615446) (xy 141.384795 -288.566032) (xy 141.404743 -288.519212) (xy 141.431944 -288.476198)
			(xy 141.465692 -288.438104) (xy 141.505114 -288.405917) (xy 141.549188 -288.380471) (xy 141.596774 -288.362424)
			(xy 141.646638 -288.352244) (xy 141.69749 -288.350195) (xy 141.748011 -288.356329) (xy 141.796895 -288.370489)
			(xy 141.842874 -288.392306) (xy 141.884758 -288.421216) (xy 141.921462 -288.456471) (xy 141.952035 -288.497157)
			(xy 141.975686 -288.54222) (xy 141.991802 -288.590494) (xy 141.999966 -288.640728) (xy 142.000478 -288.666174)
			(xy 142.308575 -288.666174) (xy 142.31267 -288.615446) (xy 142.324849 -288.566032) (xy 142.344797 -288.519212)
			(xy 142.371998 -288.476198) (xy 142.405746 -288.438104) (xy 142.445168 -288.405917) (xy 142.489242 -288.380471)
			(xy 142.536828 -288.362424) (xy 142.586692 -288.352244) (xy 142.637544 -288.350195) (xy 142.688065 -288.356329)
			(xy 142.736949 -288.370489) (xy 142.782928 -288.392306) (xy 142.824812 -288.421216) (xy 142.861516 -288.456471)
			(xy 142.892089 -288.497157) (xy 142.91574 -288.54222) (xy 142.931856 -288.590494) (xy 142.94002 -288.640728)
			(xy 142.940532 -288.666174) (xy 142.940029 -288.691163) (xy 143.247092 -288.691163) (xy 143.247092 -288.641185)
			(xy 143.254911 -288.591822) (xy 143.270355 -288.54429) (xy 143.293045 -288.499758) (xy 143.322421 -288.459325)
			(xy 143.357761 -288.423985) (xy 143.398194 -288.394609) (xy 143.442726 -288.371919) (xy 143.490258 -288.356475)
			(xy 143.539621 -288.348656) (xy 143.589599 -288.348656) (xy 143.638962 -288.356475) (xy 143.686494 -288.371919)
			(xy 143.731026 -288.394609) (xy 143.771459 -288.423985) (xy 143.806799 -288.459325) (xy 143.836175 -288.499758)
			(xy 143.858865 -288.54429) (xy 143.874309 -288.591822) (xy 143.882128 -288.641185) (xy 143.882618 -288.666174)
			(xy 143.882128 -288.691163) (xy 143.874309 -288.740526) (xy 143.858865 -288.788058) (xy 143.836175 -288.83259)
			(xy 143.806799 -288.873023) (xy 143.771459 -288.908363) (xy 143.731026 -288.937739) (xy 143.686494 -288.960429)
			(xy 143.638962 -288.975873) (xy 143.589599 -288.983692) (xy 143.539621 -288.983692) (xy 143.490258 -288.975873)
			(xy 143.442726 -288.960429) (xy 143.398194 -288.937739) (xy 143.357761 -288.908363) (xy 143.322421 -288.873023)
			(xy 143.293045 -288.83259) (xy 143.270355 -288.788058) (xy 143.254911 -288.740526) (xy 143.247092 -288.691163)
			(xy 142.940029 -288.691163) (xy 142.94002 -288.69162) (xy 142.931856 -288.741854) (xy 142.91574 -288.790128)
			(xy 142.892089 -288.835191) (xy 142.861516 -288.875877) (xy 142.824812 -288.911132) (xy 142.782928 -288.940042)
			(xy 142.736949 -288.961859) (xy 142.688065 -288.976019) (xy 142.637544 -288.982153) (xy 142.586692 -288.980104)
			(xy 142.536828 -288.969924) (xy 142.489242 -288.951877) (xy 142.445168 -288.926431) (xy 142.405746 -288.894244)
			(xy 142.371998 -288.85615) (xy 142.344797 -288.813136) (xy 142.324849 -288.766316) (xy 142.31267 -288.716902)
			(xy 142.308575 -288.666174) (xy 142.000478 -288.666174) (xy 141.999966 -288.69162) (xy 141.991802 -288.741854)
			(xy 141.975686 -288.790128) (xy 141.952035 -288.835191) (xy 141.921462 -288.875877) (xy 141.884758 -288.911132)
			(xy 141.842874 -288.940042) (xy 141.796895 -288.961859) (xy 141.748011 -288.976019) (xy 141.69749 -288.982153)
			(xy 141.646638 -288.980104) (xy 141.596774 -288.969924) (xy 141.549188 -288.951877) (xy 141.505114 -288.926431)
			(xy 141.465692 -288.894244) (xy 141.431944 -288.85615) (xy 141.404743 -288.813136) (xy 141.384795 -288.766316)
			(xy 141.372616 -288.716902) (xy 141.368521 -288.666174) (xy 141.06271 -288.666174) (xy 141.06222 -288.691163)
			(xy 141.054401 -288.740526) (xy 141.038957 -288.788058) (xy 141.016267 -288.83259) (xy 140.986891 -288.873023)
			(xy 140.951551 -288.908363) (xy 140.911118 -288.937739) (xy 140.866586 -288.960429) (xy 140.819054 -288.975873)
			(xy 140.769691 -288.983692) (xy 140.719713 -288.983692) (xy 140.67035 -288.975873) (xy 140.622818 -288.960429)
			(xy 140.578286 -288.937739) (xy 140.537853 -288.908363) (xy 140.502513 -288.873023) (xy 140.473137 -288.83259)
			(xy 140.450447 -288.788058) (xy 140.435003 -288.740526) (xy 140.427184 -288.691163) (xy 140.119867 -288.691163)
			(xy 140.119858 -288.69162) (xy 140.111694 -288.741854) (xy 140.095578 -288.790128) (xy 140.071927 -288.835191)
			(xy 140.041354 -288.875877) (xy 140.00465 -288.911132) (xy 139.962766 -288.940042) (xy 139.916787 -288.961859)
			(xy 139.867903 -288.976019) (xy 139.817382 -288.982153) (xy 139.76653 -288.980104) (xy 139.716666 -288.969924)
			(xy 139.66908 -288.951877) (xy 139.625006 -288.926431) (xy 139.585584 -288.894244) (xy 139.551836 -288.85615)
			(xy 139.524635 -288.813136) (xy 139.504687 -288.766316) (xy 139.492508 -288.716902) (xy 139.488413 -288.666174)
			(xy 139.182856 -288.666174) (xy 139.182366 -288.691163) (xy 139.174547 -288.740526) (xy 139.159103 -288.788058)
			(xy 139.136413 -288.83259) (xy 139.107037 -288.873023) (xy 139.071697 -288.908363) (xy 139.031264 -288.937739)
			(xy 138.986732 -288.960429) (xy 138.9392 -288.975873) (xy 138.889837 -288.983692) (xy 138.839859 -288.983692)
			(xy 138.790496 -288.975873) (xy 138.742964 -288.960429) (xy 138.698432 -288.937739) (xy 138.657999 -288.908363)
			(xy 138.622659 -288.873023) (xy 138.593283 -288.83259) (xy 138.570593 -288.788058) (xy 138.555149 -288.740526)
			(xy 138.54733 -288.691163) (xy 138.240013 -288.691163) (xy 138.240004 -288.69162) (xy 138.23184 -288.741854)
			(xy 138.215724 -288.790128) (xy 138.192073 -288.835191) (xy 138.1615 -288.875877) (xy 138.124796 -288.911132)
			(xy 138.082912 -288.940042) (xy 138.036933 -288.961859) (xy 137.988049 -288.976019) (xy 137.937528 -288.982153)
			(xy 137.886676 -288.980104) (xy 137.836812 -288.969924) (xy 137.789226 -288.951877) (xy 137.745152 -288.926431)
			(xy 137.70573 -288.894244) (xy 137.671982 -288.85615) (xy 137.644781 -288.813136) (xy 137.624833 -288.766316)
			(xy 137.612654 -288.716902) (xy 137.608559 -288.666174) (xy 137.302748 -288.666174) (xy 137.302258 -288.691163)
			(xy 137.294439 -288.740526) (xy 137.278995 -288.788058) (xy 137.256305 -288.83259) (xy 137.226929 -288.873023)
			(xy 137.191589 -288.908363) (xy 137.151156 -288.937739) (xy 137.106624 -288.960429) (xy 137.059092 -288.975873)
			(xy 137.009729 -288.983692) (xy 136.959751 -288.983692) (xy 136.910388 -288.975873) (xy 136.862856 -288.960429)
			(xy 136.818324 -288.937739) (xy 136.777891 -288.908363) (xy 136.742551 -288.873023) (xy 136.713175 -288.83259)
			(xy 136.690485 -288.788058) (xy 136.675041 -288.740526) (xy 136.667222 -288.691163) (xy 136.359905 -288.691163)
			(xy 136.359896 -288.69162) (xy 136.351732 -288.741854) (xy 136.335616 -288.790128) (xy 136.311965 -288.835191)
			(xy 136.281392 -288.875877) (xy 136.244688 -288.911132) (xy 136.202804 -288.940042) (xy 136.156825 -288.961859)
			(xy 136.107941 -288.976019) (xy 136.05742 -288.982153) (xy 136.006568 -288.980104) (xy 135.956704 -288.969924)
			(xy 135.909118 -288.951877) (xy 135.865044 -288.926431) (xy 135.825622 -288.894244) (xy 135.791874 -288.85615)
			(xy 135.764673 -288.813136) (xy 135.744725 -288.766316) (xy 135.732546 -288.716902) (xy 135.728451 -288.666174)
			(xy 135.420354 -288.666174) (xy 135.419842 -288.69162) (xy 135.411678 -288.741854) (xy 135.395562 -288.790128)
			(xy 135.371911 -288.835191) (xy 135.341338 -288.875877) (xy 135.304634 -288.911132) (xy 135.26275 -288.940042)
			(xy 135.216771 -288.961859) (xy 135.167887 -288.976019) (xy 135.117366 -288.982153) (xy 135.066514 -288.980104)
			(xy 135.01665 -288.969924) (xy 134.969064 -288.951877) (xy 134.92499 -288.926431) (xy 134.885568 -288.894244)
			(xy 134.85182 -288.85615) (xy 134.824619 -288.813136) (xy 134.804671 -288.766316) (xy 134.792492 -288.716902)
			(xy 134.788397 -288.666174) (xy 134.48284 -288.666174) (xy 134.48235 -288.691163) (xy 134.474531 -288.740526)
			(xy 134.459087 -288.788058) (xy 134.436397 -288.83259) (xy 134.407021 -288.873023) (xy 134.371681 -288.908363)
			(xy 134.331248 -288.937739) (xy 134.286716 -288.960429) (xy 134.239184 -288.975873) (xy 134.189821 -288.983692)
			(xy 134.139843 -288.983692) (xy 134.09048 -288.975873) (xy 134.042948 -288.960429) (xy 133.998416 -288.937739)
			(xy 133.957983 -288.908363) (xy 133.922643 -288.873023) (xy 133.893267 -288.83259) (xy 133.870577 -288.788058)
			(xy 133.855133 -288.740526) (xy 133.847314 -288.691163) (xy 133.539997 -288.691163) (xy 133.539988 -288.69162)
			(xy 133.531824 -288.741854) (xy 133.515708 -288.790128) (xy 133.492057 -288.835191) (xy 133.461484 -288.875877)
			(xy 133.42478 -288.911132) (xy 133.382896 -288.940042) (xy 133.336917 -288.961859) (xy 133.288033 -288.976019)
			(xy 133.237512 -288.982153) (xy 133.18666 -288.980104) (xy 133.136796 -288.969924) (xy 133.08921 -288.951877)
			(xy 133.045136 -288.926431) (xy 133.005714 -288.894244) (xy 132.971966 -288.85615) (xy 132.944765 -288.813136)
			(xy 132.924817 -288.766316) (xy 132.912638 -288.716902) (xy 132.908543 -288.666174) (xy 132.602732 -288.666174)
			(xy 132.602242 -288.691163) (xy 132.594423 -288.740526) (xy 132.578979 -288.788058) (xy 132.556289 -288.83259)
			(xy 132.526913 -288.873023) (xy 132.491573 -288.908363) (xy 132.45114 -288.937739) (xy 132.406608 -288.960429)
			(xy 132.359076 -288.975873) (xy 132.309713 -288.983692) (xy 132.259735 -288.983692) (xy 132.210372 -288.975873)
			(xy 132.16284 -288.960429) (xy 132.118308 -288.937739) (xy 132.077875 -288.908363) (xy 132.042535 -288.873023)
			(xy 132.013159 -288.83259) (xy 131.990469 -288.788058) (xy 131.975025 -288.740526) (xy 131.967206 -288.691163)
			(xy 131.659889 -288.691163) (xy 131.65988 -288.69162) (xy 131.651716 -288.741854) (xy 131.6356 -288.790128)
			(xy 131.611949 -288.835191) (xy 131.581376 -288.875877) (xy 131.544672 -288.911132) (xy 131.502788 -288.940042)
			(xy 131.456809 -288.961859) (xy 131.407925 -288.976019) (xy 131.357404 -288.982153) (xy 131.306552 -288.980104)
			(xy 131.256688 -288.969924) (xy 131.209102 -288.951877) (xy 131.165028 -288.926431) (xy 131.125606 -288.894244)
			(xy 131.091858 -288.85615) (xy 131.064657 -288.813136) (xy 131.044709 -288.766316) (xy 131.03253 -288.716902)
			(xy 131.028435 -288.666174) (xy 130.722878 -288.666174) (xy 130.722388 -288.691163) (xy 130.714569 -288.740526)
			(xy 130.699125 -288.788058) (xy 130.676435 -288.83259) (xy 130.647059 -288.873023) (xy 130.611719 -288.908363)
			(xy 130.571286 -288.937739) (xy 130.526754 -288.960429) (xy 130.479222 -288.975873) (xy 130.429859 -288.983692)
			(xy 130.379881 -288.983692) (xy 130.330518 -288.975873) (xy 130.282986 -288.960429) (xy 130.238454 -288.937739)
			(xy 130.198021 -288.908363) (xy 130.162681 -288.873023) (xy 130.133305 -288.83259) (xy 130.110615 -288.788058)
			(xy 130.095171 -288.740526) (xy 130.087352 -288.691163) (xy 129.780035 -288.691163) (xy 129.780026 -288.69162)
			(xy 129.771862 -288.741854) (xy 129.755746 -288.790128) (xy 129.732095 -288.835191) (xy 129.701522 -288.875877)
			(xy 129.664818 -288.911132) (xy 129.622934 -288.940042) (xy 129.576955 -288.961859) (xy 129.528071 -288.976019)
			(xy 129.47755 -288.982153) (xy 129.426698 -288.980104) (xy 129.376834 -288.969924) (xy 129.329248 -288.951877)
			(xy 129.285174 -288.926431) (xy 129.245752 -288.894244) (xy 129.212004 -288.85615) (xy 129.184803 -288.813136)
			(xy 129.164855 -288.766316) (xy 129.152676 -288.716902) (xy 129.148581 -288.666174) (xy 128.840484 -288.666174)
			(xy 128.839972 -288.69162) (xy 128.831808 -288.741854) (xy 128.815692 -288.790128) (xy 128.792041 -288.835191)
			(xy 128.761468 -288.875877) (xy 128.724764 -288.911132) (xy 128.68288 -288.940042) (xy 128.636901 -288.961859)
			(xy 128.588017 -288.976019) (xy 128.537496 -288.982153) (xy 128.486644 -288.980104) (xy 128.43678 -288.969924)
			(xy 128.389194 -288.951877) (xy 128.34512 -288.926431) (xy 128.305698 -288.894244) (xy 128.27195 -288.85615)
			(xy 128.244749 -288.813136) (xy 128.224801 -288.766316) (xy 128.212622 -288.716902) (xy 128.208527 -288.666174)
			(xy 127.294386 -288.666174) (xy 127.294386 -289.170872) (xy 127.295656 -289.18154) (xy 127.297688 -289.191446)
			(xy 127.298958 -289.197796) (xy 127.308864 -289.218116) (xy 127.310842 -289.2221) (xy 127.315944 -289.229385)
			(xy 127.319024 -289.232594) (xy 127.321564 -289.234626) (xy 127.342062 -289.252907) (xy 127.377055 -289.295232)
			(xy 127.404251 -289.342942) (xy 127.42284 -289.394619) (xy 127.432268 -289.448721) (xy 127.432816 -289.47618)
			(xy 127.738627 -289.47618) (xy 127.742722 -289.425452) (xy 127.754901 -289.376038) (xy 127.774849 -289.329218)
			(xy 127.80205 -289.286204) (xy 127.835798 -289.24811) (xy 127.87522 -289.215923) (xy 127.919294 -289.190477)
			(xy 127.96688 -289.17243) (xy 128.016744 -289.16225) (xy 128.067596 -289.160201) (xy 128.118117 -289.166335)
			(xy 128.167001 -289.180495) (xy 128.21298 -289.202312) (xy 128.254864 -289.231222) (xy 128.291568 -289.266477)
			(xy 128.322141 -289.307163) (xy 128.345792 -289.352226) (xy 128.361908 -289.4005) (xy 128.370072 -289.450734)
			(xy 128.370584 -289.47618) (xy 128.370081 -289.501169) (xy 128.677144 -289.501169) (xy 128.677144 -289.451191)
			(xy 128.684963 -289.401828) (xy 128.700407 -289.354296) (xy 128.723097 -289.309764) (xy 128.752473 -289.269331)
			(xy 128.787813 -289.233991) (xy 128.828246 -289.204615) (xy 128.872778 -289.181925) (xy 128.92031 -289.166481)
			(xy 128.969673 -289.158662) (xy 129.019651 -289.158662) (xy 129.069014 -289.166481) (xy 129.116546 -289.181925)
			(xy 129.161078 -289.204615) (xy 129.201511 -289.233991) (xy 129.236851 -289.269331) (xy 129.266227 -289.309764)
			(xy 129.288917 -289.354296) (xy 129.304361 -289.401828) (xy 129.31218 -289.451191) (xy 129.31267 -289.47618)
			(xy 129.618481 -289.47618) (xy 129.622576 -289.425452) (xy 129.634755 -289.376038) (xy 129.654703 -289.329218)
			(xy 129.681904 -289.286204) (xy 129.715652 -289.24811) (xy 129.755074 -289.215923) (xy 129.799148 -289.190477)
			(xy 129.846734 -289.17243) (xy 129.896598 -289.16225) (xy 129.94745 -289.160201) (xy 129.997971 -289.166335)
			(xy 130.046855 -289.180495) (xy 130.092834 -289.202312) (xy 130.134718 -289.231222) (xy 130.171422 -289.266477)
			(xy 130.201995 -289.307163) (xy 130.225646 -289.352226) (xy 130.241762 -289.4005) (xy 130.249926 -289.450734)
			(xy 130.250438 -289.47618) (xy 130.249935 -289.501169) (xy 130.557252 -289.501169) (xy 130.557252 -289.451191)
			(xy 130.565071 -289.401828) (xy 130.580515 -289.354296) (xy 130.603205 -289.309764) (xy 130.632581 -289.269331)
			(xy 130.667921 -289.233991) (xy 130.708354 -289.204615) (xy 130.752886 -289.181925) (xy 130.800418 -289.166481)
			(xy 130.849781 -289.158662) (xy 130.899759 -289.158662) (xy 130.949122 -289.166481) (xy 130.996654 -289.181925)
			(xy 131.041186 -289.204615) (xy 131.081619 -289.233991) (xy 131.116959 -289.269331) (xy 131.146335 -289.309764)
			(xy 131.169025 -289.354296) (xy 131.184469 -289.401828) (xy 131.192288 -289.451191) (xy 131.192778 -289.47618)
			(xy 131.498589 -289.47618) (xy 131.502684 -289.425452) (xy 131.514863 -289.376038) (xy 131.534811 -289.329218)
			(xy 131.562012 -289.286204) (xy 131.59576 -289.24811) (xy 131.635182 -289.215923) (xy 131.679256 -289.190477)
			(xy 131.726842 -289.17243) (xy 131.776706 -289.16225) (xy 131.827558 -289.160201) (xy 131.878079 -289.166335)
			(xy 131.926963 -289.180495) (xy 131.972942 -289.202312) (xy 132.014826 -289.231222) (xy 132.05153 -289.266477)
			(xy 132.082103 -289.307163) (xy 132.105754 -289.352226) (xy 132.12187 -289.4005) (xy 132.130034 -289.450734)
			(xy 132.130546 -289.47618) (xy 132.438643 -289.47618) (xy 132.442738 -289.425452) (xy 132.454917 -289.376038)
			(xy 132.474865 -289.329218) (xy 132.502066 -289.286204) (xy 132.535814 -289.24811) (xy 132.575236 -289.215923)
			(xy 132.61931 -289.190477) (xy 132.666896 -289.17243) (xy 132.71676 -289.16225) (xy 132.767612 -289.160201)
			(xy 132.818133 -289.166335) (xy 132.867017 -289.180495) (xy 132.912996 -289.202312) (xy 132.95488 -289.231222)
			(xy 132.991584 -289.266477) (xy 133.022157 -289.307163) (xy 133.045808 -289.352226) (xy 133.061924 -289.4005)
			(xy 133.070088 -289.450734) (xy 133.0706 -289.47618) (xy 133.070097 -289.501169) (xy 133.37716 -289.501169)
			(xy 133.37716 -289.451191) (xy 133.384979 -289.401828) (xy 133.400423 -289.354296) (xy 133.423113 -289.309764)
			(xy 133.452489 -289.269331) (xy 133.487829 -289.233991) (xy 133.528262 -289.204615) (xy 133.572794 -289.181925)
			(xy 133.620326 -289.166481) (xy 133.669689 -289.158662) (xy 133.719667 -289.158662) (xy 133.76903 -289.166481)
			(xy 133.816562 -289.181925) (xy 133.861094 -289.204615) (xy 133.901527 -289.233991) (xy 133.936867 -289.269331)
			(xy 133.966243 -289.309764) (xy 133.988933 -289.354296) (xy 134.004377 -289.401828) (xy 134.012196 -289.451191)
			(xy 134.012686 -289.47618) (xy 134.318497 -289.47618) (xy 134.322592 -289.425452) (xy 134.334771 -289.376038)
			(xy 134.354719 -289.329218) (xy 134.38192 -289.286204) (xy 134.415668 -289.24811) (xy 134.45509 -289.215923)
			(xy 134.499164 -289.190477) (xy 134.54675 -289.17243) (xy 134.596614 -289.16225) (xy 134.647466 -289.160201)
			(xy 134.697987 -289.166335) (xy 134.746871 -289.180495) (xy 134.79285 -289.202312) (xy 134.834734 -289.231222)
			(xy 134.871438 -289.266477) (xy 134.902011 -289.307163) (xy 134.925662 -289.352226) (xy 134.941778 -289.4005)
			(xy 134.949942 -289.450734) (xy 134.950454 -289.47618) (xy 134.949951 -289.501169) (xy 135.257268 -289.501169)
			(xy 135.257268 -289.451191) (xy 135.265087 -289.401828) (xy 135.280531 -289.354296) (xy 135.303221 -289.309764)
			(xy 135.332597 -289.269331) (xy 135.367937 -289.233991) (xy 135.40837 -289.204615) (xy 135.452902 -289.181925)
			(xy 135.500434 -289.166481) (xy 135.549797 -289.158662) (xy 135.599775 -289.158662) (xy 135.649138 -289.166481)
			(xy 135.69667 -289.181925) (xy 135.741202 -289.204615) (xy 135.781635 -289.233991) (xy 135.816975 -289.269331)
			(xy 135.846351 -289.309764) (xy 135.869041 -289.354296) (xy 135.884485 -289.401828) (xy 135.892304 -289.451191)
			(xy 135.892794 -289.47618) (xy 136.198605 -289.47618) (xy 136.2027 -289.425452) (xy 136.214879 -289.376038)
			(xy 136.234827 -289.329218) (xy 136.262028 -289.286204) (xy 136.295776 -289.24811) (xy 136.335198 -289.215923)
			(xy 136.379272 -289.190477) (xy 136.426858 -289.17243) (xy 136.476722 -289.16225) (xy 136.527574 -289.160201)
			(xy 136.578095 -289.166335) (xy 136.626979 -289.180495) (xy 136.672958 -289.202312) (xy 136.714842 -289.231222)
			(xy 136.751546 -289.266477) (xy 136.782119 -289.307163) (xy 136.80577 -289.352226) (xy 136.821886 -289.4005)
			(xy 136.83005 -289.450734) (xy 136.830562 -289.47618) (xy 136.830059 -289.501169) (xy 137.137122 -289.501169)
			(xy 137.137122 -289.451191) (xy 137.144941 -289.401828) (xy 137.160385 -289.354296) (xy 137.183075 -289.309764)
			(xy 137.212451 -289.269331) (xy 137.247791 -289.233991) (xy 137.288224 -289.204615) (xy 137.332756 -289.181925)
			(xy 137.380288 -289.166481) (xy 137.429651 -289.158662) (xy 137.479629 -289.158662) (xy 137.528992 -289.166481)
			(xy 137.576524 -289.181925) (xy 137.621056 -289.204615) (xy 137.661489 -289.233991) (xy 137.696829 -289.269331)
			(xy 137.726205 -289.309764) (xy 137.748895 -289.354296) (xy 137.764339 -289.401828) (xy 137.772158 -289.451191)
			(xy 137.772648 -289.47618) (xy 138.078459 -289.47618) (xy 138.082554 -289.425452) (xy 138.094733 -289.376038)
			(xy 138.114681 -289.329218) (xy 138.141882 -289.286204) (xy 138.17563 -289.24811) (xy 138.215052 -289.215923)
			(xy 138.259126 -289.190477) (xy 138.306712 -289.17243) (xy 138.356576 -289.16225) (xy 138.407428 -289.160201)
			(xy 138.457949 -289.166335) (xy 138.506833 -289.180495) (xy 138.552812 -289.202312) (xy 138.594696 -289.231222)
			(xy 138.6314 -289.266477) (xy 138.661973 -289.307163) (xy 138.685624 -289.352226) (xy 138.70174 -289.4005)
			(xy 138.709904 -289.450734) (xy 138.710416 -289.47618) (xy 139.018513 -289.47618) (xy 139.022608 -289.425452)
			(xy 139.034787 -289.376038) (xy 139.054735 -289.329218) (xy 139.081936 -289.286204) (xy 139.115684 -289.24811)
			(xy 139.155106 -289.215923) (xy 139.19918 -289.190477) (xy 139.246766 -289.17243) (xy 139.29663 -289.16225)
			(xy 139.347482 -289.160201) (xy 139.398003 -289.166335) (xy 139.446887 -289.180495) (xy 139.492866 -289.202312)
			(xy 139.53475 -289.231222) (xy 139.571454 -289.266477) (xy 139.602027 -289.307163) (xy 139.625678 -289.352226)
			(xy 139.641794 -289.4005) (xy 139.649958 -289.450734) (xy 139.65047 -289.47618) (xy 139.649967 -289.501169)
			(xy 139.957284 -289.501169) (xy 139.957284 -289.451191) (xy 139.965103 -289.401828) (xy 139.980547 -289.354296)
			(xy 140.003237 -289.309764) (xy 140.032613 -289.269331) (xy 140.067953 -289.233991) (xy 140.108386 -289.204615)
			(xy 140.152918 -289.181925) (xy 140.20045 -289.166481) (xy 140.249813 -289.158662) (xy 140.299791 -289.158662)
			(xy 140.349154 -289.166481) (xy 140.396686 -289.181925) (xy 140.441218 -289.204615) (xy 140.481651 -289.233991)
			(xy 140.516991 -289.269331) (xy 140.546367 -289.309764) (xy 140.569057 -289.354296) (xy 140.584501 -289.401828)
			(xy 140.59232 -289.451191) (xy 140.59281 -289.47618) (xy 140.898621 -289.47618) (xy 140.902716 -289.425452)
			(xy 140.914895 -289.376038) (xy 140.934843 -289.329218) (xy 140.962044 -289.286204) (xy 140.995792 -289.24811)
			(xy 141.035214 -289.215923) (xy 141.079288 -289.190477) (xy 141.126874 -289.17243) (xy 141.176738 -289.16225)
			(xy 141.22759 -289.160201) (xy 141.278111 -289.166335) (xy 141.326995 -289.180495) (xy 141.372974 -289.202312)
			(xy 141.414858 -289.231222) (xy 141.451562 -289.266477) (xy 141.482135 -289.307163) (xy 141.505786 -289.352226)
			(xy 141.521902 -289.4005) (xy 141.530066 -289.450734) (xy 141.530578 -289.47618) (xy 141.530075 -289.501169)
			(xy 141.837138 -289.501169) (xy 141.837138 -289.451191) (xy 141.844957 -289.401828) (xy 141.860401 -289.354296)
			(xy 141.883091 -289.309764) (xy 141.912467 -289.269331) (xy 141.947807 -289.233991) (xy 141.98824 -289.204615)
			(xy 142.032772 -289.181925) (xy 142.080304 -289.166481) (xy 142.129667 -289.158662) (xy 142.179645 -289.158662)
			(xy 142.229008 -289.166481) (xy 142.27654 -289.181925) (xy 142.321072 -289.204615) (xy 142.361505 -289.233991)
			(xy 142.396845 -289.269331) (xy 142.426221 -289.309764) (xy 142.448911 -289.354296) (xy 142.464355 -289.401828)
			(xy 142.472174 -289.451191) (xy 142.472664 -289.47618) (xy 142.778475 -289.47618) (xy 142.78257 -289.425452)
			(xy 142.794749 -289.376038) (xy 142.814697 -289.329218) (xy 142.841898 -289.286204) (xy 142.875646 -289.24811)
			(xy 142.915068 -289.215923) (xy 142.959142 -289.190477) (xy 143.006728 -289.17243) (xy 143.056592 -289.16225)
			(xy 143.107444 -289.160201) (xy 143.157965 -289.166335) (xy 143.206849 -289.180495) (xy 143.252828 -289.202312)
			(xy 143.294712 -289.231222) (xy 143.331416 -289.266477) (xy 143.361989 -289.307163) (xy 143.38564 -289.352226)
			(xy 143.401756 -289.4005) (xy 143.40992 -289.450734) (xy 143.410432 -289.47618) (xy 143.409929 -289.501169)
			(xy 143.717246 -289.501169) (xy 143.717246 -289.451191) (xy 143.725065 -289.401828) (xy 143.740509 -289.354296)
			(xy 143.763199 -289.309764) (xy 143.792575 -289.269331) (xy 143.827915 -289.233991) (xy 143.868348 -289.204615)
			(xy 143.91288 -289.181925) (xy 143.960412 -289.166481) (xy 144.009775 -289.158662) (xy 144.059753 -289.158662)
			(xy 144.109116 -289.166481) (xy 144.156648 -289.181925) (xy 144.20118 -289.204615) (xy 144.241613 -289.233991)
			(xy 144.276953 -289.269331) (xy 144.306329 -289.309764) (xy 144.329019 -289.354296) (xy 144.344463 -289.401828)
			(xy 144.352282 -289.451191) (xy 144.352772 -289.47618) (xy 144.352282 -289.501169) (xy 144.344463 -289.550532)
			(xy 144.329019 -289.598064) (xy 144.306329 -289.642596) (xy 144.276953 -289.683029) (xy 144.241613 -289.718369)
			(xy 144.20118 -289.747745) (xy 144.156648 -289.770435) (xy 144.109116 -289.785879) (xy 144.059753 -289.793698)
			(xy 144.009775 -289.793698) (xy 143.960412 -289.785879) (xy 143.91288 -289.770435) (xy 143.868348 -289.747745)
			(xy 143.827915 -289.718369) (xy 143.792575 -289.683029) (xy 143.763199 -289.642596) (xy 143.740509 -289.598064)
			(xy 143.725065 -289.550532) (xy 143.717246 -289.501169) (xy 143.409929 -289.501169) (xy 143.40992 -289.501626)
			(xy 143.401756 -289.55186) (xy 143.38564 -289.600134) (xy 143.361989 -289.645197) (xy 143.331416 -289.685883)
			(xy 143.294712 -289.721138) (xy 143.252828 -289.750048) (xy 143.206849 -289.771865) (xy 143.157965 -289.786025)
			(xy 143.107444 -289.792159) (xy 143.056592 -289.79011) (xy 143.006728 -289.77993) (xy 142.959142 -289.761883)
			(xy 142.915068 -289.736437) (xy 142.875646 -289.70425) (xy 142.841898 -289.666156) (xy 142.814697 -289.623142)
			(xy 142.794749 -289.576322) (xy 142.78257 -289.526908) (xy 142.778475 -289.47618) (xy 142.472664 -289.47618)
			(xy 142.472174 -289.501169) (xy 142.464355 -289.550532) (xy 142.448911 -289.598064) (xy 142.426221 -289.642596)
			(xy 142.396845 -289.683029) (xy 142.361505 -289.718369) (xy 142.321072 -289.747745) (xy 142.27654 -289.770435)
			(xy 142.229008 -289.785879) (xy 142.179645 -289.793698) (xy 142.129667 -289.793698) (xy 142.080304 -289.785879)
			(xy 142.032772 -289.770435) (xy 141.98824 -289.747745) (xy 141.947807 -289.718369) (xy 141.912467 -289.683029)
			(xy 141.883091 -289.642596) (xy 141.860401 -289.598064) (xy 141.844957 -289.550532) (xy 141.837138 -289.501169)
			(xy 141.530075 -289.501169) (xy 141.530066 -289.501626) (xy 141.521902 -289.55186) (xy 141.505786 -289.600134)
			(xy 141.482135 -289.645197) (xy 141.451562 -289.685883) (xy 141.414858 -289.721138) (xy 141.372974 -289.750048)
			(xy 141.326995 -289.771865) (xy 141.278111 -289.786025) (xy 141.22759 -289.792159) (xy 141.176738 -289.79011)
			(xy 141.126874 -289.77993) (xy 141.079288 -289.761883) (xy 141.035214 -289.736437) (xy 140.995792 -289.70425)
			(xy 140.962044 -289.666156) (xy 140.934843 -289.623142) (xy 140.914895 -289.576322) (xy 140.902716 -289.526908)
			(xy 140.898621 -289.47618) (xy 140.59281 -289.47618) (xy 140.59232 -289.501169) (xy 140.584501 -289.550532)
			(xy 140.569057 -289.598064) (xy 140.546367 -289.642596) (xy 140.516991 -289.683029) (xy 140.481651 -289.718369)
			(xy 140.441218 -289.747745) (xy 140.396686 -289.770435) (xy 140.349154 -289.785879) (xy 140.299791 -289.793698)
			(xy 140.249813 -289.793698) (xy 140.20045 -289.785879) (xy 140.152918 -289.770435) (xy 140.108386 -289.747745)
			(xy 140.067953 -289.718369) (xy 140.032613 -289.683029) (xy 140.003237 -289.642596) (xy 139.980547 -289.598064)
			(xy 139.965103 -289.550532) (xy 139.957284 -289.501169) (xy 139.649967 -289.501169) (xy 139.649958 -289.501626)
			(xy 139.641794 -289.55186) (xy 139.625678 -289.600134) (xy 139.602027 -289.645197) (xy 139.571454 -289.685883)
			(xy 139.53475 -289.721138) (xy 139.492866 -289.750048) (xy 139.446887 -289.771865) (xy 139.398003 -289.786025)
			(xy 139.347482 -289.792159) (xy 139.29663 -289.79011) (xy 139.246766 -289.77993) (xy 139.19918 -289.761883)
			(xy 139.155106 -289.736437) (xy 139.115684 -289.70425) (xy 139.081936 -289.666156) (xy 139.054735 -289.623142)
			(xy 139.034787 -289.576322) (xy 139.022608 -289.526908) (xy 139.018513 -289.47618) (xy 138.710416 -289.47618)
			(xy 138.709904 -289.501626) (xy 138.70174 -289.55186) (xy 138.685624 -289.600134) (xy 138.661973 -289.645197)
			(xy 138.6314 -289.685883) (xy 138.594696 -289.721138) (xy 138.552812 -289.750048) (xy 138.506833 -289.771865)
			(xy 138.457949 -289.786025) (xy 138.407428 -289.792159) (xy 138.356576 -289.79011) (xy 138.306712 -289.77993)
			(xy 138.259126 -289.761883) (xy 138.215052 -289.736437) (xy 138.17563 -289.70425) (xy 138.141882 -289.666156)
			(xy 138.114681 -289.623142) (xy 138.094733 -289.576322) (xy 138.082554 -289.526908) (xy 138.078459 -289.47618)
			(xy 137.772648 -289.47618) (xy 137.772158 -289.501169) (xy 137.764339 -289.550532) (xy 137.748895 -289.598064)
			(xy 137.726205 -289.642596) (xy 137.696829 -289.683029) (xy 137.661489 -289.718369) (xy 137.621056 -289.747745)
			(xy 137.576524 -289.770435) (xy 137.528992 -289.785879) (xy 137.479629 -289.793698) (xy 137.429651 -289.793698)
			(xy 137.380288 -289.785879) (xy 137.332756 -289.770435) (xy 137.288224 -289.747745) (xy 137.247791 -289.718369)
			(xy 137.212451 -289.683029) (xy 137.183075 -289.642596) (xy 137.160385 -289.598064) (xy 137.144941 -289.550532)
			(xy 137.137122 -289.501169) (xy 136.830059 -289.501169) (xy 136.83005 -289.501626) (xy 136.821886 -289.55186)
			(xy 136.80577 -289.600134) (xy 136.782119 -289.645197) (xy 136.751546 -289.685883) (xy 136.714842 -289.721138)
			(xy 136.672958 -289.750048) (xy 136.626979 -289.771865) (xy 136.578095 -289.786025) (xy 136.527574 -289.792159)
			(xy 136.476722 -289.79011) (xy 136.426858 -289.77993) (xy 136.379272 -289.761883) (xy 136.335198 -289.736437)
			(xy 136.295776 -289.70425) (xy 136.262028 -289.666156) (xy 136.234827 -289.623142) (xy 136.214879 -289.576322)
			(xy 136.2027 -289.526908) (xy 136.198605 -289.47618) (xy 135.892794 -289.47618) (xy 135.892304 -289.501169)
			(xy 135.884485 -289.550532) (xy 135.869041 -289.598064) (xy 135.846351 -289.642596) (xy 135.816975 -289.683029)
			(xy 135.781635 -289.718369) (xy 135.741202 -289.747745) (xy 135.69667 -289.770435) (xy 135.649138 -289.785879)
			(xy 135.599775 -289.793698) (xy 135.549797 -289.793698) (xy 135.500434 -289.785879) (xy 135.452902 -289.770435)
			(xy 135.40837 -289.747745) (xy 135.367937 -289.718369) (xy 135.332597 -289.683029) (xy 135.303221 -289.642596)
			(xy 135.280531 -289.598064) (xy 135.265087 -289.550532) (xy 135.257268 -289.501169) (xy 134.949951 -289.501169)
			(xy 134.949942 -289.501626) (xy 134.941778 -289.55186) (xy 134.925662 -289.600134) (xy 134.902011 -289.645197)
			(xy 134.871438 -289.685883) (xy 134.834734 -289.721138) (xy 134.79285 -289.750048) (xy 134.746871 -289.771865)
			(xy 134.697987 -289.786025) (xy 134.647466 -289.792159) (xy 134.596614 -289.79011) (xy 134.54675 -289.77993)
			(xy 134.499164 -289.761883) (xy 134.45509 -289.736437) (xy 134.415668 -289.70425) (xy 134.38192 -289.666156)
			(xy 134.354719 -289.623142) (xy 134.334771 -289.576322) (xy 134.322592 -289.526908) (xy 134.318497 -289.47618)
			(xy 134.012686 -289.47618) (xy 134.012196 -289.501169) (xy 134.004377 -289.550532) (xy 133.988933 -289.598064)
			(xy 133.966243 -289.642596) (xy 133.936867 -289.683029) (xy 133.901527 -289.718369) (xy 133.861094 -289.747745)
			(xy 133.816562 -289.770435) (xy 133.76903 -289.785879) (xy 133.719667 -289.793698) (xy 133.669689 -289.793698)
			(xy 133.620326 -289.785879) (xy 133.572794 -289.770435) (xy 133.528262 -289.747745) (xy 133.487829 -289.718369)
			(xy 133.452489 -289.683029) (xy 133.423113 -289.642596) (xy 133.400423 -289.598064) (xy 133.384979 -289.550532)
			(xy 133.37716 -289.501169) (xy 133.070097 -289.501169) (xy 133.070088 -289.501626) (xy 133.061924 -289.55186)
			(xy 133.045808 -289.600134) (xy 133.022157 -289.645197) (xy 132.991584 -289.685883) (xy 132.95488 -289.721138)
			(xy 132.912996 -289.750048) (xy 132.867017 -289.771865) (xy 132.818133 -289.786025) (xy 132.767612 -289.792159)
			(xy 132.71676 -289.79011) (xy 132.666896 -289.77993) (xy 132.61931 -289.761883) (xy 132.575236 -289.736437)
			(xy 132.535814 -289.70425) (xy 132.502066 -289.666156) (xy 132.474865 -289.623142) (xy 132.454917 -289.576322)
			(xy 132.442738 -289.526908) (xy 132.438643 -289.47618) (xy 132.130546 -289.47618) (xy 132.130034 -289.501626)
			(xy 132.12187 -289.55186) (xy 132.105754 -289.600134) (xy 132.082103 -289.645197) (xy 132.05153 -289.685883)
			(xy 132.014826 -289.721138) (xy 131.972942 -289.750048) (xy 131.926963 -289.771865) (xy 131.878079 -289.786025)
			(xy 131.827558 -289.792159) (xy 131.776706 -289.79011) (xy 131.726842 -289.77993) (xy 131.679256 -289.761883)
			(xy 131.635182 -289.736437) (xy 131.59576 -289.70425) (xy 131.562012 -289.666156) (xy 131.534811 -289.623142)
			(xy 131.514863 -289.576322) (xy 131.502684 -289.526908) (xy 131.498589 -289.47618) (xy 131.192778 -289.47618)
			(xy 131.192288 -289.501169) (xy 131.184469 -289.550532) (xy 131.169025 -289.598064) (xy 131.146335 -289.642596)
			(xy 131.116959 -289.683029) (xy 131.081619 -289.718369) (xy 131.041186 -289.747745) (xy 130.996654 -289.770435)
			(xy 130.949122 -289.785879) (xy 130.899759 -289.793698) (xy 130.849781 -289.793698) (xy 130.800418 -289.785879)
			(xy 130.752886 -289.770435) (xy 130.708354 -289.747745) (xy 130.667921 -289.718369) (xy 130.632581 -289.683029)
			(xy 130.603205 -289.642596) (xy 130.580515 -289.598064) (xy 130.565071 -289.550532) (xy 130.557252 -289.501169)
			(xy 130.249935 -289.501169) (xy 130.249926 -289.501626) (xy 130.241762 -289.55186) (xy 130.225646 -289.600134)
			(xy 130.201995 -289.645197) (xy 130.171422 -289.685883) (xy 130.134718 -289.721138) (xy 130.092834 -289.750048)
			(xy 130.046855 -289.771865) (xy 129.997971 -289.786025) (xy 129.94745 -289.792159) (xy 129.896598 -289.79011)
			(xy 129.846734 -289.77993) (xy 129.799148 -289.761883) (xy 129.755074 -289.736437) (xy 129.715652 -289.70425)
			(xy 129.681904 -289.666156) (xy 129.654703 -289.623142) (xy 129.634755 -289.576322) (xy 129.622576 -289.526908)
			(xy 129.618481 -289.47618) (xy 129.31267 -289.47618) (xy 129.31218 -289.501169) (xy 129.304361 -289.550532)
			(xy 129.288917 -289.598064) (xy 129.266227 -289.642596) (xy 129.236851 -289.683029) (xy 129.201511 -289.718369)
			(xy 129.161078 -289.747745) (xy 129.116546 -289.770435) (xy 129.069014 -289.785879) (xy 129.019651 -289.793698)
			(xy 128.969673 -289.793698) (xy 128.92031 -289.785879) (xy 128.872778 -289.770435) (xy 128.828246 -289.747745)
			(xy 128.787813 -289.718369) (xy 128.752473 -289.683029) (xy 128.723097 -289.642596) (xy 128.700407 -289.598064)
			(xy 128.684963 -289.550532) (xy 128.677144 -289.501169) (xy 128.370081 -289.501169) (xy 128.370072 -289.501626)
			(xy 128.361908 -289.55186) (xy 128.345792 -289.600134) (xy 128.322141 -289.645197) (xy 128.291568 -289.685883)
			(xy 128.254864 -289.721138) (xy 128.21298 -289.750048) (xy 128.167001 -289.771865) (xy 128.118117 -289.786025)
			(xy 128.067596 -289.792159) (xy 128.016744 -289.79011) (xy 127.96688 -289.77993) (xy 127.919294 -289.761883)
			(xy 127.87522 -289.736437) (xy 127.835798 -289.70425) (xy 127.80205 -289.666156) (xy 127.774849 -289.623142)
			(xy 127.754901 -289.576322) (xy 127.742722 -289.526908) (xy 127.738627 -289.47618) (xy 127.432816 -289.47618)
			(xy 127.432253 -289.5032) (xy 127.423053 -289.556452) (xy 127.414528 -289.582098) (xy 127.413512 -289.585146)
			(xy 127.411506 -289.593637) (xy 127.412682 -289.611032) (xy 127.415798 -289.619182) (xy 127.420878 -289.629596)
			(xy 127.421132 -289.630104) (xy 127.43053 -289.640772) (xy 127.436626 -289.644582) (xy 127.445516 -289.651694)
			(xy 128.048004 -290.254182) (xy 128.050544 -290.256468) (xy 128.050544 -290.256722) (xy 128.059827 -290.26397)
			(xy 128.082587 -290.269919) (xy 128.094232 -290.268152) (xy 128.16713 -290.24834) (xy 128.167638 -290.24834)
			(xy 128.180846 -290.24453) (xy 128.187272 -290.24255) (xy 128.198853 -290.235724) (xy 128.203706 -290.231068)
			(xy 128.208278 -290.226242) (xy 128.214882 -290.214812) (xy 128.216406 -290.208208) (xy 128.223354 -290.182819)
			(xy 128.24448 -290.13461) (xy 128.273259 -290.090539) (xy 128.308904 -290.051811) (xy 128.350441 -290.019482)
			(xy 128.396736 -289.994437) (xy 128.446524 -289.97736) (xy 128.498444 -289.968717) (xy 128.524762 -289.968178)
			(xy 128.549756 -289.96864) (xy 128.59913 -289.976454) (xy 128.646673 -289.991897) (xy 128.691215 -290.014588)
			(xy 128.731659 -290.043967) (xy 128.767008 -290.079312) (xy 128.796393 -290.119752) (xy 128.819088 -290.164291)
			(xy 128.834537 -290.211833) (xy 128.842357 -290.261206) (xy 128.842357 -290.286186) (xy 129.148581 -290.286186)
			(xy 129.152676 -290.235458) (xy 129.164855 -290.186044) (xy 129.184803 -290.139224) (xy 129.212004 -290.09621)
			(xy 129.245752 -290.058116) (xy 129.285174 -290.025929) (xy 129.329248 -290.000483) (xy 129.376834 -289.982436)
			(xy 129.426698 -289.972256) (xy 129.47755 -289.970207) (xy 129.528071 -289.976341) (xy 129.576955 -289.990501)
			(xy 129.622934 -290.012318) (xy 129.664818 -290.041228) (xy 129.701522 -290.076483) (xy 129.732095 -290.117169)
			(xy 129.755746 -290.162232) (xy 129.771862 -290.210506) (xy 129.780026 -290.26074) (xy 129.780538 -290.286186)
			(xy 131.028435 -290.286186) (xy 131.03253 -290.235458) (xy 131.044709 -290.186044) (xy 131.064657 -290.139224)
			(xy 131.091858 -290.09621) (xy 131.125606 -290.058116) (xy 131.165028 -290.025929) (xy 131.209102 -290.000483)
			(xy 131.256688 -289.982436) (xy 131.306552 -289.972256) (xy 131.357404 -289.970207) (xy 131.407925 -289.976341)
			(xy 131.456809 -289.990501) (xy 131.502788 -290.012318) (xy 131.544672 -290.041228) (xy 131.581376 -290.076483)
			(xy 131.611949 -290.117169) (xy 131.6356 -290.162232) (xy 131.651716 -290.210506) (xy 131.65988 -290.26074)
			(xy 131.660392 -290.286186) (xy 131.659889 -290.311175) (xy 131.967206 -290.311175) (xy 131.967206 -290.261197)
			(xy 131.975025 -290.211834) (xy 131.990469 -290.164302) (xy 132.013159 -290.11977) (xy 132.042535 -290.079337)
			(xy 132.077875 -290.043997) (xy 132.118308 -290.014621) (xy 132.16284 -289.991931) (xy 132.210372 -289.976487)
			(xy 132.259735 -289.968668) (xy 132.309713 -289.968668) (xy 132.359076 -289.976487) (xy 132.406608 -289.991931)
			(xy 132.45114 -290.014621) (xy 132.491573 -290.043997) (xy 132.526913 -290.079337) (xy 132.556289 -290.11977)
			(xy 132.578979 -290.164302) (xy 132.594423 -290.211834) (xy 132.602242 -290.261197) (xy 132.602732 -290.286186)
			(xy 132.908543 -290.286186) (xy 132.912638 -290.235458) (xy 132.924817 -290.186044) (xy 132.944765 -290.139224)
			(xy 132.971966 -290.09621) (xy 133.005714 -290.058116) (xy 133.045136 -290.025929) (xy 133.08921 -290.000483)
			(xy 133.136796 -289.982436) (xy 133.18666 -289.972256) (xy 133.237512 -289.970207) (xy 133.288033 -289.976341)
			(xy 133.336917 -289.990501) (xy 133.382896 -290.012318) (xy 133.42478 -290.041228) (xy 133.461484 -290.076483)
			(xy 133.492057 -290.117169) (xy 133.515708 -290.162232) (xy 133.531824 -290.210506) (xy 133.539988 -290.26074)
			(xy 133.5405 -290.286186) (xy 133.539997 -290.311175) (xy 133.847314 -290.311175) (xy 133.847314 -290.261197)
			(xy 133.855133 -290.211834) (xy 133.870577 -290.164302) (xy 133.893267 -290.11977) (xy 133.922643 -290.079337)
			(xy 133.957983 -290.043997) (xy 133.998416 -290.014621) (xy 134.042948 -289.991931) (xy 134.09048 -289.976487)
			(xy 134.139843 -289.968668) (xy 134.189821 -289.968668) (xy 134.239184 -289.976487) (xy 134.286716 -289.991931)
			(xy 134.331248 -290.014621) (xy 134.371681 -290.043997) (xy 134.407021 -290.079337) (xy 134.436397 -290.11977)
			(xy 134.459087 -290.164302) (xy 134.474531 -290.211834) (xy 134.48235 -290.261197) (xy 134.48284 -290.286186)
			(xy 134.788397 -290.286186) (xy 134.792492 -290.235458) (xy 134.804671 -290.186044) (xy 134.824619 -290.139224)
			(xy 134.85182 -290.09621) (xy 134.885568 -290.058116) (xy 134.92499 -290.025929) (xy 134.969064 -290.000483)
			(xy 135.01665 -289.982436) (xy 135.066514 -289.972256) (xy 135.117366 -289.970207) (xy 135.167887 -289.976341)
			(xy 135.216771 -289.990501) (xy 135.26275 -290.012318) (xy 135.304634 -290.041228) (xy 135.341338 -290.076483)
			(xy 135.371911 -290.117169) (xy 135.395562 -290.162232) (xy 135.411678 -290.210506) (xy 135.419842 -290.26074)
			(xy 135.420354 -290.286186) (xy 135.728451 -290.286186) (xy 135.732546 -290.235458) (xy 135.744725 -290.186044)
			(xy 135.764673 -290.139224) (xy 135.791874 -290.09621) (xy 135.825622 -290.058116) (xy 135.865044 -290.025929)
			(xy 135.909118 -290.000483) (xy 135.956704 -289.982436) (xy 136.006568 -289.972256) (xy 136.05742 -289.970207)
			(xy 136.107941 -289.976341) (xy 136.156825 -289.990501) (xy 136.202804 -290.012318) (xy 136.244688 -290.041228)
			(xy 136.281392 -290.076483) (xy 136.311965 -290.117169) (xy 136.335616 -290.162232) (xy 136.351732 -290.210506)
			(xy 136.359896 -290.26074) (xy 136.360408 -290.286186) (xy 137.608559 -290.286186) (xy 137.612654 -290.235458)
			(xy 137.624833 -290.186044) (xy 137.644781 -290.139224) (xy 137.671982 -290.09621) (xy 137.70573 -290.058116)
			(xy 137.745152 -290.025929) (xy 137.789226 -290.000483) (xy 137.836812 -289.982436) (xy 137.886676 -289.972256)
			(xy 137.937528 -289.970207) (xy 137.988049 -289.976341) (xy 138.036933 -289.990501) (xy 138.082912 -290.012318)
			(xy 138.124796 -290.041228) (xy 138.1615 -290.076483) (xy 138.192073 -290.117169) (xy 138.215724 -290.162232)
			(xy 138.23184 -290.210506) (xy 138.240004 -290.26074) (xy 138.240516 -290.286186) (xy 138.240013 -290.311175)
			(xy 138.54733 -290.311175) (xy 138.54733 -290.261197) (xy 138.555149 -290.211834) (xy 138.570593 -290.164302)
			(xy 138.593283 -290.11977) (xy 138.622659 -290.079337) (xy 138.657999 -290.043997) (xy 138.698432 -290.014621)
			(xy 138.742964 -289.991931) (xy 138.790496 -289.976487) (xy 138.839859 -289.968668) (xy 138.889837 -289.968668)
			(xy 138.9392 -289.976487) (xy 138.986732 -289.991931) (xy 139.031264 -290.014621) (xy 139.071697 -290.043997)
			(xy 139.107037 -290.079337) (xy 139.136413 -290.11977) (xy 139.159103 -290.164302) (xy 139.174547 -290.211834)
			(xy 139.182366 -290.261197) (xy 139.182856 -290.286186) (xy 139.488413 -290.286186) (xy 139.492508 -290.235458)
			(xy 139.504687 -290.186044) (xy 139.524635 -290.139224) (xy 139.551836 -290.09621) (xy 139.585584 -290.058116)
			(xy 139.625006 -290.025929) (xy 139.66908 -290.000483) (xy 139.716666 -289.982436) (xy 139.76653 -289.972256)
			(xy 139.817382 -289.970207) (xy 139.867903 -289.976341) (xy 139.916787 -289.990501) (xy 139.962766 -290.012318)
			(xy 140.00465 -290.041228) (xy 140.041354 -290.076483) (xy 140.071927 -290.117169) (xy 140.095578 -290.162232)
			(xy 140.111694 -290.210506) (xy 140.119858 -290.26074) (xy 140.12037 -290.286186) (xy 140.119867 -290.311175)
			(xy 140.427184 -290.311175) (xy 140.427184 -290.261197) (xy 140.435003 -290.211834) (xy 140.450447 -290.164302)
			(xy 140.473137 -290.11977) (xy 140.502513 -290.079337) (xy 140.537853 -290.043997) (xy 140.578286 -290.014621)
			(xy 140.622818 -289.991931) (xy 140.67035 -289.976487) (xy 140.719713 -289.968668) (xy 140.769691 -289.968668)
			(xy 140.819054 -289.976487) (xy 140.866586 -289.991931) (xy 140.911118 -290.014621) (xy 140.951551 -290.043997)
			(xy 140.986891 -290.079337) (xy 141.016267 -290.11977) (xy 141.038957 -290.164302) (xy 141.054401 -290.211834)
			(xy 141.06222 -290.261197) (xy 141.06271 -290.286186) (xy 141.368521 -290.286186) (xy 141.372616 -290.235458)
			(xy 141.384795 -290.186044) (xy 141.404743 -290.139224) (xy 141.431944 -290.09621) (xy 141.465692 -290.058116)
			(xy 141.505114 -290.025929) (xy 141.549188 -290.000483) (xy 141.596774 -289.982436) (xy 141.646638 -289.972256)
			(xy 141.69749 -289.970207) (xy 141.748011 -289.976341) (xy 141.796895 -289.990501) (xy 141.842874 -290.012318)
			(xy 141.884758 -290.041228) (xy 141.921462 -290.076483) (xy 141.952035 -290.117169) (xy 141.975686 -290.162232)
			(xy 141.991802 -290.210506) (xy 141.999966 -290.26074) (xy 142.000478 -290.286186) (xy 142.308575 -290.286186)
			(xy 142.31267 -290.235458) (xy 142.324849 -290.186044) (xy 142.344797 -290.139224) (xy 142.371998 -290.09621)
			(xy 142.405746 -290.058116) (xy 142.445168 -290.025929) (xy 142.489242 -290.000483) (xy 142.536828 -289.982436)
			(xy 142.586692 -289.972256) (xy 142.637544 -289.970207) (xy 142.688065 -289.976341) (xy 142.736949 -289.990501)
			(xy 142.782928 -290.012318) (xy 142.824812 -290.041228) (xy 142.861516 -290.076483) (xy 142.892089 -290.117169)
			(xy 142.91574 -290.162232) (xy 142.931856 -290.210506) (xy 142.94002 -290.26074) (xy 142.940532 -290.286186)
			(xy 142.94002 -290.311632) (xy 142.931856 -290.361866) (xy 142.91574 -290.41014) (xy 142.892089 -290.455203)
			(xy 142.861516 -290.495889) (xy 142.824812 -290.531144) (xy 142.782928 -290.560054) (xy 142.736949 -290.581871)
			(xy 142.688065 -290.596031) (xy 142.637544 -290.602165) (xy 142.586692 -290.600116) (xy 142.536828 -290.589936)
			(xy 142.489242 -290.571889) (xy 142.445168 -290.546443) (xy 142.405746 -290.514256) (xy 142.371998 -290.476162)
			(xy 142.344797 -290.433148) (xy 142.324849 -290.386328) (xy 142.31267 -290.336914) (xy 142.308575 -290.286186)
			(xy 142.000478 -290.286186) (xy 141.999966 -290.311632) (xy 141.991802 -290.361866) (xy 141.975686 -290.41014)
			(xy 141.952035 -290.455203) (xy 141.921462 -290.495889) (xy 141.884758 -290.531144) (xy 141.842874 -290.560054)
			(xy 141.796895 -290.581871) (xy 141.748011 -290.596031) (xy 141.69749 -290.602165) (xy 141.646638 -290.600116)
			(xy 141.596774 -290.589936) (xy 141.549188 -290.571889) (xy 141.505114 -290.546443) (xy 141.465692 -290.514256)
			(xy 141.431944 -290.476162) (xy 141.404743 -290.433148) (xy 141.384795 -290.386328) (xy 141.372616 -290.336914)
			(xy 141.368521 -290.286186) (xy 141.06271 -290.286186) (xy 141.06222 -290.311175) (xy 141.054401 -290.360538)
			(xy 141.038957 -290.40807) (xy 141.016267 -290.452602) (xy 140.986891 -290.493035) (xy 140.951551 -290.528375)
			(xy 140.911118 -290.557751) (xy 140.866586 -290.580441) (xy 140.819054 -290.595885) (xy 140.769691 -290.603704)
			(xy 140.719713 -290.603704) (xy 140.67035 -290.595885) (xy 140.622818 -290.580441) (xy 140.578286 -290.557751)
			(xy 140.537853 -290.528375) (xy 140.502513 -290.493035) (xy 140.473137 -290.452602) (xy 140.450447 -290.40807)
			(xy 140.435003 -290.360538) (xy 140.427184 -290.311175) (xy 140.119867 -290.311175) (xy 140.119858 -290.311632)
			(xy 140.111694 -290.361866) (xy 140.095578 -290.41014) (xy 140.071927 -290.455203) (xy 140.041354 -290.495889)
			(xy 140.00465 -290.531144) (xy 139.962766 -290.560054) (xy 139.916787 -290.581871) (xy 139.867903 -290.596031)
			(xy 139.817382 -290.602165) (xy 139.76653 -290.600116) (xy 139.716666 -290.589936) (xy 139.66908 -290.571889)
			(xy 139.625006 -290.546443) (xy 139.585584 -290.514256) (xy 139.551836 -290.476162) (xy 139.524635 -290.433148)
			(xy 139.504687 -290.386328) (xy 139.492508 -290.336914) (xy 139.488413 -290.286186) (xy 139.182856 -290.286186)
			(xy 139.182366 -290.311175) (xy 139.174547 -290.360538) (xy 139.159103 -290.40807) (xy 139.136413 -290.452602)
			(xy 139.107037 -290.493035) (xy 139.071697 -290.528375) (xy 139.031264 -290.557751) (xy 138.986732 -290.580441)
			(xy 138.9392 -290.595885) (xy 138.889837 -290.603704) (xy 138.839859 -290.603704) (xy 138.790496 -290.595885)
			(xy 138.742964 -290.580441) (xy 138.698432 -290.557751) (xy 138.657999 -290.528375) (xy 138.622659 -290.493035)
			(xy 138.593283 -290.452602) (xy 138.570593 -290.40807) (xy 138.555149 -290.360538) (xy 138.54733 -290.311175)
			(xy 138.240013 -290.311175) (xy 138.240004 -290.311632) (xy 138.23184 -290.361866) (xy 138.215724 -290.41014)
			(xy 138.192073 -290.455203) (xy 138.1615 -290.495889) (xy 138.124796 -290.531144) (xy 138.082912 -290.560054)
			(xy 138.036933 -290.581871) (xy 137.988049 -290.596031) (xy 137.937528 -290.602165) (xy 137.886676 -290.600116)
			(xy 137.836812 -290.589936) (xy 137.789226 -290.571889) (xy 137.745152 -290.546443) (xy 137.70573 -290.514256)
			(xy 137.671982 -290.476162) (xy 137.644781 -290.433148) (xy 137.624833 -290.386328) (xy 137.612654 -290.336914)
			(xy 137.608559 -290.286186) (xy 136.360408 -290.286186) (xy 136.359896 -290.311632) (xy 136.351732 -290.361866)
			(xy 136.335616 -290.41014) (xy 136.311965 -290.455203) (xy 136.281392 -290.495889) (xy 136.244688 -290.531144)
			(xy 136.202804 -290.560054) (xy 136.156825 -290.581871) (xy 136.107941 -290.596031) (xy 136.05742 -290.602165)
			(xy 136.006568 -290.600116) (xy 135.956704 -290.589936) (xy 135.909118 -290.571889) (xy 135.865044 -290.546443)
			(xy 135.825622 -290.514256) (xy 135.791874 -290.476162) (xy 135.764673 -290.433148) (xy 135.744725 -290.386328)
			(xy 135.732546 -290.336914) (xy 135.728451 -290.286186) (xy 135.420354 -290.286186) (xy 135.419842 -290.311632)
			(xy 135.411678 -290.361866) (xy 135.395562 -290.41014) (xy 135.371911 -290.455203) (xy 135.341338 -290.495889)
			(xy 135.304634 -290.531144) (xy 135.26275 -290.560054) (xy 135.216771 -290.581871) (xy 135.167887 -290.596031)
			(xy 135.117366 -290.602165) (xy 135.066514 -290.600116) (xy 135.01665 -290.589936) (xy 134.969064 -290.571889)
			(xy 134.92499 -290.546443) (xy 134.885568 -290.514256) (xy 134.85182 -290.476162) (xy 134.824619 -290.433148)
			(xy 134.804671 -290.386328) (xy 134.792492 -290.336914) (xy 134.788397 -290.286186) (xy 134.48284 -290.286186)
			(xy 134.48235 -290.311175) (xy 134.474531 -290.360538) (xy 134.459087 -290.40807) (xy 134.436397 -290.452602)
			(xy 134.407021 -290.493035) (xy 134.371681 -290.528375) (xy 134.331248 -290.557751) (xy 134.286716 -290.580441)
			(xy 134.239184 -290.595885) (xy 134.189821 -290.603704) (xy 134.139843 -290.603704) (xy 134.09048 -290.595885)
			(xy 134.042948 -290.580441) (xy 133.998416 -290.557751) (xy 133.957983 -290.528375) (xy 133.922643 -290.493035)
			(xy 133.893267 -290.452602) (xy 133.870577 -290.40807) (xy 133.855133 -290.360538) (xy 133.847314 -290.311175)
			(xy 133.539997 -290.311175) (xy 133.539988 -290.311632) (xy 133.531824 -290.361866) (xy 133.515708 -290.41014)
			(xy 133.492057 -290.455203) (xy 133.461484 -290.495889) (xy 133.42478 -290.531144) (xy 133.382896 -290.560054)
			(xy 133.336917 -290.581871) (xy 133.288033 -290.596031) (xy 133.237512 -290.602165) (xy 133.18666 -290.600116)
			(xy 133.136796 -290.589936) (xy 133.08921 -290.571889) (xy 133.045136 -290.546443) (xy 133.005714 -290.514256)
			(xy 132.971966 -290.476162) (xy 132.944765 -290.433148) (xy 132.924817 -290.386328) (xy 132.912638 -290.336914)
			(xy 132.908543 -290.286186) (xy 132.602732 -290.286186) (xy 132.602242 -290.311175) (xy 132.594423 -290.360538)
			(xy 132.578979 -290.40807) (xy 132.556289 -290.452602) (xy 132.526913 -290.493035) (xy 132.491573 -290.528375)
			(xy 132.45114 -290.557751) (xy 132.406608 -290.580441) (xy 132.359076 -290.595885) (xy 132.309713 -290.603704)
			(xy 132.259735 -290.603704) (xy 132.210372 -290.595885) (xy 132.16284 -290.580441) (xy 132.118308 -290.557751)
			(xy 132.077875 -290.528375) (xy 132.042535 -290.493035) (xy 132.013159 -290.452602) (xy 131.990469 -290.40807)
			(xy 131.975025 -290.360538) (xy 131.967206 -290.311175) (xy 131.659889 -290.311175) (xy 131.65988 -290.311632)
			(xy 131.651716 -290.361866) (xy 131.6356 -290.41014) (xy 131.611949 -290.455203) (xy 131.581376 -290.495889)
			(xy 131.544672 -290.531144) (xy 131.502788 -290.560054) (xy 131.456809 -290.581871) (xy 131.407925 -290.596031)
			(xy 131.357404 -290.602165) (xy 131.306552 -290.600116) (xy 131.256688 -290.589936) (xy 131.209102 -290.571889)
			(xy 131.165028 -290.546443) (xy 131.125606 -290.514256) (xy 131.091858 -290.476162) (xy 131.064657 -290.433148)
			(xy 131.044709 -290.386328) (xy 131.03253 -290.336914) (xy 131.028435 -290.286186) (xy 129.780538 -290.286186)
			(xy 129.780026 -290.311632) (xy 129.771862 -290.361866) (xy 129.755746 -290.41014) (xy 129.732095 -290.455203)
			(xy 129.701522 -290.495889) (xy 129.664818 -290.531144) (xy 129.622934 -290.560054) (xy 129.576955 -290.581871)
			(xy 129.528071 -290.596031) (xy 129.47755 -290.602165) (xy 129.426698 -290.600116) (xy 129.376834 -290.589936)
			(xy 129.329248 -290.571889) (xy 129.285174 -290.546443) (xy 129.245752 -290.514256) (xy 129.212004 -290.476162)
			(xy 129.184803 -290.433148) (xy 129.164855 -290.386328) (xy 129.152676 -290.336914) (xy 129.148581 -290.286186)
			(xy 128.842357 -290.286186) (xy 128.842357 -290.311194) (xy 128.834537 -290.360567) (xy 128.819088 -290.408109)
			(xy 128.796393 -290.452648) (xy 128.767008 -290.493088) (xy 128.731659 -290.528433) (xy 128.691215 -290.557813)
			(xy 128.646673 -290.580503) (xy 128.59913 -290.595946) (xy 128.549756 -290.60376) (xy 128.524762 -290.604194)
			(xy 128.524254 -290.604194) (xy 128.500804 -290.603756) (xy 128.454418 -290.59683) (xy 128.409554 -290.583163)
			(xy 128.367184 -290.563052) (xy 128.34747 -290.550346) (xy 128.341374 -290.546282) (xy 128.324864 -290.540948)
			(xy 128.320844 -290.539767) (xy 128.312544 -290.538616) (xy 128.308354 -290.538662) (xy 128.303926 -290.538895)
			(xy 128.295244 -290.540689) (xy 128.291082 -290.542218) (xy 128.286256 -290.54425) (xy 128.213358 -290.581842)
			(xy 128.213104 -290.581842) (xy 128.2049 -290.586027) (xy 128.19193 -290.599084) (xy 128.184373 -290.615865)
			(xy 128.183386 -290.625022) (xy 128.183386 -290.771072) (xy 128.184402 -290.780724) (xy 128.186025 -290.787971)
			(xy 128.192858 -290.801147) (xy 128.197864 -290.806632) (xy 128.209294 -290.818062) (xy 128.215136 -290.821364)
			(xy 128.236942 -290.834665) (xy 128.276387 -290.867108) (xy 128.310143 -290.905436) (xy 128.337342 -290.948666)
			(xy 128.357285 -290.995685) (xy 128.36946 -291.045286) (xy 128.373553 -291.096196) (xy 128.371545 -291.121181)
			(xy 128.677144 -291.121181) (xy 128.677144 -291.071203) (xy 128.684963 -291.02184) (xy 128.700407 -290.974308)
			(xy 128.723097 -290.929776) (xy 128.752473 -290.889343) (xy 128.787813 -290.854003) (xy 128.828246 -290.824627)
			(xy 128.872778 -290.801937) (xy 128.92031 -290.786493) (xy 128.969673 -290.778674) (xy 129.019651 -290.778674)
			(xy 129.069014 -290.786493) (xy 129.116546 -290.801937) (xy 129.161078 -290.824627) (xy 129.201511 -290.854003)
			(xy 129.236851 -290.889343) (xy 129.266227 -290.929776) (xy 129.288917 -290.974308) (xy 129.304361 -291.02184)
			(xy 129.31218 -291.071203) (xy 129.31267 -291.096192) (xy 129.618481 -291.096192) (xy 129.622576 -291.045464)
			(xy 129.634755 -290.99605) (xy 129.654703 -290.94923) (xy 129.681904 -290.906216) (xy 129.715652 -290.868122)
			(xy 129.755074 -290.835935) (xy 129.799148 -290.810489) (xy 129.846734 -290.792442) (xy 129.896598 -290.782262)
			(xy 129.94745 -290.780213) (xy 129.997971 -290.786347) (xy 130.046855 -290.800507) (xy 130.092834 -290.822324)
			(xy 130.134718 -290.851234) (xy 130.171422 -290.886489) (xy 130.201995 -290.927175) (xy 130.225646 -290.972238)
			(xy 130.241762 -291.020512) (xy 130.249926 -291.070746) (xy 130.250438 -291.096192) (xy 130.249935 -291.121181)
			(xy 130.557252 -291.121181) (xy 130.557252 -291.071203) (xy 130.565071 -291.02184) (xy 130.580515 -290.974308)
			(xy 130.603205 -290.929776) (xy 130.632581 -290.889343) (xy 130.667921 -290.854003) (xy 130.708354 -290.824627)
			(xy 130.752886 -290.801937) (xy 130.800418 -290.786493) (xy 130.849781 -290.778674) (xy 130.899759 -290.778674)
			(xy 130.949122 -290.786493) (xy 130.996654 -290.801937) (xy 131.041186 -290.824627) (xy 131.081619 -290.854003)
			(xy 131.116959 -290.889343) (xy 131.146335 -290.929776) (xy 131.169025 -290.974308) (xy 131.184469 -291.02184)
			(xy 131.192288 -291.071203) (xy 131.192778 -291.096192) (xy 131.498589 -291.096192) (xy 131.502684 -291.045464)
			(xy 131.514863 -290.99605) (xy 131.534811 -290.94923) (xy 131.562012 -290.906216) (xy 131.59576 -290.868122)
			(xy 131.635182 -290.835935) (xy 131.679256 -290.810489) (xy 131.726842 -290.792442) (xy 131.776706 -290.782262)
			(xy 131.827558 -290.780213) (xy 131.878079 -290.786347) (xy 131.926963 -290.800507) (xy 131.972942 -290.822324)
			(xy 132.014826 -290.851234) (xy 132.05153 -290.886489) (xy 132.082103 -290.927175) (xy 132.105754 -290.972238)
			(xy 132.12187 -291.020512) (xy 132.130034 -291.070746) (xy 132.130546 -291.096192) (xy 132.438643 -291.096192)
			(xy 132.442738 -291.045464) (xy 132.454917 -290.99605) (xy 132.474865 -290.94923) (xy 132.502066 -290.906216)
			(xy 132.535814 -290.868122) (xy 132.575236 -290.835935) (xy 132.61931 -290.810489) (xy 132.666896 -290.792442)
			(xy 132.71676 -290.782262) (xy 132.767612 -290.780213) (xy 132.818133 -290.786347) (xy 132.867017 -290.800507)
			(xy 132.912996 -290.822324) (xy 132.95488 -290.851234) (xy 132.991584 -290.886489) (xy 133.022157 -290.927175)
			(xy 133.045808 -290.972238) (xy 133.061924 -291.020512) (xy 133.070088 -291.070746) (xy 133.0706 -291.096192)
			(xy 133.070097 -291.121181) (xy 133.37716 -291.121181) (xy 133.37716 -291.071203) (xy 133.384979 -291.02184)
			(xy 133.400423 -290.974308) (xy 133.423113 -290.929776) (xy 133.452489 -290.889343) (xy 133.487829 -290.854003)
			(xy 133.528262 -290.824627) (xy 133.572794 -290.801937) (xy 133.620326 -290.786493) (xy 133.669689 -290.778674)
			(xy 133.719667 -290.778674) (xy 133.76903 -290.786493) (xy 133.816562 -290.801937) (xy 133.861094 -290.824627)
			(xy 133.901527 -290.854003) (xy 133.936867 -290.889343) (xy 133.966243 -290.929776) (xy 133.988933 -290.974308)
			(xy 134.004377 -291.02184) (xy 134.012196 -291.071203) (xy 134.012686 -291.096192) (xy 134.318497 -291.096192)
			(xy 134.322592 -291.045464) (xy 134.334771 -290.99605) (xy 134.354719 -290.94923) (xy 134.38192 -290.906216)
			(xy 134.415668 -290.868122) (xy 134.45509 -290.835935) (xy 134.499164 -290.810489) (xy 134.54675 -290.792442)
			(xy 134.596614 -290.782262) (xy 134.647466 -290.780213) (xy 134.697987 -290.786347) (xy 134.746871 -290.800507)
			(xy 134.79285 -290.822324) (xy 134.834734 -290.851234) (xy 134.871438 -290.886489) (xy 134.902011 -290.927175)
			(xy 134.925662 -290.972238) (xy 134.941778 -291.020512) (xy 134.949942 -291.070746) (xy 134.950454 -291.096192)
			(xy 134.949951 -291.121181) (xy 135.257268 -291.121181) (xy 135.257268 -291.071203) (xy 135.265087 -291.02184)
			(xy 135.280531 -290.974308) (xy 135.303221 -290.929776) (xy 135.332597 -290.889343) (xy 135.367937 -290.854003)
			(xy 135.40837 -290.824627) (xy 135.452902 -290.801937) (xy 135.500434 -290.786493) (xy 135.549797 -290.778674)
			(xy 135.599775 -290.778674) (xy 135.649138 -290.786493) (xy 135.69667 -290.801937) (xy 135.741202 -290.824627)
			(xy 135.781635 -290.854003) (xy 135.816975 -290.889343) (xy 135.846351 -290.929776) (xy 135.869041 -290.974308)
			(xy 135.884485 -291.02184) (xy 135.892304 -291.071203) (xy 135.892794 -291.096192) (xy 136.198605 -291.096192)
			(xy 136.2027 -291.045464) (xy 136.214879 -290.99605) (xy 136.234827 -290.94923) (xy 136.262028 -290.906216)
			(xy 136.295776 -290.868122) (xy 136.335198 -290.835935) (xy 136.379272 -290.810489) (xy 136.426858 -290.792442)
			(xy 136.476722 -290.782262) (xy 136.527574 -290.780213) (xy 136.578095 -290.786347) (xy 136.626979 -290.800507)
			(xy 136.672958 -290.822324) (xy 136.714842 -290.851234) (xy 136.751546 -290.886489) (xy 136.782119 -290.927175)
			(xy 136.80577 -290.972238) (xy 136.821886 -291.020512) (xy 136.83005 -291.070746) (xy 136.830562 -291.096192)
			(xy 136.830059 -291.121181) (xy 137.137122 -291.121181) (xy 137.137122 -291.071203) (xy 137.144941 -291.02184)
			(xy 137.160385 -290.974308) (xy 137.183075 -290.929776) (xy 137.212451 -290.889343) (xy 137.247791 -290.854003)
			(xy 137.288224 -290.824627) (xy 137.332756 -290.801937) (xy 137.380288 -290.786493) (xy 137.429651 -290.778674)
			(xy 137.479629 -290.778674) (xy 137.528992 -290.786493) (xy 137.576524 -290.801937) (xy 137.621056 -290.824627)
			(xy 137.661489 -290.854003) (xy 137.696829 -290.889343) (xy 137.726205 -290.929776) (xy 137.748895 -290.974308)
			(xy 137.764339 -291.02184) (xy 137.772158 -291.071203) (xy 137.772648 -291.096192) (xy 138.078459 -291.096192)
			(xy 138.082554 -291.045464) (xy 138.094733 -290.99605) (xy 138.114681 -290.94923) (xy 138.141882 -290.906216)
			(xy 138.17563 -290.868122) (xy 138.215052 -290.835935) (xy 138.259126 -290.810489) (xy 138.306712 -290.792442)
			(xy 138.356576 -290.782262) (xy 138.407428 -290.780213) (xy 138.457949 -290.786347) (xy 138.506833 -290.800507)
			(xy 138.552812 -290.822324) (xy 138.594696 -290.851234) (xy 138.6314 -290.886489) (xy 138.661973 -290.927175)
			(xy 138.685624 -290.972238) (xy 138.70174 -291.020512) (xy 138.709904 -291.070746) (xy 138.710416 -291.096192)
			(xy 139.018513 -291.096192) (xy 139.022608 -291.045464) (xy 139.034787 -290.99605) (xy 139.054735 -290.94923)
			(xy 139.081936 -290.906216) (xy 139.115684 -290.868122) (xy 139.155106 -290.835935) (xy 139.19918 -290.810489)
			(xy 139.246766 -290.792442) (xy 139.29663 -290.782262) (xy 139.347482 -290.780213) (xy 139.398003 -290.786347)
			(xy 139.446887 -290.800507) (xy 139.492866 -290.822324) (xy 139.53475 -290.851234) (xy 139.571454 -290.886489)
			(xy 139.602027 -290.927175) (xy 139.625678 -290.972238) (xy 139.641794 -291.020512) (xy 139.649958 -291.070746)
			(xy 139.65047 -291.096192) (xy 139.649967 -291.121181) (xy 139.957284 -291.121181) (xy 139.957284 -291.071203)
			(xy 139.965103 -291.02184) (xy 139.980547 -290.974308) (xy 140.003237 -290.929776) (xy 140.032613 -290.889343)
			(xy 140.067953 -290.854003) (xy 140.108386 -290.824627) (xy 140.152918 -290.801937) (xy 140.20045 -290.786493)
			(xy 140.249813 -290.778674) (xy 140.299791 -290.778674) (xy 140.349154 -290.786493) (xy 140.396686 -290.801937)
			(xy 140.441218 -290.824627) (xy 140.481651 -290.854003) (xy 140.516991 -290.889343) (xy 140.546367 -290.929776)
			(xy 140.569057 -290.974308) (xy 140.584501 -291.02184) (xy 140.59232 -291.071203) (xy 140.59281 -291.096192)
			(xy 140.898621 -291.096192) (xy 140.902716 -291.045464) (xy 140.914895 -290.99605) (xy 140.934843 -290.94923)
			(xy 140.962044 -290.906216) (xy 140.995792 -290.868122) (xy 141.035214 -290.835935) (xy 141.079288 -290.810489)
			(xy 141.126874 -290.792442) (xy 141.176738 -290.782262) (xy 141.22759 -290.780213) (xy 141.278111 -290.786347)
			(xy 141.326995 -290.800507) (xy 141.372974 -290.822324) (xy 141.414858 -290.851234) (xy 141.451562 -290.886489)
			(xy 141.482135 -290.927175) (xy 141.505786 -290.972238) (xy 141.521902 -291.020512) (xy 141.530066 -291.070746)
			(xy 141.530578 -291.096192) (xy 141.530075 -291.121181) (xy 141.837138 -291.121181) (xy 141.837138 -291.071203)
			(xy 141.844957 -291.02184) (xy 141.860401 -290.974308) (xy 141.883091 -290.929776) (xy 141.912467 -290.889343)
			(xy 141.947807 -290.854003) (xy 141.98824 -290.824627) (xy 142.032772 -290.801937) (xy 142.080304 -290.786493)
			(xy 142.129667 -290.778674) (xy 142.179645 -290.778674) (xy 142.229008 -290.786493) (xy 142.27654 -290.801937)
			(xy 142.321072 -290.824627) (xy 142.361505 -290.854003) (xy 142.396845 -290.889343) (xy 142.426221 -290.929776)
			(xy 142.448911 -290.974308) (xy 142.464355 -291.02184) (xy 142.472174 -291.071203) (xy 142.472664 -291.096192)
			(xy 142.778475 -291.096192) (xy 142.78257 -291.045464) (xy 142.794749 -290.99605) (xy 142.814697 -290.94923)
			(xy 142.841898 -290.906216) (xy 142.875646 -290.868122) (xy 142.915068 -290.835935) (xy 142.959142 -290.810489)
			(xy 143.006728 -290.792442) (xy 143.056592 -290.782262) (xy 143.107444 -290.780213) (xy 143.157965 -290.786347)
			(xy 143.206849 -290.800507) (xy 143.252828 -290.822324) (xy 143.294712 -290.851234) (xy 143.331416 -290.886489)
			(xy 143.361989 -290.927175) (xy 143.38564 -290.972238) (xy 143.401756 -291.020512) (xy 143.40992 -291.070746)
			(xy 143.410432 -291.096192) (xy 143.409929 -291.121181) (xy 143.717246 -291.121181) (xy 143.717246 -291.071203)
			(xy 143.725065 -291.02184) (xy 143.740509 -290.974308) (xy 143.763199 -290.929776) (xy 143.792575 -290.889343)
			(xy 143.827915 -290.854003) (xy 143.868348 -290.824627) (xy 143.91288 -290.801937) (xy 143.960412 -290.786493)
			(xy 144.009775 -290.778674) (xy 144.059753 -290.778674) (xy 144.109116 -290.786493) (xy 144.156648 -290.801937)
			(xy 144.20118 -290.824627) (xy 144.241613 -290.854003) (xy 144.276953 -290.889343) (xy 144.306329 -290.929776)
			(xy 144.329019 -290.974308) (xy 144.344463 -291.02184) (xy 144.352282 -291.071203) (xy 144.352772 -291.096192)
			(xy 144.352282 -291.121181) (xy 144.344463 -291.170544) (xy 144.329019 -291.218076) (xy 144.306329 -291.262608)
			(xy 144.276953 -291.303041) (xy 144.241613 -291.338381) (xy 144.20118 -291.367757) (xy 144.156648 -291.390447)
			(xy 144.109116 -291.405891) (xy 144.059753 -291.41371) (xy 144.009775 -291.41371) (xy 143.960412 -291.405891)
			(xy 143.91288 -291.390447) (xy 143.868348 -291.367757) (xy 143.827915 -291.338381) (xy 143.792575 -291.303041)
			(xy 143.763199 -291.262608) (xy 143.740509 -291.218076) (xy 143.725065 -291.170544) (xy 143.717246 -291.121181)
			(xy 143.409929 -291.121181) (xy 143.40992 -291.121638) (xy 143.401756 -291.171872) (xy 143.38564 -291.220146)
			(xy 143.361989 -291.265209) (xy 143.331416 -291.305895) (xy 143.294712 -291.34115) (xy 143.252828 -291.37006)
			(xy 143.206849 -291.391877) (xy 143.157965 -291.406037) (xy 143.107444 -291.412171) (xy 143.056592 -291.410122)
			(xy 143.006728 -291.399942) (xy 142.959142 -291.381895) (xy 142.915068 -291.356449) (xy 142.875646 -291.324262)
			(xy 142.841898 -291.286168) (xy 142.814697 -291.243154) (xy 142.794749 -291.196334) (xy 142.78257 -291.14692)
			(xy 142.778475 -291.096192) (xy 142.472664 -291.096192) (xy 142.472174 -291.121181) (xy 142.464355 -291.170544)
			(xy 142.448911 -291.218076) (xy 142.426221 -291.262608) (xy 142.396845 -291.303041) (xy 142.361505 -291.338381)
			(xy 142.321072 -291.367757) (xy 142.27654 -291.390447) (xy 142.229008 -291.405891) (xy 142.179645 -291.41371)
			(xy 142.129667 -291.41371) (xy 142.080304 -291.405891) (xy 142.032772 -291.390447) (xy 141.98824 -291.367757)
			(xy 141.947807 -291.338381) (xy 141.912467 -291.303041) (xy 141.883091 -291.262608) (xy 141.860401 -291.218076)
			(xy 141.844957 -291.170544) (xy 141.837138 -291.121181) (xy 141.530075 -291.121181) (xy 141.530066 -291.121638)
			(xy 141.521902 -291.171872) (xy 141.505786 -291.220146) (xy 141.482135 -291.265209) (xy 141.451562 -291.305895)
			(xy 141.414858 -291.34115) (xy 141.372974 -291.37006) (xy 141.326995 -291.391877) (xy 141.278111 -291.406037)
			(xy 141.22759 -291.412171) (xy 141.176738 -291.410122) (xy 141.126874 -291.399942) (xy 141.079288 -291.381895)
			(xy 141.035214 -291.356449) (xy 140.995792 -291.324262) (xy 140.962044 -291.286168) (xy 140.934843 -291.243154)
			(xy 140.914895 -291.196334) (xy 140.902716 -291.14692) (xy 140.898621 -291.096192) (xy 140.59281 -291.096192)
			(xy 140.59232 -291.121181) (xy 140.584501 -291.170544) (xy 140.569057 -291.218076) (xy 140.546367 -291.262608)
			(xy 140.516991 -291.303041) (xy 140.481651 -291.338381) (xy 140.441218 -291.367757) (xy 140.396686 -291.390447)
			(xy 140.349154 -291.405891) (xy 140.299791 -291.41371) (xy 140.249813 -291.41371) (xy 140.20045 -291.405891)
			(xy 140.152918 -291.390447) (xy 140.108386 -291.367757) (xy 140.067953 -291.338381) (xy 140.032613 -291.303041)
			(xy 140.003237 -291.262608) (xy 139.980547 -291.218076) (xy 139.965103 -291.170544) (xy 139.957284 -291.121181)
			(xy 139.649967 -291.121181) (xy 139.649958 -291.121638) (xy 139.641794 -291.171872) (xy 139.625678 -291.220146)
			(xy 139.602027 -291.265209) (xy 139.571454 -291.305895) (xy 139.53475 -291.34115) (xy 139.492866 -291.37006)
			(xy 139.446887 -291.391877) (xy 139.398003 -291.406037) (xy 139.347482 -291.412171) (xy 139.29663 -291.410122)
			(xy 139.246766 -291.399942) (xy 139.19918 -291.381895) (xy 139.155106 -291.356449) (xy 139.115684 -291.324262)
			(xy 139.081936 -291.286168) (xy 139.054735 -291.243154) (xy 139.034787 -291.196334) (xy 139.022608 -291.14692)
			(xy 139.018513 -291.096192) (xy 138.710416 -291.096192) (xy 138.709904 -291.121638) (xy 138.70174 -291.171872)
			(xy 138.685624 -291.220146) (xy 138.661973 -291.265209) (xy 138.6314 -291.305895) (xy 138.594696 -291.34115)
			(xy 138.552812 -291.37006) (xy 138.506833 -291.391877) (xy 138.457949 -291.406037) (xy 138.407428 -291.412171)
			(xy 138.356576 -291.410122) (xy 138.306712 -291.399942) (xy 138.259126 -291.381895) (xy 138.215052 -291.356449)
			(xy 138.17563 -291.324262) (xy 138.141882 -291.286168) (xy 138.114681 -291.243154) (xy 138.094733 -291.196334)
			(xy 138.082554 -291.14692) (xy 138.078459 -291.096192) (xy 137.772648 -291.096192) (xy 137.772158 -291.121181)
			(xy 137.764339 -291.170544) (xy 137.748895 -291.218076) (xy 137.726205 -291.262608) (xy 137.696829 -291.303041)
			(xy 137.661489 -291.338381) (xy 137.621056 -291.367757) (xy 137.576524 -291.390447) (xy 137.528992 -291.405891)
			(xy 137.479629 -291.41371) (xy 137.429651 -291.41371) (xy 137.380288 -291.405891) (xy 137.332756 -291.390447)
			(xy 137.288224 -291.367757) (xy 137.247791 -291.338381) (xy 137.212451 -291.303041) (xy 137.183075 -291.262608)
			(xy 137.160385 -291.218076) (xy 137.144941 -291.170544) (xy 137.137122 -291.121181) (xy 136.830059 -291.121181)
			(xy 136.83005 -291.121638) (xy 136.821886 -291.171872) (xy 136.80577 -291.220146) (xy 136.782119 -291.265209)
			(xy 136.751546 -291.305895) (xy 136.714842 -291.34115) (xy 136.672958 -291.37006) (xy 136.626979 -291.391877)
			(xy 136.578095 -291.406037) (xy 136.527574 -291.412171) (xy 136.476722 -291.410122) (xy 136.426858 -291.399942)
			(xy 136.379272 -291.381895) (xy 136.335198 -291.356449) (xy 136.295776 -291.324262) (xy 136.262028 -291.286168)
			(xy 136.234827 -291.243154) (xy 136.214879 -291.196334) (xy 136.2027 -291.14692) (xy 136.198605 -291.096192)
			(xy 135.892794 -291.096192) (xy 135.892304 -291.121181) (xy 135.884485 -291.170544) (xy 135.869041 -291.218076)
			(xy 135.846351 -291.262608) (xy 135.816975 -291.303041) (xy 135.781635 -291.338381) (xy 135.741202 -291.367757)
			(xy 135.69667 -291.390447) (xy 135.649138 -291.405891) (xy 135.599775 -291.41371) (xy 135.549797 -291.41371)
			(xy 135.500434 -291.405891) (xy 135.452902 -291.390447) (xy 135.40837 -291.367757) (xy 135.367937 -291.338381)
			(xy 135.332597 -291.303041) (xy 135.303221 -291.262608) (xy 135.280531 -291.218076) (xy 135.265087 -291.170544)
			(xy 135.257268 -291.121181) (xy 134.949951 -291.121181) (xy 134.949942 -291.121638) (xy 134.941778 -291.171872)
			(xy 134.925662 -291.220146) (xy 134.902011 -291.265209) (xy 134.871438 -291.305895) (xy 134.834734 -291.34115)
			(xy 134.79285 -291.37006) (xy 134.746871 -291.391877) (xy 134.697987 -291.406037) (xy 134.647466 -291.412171)
			(xy 134.596614 -291.410122) (xy 134.54675 -291.399942) (xy 134.499164 -291.381895) (xy 134.45509 -291.356449)
			(xy 134.415668 -291.324262) (xy 134.38192 -291.286168) (xy 134.354719 -291.243154) (xy 134.334771 -291.196334)
			(xy 134.322592 -291.14692) (xy 134.318497 -291.096192) (xy 134.012686 -291.096192) (xy 134.012196 -291.121181)
			(xy 134.004377 -291.170544) (xy 133.988933 -291.218076) (xy 133.966243 -291.262608) (xy 133.936867 -291.303041)
			(xy 133.901527 -291.338381) (xy 133.861094 -291.367757) (xy 133.816562 -291.390447) (xy 133.76903 -291.405891)
			(xy 133.719667 -291.41371) (xy 133.669689 -291.41371) (xy 133.620326 -291.405891) (xy 133.572794 -291.390447)
			(xy 133.528262 -291.367757) (xy 133.487829 -291.338381) (xy 133.452489 -291.303041) (xy 133.423113 -291.262608)
			(xy 133.400423 -291.218076) (xy 133.384979 -291.170544) (xy 133.37716 -291.121181) (xy 133.070097 -291.121181)
			(xy 133.070088 -291.121638) (xy 133.061924 -291.171872) (xy 133.045808 -291.220146) (xy 133.022157 -291.265209)
			(xy 132.991584 -291.305895) (xy 132.95488 -291.34115) (xy 132.912996 -291.37006) (xy 132.867017 -291.391877)
			(xy 132.818133 -291.406037) (xy 132.767612 -291.412171) (xy 132.71676 -291.410122) (xy 132.666896 -291.399942)
			(xy 132.61931 -291.381895) (xy 132.575236 -291.356449) (xy 132.535814 -291.324262) (xy 132.502066 -291.286168)
			(xy 132.474865 -291.243154) (xy 132.454917 -291.196334) (xy 132.442738 -291.14692) (xy 132.438643 -291.096192)
			(xy 132.130546 -291.096192) (xy 132.130034 -291.121638) (xy 132.12187 -291.171872) (xy 132.105754 -291.220146)
			(xy 132.082103 -291.265209) (xy 132.05153 -291.305895) (xy 132.014826 -291.34115) (xy 131.972942 -291.37006)
			(xy 131.926963 -291.391877) (xy 131.878079 -291.406037) (xy 131.827558 -291.412171) (xy 131.776706 -291.410122)
			(xy 131.726842 -291.399942) (xy 131.679256 -291.381895) (xy 131.635182 -291.356449) (xy 131.59576 -291.324262)
			(xy 131.562012 -291.286168) (xy 131.534811 -291.243154) (xy 131.514863 -291.196334) (xy 131.502684 -291.14692)
			(xy 131.498589 -291.096192) (xy 131.192778 -291.096192) (xy 131.192288 -291.121181) (xy 131.184469 -291.170544)
			(xy 131.169025 -291.218076) (xy 131.146335 -291.262608) (xy 131.116959 -291.303041) (xy 131.081619 -291.338381)
			(xy 131.041186 -291.367757) (xy 130.996654 -291.390447) (xy 130.949122 -291.405891) (xy 130.899759 -291.41371)
			(xy 130.849781 -291.41371) (xy 130.800418 -291.405891) (xy 130.752886 -291.390447) (xy 130.708354 -291.367757)
			(xy 130.667921 -291.338381) (xy 130.632581 -291.303041) (xy 130.603205 -291.262608) (xy 130.580515 -291.218076)
			(xy 130.565071 -291.170544) (xy 130.557252 -291.121181) (xy 130.249935 -291.121181) (xy 130.249926 -291.121638)
			(xy 130.241762 -291.171872) (xy 130.225646 -291.220146) (xy 130.201995 -291.265209) (xy 130.171422 -291.305895)
			(xy 130.134718 -291.34115) (xy 130.092834 -291.37006) (xy 130.046855 -291.391877) (xy 129.997971 -291.406037)
			(xy 129.94745 -291.412171) (xy 129.896598 -291.410122) (xy 129.846734 -291.399942) (xy 129.799148 -291.381895)
			(xy 129.755074 -291.356449) (xy 129.715652 -291.324262) (xy 129.681904 -291.286168) (xy 129.654703 -291.243154)
			(xy 129.634755 -291.196334) (xy 129.622576 -291.14692) (xy 129.618481 -291.096192) (xy 129.31267 -291.096192)
			(xy 129.31218 -291.121181) (xy 129.304361 -291.170544) (xy 129.288917 -291.218076) (xy 129.266227 -291.262608)
			(xy 129.236851 -291.303041) (xy 129.201511 -291.338381) (xy 129.161078 -291.367757) (xy 129.116546 -291.390447)
			(xy 129.069014 -291.405891) (xy 129.019651 -291.41371) (xy 128.969673 -291.41371) (xy 128.92031 -291.405891)
			(xy 128.872778 -291.390447) (xy 128.828246 -291.367757) (xy 128.787813 -291.338381) (xy 128.752473 -291.303041)
			(xy 128.723097 -291.262608) (xy 128.700407 -291.218076) (xy 128.684963 -291.170544) (xy 128.677144 -291.121181)
			(xy 128.371545 -291.121181) (xy 128.369461 -291.147106) (xy 128.357287 -291.196707) (xy 128.337346 -291.243727)
			(xy 128.310148 -291.286957) (xy 128.276393 -291.325287) (xy 128.236948 -291.357731) (xy 128.215136 -291.37102)
			(xy 128.209294 -291.374322) (xy 128.198118 -291.385498) (xy 128.195413 -291.388349) (xy 128.190821 -291.394728)
			(xy 128.188974 -291.398198) (xy 128.186387 -291.403624) (xy 128.183555 -291.415304) (xy 128.183386 -291.421312)
			(xy 128.183386 -291.567362) (xy 128.184325 -291.576534) (xy 128.191862 -291.593344) (xy 128.204875 -291.606382)
			(xy 128.213104 -291.610542) (xy 128.213358 -291.610542) (xy 128.286256 -291.648134) (xy 128.291082 -291.650166)
			(xy 128.295235 -291.651725) (xy 128.303923 -291.653518) (xy 128.308354 -291.653722) (xy 128.312541 -291.653731)
			(xy 128.320834 -291.652575) (xy 128.324864 -291.651436) (xy 128.341374 -291.646102) (xy 128.34747 -291.642038)
			(xy 128.367182 -291.629329) (xy 128.409554 -291.609218) (xy 128.454418 -291.595546) (xy 128.500804 -291.58861)
			(xy 128.524254 -291.58819) (xy 128.524762 -291.58819) (xy 128.549755 -291.588652) (xy 128.599127 -291.596466)
			(xy 128.646669 -291.611908) (xy 128.691209 -291.634598) (xy 128.731651 -291.663976) (xy 128.766999 -291.69932)
			(xy 128.796382 -291.739758) (xy 128.819077 -291.784296) (xy 128.834525 -291.831836) (xy 128.842345 -291.881207)
			(xy 128.842345 -291.906198) (xy 129.148581 -291.906198) (xy 129.152676 -291.85547) (xy 129.164855 -291.806056)
			(xy 129.184803 -291.759236) (xy 129.212004 -291.716222) (xy 129.245752 -291.678128) (xy 129.285174 -291.645941)
			(xy 129.329248 -291.620495) (xy 129.376834 -291.602448) (xy 129.426698 -291.592268) (xy 129.47755 -291.590219)
			(xy 129.528071 -291.596353) (xy 129.576955 -291.610513) (xy 129.622934 -291.63233) (xy 129.664818 -291.66124)
			(xy 129.701522 -291.696495) (xy 129.732095 -291.737181) (xy 129.755746 -291.782244) (xy 129.771862 -291.830518)
			(xy 129.780026 -291.880752) (xy 129.780538 -291.906198) (xy 129.780035 -291.931187) (xy 130.087352 -291.931187)
			(xy 130.087352 -291.881209) (xy 130.095171 -291.831846) (xy 130.110615 -291.784314) (xy 130.133305 -291.739782)
			(xy 130.162681 -291.699349) (xy 130.198021 -291.664009) (xy 130.238454 -291.634633) (xy 130.282986 -291.611943)
			(xy 130.330518 -291.596499) (xy 130.379881 -291.58868) (xy 130.429859 -291.58868) (xy 130.479222 -291.596499)
			(xy 130.526754 -291.611943) (xy 130.571286 -291.634633) (xy 130.611719 -291.664009) (xy 130.647059 -291.699349)
			(xy 130.676435 -291.739782) (xy 130.699125 -291.784314) (xy 130.714569 -291.831846) (xy 130.722388 -291.881209)
			(xy 130.722878 -291.906198) (xy 131.028435 -291.906198) (xy 131.03253 -291.85547) (xy 131.044709 -291.806056)
			(xy 131.064657 -291.759236) (xy 131.091858 -291.716222) (xy 131.125606 -291.678128) (xy 131.165028 -291.645941)
			(xy 131.209102 -291.620495) (xy 131.256688 -291.602448) (xy 131.306552 -291.592268) (xy 131.357404 -291.590219)
			(xy 131.407925 -291.596353) (xy 131.456809 -291.610513) (xy 131.502788 -291.63233) (xy 131.544672 -291.66124)
			(xy 131.581376 -291.696495) (xy 131.611949 -291.737181) (xy 131.6356 -291.782244) (xy 131.651716 -291.830518)
			(xy 131.65988 -291.880752) (xy 131.660392 -291.906198) (xy 131.659889 -291.931187) (xy 131.967206 -291.931187)
			(xy 131.967206 -291.881209) (xy 131.975025 -291.831846) (xy 131.990469 -291.784314) (xy 132.013159 -291.739782)
			(xy 132.042535 -291.699349) (xy 132.077875 -291.664009) (xy 132.118308 -291.634633) (xy 132.16284 -291.611943)
			(xy 132.210372 -291.596499) (xy 132.259735 -291.58868) (xy 132.309713 -291.58868) (xy 132.359076 -291.596499)
			(xy 132.406608 -291.611943) (xy 132.45114 -291.634633) (xy 132.491573 -291.664009) (xy 132.526913 -291.699349)
			(xy 132.556289 -291.739782) (xy 132.578979 -291.784314) (xy 132.594423 -291.831846) (xy 132.602242 -291.881209)
			(xy 132.602732 -291.906198) (xy 132.908543 -291.906198) (xy 132.912638 -291.85547) (xy 132.924817 -291.806056)
			(xy 132.944765 -291.759236) (xy 132.971966 -291.716222) (xy 133.005714 -291.678128) (xy 133.045136 -291.645941)
			(xy 133.08921 -291.620495) (xy 133.136796 -291.602448) (xy 133.18666 -291.592268) (xy 133.237512 -291.590219)
			(xy 133.288033 -291.596353) (xy 133.336917 -291.610513) (xy 133.382896 -291.63233) (xy 133.42478 -291.66124)
			(xy 133.461484 -291.696495) (xy 133.492057 -291.737181) (xy 133.515708 -291.782244) (xy 133.531824 -291.830518)
			(xy 133.539988 -291.880752) (xy 133.5405 -291.906198) (xy 133.539997 -291.931187) (xy 133.847314 -291.931187)
			(xy 133.847314 -291.881209) (xy 133.855133 -291.831846) (xy 133.870577 -291.784314) (xy 133.893267 -291.739782)
			(xy 133.922643 -291.699349) (xy 133.957983 -291.664009) (xy 133.998416 -291.634633) (xy 134.042948 -291.611943)
			(xy 134.09048 -291.596499) (xy 134.139843 -291.58868) (xy 134.189821 -291.58868) (xy 134.239184 -291.596499)
			(xy 134.286716 -291.611943) (xy 134.331248 -291.634633) (xy 134.371681 -291.664009) (xy 134.407021 -291.699349)
			(xy 134.436397 -291.739782) (xy 134.459087 -291.784314) (xy 134.474531 -291.831846) (xy 134.48235 -291.881209)
			(xy 134.48284 -291.906198) (xy 134.788397 -291.906198) (xy 134.792492 -291.85547) (xy 134.804671 -291.806056)
			(xy 134.824619 -291.759236) (xy 134.85182 -291.716222) (xy 134.885568 -291.678128) (xy 134.92499 -291.645941)
			(xy 134.969064 -291.620495) (xy 135.01665 -291.602448) (xy 135.066514 -291.592268) (xy 135.117366 -291.590219)
			(xy 135.167887 -291.596353) (xy 135.216771 -291.610513) (xy 135.26275 -291.63233) (xy 135.304634 -291.66124)
			(xy 135.341338 -291.696495) (xy 135.371911 -291.737181) (xy 135.395562 -291.782244) (xy 135.411678 -291.830518)
			(xy 135.419842 -291.880752) (xy 135.420354 -291.906198) (xy 135.728451 -291.906198) (xy 135.732546 -291.85547)
			(xy 135.744725 -291.806056) (xy 135.764673 -291.759236) (xy 135.791874 -291.716222) (xy 135.825622 -291.678128)
			(xy 135.865044 -291.645941) (xy 135.909118 -291.620495) (xy 135.956704 -291.602448) (xy 136.006568 -291.592268)
			(xy 136.05742 -291.590219) (xy 136.107941 -291.596353) (xy 136.156825 -291.610513) (xy 136.202804 -291.63233)
			(xy 136.244688 -291.66124) (xy 136.281392 -291.696495) (xy 136.311965 -291.737181) (xy 136.335616 -291.782244)
			(xy 136.351732 -291.830518) (xy 136.359896 -291.880752) (xy 136.360408 -291.906198) (xy 136.359905 -291.931187)
			(xy 136.667222 -291.931187) (xy 136.667222 -291.881209) (xy 136.675041 -291.831846) (xy 136.690485 -291.784314)
			(xy 136.713175 -291.739782) (xy 136.742551 -291.699349) (xy 136.777891 -291.664009) (xy 136.818324 -291.634633)
			(xy 136.862856 -291.611943) (xy 136.910388 -291.596499) (xy 136.959751 -291.58868) (xy 137.009729 -291.58868)
			(xy 137.059092 -291.596499) (xy 137.106624 -291.611943) (xy 137.151156 -291.634633) (xy 137.191589 -291.664009)
			(xy 137.226929 -291.699349) (xy 137.256305 -291.739782) (xy 137.278995 -291.784314) (xy 137.294439 -291.831846)
			(xy 137.302258 -291.881209) (xy 137.302748 -291.906198) (xy 137.608559 -291.906198) (xy 137.612654 -291.85547)
			(xy 137.624833 -291.806056) (xy 137.644781 -291.759236) (xy 137.671982 -291.716222) (xy 137.70573 -291.678128)
			(xy 137.745152 -291.645941) (xy 137.789226 -291.620495) (xy 137.836812 -291.602448) (xy 137.886676 -291.592268)
			(xy 137.937528 -291.590219) (xy 137.988049 -291.596353) (xy 138.036933 -291.610513) (xy 138.082912 -291.63233)
			(xy 138.124796 -291.66124) (xy 138.1615 -291.696495) (xy 138.192073 -291.737181) (xy 138.215724 -291.782244)
			(xy 138.23184 -291.830518) (xy 138.240004 -291.880752) (xy 138.240516 -291.906198) (xy 138.240013 -291.931187)
			(xy 138.54733 -291.931187) (xy 138.54733 -291.881209) (xy 138.555149 -291.831846) (xy 138.570593 -291.784314)
			(xy 138.593283 -291.739782) (xy 138.622659 -291.699349) (xy 138.657999 -291.664009) (xy 138.698432 -291.634633)
			(xy 138.742964 -291.611943) (xy 138.790496 -291.596499) (xy 138.839859 -291.58868) (xy 138.889837 -291.58868)
			(xy 138.9392 -291.596499) (xy 138.986732 -291.611943) (xy 139.031264 -291.634633) (xy 139.071697 -291.664009)
			(xy 139.107037 -291.699349) (xy 139.136413 -291.739782) (xy 139.159103 -291.784314) (xy 139.174547 -291.831846)
			(xy 139.182366 -291.881209) (xy 139.182856 -291.906198) (xy 139.488413 -291.906198) (xy 139.492508 -291.85547)
			(xy 139.504687 -291.806056) (xy 139.524635 -291.759236) (xy 139.551836 -291.716222) (xy 139.585584 -291.678128)
			(xy 139.625006 -291.645941) (xy 139.66908 -291.620495) (xy 139.716666 -291.602448) (xy 139.76653 -291.592268)
			(xy 139.817382 -291.590219) (xy 139.867903 -291.596353) (xy 139.916787 -291.610513) (xy 139.962766 -291.63233)
			(xy 140.00465 -291.66124) (xy 140.041354 -291.696495) (xy 140.071927 -291.737181) (xy 140.095578 -291.782244)
			(xy 140.111694 -291.830518) (xy 140.119858 -291.880752) (xy 140.12037 -291.906198) (xy 140.119867 -291.931187)
			(xy 140.427184 -291.931187) (xy 140.427184 -291.881209) (xy 140.435003 -291.831846) (xy 140.450447 -291.784314)
			(xy 140.473137 -291.739782) (xy 140.502513 -291.699349) (xy 140.537853 -291.664009) (xy 140.578286 -291.634633)
			(xy 140.622818 -291.611943) (xy 140.67035 -291.596499) (xy 140.719713 -291.58868) (xy 140.769691 -291.58868)
			(xy 140.819054 -291.596499) (xy 140.866586 -291.611943) (xy 140.911118 -291.634633) (xy 140.951551 -291.664009)
			(xy 140.986891 -291.699349) (xy 141.016267 -291.739782) (xy 141.038957 -291.784314) (xy 141.054401 -291.831846)
			(xy 141.06222 -291.881209) (xy 141.06271 -291.906198) (xy 141.368521 -291.906198) (xy 141.372616 -291.85547)
			(xy 141.384795 -291.806056) (xy 141.404743 -291.759236) (xy 141.431944 -291.716222) (xy 141.465692 -291.678128)
			(xy 141.505114 -291.645941) (xy 141.549188 -291.620495) (xy 141.596774 -291.602448) (xy 141.646638 -291.592268)
			(xy 141.69749 -291.590219) (xy 141.748011 -291.596353) (xy 141.796895 -291.610513) (xy 141.842874 -291.63233)
			(xy 141.884758 -291.66124) (xy 141.921462 -291.696495) (xy 141.952035 -291.737181) (xy 141.975686 -291.782244)
			(xy 141.991802 -291.830518) (xy 141.999966 -291.880752) (xy 142.000478 -291.906198) (xy 142.308575 -291.906198)
			(xy 142.31267 -291.85547) (xy 142.324849 -291.806056) (xy 142.344797 -291.759236) (xy 142.371998 -291.716222)
			(xy 142.405746 -291.678128) (xy 142.445168 -291.645941) (xy 142.489242 -291.620495) (xy 142.536828 -291.602448)
			(xy 142.586692 -291.592268) (xy 142.637544 -291.590219) (xy 142.688065 -291.596353) (xy 142.736949 -291.610513)
			(xy 142.782928 -291.63233) (xy 142.824812 -291.66124) (xy 142.861516 -291.696495) (xy 142.892089 -291.737181)
			(xy 142.91574 -291.782244) (xy 142.931856 -291.830518) (xy 142.94002 -291.880752) (xy 142.940532 -291.906198)
			(xy 142.940029 -291.931187) (xy 143.247092 -291.931187) (xy 143.247092 -291.881209) (xy 143.254911 -291.831846)
			(xy 143.270355 -291.784314) (xy 143.293045 -291.739782) (xy 143.322421 -291.699349) (xy 143.357761 -291.664009)
			(xy 143.398194 -291.634633) (xy 143.442726 -291.611943) (xy 143.490258 -291.596499) (xy 143.539621 -291.58868)
			(xy 143.589599 -291.58868) (xy 143.638962 -291.596499) (xy 143.686494 -291.611943) (xy 143.731026 -291.634633)
			(xy 143.771459 -291.664009) (xy 143.806799 -291.699349) (xy 143.836175 -291.739782) (xy 143.858865 -291.784314)
			(xy 143.874309 -291.831846) (xy 143.882128 -291.881209) (xy 143.882618 -291.906198) (xy 143.882128 -291.931187)
			(xy 143.874309 -291.98055) (xy 143.858865 -292.028082) (xy 143.836175 -292.072614) (xy 143.806799 -292.113047)
			(xy 143.771459 -292.148387) (xy 143.731026 -292.177763) (xy 143.686494 -292.200453) (xy 143.638962 -292.215897)
			(xy 143.589599 -292.223716) (xy 143.539621 -292.223716) (xy 143.490258 -292.215897) (xy 143.442726 -292.200453)
			(xy 143.398194 -292.177763) (xy 143.357761 -292.148387) (xy 143.322421 -292.113047) (xy 143.293045 -292.072614)
			(xy 143.270355 -292.028082) (xy 143.254911 -291.98055) (xy 143.247092 -291.931187) (xy 142.940029 -291.931187)
			(xy 142.94002 -291.931644) (xy 142.931856 -291.981878) (xy 142.91574 -292.030152) (xy 142.892089 -292.075215)
			(xy 142.861516 -292.115901) (xy 142.824812 -292.151156) (xy 142.782928 -292.180066) (xy 142.736949 -292.201883)
			(xy 142.688065 -292.216043) (xy 142.637544 -292.222177) (xy 142.586692 -292.220128) (xy 142.536828 -292.209948)
			(xy 142.489242 -292.191901) (xy 142.445168 -292.166455) (xy 142.405746 -292.134268) (xy 142.371998 -292.096174)
			(xy 142.344797 -292.05316) (xy 142.324849 -292.00634) (xy 142.31267 -291.956926) (xy 142.308575 -291.906198)
			(xy 142.000478 -291.906198) (xy 141.999966 -291.931644) (xy 141.991802 -291.981878) (xy 141.975686 -292.030152)
			(xy 141.952035 -292.075215) (xy 141.921462 -292.115901) (xy 141.884758 -292.151156) (xy 141.842874 -292.180066)
			(xy 141.796895 -292.201883) (xy 141.748011 -292.216043) (xy 141.69749 -292.222177) (xy 141.646638 -292.220128)
			(xy 141.596774 -292.209948) (xy 141.549188 -292.191901) (xy 141.505114 -292.166455) (xy 141.465692 -292.134268)
			(xy 141.431944 -292.096174) (xy 141.404743 -292.05316) (xy 141.384795 -292.00634) (xy 141.372616 -291.956926)
			(xy 141.368521 -291.906198) (xy 141.06271 -291.906198) (xy 141.06222 -291.931187) (xy 141.054401 -291.98055)
			(xy 141.038957 -292.028082) (xy 141.016267 -292.072614) (xy 140.986891 -292.113047) (xy 140.951551 -292.148387)
			(xy 140.911118 -292.177763) (xy 140.866586 -292.200453) (xy 140.819054 -292.215897) (xy 140.769691 -292.223716)
			(xy 140.719713 -292.223716) (xy 140.67035 -292.215897) (xy 140.622818 -292.200453) (xy 140.578286 -292.177763)
			(xy 140.537853 -292.148387) (xy 140.502513 -292.113047) (xy 140.473137 -292.072614) (xy 140.450447 -292.028082)
			(xy 140.435003 -291.98055) (xy 140.427184 -291.931187) (xy 140.119867 -291.931187) (xy 140.119858 -291.931644)
			(xy 140.111694 -291.981878) (xy 140.095578 -292.030152) (xy 140.071927 -292.075215) (xy 140.041354 -292.115901)
			(xy 140.00465 -292.151156) (xy 139.962766 -292.180066) (xy 139.916787 -292.201883) (xy 139.867903 -292.216043)
			(xy 139.817382 -292.222177) (xy 139.76653 -292.220128) (xy 139.716666 -292.209948) (xy 139.66908 -292.191901)
			(xy 139.625006 -292.166455) (xy 139.585584 -292.134268) (xy 139.551836 -292.096174) (xy 139.524635 -292.05316)
			(xy 139.504687 -292.00634) (xy 139.492508 -291.956926) (xy 139.488413 -291.906198) (xy 139.182856 -291.906198)
			(xy 139.182366 -291.931187) (xy 139.174547 -291.98055) (xy 139.159103 -292.028082) (xy 139.136413 -292.072614)
			(xy 139.107037 -292.113047) (xy 139.071697 -292.148387) (xy 139.031264 -292.177763) (xy 138.986732 -292.200453)
			(xy 138.9392 -292.215897) (xy 138.889837 -292.223716) (xy 138.839859 -292.223716) (xy 138.790496 -292.215897)
			(xy 138.742964 -292.200453) (xy 138.698432 -292.177763) (xy 138.657999 -292.148387) (xy 138.622659 -292.113047)
			(xy 138.593283 -292.072614) (xy 138.570593 -292.028082) (xy 138.555149 -291.98055) (xy 138.54733 -291.931187)
			(xy 138.240013 -291.931187) (xy 138.240004 -291.931644) (xy 138.23184 -291.981878) (xy 138.215724 -292.030152)
			(xy 138.192073 -292.075215) (xy 138.1615 -292.115901) (xy 138.124796 -292.151156) (xy 138.082912 -292.180066)
			(xy 138.036933 -292.201883) (xy 137.988049 -292.216043) (xy 137.937528 -292.222177) (xy 137.886676 -292.220128)
			(xy 137.836812 -292.209948) (xy 137.789226 -292.191901) (xy 137.745152 -292.166455) (xy 137.70573 -292.134268)
			(xy 137.671982 -292.096174) (xy 137.644781 -292.05316) (xy 137.624833 -292.00634) (xy 137.612654 -291.956926)
			(xy 137.608559 -291.906198) (xy 137.302748 -291.906198) (xy 137.302258 -291.931187) (xy 137.294439 -291.98055)
			(xy 137.278995 -292.028082) (xy 137.256305 -292.072614) (xy 137.226929 -292.113047) (xy 137.191589 -292.148387)
			(xy 137.151156 -292.177763) (xy 137.106624 -292.200453) (xy 137.059092 -292.215897) (xy 137.009729 -292.223716)
			(xy 136.959751 -292.223716) (xy 136.910388 -292.215897) (xy 136.862856 -292.200453) (xy 136.818324 -292.177763)
			(xy 136.777891 -292.148387) (xy 136.742551 -292.113047) (xy 136.713175 -292.072614) (xy 136.690485 -292.028082)
			(xy 136.675041 -291.98055) (xy 136.667222 -291.931187) (xy 136.359905 -291.931187) (xy 136.359896 -291.931644)
			(xy 136.351732 -291.981878) (xy 136.335616 -292.030152) (xy 136.311965 -292.075215) (xy 136.281392 -292.115901)
			(xy 136.244688 -292.151156) (xy 136.202804 -292.180066) (xy 136.156825 -292.201883) (xy 136.107941 -292.216043)
			(xy 136.05742 -292.222177) (xy 136.006568 -292.220128) (xy 135.956704 -292.209948) (xy 135.909118 -292.191901)
			(xy 135.865044 -292.166455) (xy 135.825622 -292.134268) (xy 135.791874 -292.096174) (xy 135.764673 -292.05316)
			(xy 135.744725 -292.00634) (xy 135.732546 -291.956926) (xy 135.728451 -291.906198) (xy 135.420354 -291.906198)
			(xy 135.419842 -291.931644) (xy 135.411678 -291.981878) (xy 135.395562 -292.030152) (xy 135.371911 -292.075215)
			(xy 135.341338 -292.115901) (xy 135.304634 -292.151156) (xy 135.26275 -292.180066) (xy 135.216771 -292.201883)
			(xy 135.167887 -292.216043) (xy 135.117366 -292.222177) (xy 135.066514 -292.220128) (xy 135.01665 -292.209948)
			(xy 134.969064 -292.191901) (xy 134.92499 -292.166455) (xy 134.885568 -292.134268) (xy 134.85182 -292.096174)
			(xy 134.824619 -292.05316) (xy 134.804671 -292.00634) (xy 134.792492 -291.956926) (xy 134.788397 -291.906198)
			(xy 134.48284 -291.906198) (xy 134.48235 -291.931187) (xy 134.474531 -291.98055) (xy 134.459087 -292.028082)
			(xy 134.436397 -292.072614) (xy 134.407021 -292.113047) (xy 134.371681 -292.148387) (xy 134.331248 -292.177763)
			(xy 134.286716 -292.200453) (xy 134.239184 -292.215897) (xy 134.189821 -292.223716) (xy 134.139843 -292.223716)
			(xy 134.09048 -292.215897) (xy 134.042948 -292.200453) (xy 133.998416 -292.177763) (xy 133.957983 -292.148387)
			(xy 133.922643 -292.113047) (xy 133.893267 -292.072614) (xy 133.870577 -292.028082) (xy 133.855133 -291.98055)
			(xy 133.847314 -291.931187) (xy 133.539997 -291.931187) (xy 133.539988 -291.931644) (xy 133.531824 -291.981878)
			(xy 133.515708 -292.030152) (xy 133.492057 -292.075215) (xy 133.461484 -292.115901) (xy 133.42478 -292.151156)
			(xy 133.382896 -292.180066) (xy 133.336917 -292.201883) (xy 133.288033 -292.216043) (xy 133.237512 -292.222177)
			(xy 133.18666 -292.220128) (xy 133.136796 -292.209948) (xy 133.08921 -292.191901) (xy 133.045136 -292.166455)
			(xy 133.005714 -292.134268) (xy 132.971966 -292.096174) (xy 132.944765 -292.05316) (xy 132.924817 -292.00634)
			(xy 132.912638 -291.956926) (xy 132.908543 -291.906198) (xy 132.602732 -291.906198) (xy 132.602242 -291.931187)
			(xy 132.594423 -291.98055) (xy 132.578979 -292.028082) (xy 132.556289 -292.072614) (xy 132.526913 -292.113047)
			(xy 132.491573 -292.148387) (xy 132.45114 -292.177763) (xy 132.406608 -292.200453) (xy 132.359076 -292.215897)
			(xy 132.309713 -292.223716) (xy 132.259735 -292.223716) (xy 132.210372 -292.215897) (xy 132.16284 -292.200453)
			(xy 132.118308 -292.177763) (xy 132.077875 -292.148387) (xy 132.042535 -292.113047) (xy 132.013159 -292.072614)
			(xy 131.990469 -292.028082) (xy 131.975025 -291.98055) (xy 131.967206 -291.931187) (xy 131.659889 -291.931187)
			(xy 131.65988 -291.931644) (xy 131.651716 -291.981878) (xy 131.6356 -292.030152) (xy 131.611949 -292.075215)
			(xy 131.581376 -292.115901) (xy 131.544672 -292.151156) (xy 131.502788 -292.180066) (xy 131.456809 -292.201883)
			(xy 131.407925 -292.216043) (xy 131.357404 -292.222177) (xy 131.306552 -292.220128) (xy 131.256688 -292.209948)
			(xy 131.209102 -292.191901) (xy 131.165028 -292.166455) (xy 131.125606 -292.134268) (xy 131.091858 -292.096174)
			(xy 131.064657 -292.05316) (xy 131.044709 -292.00634) (xy 131.03253 -291.956926) (xy 131.028435 -291.906198)
			(xy 130.722878 -291.906198) (xy 130.722388 -291.931187) (xy 130.714569 -291.98055) (xy 130.699125 -292.028082)
			(xy 130.676435 -292.072614) (xy 130.647059 -292.113047) (xy 130.611719 -292.148387) (xy 130.571286 -292.177763)
			(xy 130.526754 -292.200453) (xy 130.479222 -292.215897) (xy 130.429859 -292.223716) (xy 130.379881 -292.223716)
			(xy 130.330518 -292.215897) (xy 130.282986 -292.200453) (xy 130.238454 -292.177763) (xy 130.198021 -292.148387)
			(xy 130.162681 -292.113047) (xy 130.133305 -292.072614) (xy 130.110615 -292.028082) (xy 130.095171 -291.98055)
			(xy 130.087352 -291.931187) (xy 129.780035 -291.931187) (xy 129.780026 -291.931644) (xy 129.771862 -291.981878)
			(xy 129.755746 -292.030152) (xy 129.732095 -292.075215) (xy 129.701522 -292.115901) (xy 129.664818 -292.151156)
			(xy 129.622934 -292.180066) (xy 129.576955 -292.201883) (xy 129.528071 -292.216043) (xy 129.47755 -292.222177)
			(xy 129.426698 -292.220128) (xy 129.376834 -292.209948) (xy 129.329248 -292.191901) (xy 129.285174 -292.166455)
			(xy 129.245752 -292.134268) (xy 129.212004 -292.096174) (xy 129.184803 -292.05316) (xy 129.164855 -292.00634)
			(xy 129.152676 -291.956926) (xy 129.148581 -291.906198) (xy 128.842345 -291.906198) (xy 128.842345 -291.931193)
			(xy 128.834525 -291.980564) (xy 128.819077 -292.028104) (xy 128.796382 -292.072642) (xy 128.766999 -292.11308)
			(xy 128.731651 -292.148424) (xy 128.691209 -292.177802) (xy 128.646669 -292.200492) (xy 128.599127 -292.215934)
			(xy 128.549755 -292.223748) (xy 128.524762 -292.224206) (xy 128.524254 -292.224206) (xy 128.500804 -292.223768)
			(xy 128.454418 -292.216842) (xy 128.409553 -292.203175) (xy 128.367183 -292.183065) (xy 128.34747 -292.170358)
			(xy 128.341374 -292.166294) (xy 128.324864 -292.16096) (xy 128.320844 -292.159778) (xy 128.312544 -292.158628)
			(xy 128.308354 -292.158674) (xy 128.303926 -292.158908) (xy 128.295244 -292.160702) (xy 128.291082 -292.16223)
			(xy 128.286256 -292.164262) (xy 128.213358 -292.201854) (xy 128.213104 -292.201854) (xy 128.204901 -292.206039)
			(xy 128.191934 -292.219097) (xy 128.184381 -292.235878) (xy 128.183386 -292.245034) (xy 128.183386 -292.391084)
			(xy 128.184402 -292.400736) (xy 128.186027 -292.407982) (xy 128.192862 -292.421156) (xy 128.197864 -292.426644)
			(xy 128.209294 -292.438074) (xy 128.215136 -292.441376) (xy 128.236941 -292.454677) (xy 128.276385 -292.487119)
			(xy 128.310139 -292.525447) (xy 128.337336 -292.568676) (xy 128.357277 -292.615694) (xy 128.36945 -292.665294)
			(xy 128.373543 -292.716202) (xy 128.371534 -292.741193) (xy 128.677144 -292.741193) (xy 128.677144 -292.691215)
			(xy 128.684963 -292.641852) (xy 128.700407 -292.59432) (xy 128.723097 -292.549788) (xy 128.752473 -292.509355)
			(xy 128.787813 -292.474015) (xy 128.828246 -292.444639) (xy 128.872778 -292.421949) (xy 128.92031 -292.406505)
			(xy 128.969673 -292.398686) (xy 129.019651 -292.398686) (xy 129.069014 -292.406505) (xy 129.116546 -292.421949)
			(xy 129.161078 -292.444639) (xy 129.201511 -292.474015) (xy 129.236851 -292.509355) (xy 129.266227 -292.549788)
			(xy 129.288917 -292.59432) (xy 129.304361 -292.641852) (xy 129.31218 -292.691215) (xy 129.31267 -292.716204)
			(xy 129.618481 -292.716204) (xy 129.622576 -292.665476) (xy 129.634755 -292.616062) (xy 129.654703 -292.569242)
			(xy 129.681904 -292.526228) (xy 129.715652 -292.488134) (xy 129.755074 -292.455947) (xy 129.799148 -292.430501)
			(xy 129.846734 -292.412454) (xy 129.896598 -292.402274) (xy 129.94745 -292.400225) (xy 129.997971 -292.406359)
			(xy 130.046855 -292.420519) (xy 130.092834 -292.442336) (xy 130.134718 -292.471246) (xy 130.171422 -292.506501)
			(xy 130.201995 -292.547187) (xy 130.225646 -292.59225) (xy 130.241762 -292.640524) (xy 130.249926 -292.690758)
			(xy 130.250438 -292.716204) (xy 131.498589 -292.716204) (xy 131.502684 -292.665476) (xy 131.514863 -292.616062)
			(xy 131.534811 -292.569242) (xy 131.562012 -292.526228) (xy 131.59576 -292.488134) (xy 131.635182 -292.455947)
			(xy 131.679256 -292.430501) (xy 131.726842 -292.412454) (xy 131.776706 -292.402274) (xy 131.827558 -292.400225)
			(xy 131.878079 -292.406359) (xy 131.926963 -292.420519) (xy 131.972942 -292.442336) (xy 132.014826 -292.471246)
			(xy 132.05153 -292.506501) (xy 132.082103 -292.547187) (xy 132.105754 -292.59225) (xy 132.12187 -292.640524)
			(xy 132.130034 -292.690758) (xy 132.130546 -292.716204) (xy 132.438643 -292.716204) (xy 132.442738 -292.665476)
			(xy 132.454917 -292.616062) (xy 132.474865 -292.569242) (xy 132.502066 -292.526228) (xy 132.535814 -292.488134)
			(xy 132.575236 -292.455947) (xy 132.61931 -292.430501) (xy 132.666896 -292.412454) (xy 132.71676 -292.402274)
			(xy 132.767612 -292.400225) (xy 132.818133 -292.406359) (xy 132.867017 -292.420519) (xy 132.912996 -292.442336)
			(xy 132.95488 -292.471246) (xy 132.991584 -292.506501) (xy 133.022157 -292.547187) (xy 133.045808 -292.59225)
			(xy 133.061924 -292.640524) (xy 133.070088 -292.690758) (xy 133.0706 -292.716204) (xy 133.070097 -292.741193)
			(xy 133.37716 -292.741193) (xy 133.37716 -292.691215) (xy 133.384979 -292.641852) (xy 133.400423 -292.59432)
			(xy 133.423113 -292.549788) (xy 133.452489 -292.509355) (xy 133.487829 -292.474015) (xy 133.528262 -292.444639)
			(xy 133.572794 -292.421949) (xy 133.620326 -292.406505) (xy 133.669689 -292.398686) (xy 133.719667 -292.398686)
			(xy 133.76903 -292.406505) (xy 133.816562 -292.421949) (xy 133.861094 -292.444639) (xy 133.901527 -292.474015)
			(xy 133.936867 -292.509355) (xy 133.966243 -292.549788) (xy 133.988933 -292.59432) (xy 134.004377 -292.641852)
			(xy 134.012196 -292.691215) (xy 134.012686 -292.716204) (xy 134.318497 -292.716204) (xy 134.322592 -292.665476)
			(xy 134.334771 -292.616062) (xy 134.354719 -292.569242) (xy 134.38192 -292.526228) (xy 134.415668 -292.488134)
			(xy 134.45509 -292.455947) (xy 134.499164 -292.430501) (xy 134.54675 -292.412454) (xy 134.596614 -292.402274)
			(xy 134.647466 -292.400225) (xy 134.697987 -292.406359) (xy 134.746871 -292.420519) (xy 134.79285 -292.442336)
			(xy 134.834734 -292.471246) (xy 134.871438 -292.506501) (xy 134.902011 -292.547187) (xy 134.925662 -292.59225)
			(xy 134.941778 -292.640524) (xy 134.949942 -292.690758) (xy 134.950454 -292.716204) (xy 134.949951 -292.741193)
			(xy 135.257268 -292.741193) (xy 135.257268 -292.691215) (xy 135.265087 -292.641852) (xy 135.280531 -292.59432)
			(xy 135.303221 -292.549788) (xy 135.332597 -292.509355) (xy 135.367937 -292.474015) (xy 135.40837 -292.444639)
			(xy 135.452902 -292.421949) (xy 135.500434 -292.406505) (xy 135.549797 -292.398686) (xy 135.599775 -292.398686)
			(xy 135.649138 -292.406505) (xy 135.69667 -292.421949) (xy 135.741202 -292.444639) (xy 135.781635 -292.474015)
			(xy 135.816975 -292.509355) (xy 135.846351 -292.549788) (xy 135.869041 -292.59432) (xy 135.884485 -292.641852)
			(xy 135.892304 -292.691215) (xy 135.892794 -292.716204) (xy 136.198605 -292.716204) (xy 136.2027 -292.665476)
			(xy 136.214879 -292.616062) (xy 136.234827 -292.569242) (xy 136.262028 -292.526228) (xy 136.295776 -292.488134)
			(xy 136.335198 -292.455947) (xy 136.379272 -292.430501) (xy 136.426858 -292.412454) (xy 136.476722 -292.402274)
			(xy 136.527574 -292.400225) (xy 136.578095 -292.406359) (xy 136.626979 -292.420519) (xy 136.672958 -292.442336)
			(xy 136.714842 -292.471246) (xy 136.751546 -292.506501) (xy 136.782119 -292.547187) (xy 136.80577 -292.59225)
			(xy 136.821886 -292.640524) (xy 136.83005 -292.690758) (xy 136.830562 -292.716204) (xy 138.078459 -292.716204)
			(xy 138.082554 -292.665476) (xy 138.094733 -292.616062) (xy 138.114681 -292.569242) (xy 138.141882 -292.526228)
			(xy 138.17563 -292.488134) (xy 138.215052 -292.455947) (xy 138.259126 -292.430501) (xy 138.306712 -292.412454)
			(xy 138.356576 -292.402274) (xy 138.407428 -292.400225) (xy 138.457949 -292.406359) (xy 138.506833 -292.420519)
			(xy 138.552812 -292.442336) (xy 138.594696 -292.471246) (xy 138.6314 -292.506501) (xy 138.661973 -292.547187)
			(xy 138.685624 -292.59225) (xy 138.70174 -292.640524) (xy 138.709904 -292.690758) (xy 138.710416 -292.716204)
			(xy 139.018513 -292.716204) (xy 139.022608 -292.665476) (xy 139.034787 -292.616062) (xy 139.054735 -292.569242)
			(xy 139.081936 -292.526228) (xy 139.115684 -292.488134) (xy 139.155106 -292.455947) (xy 139.19918 -292.430501)
			(xy 139.246766 -292.412454) (xy 139.29663 -292.402274) (xy 139.347482 -292.400225) (xy 139.398003 -292.406359)
			(xy 139.446887 -292.420519) (xy 139.492866 -292.442336) (xy 139.53475 -292.471246) (xy 139.571454 -292.506501)
			(xy 139.602027 -292.547187) (xy 139.625678 -292.59225) (xy 139.641794 -292.640524) (xy 139.649958 -292.690758)
			(xy 139.65047 -292.716204) (xy 139.649967 -292.741193) (xy 139.957284 -292.741193) (xy 139.957284 -292.691215)
			(xy 139.965103 -292.641852) (xy 139.980547 -292.59432) (xy 140.003237 -292.549788) (xy 140.032613 -292.509355)
			(xy 140.067953 -292.474015) (xy 140.108386 -292.444639) (xy 140.152918 -292.421949) (xy 140.20045 -292.406505)
			(xy 140.249813 -292.398686) (xy 140.299791 -292.398686) (xy 140.349154 -292.406505) (xy 140.396686 -292.421949)
			(xy 140.441218 -292.444639) (xy 140.481651 -292.474015) (xy 140.516991 -292.509355) (xy 140.546367 -292.549788)
			(xy 140.569057 -292.59432) (xy 140.584501 -292.641852) (xy 140.59232 -292.691215) (xy 140.59281 -292.716204)
			(xy 140.898621 -292.716204) (xy 140.902716 -292.665476) (xy 140.914895 -292.616062) (xy 140.934843 -292.569242)
			(xy 140.962044 -292.526228) (xy 140.995792 -292.488134) (xy 141.035214 -292.455947) (xy 141.079288 -292.430501)
			(xy 141.126874 -292.412454) (xy 141.176738 -292.402274) (xy 141.22759 -292.400225) (xy 141.278111 -292.406359)
			(xy 141.326995 -292.420519) (xy 141.372974 -292.442336) (xy 141.414858 -292.471246) (xy 141.451562 -292.506501)
			(xy 141.482135 -292.547187) (xy 141.505786 -292.59225) (xy 141.521902 -292.640524) (xy 141.530066 -292.690758)
			(xy 141.530578 -292.716204) (xy 141.530075 -292.741193) (xy 141.837138 -292.741193) (xy 141.837138 -292.691215)
			(xy 141.844957 -292.641852) (xy 141.860401 -292.59432) (xy 141.883091 -292.549788) (xy 141.912467 -292.509355)
			(xy 141.947807 -292.474015) (xy 141.98824 -292.444639) (xy 142.032772 -292.421949) (xy 142.080304 -292.406505)
			(xy 142.129667 -292.398686) (xy 142.179645 -292.398686) (xy 142.229008 -292.406505) (xy 142.27654 -292.421949)
			(xy 142.321072 -292.444639) (xy 142.361505 -292.474015) (xy 142.396845 -292.509355) (xy 142.426221 -292.549788)
			(xy 142.448911 -292.59432) (xy 142.464355 -292.641852) (xy 142.472174 -292.691215) (xy 142.472664 -292.716204)
			(xy 142.778475 -292.716204) (xy 142.78257 -292.665476) (xy 142.794749 -292.616062) (xy 142.814697 -292.569242)
			(xy 142.841898 -292.526228) (xy 142.875646 -292.488134) (xy 142.915068 -292.455947) (xy 142.959142 -292.430501)
			(xy 143.006728 -292.412454) (xy 143.056592 -292.402274) (xy 143.107444 -292.400225) (xy 143.157965 -292.406359)
			(xy 143.206849 -292.420519) (xy 143.252828 -292.442336) (xy 143.294712 -292.471246) (xy 143.331416 -292.506501)
			(xy 143.361989 -292.547187) (xy 143.38564 -292.59225) (xy 143.401756 -292.640524) (xy 143.40992 -292.690758)
			(xy 143.410432 -292.716204) (xy 143.40992 -292.74165) (xy 143.401756 -292.791884) (xy 143.38564 -292.840158)
			(xy 143.361989 -292.885221) (xy 143.331416 -292.925907) (xy 143.294712 -292.961162) (xy 143.252828 -292.990072)
			(xy 143.206849 -293.011889) (xy 143.157965 -293.026049) (xy 143.107444 -293.032183) (xy 143.056592 -293.030134)
			(xy 143.006728 -293.019954) (xy 142.959142 -293.001907) (xy 142.915068 -292.976461) (xy 142.875646 -292.944274)
			(xy 142.841898 -292.90618) (xy 142.814697 -292.863166) (xy 142.794749 -292.816346) (xy 142.78257 -292.766932)
			(xy 142.778475 -292.716204) (xy 142.472664 -292.716204) (xy 142.472174 -292.741193) (xy 142.464355 -292.790556)
			(xy 142.448911 -292.838088) (xy 142.426221 -292.88262) (xy 142.396845 -292.923053) (xy 142.361505 -292.958393)
			(xy 142.321072 -292.987769) (xy 142.27654 -293.010459) (xy 142.229008 -293.025903) (xy 142.179645 -293.033722)
			(xy 142.129667 -293.033722) (xy 142.080304 -293.025903) (xy 142.032772 -293.010459) (xy 141.98824 -292.987769)
			(xy 141.947807 -292.958393) (xy 141.912467 -292.923053) (xy 141.883091 -292.88262) (xy 141.860401 -292.838088)
			(xy 141.844957 -292.790556) (xy 141.837138 -292.741193) (xy 141.530075 -292.741193) (xy 141.530066 -292.74165)
			(xy 141.521902 -292.791884) (xy 141.505786 -292.840158) (xy 141.482135 -292.885221) (xy 141.451562 -292.925907)
			(xy 141.414858 -292.961162) (xy 141.372974 -292.990072) (xy 141.326995 -293.011889) (xy 141.278111 -293.026049)
			(xy 141.22759 -293.032183) (xy 141.176738 -293.030134) (xy 141.126874 -293.019954) (xy 141.079288 -293.001907)
			(xy 141.035214 -292.976461) (xy 140.995792 -292.944274) (xy 140.962044 -292.90618) (xy 140.934843 -292.863166)
			(xy 140.914895 -292.816346) (xy 140.902716 -292.766932) (xy 140.898621 -292.716204) (xy 140.59281 -292.716204)
			(xy 140.59232 -292.741193) (xy 140.584501 -292.790556) (xy 140.569057 -292.838088) (xy 140.546367 -292.88262)
			(xy 140.516991 -292.923053) (xy 140.481651 -292.958393) (xy 140.441218 -292.987769) (xy 140.396686 -293.010459)
			(xy 140.349154 -293.025903) (xy 140.299791 -293.033722) (xy 140.249813 -293.033722) (xy 140.20045 -293.025903)
			(xy 140.152918 -293.010459) (xy 140.108386 -292.987769) (xy 140.067953 -292.958393) (xy 140.032613 -292.923053)
			(xy 140.003237 -292.88262) (xy 139.980547 -292.838088) (xy 139.965103 -292.790556) (xy 139.957284 -292.741193)
			(xy 139.649967 -292.741193) (xy 139.649958 -292.74165) (xy 139.641794 -292.791884) (xy 139.625678 -292.840158)
			(xy 139.602027 -292.885221) (xy 139.571454 -292.925907) (xy 139.53475 -292.961162) (xy 139.492866 -292.990072)
			(xy 139.446887 -293.011889) (xy 139.398003 -293.026049) (xy 139.347482 -293.032183) (xy 139.29663 -293.030134)
			(xy 139.246766 -293.019954) (xy 139.19918 -293.001907) (xy 139.155106 -292.976461) (xy 139.115684 -292.944274)
			(xy 139.081936 -292.90618) (xy 139.054735 -292.863166) (xy 139.034787 -292.816346) (xy 139.022608 -292.766932)
			(xy 139.018513 -292.716204) (xy 138.710416 -292.716204) (xy 138.709904 -292.74165) (xy 138.70174 -292.791884)
			(xy 138.685624 -292.840158) (xy 138.661973 -292.885221) (xy 138.6314 -292.925907) (xy 138.594696 -292.961162)
			(xy 138.552812 -292.990072) (xy 138.506833 -293.011889) (xy 138.457949 -293.026049) (xy 138.407428 -293.032183)
			(xy 138.356576 -293.030134) (xy 138.306712 -293.019954) (xy 138.259126 -293.001907) (xy 138.215052 -292.976461)
			(xy 138.17563 -292.944274) (xy 138.141882 -292.90618) (xy 138.114681 -292.863166) (xy 138.094733 -292.816346)
			(xy 138.082554 -292.766932) (xy 138.078459 -292.716204) (xy 136.830562 -292.716204) (xy 136.83005 -292.74165)
			(xy 136.821886 -292.791884) (xy 136.80577 -292.840158) (xy 136.782119 -292.885221) (xy 136.751546 -292.925907)
			(xy 136.714842 -292.961162) (xy 136.672958 -292.990072) (xy 136.626979 -293.011889) (xy 136.578095 -293.026049)
			(xy 136.527574 -293.032183) (xy 136.476722 -293.030134) (xy 136.426858 -293.019954) (xy 136.379272 -293.001907)
			(xy 136.335198 -292.976461) (xy 136.295776 -292.944274) (xy 136.262028 -292.90618) (xy 136.234827 -292.863166)
			(xy 136.214879 -292.816346) (xy 136.2027 -292.766932) (xy 136.198605 -292.716204) (xy 135.892794 -292.716204)
			(xy 135.892304 -292.741193) (xy 135.884485 -292.790556) (xy 135.869041 -292.838088) (xy 135.846351 -292.88262)
			(xy 135.816975 -292.923053) (xy 135.781635 -292.958393) (xy 135.741202 -292.987769) (xy 135.69667 -293.010459)
			(xy 135.649138 -293.025903) (xy 135.599775 -293.033722) (xy 135.549797 -293.033722) (xy 135.500434 -293.025903)
			(xy 135.452902 -293.010459) (xy 135.40837 -292.987769) (xy 135.367937 -292.958393) (xy 135.332597 -292.923053)
			(xy 135.303221 -292.88262) (xy 135.280531 -292.838088) (xy 135.265087 -292.790556) (xy 135.257268 -292.741193)
			(xy 134.949951 -292.741193) (xy 134.949942 -292.74165) (xy 134.941778 -292.791884) (xy 134.925662 -292.840158)
			(xy 134.902011 -292.885221) (xy 134.871438 -292.925907) (xy 134.834734 -292.961162) (xy 134.79285 -292.990072)
			(xy 134.746871 -293.011889) (xy 134.697987 -293.026049) (xy 134.647466 -293.032183) (xy 134.596614 -293.030134)
			(xy 134.54675 -293.019954) (xy 134.499164 -293.001907) (xy 134.45509 -292.976461) (xy 134.415668 -292.944274)
			(xy 134.38192 -292.90618) (xy 134.354719 -292.863166) (xy 134.334771 -292.816346) (xy 134.322592 -292.766932)
			(xy 134.318497 -292.716204) (xy 134.012686 -292.716204) (xy 134.012196 -292.741193) (xy 134.004377 -292.790556)
			(xy 133.988933 -292.838088) (xy 133.966243 -292.88262) (xy 133.936867 -292.923053) (xy 133.901527 -292.958393)
			(xy 133.861094 -292.987769) (xy 133.816562 -293.010459) (xy 133.76903 -293.025903) (xy 133.719667 -293.033722)
			(xy 133.669689 -293.033722) (xy 133.620326 -293.025903) (xy 133.572794 -293.010459) (xy 133.528262 -292.987769)
			(xy 133.487829 -292.958393) (xy 133.452489 -292.923053) (xy 133.423113 -292.88262) (xy 133.400423 -292.838088)
			(xy 133.384979 -292.790556) (xy 133.37716 -292.741193) (xy 133.070097 -292.741193) (xy 133.070088 -292.74165)
			(xy 133.061924 -292.791884) (xy 133.045808 -292.840158) (xy 133.022157 -292.885221) (xy 132.991584 -292.925907)
			(xy 132.95488 -292.961162) (xy 132.912996 -292.990072) (xy 132.867017 -293.011889) (xy 132.818133 -293.026049)
			(xy 132.767612 -293.032183) (xy 132.71676 -293.030134) (xy 132.666896 -293.019954) (xy 132.61931 -293.001907)
			(xy 132.575236 -292.976461) (xy 132.535814 -292.944274) (xy 132.502066 -292.90618) (xy 132.474865 -292.863166)
			(xy 132.454917 -292.816346) (xy 132.442738 -292.766932) (xy 132.438643 -292.716204) (xy 132.130546 -292.716204)
			(xy 132.130034 -292.74165) (xy 132.12187 -292.791884) (xy 132.105754 -292.840158) (xy 132.082103 -292.885221)
			(xy 132.05153 -292.925907) (xy 132.014826 -292.961162) (xy 131.972942 -292.990072) (xy 131.926963 -293.011889)
			(xy 131.878079 -293.026049) (xy 131.827558 -293.032183) (xy 131.776706 -293.030134) (xy 131.726842 -293.019954)
			(xy 131.679256 -293.001907) (xy 131.635182 -292.976461) (xy 131.59576 -292.944274) (xy 131.562012 -292.90618)
			(xy 131.534811 -292.863166) (xy 131.514863 -292.816346) (xy 131.502684 -292.766932) (xy 131.498589 -292.716204)
			(xy 130.250438 -292.716204) (xy 130.249926 -292.74165) (xy 130.241762 -292.791884) (xy 130.225646 -292.840158)
			(xy 130.201995 -292.885221) (xy 130.171422 -292.925907) (xy 130.134718 -292.961162) (xy 130.092834 -292.990072)
			(xy 130.046855 -293.011889) (xy 129.997971 -293.026049) (xy 129.94745 -293.032183) (xy 129.896598 -293.030134)
			(xy 129.846734 -293.019954) (xy 129.799148 -293.001907) (xy 129.755074 -292.976461) (xy 129.715652 -292.944274)
			(xy 129.681904 -292.90618) (xy 129.654703 -292.863166) (xy 129.634755 -292.816346) (xy 129.622576 -292.766932)
			(xy 129.618481 -292.716204) (xy 129.31267 -292.716204) (xy 129.31218 -292.741193) (xy 129.304361 -292.790556)
			(xy 129.288917 -292.838088) (xy 129.266227 -292.88262) (xy 129.236851 -292.923053) (xy 129.201511 -292.958393)
			(xy 129.161078 -292.987769) (xy 129.116546 -293.010459) (xy 129.069014 -293.025903) (xy 129.019651 -293.033722)
			(xy 128.969673 -293.033722) (xy 128.92031 -293.025903) (xy 128.872778 -293.010459) (xy 128.828246 -292.987769)
			(xy 128.787813 -292.958393) (xy 128.752473 -292.923053) (xy 128.723097 -292.88262) (xy 128.700407 -292.838088)
			(xy 128.684963 -292.790556) (xy 128.677144 -292.741193) (xy 128.371534 -292.741193) (xy 128.36945 -292.76711)
			(xy 128.357276 -292.81671) (xy 128.337334 -292.863728) (xy 128.310136 -292.906956) (xy 128.276382 -292.945283)
			(xy 128.236937 -292.977726) (xy 128.215136 -292.991032) (xy 128.209294 -292.994334) (xy 128.198118 -293.00551)
			(xy 128.195413 -293.008362) (xy 128.190823 -293.014741) (xy 128.188974 -293.01821) (xy 128.186389 -293.023636)
			(xy 128.183559 -293.035316) (xy 128.183386 -293.041324) (xy 128.183386 -293.187374) (xy 128.184326 -293.196545)
			(xy 128.191865 -293.213351) (xy 128.20488 -293.226387) (xy 128.213104 -293.230554) (xy 128.213358 -293.230554)
			(xy 128.286256 -293.268146) (xy 128.291082 -293.270178) (xy 128.295235 -293.271736) (xy 128.303923 -293.27353)
			(xy 128.308354 -293.273734) (xy 128.312541 -293.273743) (xy 128.320834 -293.272587) (xy 128.324864 -293.271448)
			(xy 128.341374 -293.266114) (xy 128.34747 -293.26205) (xy 128.367182 -293.24934) (xy 128.409553 -293.229229)
			(xy 128.454418 -293.215556) (xy 128.500804 -293.20862) (xy 128.524254 -293.208202) (xy 128.524762 -293.208202)
			(xy 128.549755 -293.208664) (xy 128.599126 -293.216478) (xy 128.646667 -293.23192) (xy 128.691206 -293.25461)
			(xy 128.731647 -293.283988) (xy 128.766994 -293.319332) (xy 128.796376 -293.35977) (xy 128.819069 -293.404308)
			(xy 128.834516 -293.451847) (xy 128.842334 -293.501217) (xy 128.84277 -293.52621) (xy 128.842674 -293.538644)
			(xy 128.840769 -293.563438) (xy 128.83896 -293.57574) (xy 128.837182 -293.586916) (xy 128.84023 -293.597584)
			(xy 128.841861 -293.602779) (xy 128.84699 -293.612381) (xy 128.85039 -293.616634) (xy 128.899412 -293.673784)
			(xy 128.904951 -293.679791) (xy 128.918945 -293.688205) (xy 128.926844 -293.690294) (xy 128.93802 -293.691564)
			(xy 129.051304 -293.691564) (xy 129.060956 -293.690548) (xy 129.066789 -293.689256) (xy 129.077687 -293.684372)
			(xy 129.082546 -293.680896) (xy 129.087372 -293.677086) (xy 129.139188 -293.616634) (xy 129.142596 -293.612387)
			(xy 129.147711 -293.602778) (xy 129.149348 -293.597584) (xy 129.152396 -293.586916) (xy 129.150618 -293.57574)
			(xy 129.148819 -293.563437) (xy 129.146908 -293.538644) (xy 129.146808 -293.52621) (xy 129.147298 -293.501221)
			(xy 129.155117 -293.451858) (xy 129.170561 -293.404326) (xy 129.193251 -293.359794) (xy 129.222627 -293.319361)
			(xy 129.257967 -293.284021) (xy 129.2984 -293.254645) (xy 129.342932 -293.231955) (xy 129.390464 -293.216511)
			(xy 129.439827 -293.208692) (xy 129.489805 -293.208692) (xy 129.539168 -293.216511) (xy 129.5867 -293.231955)
			(xy 129.631232 -293.254645) (xy 129.671665 -293.284021) (xy 129.707005 -293.319361) (xy 129.736381 -293.359794)
			(xy 129.759071 -293.404326) (xy 129.774515 -293.451858) (xy 129.782334 -293.501221) (xy 129.782824 -293.52621)
			(xy 129.782725 -293.538644) (xy 129.78082 -293.563438) (xy 129.779014 -293.57574) (xy 129.777236 -293.586916)
			(xy 129.780284 -293.597584) (xy 129.781913 -293.60278) (xy 129.787038 -293.612385) (xy 129.790444 -293.616634)
			(xy 129.839466 -293.673784) (xy 129.845002 -293.679795) (xy 129.858993 -293.688222) (xy 129.866898 -293.690294)
			(xy 129.878074 -293.691564) (xy 129.991358 -293.691564) (xy 130.00101 -293.690548) (xy 130.006845 -293.689261)
			(xy 130.017749 -293.684384) (xy 130.0226 -293.680896) (xy 130.027426 -293.677086) (xy 130.079242 -293.616634)
			(xy 130.082652 -293.612389) (xy 130.087772 -293.60278) (xy 130.089402 -293.597584) (xy 130.09245 -293.586916)
			(xy 130.090672 -293.57574) (xy 130.088873 -293.563437) (xy 130.086963 -293.538644) (xy 130.086862 -293.52621)
			(xy 130.087352 -293.501219) (xy 130.095168 -293.451853) (xy 130.110611 -293.404318) (xy 130.1333 -293.359783)
			(xy 130.162676 -293.319346) (xy 130.198016 -293.284002) (xy 130.238449 -293.254621) (xy 130.282981 -293.231927)
			(xy 130.330514 -293.216478) (xy 130.37988 -293.208655) (xy 130.40487 -293.208202) (xy 130.405124 -293.208202)
			(xy 130.417816 -293.208343) (xy 130.443118 -293.21038) (xy 130.45567 -293.212266) (xy 130.479153 -293.216502)
			(xy 130.524588 -293.231081) (xy 130.567336 -293.252283) (xy 130.606437 -293.279631) (xy 130.641016 -293.312513)
			(xy 130.670296 -293.350189) (xy 130.693621 -293.391817) (xy 130.710467 -293.436461) (xy 130.720456 -293.48312)
			(xy 130.72237 -293.506906) (xy 130.722878 -293.516812) (xy 130.726688 -293.525194) (xy 130.728659 -293.529401)
			(xy 130.733895 -293.537074) (xy 130.737102 -293.540434) (xy 130.747867 -293.551199) (xy 131.027152 -293.551199)
			(xy 131.027152 -293.501221) (xy 131.034971 -293.451858) (xy 131.050415 -293.404326) (xy 131.073105 -293.359794)
			(xy 131.102481 -293.319361) (xy 131.137821 -293.284021) (xy 131.178254 -293.254645) (xy 131.222786 -293.231955)
			(xy 131.270318 -293.216511) (xy 131.319681 -293.208692) (xy 131.369659 -293.208692) (xy 131.419022 -293.216511)
			(xy 131.466554 -293.231955) (xy 131.511086 -293.254645) (xy 131.551519 -293.284021) (xy 131.586859 -293.319361)
			(xy 131.616235 -293.359794) (xy 131.638925 -293.404326) (xy 131.654369 -293.451858) (xy 131.662188 -293.501221)
			(xy 131.662678 -293.52621) (xy 131.662188 -293.551199) (xy 131.967206 -293.551199) (xy 131.967206 -293.501221)
			(xy 131.975025 -293.451858) (xy 131.990469 -293.404326) (xy 132.013159 -293.359794) (xy 132.042535 -293.319361)
			(xy 132.077875 -293.284021) (xy 132.118308 -293.254645) (xy 132.16284 -293.231955) (xy 132.210372 -293.216511)
			(xy 132.259735 -293.208692) (xy 132.309713 -293.208692) (xy 132.359076 -293.216511) (xy 132.406608 -293.231955)
			(xy 132.45114 -293.254645) (xy 132.491573 -293.284021) (xy 132.526913 -293.319361) (xy 132.556289 -293.359794)
			(xy 132.578979 -293.404326) (xy 132.594423 -293.451858) (xy 132.602242 -293.501221) (xy 132.602732 -293.52621)
			(xy 132.908543 -293.52621) (xy 132.912638 -293.475482) (xy 132.924817 -293.426068) (xy 132.944765 -293.379248)
			(xy 132.971966 -293.336234) (xy 133.005714 -293.29814) (xy 133.045136 -293.265953) (xy 133.08921 -293.240507)
			(xy 133.136796 -293.22246) (xy 133.18666 -293.21228) (xy 133.237512 -293.210231) (xy 133.288033 -293.216365)
			(xy 133.336917 -293.230525) (xy 133.382896 -293.252342) (xy 133.42478 -293.281252) (xy 133.461484 -293.316507)
			(xy 133.492057 -293.357193) (xy 133.515708 -293.402256) (xy 133.531824 -293.45053) (xy 133.539988 -293.500764)
			(xy 133.5405 -293.52621) (xy 133.539997 -293.551199) (xy 133.847314 -293.551199) (xy 133.847314 -293.501221)
			(xy 133.855133 -293.451858) (xy 133.870577 -293.404326) (xy 133.893267 -293.359794) (xy 133.922643 -293.319361)
			(xy 133.957983 -293.284021) (xy 133.998416 -293.254645) (xy 134.042948 -293.231955) (xy 134.09048 -293.216511)
			(xy 134.139843 -293.208692) (xy 134.189821 -293.208692) (xy 134.239184 -293.216511) (xy 134.286716 -293.231955)
			(xy 134.331248 -293.254645) (xy 134.371681 -293.284021) (xy 134.407021 -293.319361) (xy 134.436397 -293.359794)
			(xy 134.459087 -293.404326) (xy 134.474531 -293.451858) (xy 134.48235 -293.501221) (xy 134.48284 -293.52621)
			(xy 134.788397 -293.52621) (xy 134.792492 -293.475482) (xy 134.804671 -293.426068) (xy 134.824619 -293.379248)
			(xy 134.85182 -293.336234) (xy 134.885568 -293.29814) (xy 134.92499 -293.265953) (xy 134.969064 -293.240507)
			(xy 135.01665 -293.22246) (xy 135.066514 -293.21228) (xy 135.117366 -293.210231) (xy 135.167887 -293.216365)
			(xy 135.216771 -293.230525) (xy 135.26275 -293.252342) (xy 135.304634 -293.281252) (xy 135.341338 -293.316507)
			(xy 135.371911 -293.357193) (xy 135.395562 -293.402256) (xy 135.411678 -293.45053) (xy 135.419842 -293.500764)
			(xy 135.420354 -293.52621) (xy 135.419851 -293.551199) (xy 135.727168 -293.551199) (xy 135.727168 -293.501221)
			(xy 135.734987 -293.451858) (xy 135.750431 -293.404326) (xy 135.773121 -293.359794) (xy 135.802497 -293.319361)
			(xy 135.837837 -293.284021) (xy 135.87827 -293.254645) (xy 135.922802 -293.231955) (xy 135.970334 -293.216511)
			(xy 136.019697 -293.208692) (xy 136.069675 -293.208692) (xy 136.119038 -293.216511) (xy 136.16657 -293.231955)
			(xy 136.211102 -293.254645) (xy 136.251535 -293.284021) (xy 136.286875 -293.319361) (xy 136.316251 -293.359794)
			(xy 136.338941 -293.404326) (xy 136.354385 -293.451858) (xy 136.362204 -293.501221) (xy 136.362694 -293.52621)
			(xy 136.362204 -293.551199) (xy 136.667222 -293.551199) (xy 136.667222 -293.501221) (xy 136.675041 -293.451858)
			(xy 136.690485 -293.404326) (xy 136.713175 -293.359794) (xy 136.742551 -293.319361) (xy 136.777891 -293.284021)
			(xy 136.818324 -293.254645) (xy 136.862856 -293.231955) (xy 136.910388 -293.216511) (xy 136.959751 -293.208692)
			(xy 137.009729 -293.208692) (xy 137.059092 -293.216511) (xy 137.106624 -293.231955) (xy 137.151156 -293.254645)
			(xy 137.191589 -293.284021) (xy 137.226929 -293.319361) (xy 137.256305 -293.359794) (xy 137.278995 -293.404326)
			(xy 137.294439 -293.451858) (xy 137.302258 -293.501221) (xy 137.302748 -293.52621) (xy 137.302258 -293.551199)
			(xy 137.607276 -293.551199) (xy 137.607276 -293.501221) (xy 137.615095 -293.451858) (xy 137.630539 -293.404326)
			(xy 137.653229 -293.359794) (xy 137.682605 -293.319361) (xy 137.717945 -293.284021) (xy 137.758378 -293.254645)
			(xy 137.80291 -293.231955) (xy 137.850442 -293.216511) (xy 137.899805 -293.208692) (xy 137.949783 -293.208692)
			(xy 137.999146 -293.216511) (xy 138.046678 -293.231955) (xy 138.09121 -293.254645) (xy 138.131643 -293.284021)
			(xy 138.166983 -293.319361) (xy 138.196359 -293.359794) (xy 138.219049 -293.404326) (xy 138.234493 -293.451858)
			(xy 138.242312 -293.501221) (xy 138.242802 -293.52621) (xy 138.242312 -293.551199) (xy 138.54733 -293.551199)
			(xy 138.54733 -293.501221) (xy 138.555149 -293.451858) (xy 138.570593 -293.404326) (xy 138.593283 -293.359794)
			(xy 138.622659 -293.319361) (xy 138.657999 -293.284021) (xy 138.698432 -293.254645) (xy 138.742964 -293.231955)
			(xy 138.790496 -293.216511) (xy 138.839859 -293.208692) (xy 138.889837 -293.208692) (xy 138.9392 -293.216511)
			(xy 138.986732 -293.231955) (xy 139.031264 -293.254645) (xy 139.071697 -293.284021) (xy 139.107037 -293.319361)
			(xy 139.136413 -293.359794) (xy 139.159103 -293.404326) (xy 139.174547 -293.451858) (xy 139.182366 -293.501221)
			(xy 139.182856 -293.52621) (xy 139.488413 -293.52621) (xy 139.492508 -293.475482) (xy 139.504687 -293.426068)
			(xy 139.524635 -293.379248) (xy 139.551836 -293.336234) (xy 139.585584 -293.29814) (xy 139.625006 -293.265953)
			(xy 139.66908 -293.240507) (xy 139.716666 -293.22246) (xy 139.76653 -293.21228) (xy 139.817382 -293.210231)
			(xy 139.867903 -293.216365) (xy 139.916787 -293.230525) (xy 139.962766 -293.252342) (xy 140.00465 -293.281252)
			(xy 140.041354 -293.316507) (xy 140.071927 -293.357193) (xy 140.095578 -293.402256) (xy 140.111694 -293.45053)
			(xy 140.119858 -293.500764) (xy 140.12037 -293.52621) (xy 140.119867 -293.551199) (xy 140.427184 -293.551199)
			(xy 140.427184 -293.501221) (xy 140.435003 -293.451858) (xy 140.450447 -293.404326) (xy 140.473137 -293.359794)
			(xy 140.502513 -293.319361) (xy 140.537853 -293.284021) (xy 140.578286 -293.254645) (xy 140.622818 -293.231955)
			(xy 140.67035 -293.216511) (xy 140.719713 -293.208692) (xy 140.769691 -293.208692) (xy 140.819054 -293.216511)
			(xy 140.866586 -293.231955) (xy 140.911118 -293.254645) (xy 140.951551 -293.284021) (xy 140.986891 -293.319361)
			(xy 141.016267 -293.359794) (xy 141.038957 -293.404326) (xy 141.054401 -293.451858) (xy 141.06222 -293.501221)
			(xy 141.06271 -293.52621) (xy 141.368521 -293.52621) (xy 141.372616 -293.475482) (xy 141.384795 -293.426068)
			(xy 141.404743 -293.379248) (xy 141.431944 -293.336234) (xy 141.465692 -293.29814) (xy 141.505114 -293.265953)
			(xy 141.549188 -293.240507) (xy 141.596774 -293.22246) (xy 141.646638 -293.21228) (xy 141.69749 -293.210231)
			(xy 141.748011 -293.216365) (xy 141.796895 -293.230525) (xy 141.842874 -293.252342) (xy 141.884758 -293.281252)
			(xy 141.921462 -293.316507) (xy 141.952035 -293.357193) (xy 141.975686 -293.402256) (xy 141.991802 -293.45053)
			(xy 141.999966 -293.500764) (xy 142.000478 -293.52621) (xy 141.999975 -293.551199) (xy 142.307292 -293.551199)
			(xy 142.307292 -293.501221) (xy 142.315111 -293.451858) (xy 142.330555 -293.404326) (xy 142.353245 -293.359794)
			(xy 142.382621 -293.319361) (xy 142.417961 -293.284021) (xy 142.458394 -293.254645) (xy 142.502926 -293.231955)
			(xy 142.550458 -293.216511) (xy 142.599821 -293.208692) (xy 142.649799 -293.208692) (xy 142.699162 -293.216511)
			(xy 142.746694 -293.231955) (xy 142.791226 -293.254645) (xy 142.831659 -293.284021) (xy 142.866999 -293.319361)
			(xy 142.896375 -293.359794) (xy 142.919065 -293.404326) (xy 142.934509 -293.451858) (xy 142.942328 -293.501221)
			(xy 142.942818 -293.52621) (xy 142.942328 -293.551199) (xy 143.247092 -293.551199) (xy 143.247092 -293.501221)
			(xy 143.254911 -293.451858) (xy 143.270355 -293.404326) (xy 143.293045 -293.359794) (xy 143.322421 -293.319361)
			(xy 143.357761 -293.284021) (xy 143.398194 -293.254645) (xy 143.442726 -293.231955) (xy 143.490258 -293.216511)
			(xy 143.539621 -293.208692) (xy 143.589599 -293.208692) (xy 143.638962 -293.216511) (xy 143.686494 -293.231955)
			(xy 143.731026 -293.254645) (xy 143.771459 -293.284021) (xy 143.806799 -293.319361) (xy 143.836175 -293.359794)
			(xy 143.858865 -293.404326) (xy 143.874309 -293.451858) (xy 143.882128 -293.501221) (xy 143.882618 -293.52621)
			(xy 143.882128 -293.551199) (xy 144.187146 -293.551199) (xy 144.187146 -293.501221) (xy 144.194965 -293.451858)
			(xy 144.210409 -293.404326) (xy 144.233099 -293.359794) (xy 144.262475 -293.319361) (xy 144.297815 -293.284021)
			(xy 144.338248 -293.254645) (xy 144.38278 -293.231955) (xy 144.430312 -293.216511) (xy 144.479675 -293.208692)
			(xy 144.529653 -293.208692) (xy 144.579016 -293.216511) (xy 144.626548 -293.231955) (xy 144.67108 -293.254645)
			(xy 144.711513 -293.284021) (xy 144.746853 -293.319361) (xy 144.776229 -293.359794) (xy 144.798919 -293.404326)
			(xy 144.814363 -293.451858) (xy 144.822182 -293.501221) (xy 144.822672 -293.52621) (xy 144.822182 -293.551199)
			(xy 144.814363 -293.600562) (xy 144.798919 -293.648094) (xy 144.776229 -293.692626) (xy 144.746853 -293.733059)
			(xy 144.711513 -293.768399) (xy 144.67108 -293.797775) (xy 144.626548 -293.820465) (xy 144.579016 -293.835909)
			(xy 144.529653 -293.843728) (xy 144.479675 -293.843728) (xy 144.430312 -293.835909) (xy 144.38278 -293.820465)
			(xy 144.338248 -293.797775) (xy 144.297815 -293.768399) (xy 144.262475 -293.733059) (xy 144.233099 -293.692626)
			(xy 144.210409 -293.648094) (xy 144.194965 -293.600562) (xy 144.187146 -293.551199) (xy 143.882128 -293.551199)
			(xy 143.874309 -293.600562) (xy 143.858865 -293.648094) (xy 143.836175 -293.692626) (xy 143.806799 -293.733059)
			(xy 143.771459 -293.768399) (xy 143.731026 -293.797775) (xy 143.686494 -293.820465) (xy 143.638962 -293.835909)
			(xy 143.589599 -293.843728) (xy 143.539621 -293.843728) (xy 143.490258 -293.835909) (xy 143.442726 -293.820465)
			(xy 143.398194 -293.797775) (xy 143.357761 -293.768399) (xy 143.322421 -293.733059) (xy 143.293045 -293.692626)
			(xy 143.270355 -293.648094) (xy 143.254911 -293.600562) (xy 143.247092 -293.551199) (xy 142.942328 -293.551199)
			(xy 142.934509 -293.600562) (xy 142.919065 -293.648094) (xy 142.896375 -293.692626) (xy 142.866999 -293.733059)
			(xy 142.831659 -293.768399) (xy 142.791226 -293.797775) (xy 142.746694 -293.820465) (xy 142.699162 -293.835909)
			(xy 142.649799 -293.843728) (xy 142.599821 -293.843728) (xy 142.550458 -293.835909) (xy 142.502926 -293.820465)
			(xy 142.458394 -293.797775) (xy 142.417961 -293.768399) (xy 142.382621 -293.733059) (xy 142.353245 -293.692626)
			(xy 142.330555 -293.648094) (xy 142.315111 -293.600562) (xy 142.307292 -293.551199) (xy 141.999975 -293.551199)
			(xy 141.999966 -293.551656) (xy 141.991802 -293.60189) (xy 141.975686 -293.650164) (xy 141.952035 -293.695227)
			(xy 141.921462 -293.735913) (xy 141.884758 -293.771168) (xy 141.842874 -293.800078) (xy 141.796895 -293.821895)
			(xy 141.748011 -293.836055) (xy 141.69749 -293.842189) (xy 141.646638 -293.84014) (xy 141.596774 -293.82996)
			(xy 141.549188 -293.811913) (xy 141.505114 -293.786467) (xy 141.465692 -293.75428) (xy 141.431944 -293.716186)
			(xy 141.404743 -293.673172) (xy 141.384795 -293.626352) (xy 141.372616 -293.576938) (xy 141.368521 -293.52621)
			(xy 141.06271 -293.52621) (xy 141.06222 -293.551199) (xy 141.054401 -293.600562) (xy 141.038957 -293.648094)
			(xy 141.016267 -293.692626) (xy 140.986891 -293.733059) (xy 140.951551 -293.768399) (xy 140.911118 -293.797775)
			(xy 140.866586 -293.820465) (xy 140.819054 -293.835909) (xy 140.769691 -293.843728) (xy 140.719713 -293.843728)
			(xy 140.67035 -293.835909) (xy 140.622818 -293.820465) (xy 140.578286 -293.797775) (xy 140.537853 -293.768399)
			(xy 140.502513 -293.733059) (xy 140.473137 -293.692626) (xy 140.450447 -293.648094) (xy 140.435003 -293.600562)
			(xy 140.427184 -293.551199) (xy 140.119867 -293.551199) (xy 140.119858 -293.551656) (xy 140.111694 -293.60189)
			(xy 140.095578 -293.650164) (xy 140.071927 -293.695227) (xy 140.041354 -293.735913) (xy 140.00465 -293.771168)
			(xy 139.962766 -293.800078) (xy 139.916787 -293.821895) (xy 139.867903 -293.836055) (xy 139.817382 -293.842189)
			(xy 139.76653 -293.84014) (xy 139.716666 -293.82996) (xy 139.66908 -293.811913) (xy 139.625006 -293.786467)
			(xy 139.585584 -293.75428) (xy 139.551836 -293.716186) (xy 139.524635 -293.673172) (xy 139.504687 -293.626352)
			(xy 139.492508 -293.576938) (xy 139.488413 -293.52621) (xy 139.182856 -293.52621) (xy 139.182366 -293.551199)
			(xy 139.174547 -293.600562) (xy 139.159103 -293.648094) (xy 139.136413 -293.692626) (xy 139.107037 -293.733059)
			(xy 139.071697 -293.768399) (xy 139.031264 -293.797775) (xy 138.986732 -293.820465) (xy 138.9392 -293.835909)
			(xy 138.889837 -293.843728) (xy 138.839859 -293.843728) (xy 138.790496 -293.835909) (xy 138.742964 -293.820465)
			(xy 138.698432 -293.797775) (xy 138.657999 -293.768399) (xy 138.622659 -293.733059) (xy 138.593283 -293.692626)
			(xy 138.570593 -293.648094) (xy 138.555149 -293.600562) (xy 138.54733 -293.551199) (xy 138.242312 -293.551199)
			(xy 138.234493 -293.600562) (xy 138.219049 -293.648094) (xy 138.196359 -293.692626) (xy 138.166983 -293.733059)
			(xy 138.131643 -293.768399) (xy 138.09121 -293.797775) (xy 138.046678 -293.820465) (xy 137.999146 -293.835909)
			(xy 137.949783 -293.843728) (xy 137.899805 -293.843728) (xy 137.850442 -293.835909) (xy 137.80291 -293.820465)
			(xy 137.758378 -293.797775) (xy 137.717945 -293.768399) (xy 137.682605 -293.733059) (xy 137.653229 -293.692626)
			(xy 137.630539 -293.648094) (xy 137.615095 -293.600562) (xy 137.607276 -293.551199) (xy 137.302258 -293.551199)
			(xy 137.294439 -293.600562) (xy 137.278995 -293.648094) (xy 137.256305 -293.692626) (xy 137.226929 -293.733059)
			(xy 137.191589 -293.768399) (xy 137.151156 -293.797775) (xy 137.106624 -293.820465) (xy 137.059092 -293.835909)
			(xy 137.009729 -293.843728) (xy 136.959751 -293.843728) (xy 136.910388 -293.835909) (xy 136.862856 -293.820465)
			(xy 136.818324 -293.797775) (xy 136.777891 -293.768399) (xy 136.742551 -293.733059) (xy 136.713175 -293.692626)
			(xy 136.690485 -293.648094) (xy 136.675041 -293.600562) (xy 136.667222 -293.551199) (xy 136.362204 -293.551199)
			(xy 136.354385 -293.600562) (xy 136.338941 -293.648094) (xy 136.316251 -293.692626) (xy 136.286875 -293.733059)
			(xy 136.251535 -293.768399) (xy 136.211102 -293.797775) (xy 136.16657 -293.820465) (xy 136.119038 -293.835909)
			(xy 136.069675 -293.843728) (xy 136.019697 -293.843728) (xy 135.970334 -293.835909) (xy 135.922802 -293.820465)
			(xy 135.87827 -293.797775) (xy 135.837837 -293.768399) (xy 135.802497 -293.733059) (xy 135.773121 -293.692626)
			(xy 135.750431 -293.648094) (xy 135.734987 -293.600562) (xy 135.727168 -293.551199) (xy 135.419851 -293.551199)
			(xy 135.419842 -293.551656) (xy 135.411678 -293.60189) (xy 135.395562 -293.650164) (xy 135.371911 -293.695227)
			(xy 135.341338 -293.735913) (xy 135.304634 -293.771168) (xy 135.26275 -293.800078) (xy 135.216771 -293.821895)
			(xy 135.167887 -293.836055) (xy 135.117366 -293.842189) (xy 135.066514 -293.84014) (xy 135.01665 -293.82996)
			(xy 134.969064 -293.811913) (xy 134.92499 -293.786467) (xy 134.885568 -293.75428) (xy 134.85182 -293.716186)
			(xy 134.824619 -293.673172) (xy 134.804671 -293.626352) (xy 134.792492 -293.576938) (xy 134.788397 -293.52621)
			(xy 134.48284 -293.52621) (xy 134.48235 -293.551199) (xy 134.474531 -293.600562) (xy 134.459087 -293.648094)
			(xy 134.436397 -293.692626) (xy 134.407021 -293.733059) (xy 134.371681 -293.768399) (xy 134.331248 -293.797775)
			(xy 134.286716 -293.820465) (xy 134.239184 -293.835909) (xy 134.189821 -293.843728) (xy 134.139843 -293.843728)
			(xy 134.09048 -293.835909) (xy 134.042948 -293.820465) (xy 133.998416 -293.797775) (xy 133.957983 -293.768399)
			(xy 133.922643 -293.733059) (xy 133.893267 -293.692626) (xy 133.870577 -293.648094) (xy 133.855133 -293.600562)
			(xy 133.847314 -293.551199) (xy 133.539997 -293.551199) (xy 133.539988 -293.551656) (xy 133.531824 -293.60189)
			(xy 133.515708 -293.650164) (xy 133.492057 -293.695227) (xy 133.461484 -293.735913) (xy 133.42478 -293.771168)
			(xy 133.382896 -293.800078) (xy 133.336917 -293.821895) (xy 133.288033 -293.836055) (xy 133.237512 -293.842189)
			(xy 133.18666 -293.84014) (xy 133.136796 -293.82996) (xy 133.08921 -293.811913) (xy 133.045136 -293.786467)
			(xy 133.005714 -293.75428) (xy 132.971966 -293.716186) (xy 132.944765 -293.673172) (xy 132.924817 -293.626352)
			(xy 132.912638 -293.576938) (xy 132.908543 -293.52621) (xy 132.602732 -293.52621) (xy 132.602242 -293.551199)
			(xy 132.594423 -293.600562) (xy 132.578979 -293.648094) (xy 132.556289 -293.692626) (xy 132.526913 -293.733059)
			(xy 132.491573 -293.768399) (xy 132.45114 -293.797775) (xy 132.406608 -293.820465) (xy 132.359076 -293.835909)
			(xy 132.309713 -293.843728) (xy 132.259735 -293.843728) (xy 132.210372 -293.835909) (xy 132.16284 -293.820465)
			(xy 132.118308 -293.797775) (xy 132.077875 -293.768399) (xy 132.042535 -293.733059) (xy 132.013159 -293.692626)
			(xy 131.990469 -293.648094) (xy 131.975025 -293.600562) (xy 131.967206 -293.551199) (xy 131.662188 -293.551199)
			(xy 131.654369 -293.600562) (xy 131.638925 -293.648094) (xy 131.616235 -293.692626) (xy 131.586859 -293.733059)
			(xy 131.551519 -293.768399) (xy 131.511086 -293.797775) (xy 131.466554 -293.820465) (xy 131.419022 -293.835909)
			(xy 131.369659 -293.843728) (xy 131.319681 -293.843728) (xy 131.270318 -293.835909) (xy 131.222786 -293.820465)
			(xy 131.178254 -293.797775) (xy 131.137821 -293.768399) (xy 131.102481 -293.733059) (xy 131.073105 -293.692626)
			(xy 131.050415 -293.648094) (xy 131.034971 -293.600562) (xy 131.027152 -293.551199) (xy 130.747867 -293.551199)
			(xy 131.385056 -294.188388) (xy 131.396255 -294.198872) (xy 131.423374 -294.213181) (xy 131.453515 -294.218808)
			(xy 131.48397 -294.215247) (xy 131.512001 -294.202818) (xy 131.535087 -294.182638) (xy 131.543552 -294.169846)
			(xy 131.558179 -294.147043) (xy 131.593911 -294.106326) (xy 131.636018 -294.072244) (xy 131.683286 -294.04578)
			(xy 131.73435 -294.027697) (xy 131.787738 -294.018516) (xy 131.814824 -294.017954) (xy 131.839831 -294.018446)
			(xy 131.88923 -294.026274) (xy 131.936796 -294.041733) (xy 131.981358 -294.064442) (xy 132.021819 -294.093843)
			(xy 132.057183 -294.129211) (xy 132.086579 -294.169676) (xy 132.109282 -294.214241) (xy 132.124735 -294.261809)
			(xy 132.132557 -294.311208) (xy 132.133086 -294.336216) (xy 132.133086 -294.33647) (xy 132.131562 -294.367458)
			(xy 132.130977 -294.378268) (xy 132.137814 -294.398788) (xy 132.14477 -294.407082) (xy 132.19684 -294.462962)
			(xy 132.204523 -294.470557) (xy 132.224394 -294.478985) (xy 132.235194 -294.479218) (xy 132.287772 -294.478456)
			(xy 132.335016 -294.478964) (xy 132.345811 -294.478694) (xy 132.365683 -294.47029) (xy 132.37337 -294.462708)
			(xy 132.425186 -294.407082) (xy 132.432183 -294.398807) (xy 132.439043 -294.378274) (xy 132.438394 -294.367458)
			(xy 132.43687 -294.33647) (xy 132.43687 -294.336216) (xy 132.43736 -294.311227) (xy 132.445179 -294.261864)
			(xy 132.460623 -294.214332) (xy 132.483313 -294.1698) (xy 132.512689 -294.129367) (xy 132.548029 -294.094027)
			(xy 132.588462 -294.064651) (xy 132.632994 -294.041961) (xy 132.680526 -294.026517) (xy 132.729889 -294.018698)
			(xy 132.779867 -294.018698) (xy 132.82923 -294.026517) (xy 132.876762 -294.041961) (xy 132.921294 -294.064651)
			(xy 132.961727 -294.094027) (xy 132.997067 -294.129367) (xy 133.026443 -294.1698) (xy 133.049133 -294.214332)
			(xy 133.064577 -294.261864) (xy 133.072396 -294.311227) (xy 133.072886 -294.336216) (xy 133.072886 -294.336724)
			(xy 133.072278 -294.364305) (xy 133.062728 -294.418635) (xy 133.043951 -294.470504) (xy 133.030722 -294.494712)
			(xy 133.025134 -294.50411) (xy 133.023102 -294.525954) (xy 133.054344 -294.61841) (xy 133.069076 -294.634412)
			(xy 133.079236 -294.63873) (xy 133.111097 -294.652395) (xy 133.173977 -294.681609) (xy 133.204966 -294.69715)
			(xy 133.215903 -294.70194) (xy 133.239749 -294.70194) (xy 133.250686 -294.69715) (xy 133.280564 -294.682185)
			(xy 133.341156 -294.653986) (xy 133.371844 -294.640762) (xy 133.382004 -294.636444) (xy 133.396736 -294.620442)
			(xy 133.424168 -294.537638) (xy 133.427102 -294.527249) (xy 133.424862 -294.505798) (xy 133.41985 -294.496236)
			(xy 133.406284 -294.471772) (xy 133.387028 -294.419257) (xy 133.377256 -294.364183) (xy 133.37667 -294.336216)
			(xy 133.37716 -294.311227) (xy 133.384979 -294.261864) (xy 133.400423 -294.214332) (xy 133.423113 -294.1698)
			(xy 133.452489 -294.129367) (xy 133.487829 -294.094027) (xy 133.528262 -294.064651) (xy 133.572794 -294.041961)
			(xy 133.620326 -294.026517) (xy 133.669689 -294.018698) (xy 133.719667 -294.018698) (xy 133.76903 -294.026517)
			(xy 133.816562 -294.041961) (xy 133.861094 -294.064651) (xy 133.901527 -294.094027) (xy 133.936867 -294.129367)
			(xy 133.966243 -294.1698) (xy 133.988933 -294.214332) (xy 134.004377 -294.261864) (xy 134.012196 -294.311227)
			(xy 134.012686 -294.336216) (xy 134.012686 -294.33647) (xy 134.011162 -294.367458) (xy 134.010577 -294.378268)
			(xy 134.017414 -294.398788) (xy 134.02437 -294.407082) (xy 134.07644 -294.462962) (xy 134.084123 -294.470557)
			(xy 134.103994 -294.478985) (xy 134.114794 -294.479218) (xy 134.16788 -294.478456) (xy 134.21487 -294.478964)
			(xy 134.22566 -294.478684) (xy 134.245517 -294.470265) (xy 134.253224 -294.462708) (xy 134.30504 -294.407082)
			(xy 134.312031 -294.398805) (xy 134.318884 -294.378273) (xy 134.318248 -294.367458) (xy 134.316724 -294.33647)
			(xy 134.316724 -294.336216) (xy 134.317214 -294.311227) (xy 134.325033 -294.261864) (xy 134.340477 -294.214332)
			(xy 134.363167 -294.1698) (xy 134.392543 -294.129367) (xy 134.427883 -294.094027) (xy 134.468316 -294.064651)
			(xy 134.512848 -294.041961) (xy 134.56038 -294.026517) (xy 134.609743 -294.018698) (xy 134.659721 -294.018698)
			(xy 134.709084 -294.026517) (xy 134.756616 -294.041961) (xy 134.801148 -294.064651) (xy 134.841581 -294.094027)
			(xy 134.876921 -294.129367) (xy 134.906297 -294.1698) (xy 134.928987 -294.214332) (xy 134.944431 -294.261864)
			(xy 134.95225 -294.311227) (xy 134.95274 -294.336216) (xy 134.95274 -294.33647) (xy 134.951216 -294.367458)
			(xy 134.950631 -294.378267) (xy 134.957474 -294.398783) (xy 134.964424 -294.407082) (xy 135.016494 -294.462962)
			(xy 135.02418 -294.470548) (xy 135.04405 -294.478955) (xy 135.054848 -294.479218) (xy 135.107934 -294.478456)
			(xy 135.154924 -294.478964) (xy 135.165718 -294.478693) (xy 135.185588 -294.470286) (xy 135.193278 -294.462708)
			(xy 135.245094 -294.407082) (xy 135.25209 -294.398807) (xy 135.258949 -294.378274) (xy 135.258302 -294.367458)
			(xy 135.256778 -294.33647) (xy 135.256778 -294.336216) (xy 135.257268 -294.311227) (xy 135.265087 -294.261864)
			(xy 135.280531 -294.214332) (xy 135.303221 -294.1698) (xy 135.332597 -294.129367) (xy 135.367937 -294.094027)
			(xy 135.40837 -294.064651) (xy 135.452902 -294.041961) (xy 135.500434 -294.026517) (xy 135.549797 -294.018698)
			(xy 135.599775 -294.018698) (xy 135.649138 -294.026517) (xy 135.69667 -294.041961) (xy 135.741202 -294.064651)
			(xy 135.781635 -294.094027) (xy 135.816975 -294.129367) (xy 135.846351 -294.1698) (xy 135.869041 -294.214332)
			(xy 135.884485 -294.261864) (xy 135.892304 -294.311227) (xy 135.892794 -294.336216) (xy 135.892794 -294.336724)
			(xy 135.892254 -294.361205) (xy 136.197322 -294.361205) (xy 136.197322 -294.311227) (xy 136.205141 -294.261864)
			(xy 136.220585 -294.214332) (xy 136.243275 -294.1698) (xy 136.272651 -294.129367) (xy 136.307991 -294.094027)
			(xy 136.348424 -294.064651) (xy 136.392956 -294.041961) (xy 136.440488 -294.026517) (xy 136.489851 -294.018698)
			(xy 136.539829 -294.018698) (xy 136.589192 -294.026517) (xy 136.636724 -294.041961) (xy 136.681256 -294.064651)
			(xy 136.721689 -294.094027) (xy 136.757029 -294.129367) (xy 136.786405 -294.1698) (xy 136.809095 -294.214332)
			(xy 136.824539 -294.261864) (xy 136.832358 -294.311227) (xy 136.832848 -294.336216) (xy 136.832358 -294.361205)
			(xy 137.137122 -294.361205) (xy 137.137122 -294.311227) (xy 137.144941 -294.261864) (xy 137.160385 -294.214332)
			(xy 137.183075 -294.1698) (xy 137.212451 -294.129367) (xy 137.247791 -294.094027) (xy 137.288224 -294.064651)
			(xy 137.332756 -294.041961) (xy 137.380288 -294.026517) (xy 137.429651 -294.018698) (xy 137.479629 -294.018698)
			(xy 137.528992 -294.026517) (xy 137.576524 -294.041961) (xy 137.621056 -294.064651) (xy 137.661489 -294.094027)
			(xy 137.696829 -294.129367) (xy 137.726205 -294.1698) (xy 137.748895 -294.214332) (xy 137.764339 -294.261864)
			(xy 137.772158 -294.311227) (xy 137.772648 -294.336216) (xy 137.772158 -294.361205) (xy 138.077176 -294.361205)
			(xy 138.077176 -294.311227) (xy 138.084995 -294.261864) (xy 138.100439 -294.214332) (xy 138.123129 -294.1698)
			(xy 138.152505 -294.129367) (xy 138.187845 -294.094027) (xy 138.228278 -294.064651) (xy 138.27281 -294.041961)
			(xy 138.320342 -294.026517) (xy 138.369705 -294.018698) (xy 138.419683 -294.018698) (xy 138.469046 -294.026517)
			(xy 138.516578 -294.041961) (xy 138.56111 -294.064651) (xy 138.601543 -294.094027) (xy 138.636883 -294.129367)
			(xy 138.666259 -294.1698) (xy 138.688949 -294.214332) (xy 138.704393 -294.261864) (xy 138.712212 -294.311227)
			(xy 138.712702 -294.336216) (xy 138.712212 -294.361205) (xy 139.01723 -294.361205) (xy 139.01723 -294.311227)
			(xy 139.025049 -294.261864) (xy 139.040493 -294.214332) (xy 139.063183 -294.1698) (xy 139.092559 -294.129367)
			(xy 139.127899 -294.094027) (xy 139.168332 -294.064651) (xy 139.212864 -294.041961) (xy 139.260396 -294.026517)
			(xy 139.309759 -294.018698) (xy 139.359737 -294.018698) (xy 139.4091 -294.026517) (xy 139.456632 -294.041961)
			(xy 139.501164 -294.064651) (xy 139.541597 -294.094027) (xy 139.576937 -294.129367) (xy 139.606313 -294.1698)
			(xy 139.629003 -294.214332) (xy 139.644447 -294.261864) (xy 139.652266 -294.311227) (xy 139.652756 -294.336216)
			(xy 139.652266 -294.361205) (xy 139.957284 -294.361205) (xy 139.957284 -294.311227) (xy 139.965103 -294.261864)
			(xy 139.980547 -294.214332) (xy 140.003237 -294.1698) (xy 140.032613 -294.129367) (xy 140.067953 -294.094027)
			(xy 140.108386 -294.064651) (xy 140.152918 -294.041961) (xy 140.20045 -294.026517) (xy 140.249813 -294.018698)
			(xy 140.299791 -294.018698) (xy 140.349154 -294.026517) (xy 140.396686 -294.041961) (xy 140.441218 -294.064651)
			(xy 140.481651 -294.094027) (xy 140.516991 -294.129367) (xy 140.546367 -294.1698) (xy 140.569057 -294.214332)
			(xy 140.584501 -294.261864) (xy 140.59232 -294.311227) (xy 140.59281 -294.336216) (xy 140.59232 -294.361205)
			(xy 140.897338 -294.361205) (xy 140.897338 -294.311227) (xy 140.905157 -294.261864) (xy 140.920601 -294.214332)
			(xy 140.943291 -294.1698) (xy 140.972667 -294.129367) (xy 141.008007 -294.094027) (xy 141.04844 -294.064651)
			(xy 141.092972 -294.041961) (xy 141.140504 -294.026517) (xy 141.189867 -294.018698) (xy 141.239845 -294.018698)
			(xy 141.289208 -294.026517) (xy 141.33674 -294.041961) (xy 141.381272 -294.064651) (xy 141.421705 -294.094027)
			(xy 141.457045 -294.129367) (xy 141.486421 -294.1698) (xy 141.509111 -294.214332) (xy 141.524555 -294.261864)
			(xy 141.532374 -294.311227) (xy 141.532864 -294.336216) (xy 141.532374 -294.361205) (xy 141.837138 -294.361205)
			(xy 141.837138 -294.311227) (xy 141.844957 -294.261864) (xy 141.860401 -294.214332) (xy 141.883091 -294.1698)
			(xy 141.912467 -294.129367) (xy 141.947807 -294.094027) (xy 141.98824 -294.064651) (xy 142.032772 -294.041961)
			(xy 142.080304 -294.026517) (xy 142.129667 -294.018698) (xy 142.179645 -294.018698) (xy 142.229008 -294.026517)
			(xy 142.27654 -294.041961) (xy 142.321072 -294.064651) (xy 142.361505 -294.094027) (xy 142.396845 -294.129367)
			(xy 142.426221 -294.1698) (xy 142.448911 -294.214332) (xy 142.464355 -294.261864) (xy 142.472174 -294.311227)
			(xy 142.472664 -294.336216) (xy 142.472174 -294.361205) (xy 142.464355 -294.410568) (xy 142.448911 -294.4581)
			(xy 142.426221 -294.502632) (xy 142.396845 -294.543065) (xy 142.361505 -294.578405) (xy 142.321072 -294.607781)
			(xy 142.27654 -294.630471) (xy 142.229008 -294.645915) (xy 142.179645 -294.653734) (xy 142.129667 -294.653734)
			(xy 142.080304 -294.645915) (xy 142.032772 -294.630471) (xy 141.98824 -294.607781) (xy 141.947807 -294.578405)
			(xy 141.912467 -294.543065) (xy 141.883091 -294.502632) (xy 141.860401 -294.4581) (xy 141.844957 -294.410568)
			(xy 141.837138 -294.361205) (xy 141.532374 -294.361205) (xy 141.524555 -294.410568) (xy 141.509111 -294.4581)
			(xy 141.486421 -294.502632) (xy 141.457045 -294.543065) (xy 141.421705 -294.578405) (xy 141.381272 -294.607781)
			(xy 141.33674 -294.630471) (xy 141.289208 -294.645915) (xy 141.239845 -294.653734) (xy 141.189867 -294.653734)
			(xy 141.140504 -294.645915) (xy 141.092972 -294.630471) (xy 141.04844 -294.607781) (xy 141.008007 -294.578405)
			(xy 140.972667 -294.543065) (xy 140.943291 -294.502632) (xy 140.920601 -294.4581) (xy 140.905157 -294.410568)
			(xy 140.897338 -294.361205) (xy 140.59232 -294.361205) (xy 140.584501 -294.410568) (xy 140.569057 -294.4581)
			(xy 140.546367 -294.502632) (xy 140.516991 -294.543065) (xy 140.481651 -294.578405) (xy 140.441218 -294.607781)
			(xy 140.396686 -294.630471) (xy 140.349154 -294.645915) (xy 140.299791 -294.653734) (xy 140.249813 -294.653734)
			(xy 140.20045 -294.645915) (xy 140.152918 -294.630471) (xy 140.108386 -294.607781) (xy 140.067953 -294.578405)
			(xy 140.032613 -294.543065) (xy 140.003237 -294.502632) (xy 139.980547 -294.4581) (xy 139.965103 -294.410568)
			(xy 139.957284 -294.361205) (xy 139.652266 -294.361205) (xy 139.644447 -294.410568) (xy 139.629003 -294.4581)
			(xy 139.606313 -294.502632) (xy 139.576937 -294.543065) (xy 139.541597 -294.578405) (xy 139.501164 -294.607781)
			(xy 139.456632 -294.630471) (xy 139.4091 -294.645915) (xy 139.359737 -294.653734) (xy 139.309759 -294.653734)
			(xy 139.260396 -294.645915) (xy 139.212864 -294.630471) (xy 139.168332 -294.607781) (xy 139.127899 -294.578405)
			(xy 139.092559 -294.543065) (xy 139.063183 -294.502632) (xy 139.040493 -294.4581) (xy 139.025049 -294.410568)
			(xy 139.01723 -294.361205) (xy 138.712212 -294.361205) (xy 138.704393 -294.410568) (xy 138.688949 -294.4581)
			(xy 138.666259 -294.502632) (xy 138.636883 -294.543065) (xy 138.601543 -294.578405) (xy 138.56111 -294.607781)
			(xy 138.516578 -294.630471) (xy 138.469046 -294.645915) (xy 138.419683 -294.653734) (xy 138.369705 -294.653734)
			(xy 138.320342 -294.645915) (xy 138.27281 -294.630471) (xy 138.228278 -294.607781) (xy 138.187845 -294.578405)
			(xy 138.152505 -294.543065) (xy 138.123129 -294.502632) (xy 138.100439 -294.4581) (xy 138.084995 -294.410568)
			(xy 138.077176 -294.361205) (xy 137.772158 -294.361205) (xy 137.764339 -294.410568) (xy 137.748895 -294.4581)
			(xy 137.726205 -294.502632) (xy 137.696829 -294.543065) (xy 137.661489 -294.578405) (xy 137.621056 -294.607781)
			(xy 137.576524 -294.630471) (xy 137.528992 -294.645915) (xy 137.479629 -294.653734) (xy 137.429651 -294.653734)
			(xy 137.380288 -294.645915) (xy 137.332756 -294.630471) (xy 137.288224 -294.607781) (xy 137.247791 -294.578405)
			(xy 137.212451 -294.543065) (xy 137.183075 -294.502632) (xy 137.160385 -294.4581) (xy 137.144941 -294.410568)
			(xy 137.137122 -294.361205) (xy 136.832358 -294.361205) (xy 136.824539 -294.410568) (xy 136.809095 -294.4581)
			(xy 136.786405 -294.502632) (xy 136.757029 -294.543065) (xy 136.721689 -294.578405) (xy 136.681256 -294.607781)
			(xy 136.636724 -294.630471) (xy 136.589192 -294.645915) (xy 136.539829 -294.653734) (xy 136.489851 -294.653734)
			(xy 136.440488 -294.645915) (xy 136.392956 -294.630471) (xy 136.348424 -294.607781) (xy 136.307991 -294.578405)
			(xy 136.272651 -294.543065) (xy 136.243275 -294.502632) (xy 136.220585 -294.4581) (xy 136.205141 -294.410568)
			(xy 136.197322 -294.361205) (xy 135.892254 -294.361205) (xy 135.892186 -294.364305) (xy 135.882633 -294.418633)
			(xy 135.863852 -294.4705) (xy 135.85063 -294.494712) (xy 135.845042 -294.50411) (xy 135.84301 -294.525954)
			(xy 135.874252 -294.61841) (xy 135.888984 -294.634412) (xy 135.899144 -294.63873) (xy 135.95993 -294.665012)
			(xy 136.078301 -294.724424) (xy 136.192553 -294.791416) (xy 136.302201 -294.865704) (xy 136.406781 -294.946973)
			(xy 136.456674 -294.99052) (xy 136.463786 -294.99687) (xy 136.480804 -295.00322)
		)
		(stroke
			(width 0)
			(type solid)
		)
		(fill yes)
		(layer "B.Cu")
		(net "PVDD11_S3_P1")
	)
	(gr_poly
		(pts
			(xy 349.57131 -295.657524) (xy 349.597821 -295.648406) (xy 349.653009 -295.638563) (xy 349.681038 -295.637966)
			(xy 349.709068 -295.638558) (xy 349.764258 -295.648395) (xy 349.790766 -295.657524) (xy 349.799148 -295.660572)
			(xy 355.202998 -295.660572) (xy 355.21138 -295.657524) (xy 355.237892 -295.648412) (xy 355.29308 -295.638581)
			(xy 355.321108 -295.637966) (xy 355.349138 -295.638555) (xy 355.40433 -295.648387) (xy 355.430836 -295.657524)
			(xy 355.439218 -295.660572) (xy 356.022656 -295.660572) (xy 356.030022 -295.658286) (xy 356.038658 -295.655746)
			(xy 356.046532 -295.652698) (xy 356.055676 -295.648126) (xy 356.058216 -295.646348) (xy 356.080923 -295.63206)
			(xy 356.129585 -295.609473) (xy 356.180997 -295.594148) (xy 356.234084 -295.586405) (xy 356.260908 -295.585896)
			(xy 356.261416 -295.585896) (xy 356.288626 -295.586398) (xy 356.342456 -295.594401) (xy 356.394537 -295.610187)
			(xy 356.44375 -295.633419) (xy 356.466648 -295.648126) (xy 356.472744 -295.65219) (xy 356.492556 -295.658286)
			(xy 356.499922 -295.660572) (xy 356.754684 -295.660572) (xy 356.764433 -295.660054) (xy 356.78246 -295.652604)
			(xy 356.789736 -295.646094) (xy 357.288084 -295.147746) (xy 357.291175 -295.144546) (xy 357.296281 -295.137261)
			(xy 357.298244 -295.133268) (xy 357.3018 -295.125394) (xy 357.302562 -295.11625) (xy 357.305106 -295.090295)
			(xy 357.316565 -295.03942) (xy 357.335059 -294.990659) (xy 357.360221 -294.944981) (xy 357.391552 -294.903291)
			(xy 357.42843 -294.866418) (xy 357.470124 -294.835093) (xy 357.515806 -294.809937) (xy 357.564569 -294.79145)
			(xy 357.615447 -294.779998) (xy 357.641398 -294.777414) (xy 357.650542 -294.776652) (xy 357.658416 -294.773096)
			(xy 357.662399 -294.771117) (xy 357.669682 -294.766012) (xy 357.672894 -294.762936) (xy 357.79583 -294.64)
			(xy 357.802543 -294.632762) (xy 357.810138 -294.614557) (xy 357.810562 -294.604694) (xy 357.810562 -294.335454)
			(xy 357.811112 -294.308683) (xy 357.819796 -294.255848) (xy 357.836864 -294.205098) (xy 357.861873 -294.157753)
			(xy 357.894172 -294.115048) (xy 357.913178 -294.096186) (xy 357.920798 -294.08882) (xy 357.924608 -294.080438)
			(xy 357.926652 -294.075669) (xy 357.928968 -294.065556) (xy 357.92918 -294.060372) (xy 357.930196 -293.997126)
			(xy 357.930196 -293.989506) (xy 357.930115 -293.982664) (xy 357.926777 -293.969399) (xy 357.923592 -293.963344)
			(xy 357.919528 -293.95674) (xy 357.811324 -293.848536) (xy 357.807597 -293.845009) (xy 357.799027 -293.839369)
			(xy 357.794306 -293.83736) (xy 357.78567 -293.833804) (xy 357.756968 -293.833804) (xy 357.7463 -293.835074)
			(xy 357.744014 -293.835328) (xy 357.742744 -293.835836) (xy 357.725145 -293.839632) (xy 357.689372 -293.843704)
			(xy 357.67137 -293.843964) (xy 357.671116 -293.843964) (xy 357.646127 -293.8435) (xy 357.596765 -293.835685)
			(xy 357.549234 -293.820243) (xy 357.504703 -293.797555) (xy 357.46427 -293.768181) (xy 357.42893 -293.732842)
			(xy 357.399553 -293.692411) (xy 357.376863 -293.647881) (xy 357.361419 -293.60035) (xy 357.353601 -293.550989)
			(xy 357.353601 -293.501011) (xy 357.361419 -293.45165) (xy 357.376863 -293.404119) (xy 357.399553 -293.359589)
			(xy 357.42893 -293.319158) (xy 357.46427 -293.283819) (xy 357.504703 -293.254445) (xy 357.549234 -293.231757)
			(xy 357.596765 -293.216315) (xy 357.646127 -293.2085) (xy 357.671116 -293.207948) (xy 357.689832 -293.208189)
			(xy 357.727013 -293.212518) (xy 357.745284 -293.216584) (xy 357.751126 -293.218108) (xy 357.9241 -293.218108)
			(xy 357.948292 -293.218558) (xy 357.996081 -293.226128) (xy 358.042097 -293.241082) (xy 358.085206 -293.263052)
			(xy 358.124347 -293.291496) (xy 358.141778 -293.308278) (xy 358.194102 -293.360856) (xy 358.194356 -293.36111)
			(xy 358.201764 -293.3678) (xy 358.2202 -293.375397) (xy 358.23017 -293.375842) (xy 358.234996 -293.375842)
			(xy 358.311196 -293.36873) (xy 358.316671 -293.368084) (xy 358.327177 -293.364752) (xy 358.332024 -293.362126)
			(xy 358.34193 -293.356284) (xy 358.348026 -293.347394) (xy 358.360701 -293.329344) (xy 358.390241 -293.296591)
			(xy 358.42403 -293.268243) (xy 358.442514 -293.256208) (xy 358.444546 -293.254938) (xy 358.452857 -293.248529)
			(xy 358.463877 -293.230695) (xy 358.465882 -293.220394) (xy 358.474772 -293.141654) (xy 358.475211 -293.134442)
			(xy 358.47251 -293.120253) (xy 358.469438 -293.113714) (xy 358.467152 -293.109396) (xy 358.461056 -293.101268)
			(xy 358.398572 -293.03853) (xy 358.398318 -293.038276) (xy 358.393238 -293.033704) (xy 358.386438 -293.029016)
			(xy 358.370759 -293.023852) (xy 358.362504 -293.023544) (xy 358.222042 -293.023544) (xy 358.215946 -293.025068)
			(xy 358.197309 -293.029278) (xy 358.15936 -293.033732) (xy 358.140254 -293.033958) (xy 358.132126 -293.033958)
			(xy 358.107606 -293.03279) (xy 358.059339 -293.023846) (xy 358.013018 -293.007601) (xy 357.969738 -292.984438)
			(xy 357.930526 -292.954908) (xy 357.896312 -292.919709) (xy 357.867904 -292.879676) (xy 357.845978 -292.835757)
			(xy 357.831052 -292.788994) (xy 357.82348 -292.740494) (xy 357.823008 -292.71595) (xy 357.823469 -292.690957)
			(xy 357.831282 -292.641584) (xy 357.846723 -292.594043) (xy 357.869412 -292.549502) (xy 357.89879 -292.50906)
			(xy 357.934134 -292.473712) (xy 357.974573 -292.44433) (xy 358.019111 -292.421636) (xy 358.066651 -292.40619)
			(xy 358.116023 -292.398371) (xy 358.141016 -292.397942) (xy 358.141524 -292.397942) (xy 358.160374 -292.398222)
			(xy 358.19781 -292.40268) (xy 358.2162 -292.406832) (xy 358.222296 -292.408356) (xy 358.511602 -292.408356)
			(xy 358.535731 -292.408848) (xy 358.583393 -292.416421) (xy 358.629291 -292.431333) (xy 358.672302 -292.45322)
			(xy 358.711373 -292.481547) (xy 358.728772 -292.498272) (xy 359.297986 -293.067486) (xy 359.30541 -293.073954)
			(xy 359.323695 -293.081211) (xy 359.343367 -293.081082) (xy 359.361555 -293.073586) (xy 359.368852 -293.066978)
			(xy 359.531666 -292.904164) (xy 359.538903 -292.897446) (xy 359.557107 -292.889839) (xy 359.566972 -292.889432)
			(xy 361.482894 -292.889432) (xy 361.492546 -292.888416) (xy 361.499792 -292.886791) (xy 361.512966 -292.879955)
			(xy 361.518454 -292.874954) (xy 361.520994 -292.872414) (xy 361.565952 -292.818566) (xy 361.566714 -292.817804)
			(xy 361.570524 -292.813232) (xy 361.573935 -292.808987) (xy 361.579056 -292.799379) (xy 361.580684 -292.794182)
			(xy 361.583732 -292.78326) (xy 361.5817 -292.77183) (xy 361.579419 -292.757973) (xy 361.577003 -292.729993)
			(xy 361.576874 -292.71595) (xy 361.577335 -292.690956) (xy 361.585147 -292.641582) (xy 361.600588 -292.594038)
			(xy 361.623277 -292.549495) (xy 361.652654 -292.50905) (xy 361.687998 -292.473699) (xy 361.728437 -292.444312)
			(xy 361.772975 -292.421614) (xy 361.820515 -292.406163) (xy 361.869888 -292.39834) (xy 361.894882 -292.397942)
			(xy 361.89539 -292.397942) (xy 361.914241 -292.39822) (xy 361.951678 -292.402674) (xy 361.970066 -292.406832)
			(xy 361.976162 -292.408356) (xy 362.139484 -292.408356) (xy 362.163611 -292.408854) (xy 362.211266 -292.416438)
			(xy 362.257156 -292.43136) (xy 362.300157 -292.453254) (xy 362.339219 -292.481587) (xy 362.356654 -292.498272)
			(xy 362.903516 -293.045388) (xy 362.909583 -293.050772) (xy 362.92422 -293.057745) (xy 362.932218 -293.059104)
			(xy 362.938822 -293.059612) (xy 364.374684 -293.059612) (xy 364.383776 -293.059188) (xy 364.400784 -293.05274)
			(xy 364.414469 -293.040759) (xy 364.419134 -293.032942) (xy 364.450376 -292.97249) (xy 364.453047 -292.967018)
			(xy 364.455996 -292.955207) (xy 364.456218 -292.949122) (xy 364.456218 -292.916102) (xy 364.454186 -292.902132)
			(xy 364.452408 -292.895782) (xy 364.44809 -292.889178) (xy 364.435946 -292.869748) (xy 364.416762 -292.828138)
			(xy 364.40375 -292.784205) (xy 364.397179 -292.73886) (xy 364.396782 -292.71595) (xy 364.397243 -292.690956)
			(xy 364.405055 -292.641582) (xy 364.420496 -292.594039) (xy 364.443185 -292.549496) (xy 364.472563 -292.509052)
			(xy 364.507906 -292.473702) (xy 364.548345 -292.444316) (xy 364.592883 -292.421619) (xy 364.640424 -292.406169)
			(xy 364.689796 -292.398347) (xy 364.71479 -292.397942) (xy 364.74012 -292.398433) (xy 364.790139 -292.406465)
			(xy 364.838252 -292.422326) (xy 364.883242 -292.445615) (xy 364.923969 -292.475744) (xy 364.959403 -292.51195)
			(xy 364.988648 -292.553316) (xy 365.010964 -292.598796) (xy 365.025786 -292.647239) (xy 365.02975 -292.672262)
			(xy 365.030258 -292.67658) (xy 365.030512 -292.676834) (xy 365.032544 -292.692328) (xy 365.033052 -292.699186)
			(xy 365.033052 -292.71595) (xy 365.032589 -292.740712) (xy 365.024922 -292.789638) (xy 365.00975 -292.836781)
			(xy 364.987441 -292.880995) (xy 364.973362 -292.90137) (xy 364.969437 -292.907165) (xy 364.964657 -292.920314)
			(xy 364.963964 -292.927278) (xy 364.962948 -292.941248) (xy 365.010954 -293.034466) (xy 365.015717 -293.041897)
			(xy 365.029249 -293.053206) (xy 365.045824 -293.059231) (xy 365.054642 -293.059612) (xy 365.297212 -293.059612)
			(xy 365.307079 -293.059196) (xy 365.32531 -293.051638) (xy 365.339259 -293.037678) (xy 365.346804 -293.019442)
			(xy 365.34725 -293.009574) (xy 365.34725 -292.796976) (xy 365.345726 -292.79088) (xy 365.341615 -292.772741)
			(xy 365.337157 -292.735816) (xy 365.336836 -292.71722) (xy 365.336836 -292.715188) (xy 365.336836 -292.70706)
			(xy 365.338002 -292.682538) (xy 365.346941 -292.634267) (xy 365.363184 -292.587941) (xy 365.386344 -292.544656)
			(xy 365.415874 -292.505439) (xy 365.451073 -292.47122) (xy 365.491108 -292.442808) (xy 365.535029 -292.420878)
			(xy 365.581795 -292.405949) (xy 365.630299 -292.398375) (xy 365.654844 -292.397942) (xy 365.679831 -292.39841)
			(xy 365.72919 -292.406235) (xy 365.776717 -292.421685) (xy 365.821242 -292.44438) (xy 365.861669 -292.47376)
			(xy 365.897001 -292.509103) (xy 365.92637 -292.549538) (xy 365.949051 -292.59407) (xy 365.964487 -292.641601)
			(xy 365.972297 -292.690962) (xy 365.972852 -292.71595) (xy 365.972852 -292.716458) (xy 365.97257 -292.735308)
			(xy 365.968108 -292.772743) (xy 365.963962 -292.791134) (xy 365.962438 -292.79723) (xy 365.962438 -293.009574)
			(xy 365.962847 -293.01945) (xy 365.970396 -293.037702) (xy 365.984356 -293.051676) (xy 366.0026 -293.059244)
			(xy 366.012476 -293.059612) (xy 367.176812 -293.059612) (xy 367.186679 -293.059196) (xy 367.20491 -293.051638)
			(xy 367.218859 -293.037678) (xy 367.226404 -293.019442) (xy 367.22685 -293.009574) (xy 367.22685 -292.801802)
			(xy 367.22558 -292.791134) (xy 367.225072 -292.788848) (xy 367.224818 -292.787578) (xy 367.221021 -292.769979)
			(xy 367.216946 -292.734206) (xy 367.21669 -292.716204) (xy 367.21669 -292.71595) (xy 367.21718 -292.690961)
			(xy 367.224999 -292.641598) (xy 367.240443 -292.594066) (xy 367.263133 -292.549534) (xy 367.292509 -292.509101)
			(xy 367.327849 -292.473761) (xy 367.368282 -292.444385) (xy 367.412814 -292.421695) (xy 367.460346 -292.406251)
			(xy 367.509709 -292.398432) (xy 367.559687 -292.398432) (xy 367.60905 -292.406251) (xy 367.656582 -292.421695)
			(xy 367.701114 -292.444385) (xy 367.741547 -292.473761) (xy 367.776887 -292.509101) (xy 367.806263 -292.549534)
			(xy 367.828953 -292.594066) (xy 367.844397 -292.641598) (xy 367.852216 -292.690961) (xy 367.852706 -292.71595)
			(xy 367.85251 -292.734858) (xy 367.84818 -292.772423) (xy 367.84407 -292.79088) (xy 367.842546 -292.796722)
			(xy 367.842546 -293.009574) (xy 367.842955 -293.01945) (xy 367.850504 -293.0377) (xy 367.864464 -293.051672)
			(xy 367.882709 -293.059237) (xy 367.892584 -293.059612) (xy 368.134646 -293.059612) (xy 368.143742 -293.059194)
			(xy 368.16076 -293.052755) (xy 368.174455 -293.040775) (xy 368.179096 -293.032942) (xy 368.210338 -292.97249)
			(xy 368.213006 -292.967017) (xy 368.215951 -292.955207) (xy 368.21618 -292.949122) (xy 368.21618 -292.916102)
			(xy 368.214148 -292.902132) (xy 368.21237 -292.895782) (xy 368.208052 -292.889178) (xy 368.195906 -292.869748)
			(xy 368.176718 -292.828139) (xy 368.163703 -292.784207) (xy 368.157132 -292.73886) (xy 368.156744 -292.71595)
			(xy 368.157205 -292.690955) (xy 368.165017 -292.641579) (xy 368.180457 -292.594033) (xy 368.203146 -292.549488)
			(xy 368.232523 -292.50904) (xy 368.267866 -292.473687) (xy 368.308304 -292.444297) (xy 368.352842 -292.421595)
			(xy 368.400383 -292.40614) (xy 368.449757 -292.398312) (xy 368.474752 -292.397942) (xy 368.500084 -292.39843)
			(xy 368.550108 -292.406457) (xy 368.598226 -292.422315) (xy 368.64322 -292.445602) (xy 368.683952 -292.47573)
			(xy 368.719391 -292.511936) (xy 368.748641 -292.553304) (xy 368.77096 -292.598786) (xy 368.785784 -292.647232)
			(xy 368.789712 -292.672262) (xy 368.79022 -292.67658) (xy 368.790474 -292.676834) (xy 368.792506 -292.692328)
			(xy 368.793014 -292.699186) (xy 368.793014 -292.71595) (xy 368.792551 -292.740712) (xy 368.784883 -292.789638)
			(xy 368.769709 -292.836779) (xy 368.747398 -292.880992) (xy 368.733324 -292.90137) (xy 368.729402 -292.907166)
			(xy 368.724626 -292.920315) (xy 368.723926 -292.927278) (xy 368.72291 -292.941248) (xy 368.770916 -293.034466)
			(xy 368.775681 -293.04189) (xy 368.789217 -293.053183) (xy 368.80579 -293.059188) (xy 368.814604 -293.059612)
			(xy 369.743228 -293.059612) (xy 369.75308 -293.059126) (xy 369.77128 -293.051576) (xy 369.785206 -293.037635)
			(xy 369.792737 -293.019426) (xy 369.793266 -293.009574) (xy 369.793266 -292.71595) (xy 369.793755 -292.682007)
			(xy 369.801932 -292.614615) (xy 369.818173 -292.548699) (xy 369.84224 -292.485222) (xy 369.873783 -292.425109)
			(xy 369.912343 -292.369237) (xy 369.957356 -292.318419) (xy 370.008166 -292.273398) (xy 370.064032 -292.23483)
			(xy 370.12414 -292.203277) (xy 370.187613 -292.179199) (xy 370.253526 -292.162948) (xy 370.320917 -292.154761)
			(xy 370.35486 -292.154356) (xy 370.37179 -292.154411) (xy 370.405595 -292.156319) (xy 370.422424 -292.158166)
			(xy 370.435378 -292.160198) (xy 370.448078 -292.155118) (xy 370.454359 -292.152469) (xy 370.465302 -292.144352)
			(xy 370.469668 -292.139116) (xy 370.521992 -292.071044) (xy 370.525787 -292.06583) (xy 370.530931 -292.054008)
			(xy 370.532152 -292.047676) (xy 370.53393 -292.03523) (xy 370.52885 -292.022276) (xy 370.518656 -291.994669)
			(xy 370.507535 -291.936886) (xy 370.506752 -291.907468) (xy 370.506752 -291.902896) (xy 370.507465 -291.878063)
			(xy 370.515654 -291.829065) (xy 370.531364 -291.781938) (xy 370.554212 -291.737826) (xy 370.583642 -291.697805)
			(xy 370.618937 -291.662847) (xy 370.659241 -291.633805) (xy 370.70357 -291.611383) (xy 370.750847 -291.596128)
			(xy 370.799921 -291.588412) (xy 370.82476 -291.587936) (xy 370.849752 -291.588398) (xy 370.899121 -291.596212)
			(xy 370.94666 -291.611655) (xy 370.991197 -291.634345) (xy 371.031635 -291.663724) (xy 371.066979 -291.699068)
			(xy 371.096357 -291.739507) (xy 371.119047 -291.784044) (xy 371.134489 -291.831583) (xy 371.142302 -291.880952)
			(xy 371.142768 -291.905944) (xy 371.142292 -291.930804) (xy 371.142272 -291.930933) (xy 371.447296 -291.930933)
			(xy 371.447296 -291.880955) (xy 371.455115 -291.831592) (xy 371.470559 -291.78406) (xy 371.493249 -291.739528)
			(xy 371.522625 -291.699095) (xy 371.557965 -291.663755) (xy 371.598398 -291.634379) (xy 371.64293 -291.611689)
			(xy 371.690462 -291.596245) (xy 371.739825 -291.588426) (xy 371.789803 -291.588426) (xy 371.839166 -291.596245)
			(xy 371.886698 -291.611689) (xy 371.93123 -291.634379) (xy 371.971663 -291.663755) (xy 372.007003 -291.699095)
			(xy 372.036379 -291.739528) (xy 372.059069 -291.78406) (xy 372.074513 -291.831592) (xy 372.082332 -291.880955)
			(xy 372.082822 -291.905944) (xy 372.082332 -291.930933) (xy 373.327404 -291.930933) (xy 373.327404 -291.880955)
			(xy 373.335223 -291.831592) (xy 373.350667 -291.78406) (xy 373.373357 -291.739528) (xy 373.402733 -291.699095)
			(xy 373.438073 -291.663755) (xy 373.478506 -291.634379) (xy 373.523038 -291.611689) (xy 373.57057 -291.596245)
			(xy 373.619933 -291.588426) (xy 373.669911 -291.588426) (xy 373.719274 -291.596245) (xy 373.766806 -291.611689)
			(xy 373.811338 -291.634379) (xy 373.851771 -291.663755) (xy 373.887111 -291.699095) (xy 373.916487 -291.739528)
			(xy 373.939177 -291.78406) (xy 373.954621 -291.831592) (xy 373.96244 -291.880955) (xy 373.96293 -291.905944)
			(xy 373.96244 -291.930933) (xy 374.267204 -291.930933) (xy 374.267204 -291.880955) (xy 374.275023 -291.831592)
			(xy 374.290467 -291.78406) (xy 374.313157 -291.739528) (xy 374.342533 -291.699095) (xy 374.377873 -291.663755)
			(xy 374.418306 -291.634379) (xy 374.462838 -291.611689) (xy 374.51037 -291.596245) (xy 374.559733 -291.588426)
			(xy 374.609711 -291.588426) (xy 374.659074 -291.596245) (xy 374.706606 -291.611689) (xy 374.751138 -291.634379)
			(xy 374.791571 -291.663755) (xy 374.826911 -291.699095) (xy 374.856287 -291.739528) (xy 374.878977 -291.78406)
			(xy 374.894421 -291.831592) (xy 374.90224 -291.880955) (xy 374.90273 -291.905944) (xy 374.90224 -291.930933)
			(xy 374.894421 -291.980296) (xy 374.878977 -292.027828) (xy 374.856287 -292.07236) (xy 374.826911 -292.112793)
			(xy 374.791571 -292.148133) (xy 374.751138 -292.177509) (xy 374.706606 -292.200199) (xy 374.659074 -292.215643)
			(xy 374.609711 -292.223462) (xy 374.559733 -292.223462) (xy 374.51037 -292.215643) (xy 374.462838 -292.200199)
			(xy 374.418306 -292.177509) (xy 374.377873 -292.148133) (xy 374.342533 -292.112793) (xy 374.313157 -292.07236)
			(xy 374.290467 -292.027828) (xy 374.275023 -291.980296) (xy 374.267204 -291.930933) (xy 373.96244 -291.930933)
			(xy 373.954621 -291.980296) (xy 373.939177 -292.027828) (xy 373.916487 -292.07236) (xy 373.887111 -292.112793)
			(xy 373.851771 -292.148133) (xy 373.811338 -292.177509) (xy 373.766806 -292.200199) (xy 373.719274 -292.215643)
			(xy 373.669911 -292.223462) (xy 373.619933 -292.223462) (xy 373.57057 -292.215643) (xy 373.523038 -292.200199)
			(xy 373.478506 -292.177509) (xy 373.438073 -292.148133) (xy 373.402733 -292.112793) (xy 373.373357 -292.07236)
			(xy 373.350667 -292.027828) (xy 373.335223 -291.980296) (xy 373.327404 -291.930933) (xy 372.082332 -291.930933)
			(xy 372.074513 -291.980296) (xy 372.059069 -292.027828) (xy 372.036379 -292.07236) (xy 372.007003 -292.112793)
			(xy 371.971663 -292.148133) (xy 371.93123 -292.177509) (xy 371.886698 -292.200199) (xy 371.839166 -292.215643)
			(xy 371.789803 -292.223462) (xy 371.739825 -292.223462) (xy 371.690462 -292.215643) (xy 371.64293 -292.200199)
			(xy 371.598398 -292.177509) (xy 371.557965 -292.148133) (xy 371.522625 -292.112793) (xy 371.493249 -292.07236)
			(xy 371.470559 -292.027828) (xy 371.455115 -291.980296) (xy 371.447296 -291.930933) (xy 371.142272 -291.930933)
			(xy 371.134562 -291.97992) (xy 371.119281 -292.027233) (xy 371.096822 -292.071592) (xy 371.067732 -292.111914)
			(xy 371.03272 -292.147217) (xy 370.99264 -292.17664) (xy 370.94847 -292.199466) (xy 370.901284 -292.215139)
			(xy 370.87683 -292.219634) (xy 370.870734 -292.22065) (xy 370.857272 -292.226492) (xy 370.849398 -292.23081)
			(xy 370.843298 -292.235137) (xy 370.833734 -292.246625) (xy 370.830602 -292.253416) (xy 370.827046 -292.261798)
			(xy 370.799106 -292.3286) (xy 370.796628 -292.336588) (xy 370.796381 -292.353301) (xy 370.798598 -292.361366)
			(xy 370.798852 -292.361874) (xy 370.804186 -292.378638) (xy 370.809012 -292.385242) (xy 370.82595 -292.409062)
			(xy 370.855343 -292.459586) (xy 370.867686 -292.48608) (xy 370.87048 -292.49243) (xy 370.873782 -292.496494)
			(xy 370.882418 -292.50513) (xy 370.9035 -292.521132) (xy 370.908375 -292.524458) (xy 370.919288 -292.52894)
			(xy 370.92509 -292.530022) (xy 370.939822 -292.532054) (xy 370.94033 -292.532054) (xy 370.997226 -292.53942)
			(xy 371.008888 -292.540374) (xy 371.03101 -292.532837) (xy 371.039644 -292.524942) (xy 371.043962 -292.520624)
			(xy 371.04574 -292.518338) (xy 371.060908 -292.499898) (xy 371.095832 -292.467342) (xy 371.135232 -292.440373)
			(xy 371.17822 -292.419598) (xy 371.223832 -292.405483) (xy 371.271041 -292.398347) (xy 371.294914 -292.397942)
			(xy 371.320243 -292.398435) (xy 371.370259 -292.406469) (xy 371.418369 -292.422333) (xy 371.463355 -292.445624)
			(xy 371.504079 -292.475753) (xy 371.53951 -292.511958) (xy 371.568753 -292.553324) (xy 371.591066 -292.598802)
			(xy 371.605887 -292.647244) (xy 371.609874 -292.672262) (xy 371.610382 -292.67658) (xy 371.610636 -292.676834)
			(xy 371.612668 -292.692328) (xy 371.613176 -292.699186) (xy 371.613176 -292.71595) (xy 371.612713 -292.740712)
			(xy 371.605046 -292.789639) (xy 371.589875 -292.836782) (xy 371.567568 -292.880997) (xy 371.553486 -292.90137)
			(xy 371.54956 -292.907165) (xy 371.544777 -292.920313) (xy 371.544088 -292.927278) (xy 371.543072 -292.941248)
			(xy 371.591078 -293.034466) (xy 371.595842 -293.041894) (xy 371.609375 -293.053197) (xy 371.62595 -293.059214)
			(xy 371.634766 -293.059612) (xy 372.728236 -293.059612) (xy 372.737645 -293.059211) (xy 372.755153 -293.052308)
			(xy 372.768918 -293.039475) (xy 372.777029 -293.022493) (xy 372.77802 -293.01313) (xy 372.77802 -292.71595)
			(xy 372.778526 -292.68761) (xy 372.786592 -292.631507) (xy 372.802561 -292.577124) (xy 372.826106 -292.525566)
			(xy 372.856749 -292.477884) (xy 372.893867 -292.435049) (xy 372.936702 -292.397931) (xy 372.984384 -292.367288)
			(xy 373.035942 -292.343743) (xy 373.090325 -292.327774) (xy 373.146428 -292.319708) (xy 373.203108 -292.319708)
			(xy 373.259211 -292.327774) (xy 373.313594 -292.343743) (xy 373.365152 -292.367288) (xy 373.412834 -292.397931)
			(xy 373.455669 -292.435049) (xy 373.492787 -292.477884) (xy 373.52343 -292.525566) (xy 373.546975 -292.577124)
			(xy 373.562944 -292.631507) (xy 373.57101 -292.68761) (xy 373.571516 -292.71595) (xy 373.571516 -293.01313)
			(xy 373.572531 -293.022497) (xy 373.580593 -293.03951) (xy 373.594356 -293.052354) (xy 373.611885 -293.059222)
			(xy 373.6213 -293.059612) (xy 373.774716 -293.059612) (xy 373.783815 -293.059199) (xy 373.80084 -293.052766)
			(xy 373.814544 -293.040788) (xy 373.819166 -293.032942) (xy 373.850408 -292.97249) (xy 373.853078 -292.967018)
			(xy 373.856024 -292.955207) (xy 373.85625 -292.949122) (xy 373.85625 -292.916102) (xy 373.854218 -292.902132)
			(xy 373.85244 -292.895782) (xy 373.848122 -292.889178) (xy 373.835977 -292.869748) (xy 373.816791 -292.828139)
			(xy 373.803778 -292.784206) (xy 373.797206 -292.73886) (xy 373.796814 -292.71595) (xy 373.797275 -292.690957)
			(xy 373.805088 -292.641585) (xy 373.820529 -292.594044) (xy 373.843219 -292.549504) (xy 373.872597 -292.509062)
			(xy 373.907941 -292.473715) (xy 373.94838 -292.444333) (xy 373.992918 -292.42164) (xy 374.040458 -292.406195)
			(xy 374.089829 -292.398377) (xy 374.114822 -292.397942) (xy 374.14015 -292.398436) (xy 374.190166 -292.406471)
			(xy 374.238275 -292.422335) (xy 374.28326 -292.445627) (xy 374.323982 -292.475756) (xy 374.359413 -292.511961)
			(xy 374.388654 -292.553326) (xy 374.410967 -292.598804) (xy 374.425787 -292.647245) (xy 374.429782 -292.672262)
			(xy 374.43029 -292.67658) (xy 374.430544 -292.676834) (xy 374.432576 -292.692328) (xy 374.433084 -292.699186)
			(xy 374.433084 -292.71595) (xy 374.432621 -292.740712) (xy 374.424954 -292.789639) (xy 374.409784 -292.836782)
			(xy 374.387477 -292.880998) (xy 374.373394 -292.90137) (xy 374.369467 -292.907164) (xy 374.364684 -292.920313)
			(xy 374.363996 -292.927278) (xy 374.36298 -292.941248) (xy 374.410986 -293.034466) (xy 374.41575 -293.041893)
			(xy 374.429284 -293.053194) (xy 374.445858 -293.059208) (xy 374.454674 -293.059612) (xy 375.337324 -293.059612)
			(xy 375.347077 -293.059103) (xy 375.365113 -293.051661) (xy 375.372376 -293.045134) (xy 375.653554 -292.763956)
			(xy 375.657183 -292.760129) (xy 375.662937 -292.751291) (xy 375.664984 -292.74643) (xy 375.668794 -292.736778)
			(xy 375.668286 -292.72611) (xy 375.668032 -292.716204) (xy 375.668032 -292.715696) (xy 375.668589 -292.688882)
			(xy 375.677379 -292.635978) (xy 375.69469 -292.585219) (xy 375.720057 -292.537968) (xy 375.752798 -292.495494)
			(xy 375.792036 -292.458936) (xy 375.814082 -292.443662) (xy 375.819416 -292.440106) (xy 375.823226 -292.436042)
			(xy 375.82856 -292.429438) (xy 375.842022 -292.405308) (xy 375.844797 -292.399797) (xy 375.847872 -292.387852)
			(xy 375.848118 -292.381686) (xy 375.848118 -291.430202) (xy 375.847884 -291.424036) (xy 375.8448 -291.41209)
			(xy 375.842022 -291.40658) (xy 375.82856 -291.38245) (xy 375.823226 -291.375846) (xy 375.819416 -291.371782)
			(xy 375.814082 -291.368226) (xy 375.793699 -291.354143) (xy 375.757035 -291.320825) (xy 375.725818 -291.282356)
			(xy 375.700763 -291.239618) (xy 375.682444 -291.193587) (xy 375.671281 -291.14532) (xy 375.66753 -291.095921)
			(xy 375.671275 -291.046521) (xy 375.682432 -290.998253) (xy 375.700745 -290.95222) (xy 375.725794 -290.909478)
			(xy 375.757006 -290.871005) (xy 375.793666 -290.837683) (xy 375.814082 -290.82365) (xy 375.819416 -290.820094)
			(xy 375.823226 -290.81603) (xy 375.82856 -290.809426) (xy 375.842022 -290.785296) (xy 375.844796 -290.779785)
			(xy 375.847868 -290.767839) (xy 375.848118 -290.761674) (xy 375.848118 -290.59378) (xy 375.848025 -290.588902)
			(xy 375.84624 -290.579311) (xy 375.844562 -290.57473) (xy 375.840752 -290.565586) (xy 375.8057 -290.530534)
			(xy 375.800329 -290.525534) (xy 375.787429 -290.518552) (xy 375.7803 -290.516818) (xy 375.770394 -290.514532)
			(xy 375.756932 -290.517072) (xy 375.751852 -290.519104) (xy 375.751344 -290.519104) (xy 375.734326 -290.525708)
			(xy 375.727722 -290.531042) (xy 375.727468 -290.531296) (xy 375.705933 -290.548257) (xy 375.658266 -290.575315)
			(xy 375.60668 -290.593842) (xy 375.552689 -290.603294) (xy 375.525284 -290.60394) (xy 375.524776 -290.60394)
			(xy 375.499448 -290.603446) (xy 375.449434 -290.59541) (xy 375.401326 -290.579546) (xy 375.356343 -290.556254)
			(xy 375.315622 -290.526124) (xy 375.280194 -290.489918) (xy 375.250954 -290.448553) (xy 375.228644 -290.403075)
			(xy 375.213827 -290.354634) (xy 375.209816 -290.32962) (xy 375.209308 -290.325302) (xy 375.209054 -290.325048)
			(xy 375.207022 -290.309554) (xy 375.206514 -290.302696) (xy 375.206514 -290.285932) (xy 375.207058 -290.259453)
			(xy 375.21587 -290.207232) (xy 375.233223 -290.157197) (xy 375.258634 -290.110733) (xy 375.274586 -290.08959)
			(xy 375.27611 -290.087812) (xy 375.280408 -290.081283) (xy 375.285194 -290.066412) (xy 375.285508 -290.058602)
			(xy 375.285508 -290.03117) (xy 375.285414 -290.026292) (xy 375.283627 -290.016702) (xy 375.281952 -290.01212)
			(xy 375.278142 -290.002976) (xy 375.090944 -289.815778) (xy 375.083832 -289.808412) (xy 375.049034 -289.794188)
			(xy 375.040144 -289.79368) (xy 375.03989 -289.79368) (xy 375.018885 -289.792348) (xy 374.977474 -289.784825)
			(xy 374.95734 -289.778694) (xy 374.933718 -289.770571) (xy 374.889154 -289.748011) (xy 374.848666 -289.718759)
			(xy 374.813252 -289.683534) (xy 374.783782 -289.643204) (xy 374.760983 -289.598762) (xy 374.745415 -289.5513)
			(xy 374.740932 -289.526726) (xy 374.739023 -289.514177) (xy 374.736989 -289.488873) (xy 374.736868 -289.47618)
			(xy 374.736868 -289.475926) (xy 374.737377 -289.450005) (xy 374.745781 -289.398849) (xy 374.762371 -289.349734)
			(xy 374.786707 -289.303959) (xy 374.818144 -289.262738) (xy 374.855851 -289.227161) (xy 374.877076 -289.212274)
			(xy 374.882156 -289.208718) (xy 374.885966 -289.204654) (xy 374.89257 -289.19551) (xy 374.904 -289.176206)
			(xy 374.906794 -289.170618) (xy 374.908267 -289.166957) (xy 374.910184 -289.159302) (xy 374.910604 -289.155378)
			(xy 374.910858 -289.150806) (xy 374.910858 -289.018218) (xy 374.910604 -289.014154) (xy 374.908958 -289.001559)
			(xy 374.895224 -288.980231) (xy 374.884442 -288.973514) (xy 374.884188 -288.973514) (xy 374.807226 -288.931858)
			(xy 374.805448 -288.931096) (xy 374.793891 -288.926245) (xy 374.768872 -288.927194) (xy 374.757696 -288.932874)
			(xy 374.753886 -288.93516) (xy 374.753632 -288.935414) (xy 374.72786 -288.950737) (xy 374.671984 -288.972463)
			(xy 374.642634 -288.978594) (xy 374.628286 -288.981088) (xy 374.599284 -288.983762) (xy 374.584722 -288.983928)
			(xy 374.559728 -288.983465) (xy 374.510355 -288.975648) (xy 374.462813 -288.960204) (xy 374.418273 -288.937512)
			(xy 374.37783 -288.908132) (xy 374.342483 -288.872786) (xy 374.313099 -288.832346) (xy 374.290404 -288.787807)
			(xy 374.274957 -288.740266) (xy 374.267137 -288.690894) (xy 374.267137 -288.640906) (xy 374.274957 -288.591534)
			(xy 374.290404 -288.543993) (xy 374.313099 -288.499454) (xy 374.342483 -288.459014) (xy 374.37783 -288.423668)
			(xy 374.418273 -288.394288) (xy 374.462813 -288.371596) (xy 374.510355 -288.356152) (xy 374.559728 -288.348335)
			(xy 374.584722 -288.347912) (xy 374.61244 -288.348513) (xy 374.667037 -288.358117) (xy 374.719146 -288.377031)
			(xy 374.743472 -288.39033) (xy 374.746774 -288.392108) (xy 374.755664 -288.395664) (xy 374.759611 -288.396928)
			(xy 374.767778 -288.398332) (xy 374.77192 -288.398458) (xy 374.798082 -288.398458) (xy 374.811544 -288.39668)
			(xy 374.821196 -288.39287) (xy 374.885712 -288.357564) (xy 374.893151 -288.352807) (xy 374.904477 -288.339277)
			(xy 374.910515 -288.322698) (xy 374.910858 -288.313876) (xy 374.910858 -288.181542) (xy 374.910623 -288.175026)
			(xy 374.90728 -288.162426) (xy 374.904254 -288.15665) (xy 374.896888 -288.143442) (xy 374.889776 -288.13379)
			(xy 374.877838 -288.120836) (xy 374.873266 -288.117534) (xy 374.852563 -288.102524) (xy 374.815781 -288.067004)
			(xy 374.785152 -288.026059) (xy 374.761464 -287.980744) (xy 374.745326 -287.932224) (xy 374.737153 -287.881748)
			(xy 374.737156 -287.830615) (xy 374.745334 -287.78014) (xy 374.761478 -287.731622) (xy 374.785172 -287.68631)
			(xy 374.815805 -287.645369) (xy 374.852591 -287.609852) (xy 374.873266 -287.594802) (xy 374.877838 -287.5915)
			(xy 374.889776 -287.578546) (xy 374.896888 -287.568894) (xy 374.904254 -287.555686) (xy 374.907309 -287.549921)
			(xy 374.910656 -287.537315) (xy 374.910858 -287.530794) (xy 374.910858 -286.56153) (xy 374.910622 -286.555014)
			(xy 374.907276 -286.542416) (xy 374.904254 -286.536638) (xy 374.896888 -286.52343) (xy 374.889776 -286.513778)
			(xy 374.877838 -286.500824) (xy 374.873266 -286.497522) (xy 374.852564 -286.482512) (xy 374.815784 -286.446992)
			(xy 374.785157 -286.406048) (xy 374.76147 -286.360734) (xy 374.745333 -286.312215) (xy 374.737162 -286.261741)
			(xy 374.737166 -286.210609) (xy 374.745345 -286.160136) (xy 374.76149 -286.11162) (xy 374.785184 -286.066309)
			(xy 374.815817 -286.02537) (xy 374.852603 -285.989856) (xy 374.873266 -285.97479) (xy 374.877838 -285.971488)
			(xy 374.889776 -285.958534) (xy 374.896888 -285.948882) (xy 374.904254 -285.935674) (xy 374.907308 -285.929909)
			(xy 374.910651 -285.917303) (xy 374.910858 -285.910782) (xy 374.910858 -285.778448) (xy 374.910604 -285.774384)
			(xy 374.908964 -285.761785) (xy 374.895236 -285.740445) (xy 374.884442 -285.733744) (xy 374.884188 -285.733744)
			(xy 374.807226 -285.692088) (xy 374.805448 -285.691326) (xy 374.793891 -285.686473) (xy 374.768871 -285.687423)
			(xy 374.757696 -285.693104) (xy 374.753886 -285.69539) (xy 374.753632 -285.695644) (xy 374.727861 -285.71097)
			(xy 374.671986 -285.7327) (xy 374.642634 -285.738824) (xy 374.628286 -285.741317) (xy 374.599284 -285.743991)
			(xy 374.584722 -285.744158) (xy 374.559726 -285.743695) (xy 374.510348 -285.735878) (xy 374.462802 -285.720432)
			(xy 374.418257 -285.697738) (xy 374.377811 -285.668355) (xy 374.34246 -285.633006) (xy 374.313074 -285.592562)
			(xy 374.290377 -285.548019) (xy 374.274928 -285.500473) (xy 374.267107 -285.451096) (xy 374.267107 -285.401104)
			(xy 374.274928 -285.351727) (xy 374.290377 -285.304181) (xy 374.313074 -285.259638) (xy 374.34246 -285.219194)
			(xy 374.377811 -285.183845) (xy 374.418257 -285.154462) (xy 374.462802 -285.131768) (xy 374.510348 -285.116322)
			(xy 374.559726 -285.108505) (xy 374.584722 -285.108142) (xy 374.61244 -285.108743) (xy 374.667036 -285.118348)
			(xy 374.719144 -285.137263) (xy 374.743472 -285.15056) (xy 374.746774 -285.152338) (xy 374.755664 -285.155894)
			(xy 374.759611 -285.157157) (xy 374.767778 -285.15856) (xy 374.77192 -285.158688) (xy 374.798082 -285.158688)
			(xy 374.811544 -285.15691) (xy 374.821196 -285.1531) (xy 374.885712 -285.117794) (xy 374.893144 -285.113033)
			(xy 374.904451 -285.099501) (xy 374.910466 -285.082923) (xy 374.910858 -285.074106) (xy 374.910858 -284.941518)
			(xy 374.91062 -284.935002) (xy 374.907272 -284.922406) (xy 374.904254 -284.916626) (xy 374.896888 -284.903418)
			(xy 374.889776 -284.893766) (xy 374.877838 -284.880812) (xy 374.873266 -284.87751) (xy 374.852556 -284.862501)
			(xy 374.815763 -284.826978) (xy 374.785122 -284.786029) (xy 374.761423 -284.740708) (xy 374.745275 -284.692181)
			(xy 374.737094 -284.641697) (xy 374.737089 -284.590553) (xy 374.745263 -284.540067) (xy 374.761403 -284.491538)
			(xy 374.785095 -284.446213) (xy 374.815729 -284.40526) (xy 374.852518 -284.369731) (xy 374.873266 -284.354778)
			(xy 374.877838 -284.351476) (xy 374.889776 -284.338522) (xy 374.896888 -284.32887) (xy 374.904254 -284.315662)
			(xy 374.907306 -284.309896) (xy 374.910647 -284.297291) (xy 374.910858 -284.29077) (xy 374.910858 -283.321506)
			(xy 374.910641 -283.315277) (xy 374.907547 -283.303207) (xy 374.904762 -283.29763) (xy 374.890284 -283.271976)
			(xy 374.885966 -283.267404) (xy 374.882156 -283.26334) (xy 374.881394 -283.262578) (xy 374.877076 -283.259784)
			(xy 374.856055 -283.245014) (xy 374.818632 -283.209817) (xy 374.787353 -283.169063) (xy 374.763031 -283.123811)
			(xy 374.746299 -283.075238) (xy 374.737591 -283.024608) (xy 374.736868 -282.998926) (xy 374.736868 -282.995116)
			(xy 374.737376 -282.97378) (xy 374.73763 -282.973018) (xy 374.738392 -282.965144) (xy 374.738392 -282.959048)
			(xy 374.737908 -282.949085) (xy 374.730323 -282.930658) (xy 374.72366 -282.923234) (xy 374.53443 -282.734004)
			(xy 374.52771 -282.726769) (xy 374.520103 -282.708563) (xy 374.519698 -282.698698) (xy 374.519698 -282.535884)
			(xy 374.519453 -282.527856) (xy 374.514525 -282.512579) (xy 374.510046 -282.505912) (xy 374.505728 -282.50007)
			(xy 374.493282 -282.490926) (xy 374.4849 -282.488132) (xy 374.461412 -282.479863) (xy 374.417144 -282.457064)
			(xy 374.37697 -282.427647) (xy 374.34187 -282.392329) (xy 374.312702 -282.351973) (xy 374.290178 -282.307565)
			(xy 374.27485 -282.26019) (xy 374.26709 -282.211005) (xy 374.267088 -282.161211) (xy 374.274846 -282.112026)
			(xy 374.290172 -282.06465) (xy 374.312694 -282.020241) (xy 374.34186 -281.979884) (xy 374.376958 -281.944564)
			(xy 374.41713 -281.915144) (xy 374.461397 -281.892343) (xy 374.4849 -281.88412) (xy 374.48998 -281.882342)
			(xy 374.498607 -281.877946) (xy 374.511989 -281.863973) (xy 374.519246 -281.846039) (xy 374.519698 -281.836368)
			(xy 374.519698 -281.675586) (xy 374.519167 -281.66563) (xy 374.511511 -281.647244) (xy 374.49746 -281.633126)
			(xy 374.488456 -281.62885) (xy 374.451118 -281.613356) (xy 374.45061 -281.613356) (xy 374.402604 -281.594052)
			(xy 374.395606 -281.591455) (xy 374.380756 -281.590031) (xy 374.373394 -281.591258) (xy 374.366282 -281.592782)
			(xy 374.353074 -281.599894) (xy 374.34774 -281.605482) (xy 374.329185 -281.623617) (xy 374.287401 -281.65437)
			(xy 374.241284 -281.678138) (xy 374.191992 -281.694324) (xy 374.140763 -281.702522) (xy 374.114822 -281.703018)
			(xy 374.089129 -281.702542) (xy 374.038377 -281.694507) (xy 373.989506 -281.678631) (xy 373.94372 -281.655305)
			(xy 373.902147 -281.625103) (xy 373.865812 -281.588769) (xy 373.835607 -281.547199) (xy 373.812278 -281.501415)
			(xy 373.796398 -281.452545) (xy 373.78836 -281.401793) (xy 373.78836 -281.350407) (xy 373.796398 -281.299655)
			(xy 373.812278 -281.250785) (xy 373.835607 -281.205001) (xy 373.865812 -281.163431) (xy 373.902147 -281.127097)
			(xy 373.94372 -281.096895) (xy 373.989506 -281.073569) (xy 374.038377 -281.057693) (xy 374.089129 -281.049658)
			(xy 374.114822 -281.049222) (xy 374.140762 -281.049721) (xy 374.19199 -281.05792) (xy 374.241281 -281.074107)
			(xy 374.287395 -281.097877) (xy 374.329176 -281.128633) (xy 374.34774 -281.146758) (xy 374.353234 -281.151974)
			(xy 374.366538 -281.159204) (xy 374.373902 -281.160982) (xy 374.381014 -281.162506) (xy 374.395492 -281.161236)
			(xy 374.45061 -281.138884) (xy 374.451118 -281.138884) (xy 374.488456 -281.12339) (xy 374.497483 -281.11913)
			(xy 374.511593 -281.10504) (xy 374.519239 -281.086624) (xy 374.519698 -281.076654) (xy 374.519698 -280.915872)
			(xy 374.519451 -280.907845) (xy 374.514521 -280.89257) (xy 374.510046 -280.8859) (xy 374.505728 -280.880058)
			(xy 374.493282 -280.870914) (xy 374.4849 -280.86812) (xy 374.461413 -280.859851) (xy 374.417147 -280.837053)
			(xy 374.376975 -280.807636) (xy 374.341876 -280.772318) (xy 374.31271 -280.731964) (xy 374.290188 -280.687557)
			(xy 374.27486 -280.640183) (xy 374.267101 -280.591) (xy 374.2671 -280.541209) (xy 374.274858 -280.492025)
			(xy 374.290184 -280.444651) (xy 374.312705 -280.400244) (xy 374.341871 -280.359888) (xy 374.376968 -280.32457)
			(xy 374.41714 -280.295152) (xy 374.461405 -280.272353) (xy 374.4849 -280.264108) (xy 374.48998 -280.26233)
			(xy 374.498605 -280.257933) (xy 374.511984 -280.24396) (xy 374.519237 -280.226026) (xy 374.519698 -280.216356)
			(xy 374.519698 -280.042874) (xy 374.519252 -280.032733) (xy 374.511407 -280.01403) (xy 374.496944 -279.99981)
			(xy 374.487694 -279.99563) (xy 374.40235 -279.961594) (xy 374.393013 -279.95838) (xy 374.373286 -279.958557)
			(xy 374.355084 -279.966166) (xy 374.34774 -279.97277) (xy 374.344946 -279.975564) (xy 374.326816 -279.993848)
			(xy 374.285738 -280.024891) (xy 374.240197 -280.048913) (xy 374.191382 -280.065286) (xy 374.140566 -280.073583)
			(xy 374.114822 -280.074116) (xy 374.089829 -280.073653) (xy 374.040459 -280.065837) (xy 373.99292 -280.050394)
			(xy 373.948381 -280.027703) (xy 373.907941 -279.998325) (xy 373.872595 -279.962982) (xy 373.843212 -279.922544)
			(xy 373.820518 -279.878008) (xy 373.80507 -279.83047) (xy 373.797249 -279.781101) (xy 373.796814 -279.756108)
			(xy 373.797282 -279.731382) (xy 373.804934 -279.682527) (xy 373.820054 -279.635444) (xy 373.842278 -279.591269)
			(xy 373.871071 -279.551065) (xy 373.905739 -279.515801) (xy 373.945447 -279.486327) (xy 373.989237 -279.463353)
			(xy 374.036055 -279.447433) (xy 374.084773 -279.43895) (xy 374.109488 -279.4381) (xy 374.11533 -279.4381)
			(xy 374.141266 -279.438638) (xy 374.192444 -279.447102) (xy 374.241573 -279.463754) (xy 374.287351 -279.488151)
			(xy 374.328567 -279.519648) (xy 374.346724 -279.538176) (xy 374.346978 -279.53843) (xy 374.352331 -279.543674)
			(xy 374.365377 -279.55103) (xy 374.372632 -279.552908) (xy 374.380252 -279.554686) (xy 374.395238 -279.553416)
			(xy 374.487694 -279.516586) (xy 374.496956 -279.512426) (xy 374.511427 -279.498208) (xy 374.519244 -279.479487)
			(xy 374.519698 -279.469342) (xy 374.519698 -279.455626) (xy 374.520235 -279.445789) (xy 374.527823 -279.427629)
			(xy 374.53443 -279.42032) (xy 374.9421 -279.01265) (xy 374.948652 -279.005401) (xy 374.956103 -278.987358)
			(xy 374.956578 -278.977598) (xy 374.956578 -278.48814) (xy 374.956328 -278.480727) (xy 374.952072 -278.466524)
			(xy 374.948196 -278.4602) (xy 374.934226 -278.438864) (xy 374.925082 -278.42845) (xy 374.92051 -278.424386)
			(xy 374.89713 -278.412933) (xy 374.854138 -278.383579) (xy 374.816499 -278.347615) (xy 374.78522 -278.306002)
			(xy 374.761133 -278.259851) (xy 374.744884 -278.210394) (xy 374.736905 -278.158951) (xy 374.737409 -278.106896)
			(xy 374.746384 -278.055617) (xy 374.763588 -278.006484) (xy 374.788564 -277.960808) (xy 374.820644 -277.91981)
			(xy 374.858972 -277.884582) (xy 374.902525 -277.856066) (xy 374.926098 -277.845012) (xy 374.926606 -277.845012)
			(xy 374.92686 -277.844758) (xy 374.933326 -277.841531) (xy 374.944289 -277.832124) (xy 374.94845 -277.826216)
			(xy 374.952514 -277.82012) (xy 374.956578 -277.80615) (xy 374.956578 -277.644098) (xy 374.956128 -277.634848)
			(xy 374.949487 -277.617575) (xy 374.937171 -277.603762) (xy 374.929146 -277.59914) (xy 374.847104 -277.56104)
			(xy 374.838576 -277.557996) (xy 374.820489 -277.557482) (xy 374.811798 -277.560024) (xy 374.80113 -277.564088)
			(xy 374.791986 -277.56739) (xy 374.785636 -277.572724) (xy 374.764215 -277.589439) (xy 374.716861 -277.616074)
			(xy 374.665675 -277.634288) (xy 374.612141 -277.643553) (xy 374.584976 -277.644098) (xy 374.584722 -277.644098)
			(xy 374.55973 -277.643635) (xy 374.510362 -277.635819) (xy 374.462825 -277.620376) (xy 374.418288 -277.597687)
			(xy 374.37785 -277.568309) (xy 374.342505 -277.532967) (xy 374.313125 -277.49253) (xy 374.290432 -277.447996)
			(xy 374.274986 -277.400459) (xy 374.267166 -277.351092) (xy 374.267166 -277.301108) (xy 374.274986 -277.251741)
			(xy 374.290432 -277.204204) (xy 374.313125 -277.15967) (xy 374.342505 -277.119233) (xy 374.37785 -277.083891)
			(xy 374.418288 -277.054513) (xy 374.462825 -277.031824) (xy 374.510362 -277.016381) (xy 374.55973 -277.008565)
			(xy 374.584722 -277.008082) (xy 374.610754 -277.008599) (xy 374.662123 -277.017083) (xy 374.711418 -277.033836)
			(xy 374.757318 -277.05841) (xy 374.77827 -277.073868) (xy 374.778524 -277.074122) (xy 374.785382 -277.079202)
			(xy 374.792748 -277.081742) (xy 374.796755 -277.083028) (xy 374.805051 -277.084436) (xy 374.809258 -277.084536)
			(xy 374.850152 -277.084536) (xy 374.85567 -277.084368) (xy 374.866434 -277.08193) (xy 374.871488 -277.07971)
			(xy 374.927114 -277.054056) (xy 374.935705 -277.049642) (xy 374.948999 -277.035654) (xy 374.956153 -277.017731)
			(xy 374.956578 -277.008082) (xy 374.956578 -276.868128) (xy 374.956326 -276.860715) (xy 374.952067 -276.846515)
			(xy 374.948196 -276.840188) (xy 374.934226 -276.818852) (xy 374.925082 -276.808438) (xy 374.92051 -276.804374)
			(xy 374.897131 -276.792922) (xy 374.854141 -276.763567) (xy 374.816504 -276.727604) (xy 374.785226 -276.685992)
			(xy 374.761142 -276.639842) (xy 374.744893 -276.590387) (xy 374.736915 -276.538946) (xy 374.737421 -276.486892)
			(xy 374.746395 -276.435615) (xy 374.7636 -276.386484) (xy 374.788576 -276.34081) (xy 374.820655 -276.299813)
			(xy 374.858983 -276.264587) (xy 374.902535 -276.236073) (xy 374.926098 -276.225) (xy 374.926606 -276.225)
			(xy 374.92686 -276.224746) (xy 374.933326 -276.221519) (xy 374.944286 -276.21211) (xy 374.94845 -276.206204)
			(xy 374.952514 -276.200108) (xy 374.956578 -276.186138) (xy 374.956578 -275.248116) (xy 374.956324 -275.240704)
			(xy 374.952063 -275.226505) (xy 374.948196 -275.220176) (xy 374.934226 -275.19884) (xy 374.925082 -275.188426)
			(xy 374.92051 -275.184362) (xy 374.897124 -275.172909) (xy 374.854119 -275.143552) (xy 374.816469 -275.107585)
			(xy 374.785178 -275.065966) (xy 374.761082 -275.019807) (xy 374.744824 -274.970341) (xy 374.736839 -274.918888)
			(xy 374.737338 -274.866821) (xy 374.746309 -274.81553) (xy 374.763513 -274.766384) (xy 374.788489 -274.720697)
			(xy 374.820573 -274.679686) (xy 374.858906 -274.644446) (xy 374.902465 -274.61592) (xy 374.926098 -274.604988)
			(xy 374.926606 -274.604988) (xy 374.92686 -274.604734) (xy 374.933325 -274.601506) (xy 374.944284 -274.592096)
			(xy 374.94845 -274.586192) (xy 374.952514 -274.580096) (xy 374.956578 -274.566126) (xy 374.956578 -274.404074)
			(xy 374.956124 -274.394826) (xy 374.949478 -274.377559) (xy 374.93716 -274.363754) (xy 374.929146 -274.359116)
			(xy 374.847104 -274.321016) (xy 374.838577 -274.317969) (xy 374.820489 -274.317455) (xy 374.811798 -274.32)
			(xy 374.80113 -274.324064) (xy 374.791986 -274.327366) (xy 374.785636 -274.3327) (xy 374.764214 -274.349412)
			(xy 374.716859 -274.376041) (xy 374.665673 -274.39425) (xy 374.61214 -274.403513) (xy 374.584976 -274.404074)
			(xy 374.584722 -274.404074) (xy 374.559732 -274.403611) (xy 374.510368 -274.395795) (xy 374.462834 -274.380354)
			(xy 374.418301 -274.357666) (xy 374.377866 -274.32829) (xy 374.342524 -274.292951) (xy 374.313146 -274.252518)
			(xy 374.290455 -274.207986) (xy 374.27501 -274.160453) (xy 374.267191 -274.11109) (xy 374.267191 -274.06111)
			(xy 374.27501 -274.011747) (xy 374.290455 -273.964214) (xy 374.313146 -273.919682) (xy 374.342524 -273.879249)
			(xy 374.377866 -273.84391) (xy 374.418301 -273.814534) (xy 374.462834 -273.791846) (xy 374.510368 -273.776405)
			(xy 374.559732 -273.768589) (xy 374.584722 -273.768058) (xy 374.610754 -273.768575) (xy 374.662123 -273.777058)
			(xy 374.711419 -273.793811) (xy 374.757321 -273.818382) (xy 374.77827 -273.833844) (xy 374.778524 -273.834098)
			(xy 374.785382 -273.839178) (xy 374.792748 -273.841718) (xy 374.796755 -273.843004) (xy 374.805051 -273.844413)
			(xy 374.809258 -273.844512) (xy 374.850152 -273.844512) (xy 374.85567 -273.844344) (xy 374.866433 -273.841905)
			(xy 374.871488 -273.839686) (xy 374.927114 -273.814032) (xy 374.935702 -273.809617) (xy 374.948989 -273.795627)
			(xy 374.956136 -273.777705) (xy 374.956578 -273.768058) (xy 374.956578 -273.628104) (xy 374.956323 -273.620692)
			(xy 374.952058 -273.606496) (xy 374.948196 -273.600164) (xy 374.934226 -273.578828) (xy 374.925082 -273.568414)
			(xy 374.92051 -273.56435) (xy 374.897125 -273.552897) (xy 374.854122 -273.523541) (xy 374.816474 -273.487574)
			(xy 374.785185 -273.445956) (xy 374.76109 -273.399798) (xy 374.744834 -273.350334) (xy 374.736849 -273.298882)
			(xy 374.737349 -273.246817) (xy 374.746321 -273.195528) (xy 374.763525 -273.146384) (xy 374.788501 -273.100698)
			(xy 374.820584 -273.059689) (xy 374.858916 -273.024452) (xy 374.902475 -272.995927) (xy 374.926098 -272.984976)
			(xy 374.926606 -272.984976) (xy 374.92686 -272.984722) (xy 374.933325 -272.981494) (xy 374.944281 -272.972082)
			(xy 374.94845 -272.96618) (xy 374.952514 -272.960084) (xy 374.956578 -272.946114) (xy 374.956578 -272.008092)
			(xy 374.956321 -272.000681) (xy 374.952054 -271.986486) (xy 374.948196 -271.980152) (xy 374.934226 -271.958816)
			(xy 374.925082 -271.948402) (xy 374.92051 -271.944338) (xy 374.897126 -271.932885) (xy 374.854125 -271.903529)
			(xy 374.816479 -271.867563) (xy 374.785191 -271.825946) (xy 374.761098 -271.77979) (xy 374.744843 -271.730326)
			(xy 374.736859 -271.678876) (xy 374.73736 -271.626813) (xy 374.746333 -271.575526) (xy 374.763537 -271.526384)
			(xy 374.788513 -271.4807) (xy 374.820595 -271.439693) (xy 374.858927 -271.404458) (xy 374.902484 -271.375934)
			(xy 374.926098 -271.364964) (xy 374.926606 -271.364964) (xy 374.92686 -271.36471) (xy 374.933324 -271.361481)
			(xy 374.944279 -271.352069) (xy 374.94845 -271.346168) (xy 374.952514 -271.340072) (xy 374.956578 -271.326102)
			(xy 374.956578 -271.16405) (xy 374.95612 -271.154804) (xy 374.949469 -271.137544) (xy 374.93715 -271.123746)
			(xy 374.929146 -271.119092) (xy 374.847104 -271.080992) (xy 374.838577 -271.077946) (xy 374.820489 -271.077432)
			(xy 374.811798 -271.079976) (xy 374.80113 -271.08404) (xy 374.791986 -271.087342) (xy 374.785636 -271.092676)
			(xy 374.764214 -271.109388) (xy 374.716859 -271.136019) (xy 374.665674 -271.15423) (xy 374.61214 -271.163494)
			(xy 374.584976 -271.16405) (xy 374.584722 -271.16405) (xy 374.559726 -271.163587) (xy 374.51035 -271.15577)
			(xy 374.462805 -271.140324) (xy 374.418261 -271.117631) (xy 374.377816 -271.088248) (xy 374.342466 -271.052901)
			(xy 374.313081 -271.012458) (xy 374.290384 -270.967916) (xy 374.274935 -270.920371) (xy 374.267115 -270.870996)
			(xy 374.267115 -270.821004) (xy 374.274935 -270.771629) (xy 374.290384 -270.724084) (xy 374.313081 -270.679542)
			(xy 374.342466 -270.639099) (xy 374.377816 -270.603751) (xy 374.418261 -270.574369) (xy 374.462805 -270.551676)
			(xy 374.51035 -270.53623) (xy 374.559726 -270.528413) (xy 374.584722 -270.528034) (xy 374.610755 -270.528551)
			(xy 374.662124 -270.537034) (xy 374.71142 -270.553785) (xy 374.757323 -270.578355) (xy 374.77827 -270.59382)
			(xy 374.778524 -270.594074) (xy 374.785382 -270.599154) (xy 374.792748 -270.601694) (xy 374.796755 -270.602979)
			(xy 374.805051 -270.604386) (xy 374.809258 -270.604488) (xy 374.850152 -270.604488) (xy 374.855669 -270.60432)
			(xy 374.866433 -270.60188) (xy 374.871488 -270.599662) (xy 374.927114 -270.574008) (xy 374.935699 -270.569592)
			(xy 374.94898 -270.555601) (xy 374.956118 -270.53768) (xy 374.956578 -270.528034) (xy 374.956578 -270.38808)
			(xy 374.956319 -270.380669) (xy 374.952049 -270.366476) (xy 374.948196 -270.36014) (xy 374.934226 -270.338804)
			(xy 374.925082 -270.32839) (xy 374.92051 -270.324326) (xy 374.897127 -270.312873) (xy 374.854128 -270.283517)
			(xy 374.816483 -270.247552) (xy 374.785198 -270.205936) (xy 374.761107 -270.159781) (xy 374.744853 -270.110319)
			(xy 374.73687 -270.05887) (xy 374.737372 -270.006809) (xy 374.746344 -269.955524) (xy 374.763548 -269.906384)
			(xy 374.788525 -269.860702) (xy 374.820606 -269.819697) (xy 374.858937 -269.784463) (xy 374.902494 -269.755941)
			(xy 374.926098 -269.744952) (xy 374.926606 -269.744952) (xy 374.92686 -269.744698) (xy 374.933328 -269.741473)
			(xy 374.944296 -269.73207) (xy 374.94845 -269.726156) (xy 374.952514 -269.72006) (xy 374.956578 -269.70609)
			(xy 374.956578 -268.753336) (xy 374.956154 -268.743621) (xy 374.948937 -268.72558) (xy 374.935526 -268.71152)
			(xy 374.92686 -268.707108) (xy 374.926352 -268.706854) (xy 374.926098 -268.706854) (xy 374.902314 -268.695754)
			(xy 374.858445 -268.666945) (xy 374.819899 -268.631326) (xy 374.787723 -268.589863) (xy 374.76279 -268.543681)
			(xy 374.745774 -268.494033) (xy 374.73714 -268.442265) (xy 374.736614 -268.416024) (xy 374.736868 -268.4018)
			(xy 374.737122 -268.398752) (xy 374.738392 -268.387068) (xy 374.734582 -268.3764) (xy 374.732577 -268.371088)
			(xy 374.726552 -268.361468) (xy 374.722644 -268.35735) (xy 374.626124 -268.26083) (xy 374.622822 -268.257782)
			(xy 373.431308 -267.066268) (xy 373.426164 -267.061509) (xy 373.41393 -267.054685) (xy 373.407178 -267.052806)
			(xy 373.40032 -267.051028) (xy 373.386604 -267.05179) (xy 373.364252 -267.059156) (xy 373.358156 -267.06322)
			(xy 373.339614 -267.075496) (xy 373.299852 -267.095405) (xy 373.257743 -267.109696) (xy 373.235982 -267.114274)
			(xy 373.228108 -267.115798) (xy 373.217948 -267.121386) (xy 373.207405 -267.128159) (xy 373.194064 -267.149335)
			(xy 373.192548 -267.161772) (xy 373.192294 -267.165582) (xy 373.192294 -267.756386) (xy 373.19204 -267.758418)
			(xy 373.19204 -267.773658) (xy 373.162322 -267.803376) (xy 373.004588 -267.803376) (xy 372.993394 -267.803968)
			(xy 372.973118 -267.813465) (xy 372.965472 -267.821664) (xy 372.956654 -267.832108) (xy 372.937578 -267.851688)
			(xy 372.927372 -267.86078) (xy 372.927372 -267.86332) (xy 372.924578 -267.86332) (xy 372.906117 -267.878542)
			(xy 372.865718 -267.904178) (xy 372.822109 -267.923866) (xy 372.776161 -267.937211) (xy 372.728791 -267.943949)
			(xy 372.704868 -267.944346) (xy 372.678283 -267.943822) (xy 372.625769 -267.9355) (xy 372.575202 -267.919067)
			(xy 372.527829 -267.894926) (xy 372.484815 -267.863672) (xy 372.447219 -267.826074) (xy 372.415967 -267.783059)
			(xy 372.391828 -267.735685) (xy 372.375396 -267.685118) (xy 372.367077 -267.632603) (xy 372.36654 -267.606018)
			(xy 372.366926 -267.582198) (xy 372.373573 -267.535025) (xy 372.386782 -267.489253) (xy 372.406289 -267.445791)
			(xy 372.431708 -267.4055) (xy 372.446804 -267.38707) (xy 372.452352 -267.380037) (xy 372.458582 -267.363254)
			(xy 372.458996 -267.354304) (xy 372.458996 -267.351002) (xy 372.459158 -267.329803) (xy 372.46684 -267.288116)
			(xy 372.482576 -267.248758) (xy 372.505753 -267.213267) (xy 372.535462 -267.183033) (xy 372.570541 -267.159238)
			(xy 372.609618 -267.142814) (xy 372.651163 -267.134403) (xy 372.672356 -267.133832) (xy 372.830598 -267.133832)
			(xy 372.837266 -267.133638) (xy 372.85014 -267.130165) (xy 372.855998 -267.126974) (xy 372.861586 -267.123926)
			(xy 372.870476 -267.11529) (xy 372.874286 -267.10894) (xy 372.876318 -267.105638) (xy 372.902734 -267.055092)
			(xy 372.902734 -267.054838) (xy 372.91137 -267.038328) (xy 372.915434 -267.028676) (xy 372.916907 -267.023083)
			(xy 372.917555 -267.011537) (xy 372.916704 -267.005816) (xy 372.914926 -266.998704) (xy 372.909592 -266.982702)
			(xy 372.905528 -266.976606) (xy 372.892576 -266.956493) (xy 372.872084 -266.913266) (xy 372.858158 -266.867499)
			(xy 372.851099 -266.820185) (xy 372.850664 -266.796266) (xy 372.850664 -266.796012) (xy 372.850757 -266.781715)
			(xy 372.85317 -266.753224) (xy 372.85549 -266.739116) (xy 372.853458 -266.732258) (xy 372.796054 -266.668504)
			(xy 372.78851 -266.660991) (xy 372.769092 -266.652317) (xy 372.758462 -266.65174) (xy 372.656608 -266.65174)
			(xy 372.652544 -266.651994) (xy 372.63959 -266.653772) (xy 372.631535 -266.655665) (xy 372.617154 -266.66383)
			(xy 372.611396 -266.669774) (xy 372.611142 -266.670028) (xy 372.563898 -266.723114) (xy 372.557548 -266.730226)
			(xy 372.550944 -266.747498) (xy 372.550944 -266.76096) (xy 372.551198 -266.7635) (xy 372.552722 -266.794234)
			(xy 372.552722 -266.796774) (xy 372.552175 -266.821724) (xy 372.544262 -266.870995) (xy 372.52875 -266.918425)
			(xy 372.506021 -266.962851) (xy 372.476631 -267.00318) (xy 372.441302 -267.038425) (xy 372.400902 -267.067718)
			(xy 372.356423 -267.090341) (xy 372.308955 -267.105739) (xy 372.259665 -267.113534) (xy 372.209763 -267.113534)
			(xy 372.160473 -267.105739) (xy 372.113005 -267.090341) (xy 372.068526 -267.067718) (xy 372.028126 -267.038425)
			(xy 371.992797 -267.00318) (xy 371.963407 -266.962851) (xy 371.940678 -266.918425) (xy 371.925166 -266.870995)
			(xy 371.917253 -266.821724) (xy 371.916706 -266.796774) (xy 371.916706 -266.79525) (xy 371.918484 -266.762992)
			(xy 371.9195 -266.751562) (xy 371.912388 -266.730734) (xy 371.905276 -266.723114) (xy 371.854222 -266.666726)
			(xy 371.846874 -266.659925) (xy 371.828411 -266.652217) (xy 371.818408 -266.65174) (xy 371.715792 -266.65174)
			(xy 371.710966 -266.651994) (xy 371.701568 -266.653518) (xy 371.692985 -266.655263) (xy 371.677652 -266.663702)
			(xy 371.671596 -266.670028) (xy 371.629432 -266.717272) (xy 371.626043 -266.721279) (xy 371.620806 -266.730371)
			(xy 371.619018 -266.735306) (xy 371.615462 -266.746482) (xy 371.616732 -266.757658) (xy 371.616732 -266.757912)
			(xy 371.617778 -266.767275) (xy 371.618921 -266.786083) (xy 371.619018 -266.795504) (xy 371.619018 -266.796012)
			(xy 371.618498 -266.822046) (xy 371.610173 -266.873444) (xy 371.593737 -266.922849) (xy 371.569615 -266.968992)
			(xy 371.538426 -267.010685) (xy 371.500972 -267.046856) (xy 371.458218 -267.076574) (xy 371.411263 -267.099074)
			(xy 371.361315 -267.113779) (xy 371.335554 -267.117576) (xy 371.3353 -267.117576) (xy 371.325902 -267.118846)
			(xy 371.314726 -267.124688) (xy 371.310928 -267.126767) (xy 371.304031 -267.132) (xy 371.30101 -267.135102)
			(xy 371.29573 -267.141216) (xy 371.288884 -267.155836) (xy 371.287548 -267.163804) (xy 371.287294 -267.1699)
			(xy 371.287294 -267.756386) (xy 371.28704 -267.758418) (xy 371.28704 -267.773658) (xy 371.257322 -267.803376)
			(xy 371.136672 -267.803376) (xy 371.131091 -267.803527) (xy 371.1202 -267.805971) (xy 371.115082 -267.808202)
			(xy 371.087142 -267.82141) (xy 371.080284 -267.829538) (xy 371.064071 -267.847387) (xy 371.027476 -267.878783)
			(xy 370.986811 -267.904693) (xy 370.942892 -267.924597) (xy 370.896602 -267.938096) (xy 370.848869 -267.944918)
			(xy 370.82476 -267.945362) (xy 370.798096 -267.944836) (xy 370.745425 -267.936488) (xy 370.694707 -267.920004)
			(xy 370.647193 -267.895791) (xy 370.604051 -267.864443) (xy 370.566343 -267.826732) (xy 370.534998 -267.783588)
			(xy 370.510787 -267.736072) (xy 370.494307 -267.685354) (xy 370.485962 -267.632682) (xy 370.485416 -267.606018)
			(xy 370.485416 -267.605764) (xy 370.485895 -267.581456) (xy 370.492903 -267.533345) (xy 370.506685 -267.486721)
			(xy 370.526961 -267.442532) (xy 370.539772 -267.421868) (xy 370.54028 -267.421106) (xy 370.54536 -267.412978)
			(xy 370.55171 -267.392658) (xy 370.552765 -267.389001) (xy 370.553916 -267.381477) (xy 370.553996 -267.377672)
			(xy 370.553996 -267.35151) (xy 370.553996 -267.350748) (xy 370.554182 -267.329565) (xy 370.561901 -267.287919)
			(xy 370.577661 -267.248604) (xy 370.600845 -267.213158) (xy 370.63055 -267.182964) (xy 370.665613 -267.159203)
			(xy 370.704664 -267.142803) (xy 370.746179 -267.134405) (xy 370.767356 -267.133832) (xy 370.950744 -267.133832)
			(xy 370.95741 -267.133632) (xy 370.970278 -267.130149) (xy 370.976144 -267.126974) (xy 370.981732 -267.123926)
			(xy 370.990622 -267.11529) (xy 370.994432 -267.10894) (xy 370.996464 -267.105638) (xy 371.02288 -267.055092)
			(xy 371.02288 -267.054838) (xy 371.031516 -267.038328) (xy 371.03558 -267.028676) (xy 371.037052 -267.023083)
			(xy 371.037699 -267.011537) (xy 371.03685 -267.005816) (xy 371.035072 -266.998704) (xy 371.029738 -266.982702)
			(xy 371.025674 -266.976606) (xy 371.01272 -266.956494) (xy 370.992226 -266.913267) (xy 370.978298 -266.8675)
			(xy 370.971238 -266.820185) (xy 370.97081 -266.796266) (xy 370.97081 -266.796012) (xy 370.970903 -266.781715)
			(xy 370.973316 -266.753224) (xy 370.975636 -266.739116) (xy 370.973604 -266.732258) (xy 370.9162 -266.668504)
			(xy 370.908653 -266.660999) (xy 370.889234 -266.652346) (xy 370.878608 -266.65174) (xy 369.8367 -266.65174)
			(xy 369.832636 -266.651994) (xy 369.819682 -266.653772) (xy 369.811627 -266.655666) (xy 369.797248 -266.663833)
			(xy 369.791488 -266.669774) (xy 369.791234 -266.670028) (xy 369.74399 -266.723114) (xy 369.73764 -266.730226)
			(xy 369.731036 -266.747498) (xy 369.731036 -266.760706) (xy 369.73129 -266.762992) (xy 369.732052 -266.772898)
			(xy 369.732052 -266.773914) (xy 369.732814 -266.787884) (xy 369.732814 -266.788646) (xy 369.733068 -266.794488)
			(xy 369.733068 -266.796012) (xy 369.732625 -266.819786) (xy 369.725547 -266.866805) (xy 369.711551 -266.912246)
			(xy 369.690948 -266.955099) (xy 369.664197 -266.994408) (xy 369.631894 -267.029299) (xy 369.594758 -267.058994)
			(xy 369.553617 -267.082832) (xy 369.531646 -267.091922) (xy 369.514152 -267.098539) (xy 369.477989 -267.108085)
			(xy 369.45951 -267.110972) (xy 369.455446 -267.11148) (xy 369.445032 -267.114782) (xy 369.440714 -267.116052)
			(xy 369.427252 -267.12291) (xy 369.426998 -267.12291) (xy 369.424204 -267.124434) (xy 369.415822 -267.129514)
			(xy 369.410488 -267.13434) (xy 369.396772 -267.14831) (xy 369.39018 -267.155688) (xy 369.382711 -267.173987)
			(xy 369.382294 -267.18387) (xy 369.382294 -267.756386) (xy 369.38204 -267.758418) (xy 369.38204 -267.773658)
			(xy 369.352322 -267.803376) (xy 369.234466 -267.803376) (xy 369.22456 -267.804392) (xy 369.224306 -267.804392)
			(xy 369.212622 -267.806678) (xy 369.202208 -267.80998) (xy 369.181126 -267.819378) (xy 369.174014 -267.826744)
			(xy 369.155875 -267.844796) (xy 369.114902 -267.875452) (xy 369.069556 -267.899167) (xy 369.021004 -267.915329)
			(xy 368.970492 -267.923524) (xy 368.944906 -267.924026) (xy 368.919916 -267.923536) (xy 368.870551 -267.915719)
			(xy 368.823017 -267.900275) (xy 368.778484 -267.877586) (xy 368.738048 -267.84821) (xy 368.702706 -267.81287)
			(xy 368.673326 -267.772437) (xy 368.650634 -267.727905) (xy 368.635187 -267.680372) (xy 368.627366 -267.631008)
			(xy 368.626898 -267.606018) (xy 368.626898 -267.60551) (xy 368.627512 -267.577887) (xy 368.637091 -267.523477)
			(xy 368.645948 -267.497306) (xy 368.648996 -267.488924) (xy 368.648996 -267.35151) (xy 368.648996 -267.350748)
			(xy 368.649182 -267.329565) (xy 368.656901 -267.287919) (xy 368.672661 -267.248604) (xy 368.695845 -267.213158)
			(xy 368.72555 -267.182964) (xy 368.760613 -267.159203) (xy 368.799664 -267.142803) (xy 368.841179 -267.134405)
			(xy 368.862356 -267.133832) (xy 369.087654 -267.133832) (xy 369.117372 -267.16355) (xy 369.117372 -267.173964)
			(xy 369.118896 -267.17752) (xy 369.131342 -267.185648) (xy 369.137623 -267.189441) (xy 369.151694 -267.193574)
			(xy 369.159028 -267.193776) (xy 369.289838 -267.193776) (xy 369.299839 -267.193281) (xy 369.318314 -267.185614)
			(xy 369.332449 -267.171461) (xy 369.340093 -267.152977) (xy 369.340638 -267.142976) (xy 369.340638 -267.134848)
			(xy 369.335812 -267.120116) (xy 369.33124 -267.113512) (xy 369.326661 -267.107485) (xy 369.314642 -267.098296)
			(xy 369.307618 -267.095478) (xy 369.30711 -267.095224) (xy 369.284385 -267.086555) (xy 369.241664 -267.063309)
			(xy 369.20298 -267.033828) (xy 369.169237 -266.998802) (xy 369.14122 -266.959046) (xy 369.119583 -266.915487)
			(xy 369.104832 -266.869142) (xy 369.097309 -266.821091) (xy 369.096798 -266.796774) (xy 369.096798 -266.79525)
			(xy 369.098576 -266.762992) (xy 369.099592 -266.751562) (xy 369.09248 -266.730734) (xy 369.085368 -266.723114)
			(xy 369.034314 -266.666726) (xy 369.026971 -266.659911) (xy 369.008508 -266.652169) (xy 368.9985 -266.65174)
			(xy 368.896646 -266.65174) (xy 368.892582 -266.651994) (xy 368.879628 -266.653772) (xy 368.871569 -266.65566)
			(xy 368.85718 -266.663818) (xy 368.851434 -266.669774) (xy 368.85118 -266.670028) (xy 368.803936 -266.723114)
			(xy 368.797586 -266.730226) (xy 368.790982 -266.747498) (xy 368.790982 -266.76096) (xy 368.791236 -266.7635)
			(xy 368.79276 -266.794234) (xy 368.79276 -266.796774) (xy 368.792213 -266.821724) (xy 368.7843 -266.870995)
			(xy 368.768788 -266.918425) (xy 368.746059 -266.962851) (xy 368.716669 -267.00318) (xy 368.68134 -267.038425)
			(xy 368.64094 -267.067718) (xy 368.596461 -267.090341) (xy 368.548993 -267.105739) (xy 368.499703 -267.113534)
			(xy 368.449801 -267.113534) (xy 368.400511 -267.105739) (xy 368.353043 -267.090341) (xy 368.308564 -267.067718)
			(xy 368.268164 -267.038425) (xy 368.232835 -267.00318) (xy 368.203445 -266.962851) (xy 368.180716 -266.918425)
			(xy 368.165204 -266.870995) (xy 368.157291 -266.821724) (xy 368.156744 -266.796774) (xy 368.156744 -266.79525)
			(xy 368.158522 -266.762992) (xy 368.159538 -266.751562) (xy 368.152426 -266.730734) (xy 368.145314 -266.723114)
			(xy 368.09426 -266.666726) (xy 368.086914 -266.659919) (xy 368.068451 -266.652197) (xy 368.058446 -266.65174)
			(xy 367.955576 -266.65174) (xy 367.95075 -266.651994) (xy 367.941352 -266.653518) (xy 367.93277 -266.655265)
			(xy 367.917441 -266.663707) (xy 367.91138 -266.670028) (xy 367.869216 -266.717272) (xy 367.865822 -266.721276)
			(xy 367.860577 -266.730366) (xy 367.858802 -266.735306) (xy 367.855246 -266.746482) (xy 367.856516 -266.757658)
			(xy 367.856516 -266.757912) (xy 367.857562 -266.767275) (xy 367.858705 -266.786083) (xy 367.858802 -266.795504)
			(xy 367.858802 -266.796012) (xy 367.858329 -266.821216) (xy 367.850533 -266.871019) (xy 367.835117 -266.919012)
			(xy 367.812451 -266.964037) (xy 367.783083 -267.005008) (xy 367.747723 -267.040934) (xy 367.707224 -267.070949)
			(xy 367.662564 -267.094327) (xy 367.638838 -267.102844) (xy 367.636044 -267.10386) (xy 367.629532 -267.106742)
			(xy 367.618324 -267.115515) (xy 367.613946 -267.121132) (xy 367.613946 -267.121386) (xy 367.609541 -267.128017)
			(xy 367.604628 -267.14315) (xy 367.604294 -267.151104) (xy 367.604294 -267.756386) (xy 367.60404 -267.758418)
			(xy 367.60404 -267.773658) (xy 367.574322 -267.803376) (xy 367.389156 -267.803376) (xy 367.379747 -267.803778)
			(xy 367.36224 -267.810682) (xy 367.348475 -267.823515) (xy 367.340362 -267.840495) (xy 367.339372 -267.849858)
			(xy 367.339372 -267.86332) (xy 367.268252 -267.86332) (xy 367.26495 -267.86332) (xy 367.251742 -267.866114)
			(xy 367.242598 -267.869924) (xy 367.23828 -267.872718) (xy 367.218852 -267.884869) (xy 367.177245 -267.904065)
			(xy 367.133311 -267.917085) (xy 367.087963 -267.92366) (xy 367.065052 -267.924026) (xy 367.064798 -267.924026)
			(xy 367.039808 -267.923536) (xy 366.990445 -267.915717) (xy 366.942911 -267.900273) (xy 366.898379 -267.877583)
			(xy 366.857945 -267.848207) (xy 366.822603 -267.812867) (xy 366.793225 -267.772434) (xy 366.770533 -267.727903)
			(xy 366.755087 -267.680371) (xy 366.747266 -267.631008) (xy 366.74679 -267.606018) (xy 366.747327 -267.579839)
			(xy 366.755903 -267.528189) (xy 366.772811 -267.478637) (xy 366.797596 -267.432517) (xy 366.829589 -267.391071)
			(xy 366.84839 -267.372846) (xy 366.855248 -267.366496) (xy 366.87125 -267.333476) (xy 366.872266 -267.324586)
			(xy 366.872266 -267.324332) (xy 366.874779 -267.304959) (xy 366.885936 -267.267527) (xy 366.903723 -267.232751)
			(xy 366.927545 -267.201797) (xy 366.956606 -267.175698) (xy 366.989934 -267.155327) (xy 367.026413 -267.141366)
			(xy 367.064826 -267.134281) (xy 367.084356 -267.133832) (xy 367.190528 -267.133832) (xy 367.197195 -267.133634)
			(xy 367.210065 -267.130154) (xy 367.215928 -267.126974) (xy 367.221516 -267.123926) (xy 367.230406 -267.11529)
			(xy 367.234216 -267.10894) (xy 367.236248 -267.105638) (xy 367.262664 -267.055092) (xy 367.262664 -267.054838)
			(xy 367.2713 -267.038328) (xy 367.275364 -267.028676) (xy 367.276837 -267.023083) (xy 367.277483 -267.011537)
			(xy 367.276634 -267.005816) (xy 367.274856 -266.998704) (xy 367.269522 -266.982702) (xy 367.265458 -266.976606)
			(xy 367.252504 -266.956493) (xy 367.232011 -266.913266) (xy 367.218084 -266.8675) (xy 367.211024 -266.820185)
			(xy 367.210594 -266.796266) (xy 367.210594 -266.796012) (xy 367.210687 -266.781715) (xy 367.2131 -266.753224)
			(xy 367.21542 -266.739116) (xy 367.213388 -266.732258) (xy 367.155984 -266.668504) (xy 367.148437 -266.661002)
			(xy 367.129017 -266.652354) (xy 367.118392 -266.65174) (xy 366.076738 -266.65174) (xy 366.072674 -266.651994)
			(xy 366.05972 -266.653772) (xy 366.051662 -266.655661) (xy 366.037275 -266.663821) (xy 366.031526 -266.669774)
			(xy 366.031272 -266.670028) (xy 365.984028 -266.723114) (xy 365.977678 -266.730226) (xy 365.971074 -266.747498)
			(xy 365.971074 -266.76096) (xy 365.971328 -266.7635) (xy 365.972852 -266.794234) (xy 365.972852 -266.796774)
			(xy 365.972304 -266.821725) (xy 365.96439 -266.870997) (xy 365.948878 -266.918428) (xy 365.926148 -266.962855)
			(xy 365.896759 -267.003187) (xy 365.861431 -267.038434) (xy 365.821032 -267.067731) (xy 365.776553 -267.090358)
			(xy 365.729086 -267.105761) (xy 365.679796 -267.113562) (xy 365.654844 -267.11402) (xy 365.654082 -267.11402)
			(xy 365.631412 -267.113578) (xy 365.586539 -267.107071) (xy 365.564674 -267.101066) (xy 365.562134 -267.100304)
			(xy 365.557054 -267.099288) (xy 365.546777 -267.098106) (xy 365.526719 -267.10309) (xy 365.510242 -267.115567)
			(xy 365.500007 -267.133523) (xy 365.49838 -267.143738) (xy 365.498126 -267.14958) (xy 365.498126 -267.174726)
			(xy 365.498611 -267.184583) (xy 365.506159 -267.202794) (xy 365.520097 -267.216736) (xy 365.538307 -267.224287)
			(xy 365.548164 -267.224764) (xy 365.712248 -267.224764) (xy 365.722252 -267.22526) (xy 365.740734 -267.232927)
			(xy 365.75488 -267.247077) (xy 365.762543 -267.26556) (xy 365.763048 -267.275564) (xy 365.763048 -267.783056)
			(xy 365.762568 -267.793073) (xy 365.754918 -267.811588) (xy 365.740765 -267.825767) (xy 365.722264 -267.83345)
			(xy 365.712248 -267.833856) (xy 365.548164 -267.833856) (xy 365.538311 -267.834343) (xy 365.520108 -267.841894)
			(xy 365.506177 -267.855833) (xy 365.498637 -267.874041) (xy 365.498126 -267.883894) (xy 365.498126 -267.8938)
			(xy 365.335058 -267.8938) (xy 365.324136 -267.89507) (xy 365.314992 -267.897356) (xy 365.308134 -267.899134)
			(xy 365.305848 -267.90015) (xy 365.304832 -267.900658) (xy 365.276312 -267.911493) (xy 365.216458 -267.923265)
			(xy 365.18596 -267.924026) (xy 365.180372 -267.924026) (xy 365.155608 -267.923215) (xy 365.10677 -267.914864)
			(xy 365.05982 -267.899039) (xy 365.015892 -267.876123) (xy 364.97605 -267.84667) (xy 364.94126 -267.811393)
			(xy 364.912362 -267.771147) (xy 364.890057 -267.726905) (xy 364.874884 -267.67974) (xy 364.867212 -267.630791)
			(xy 364.866682 -267.606018) (xy 364.867223 -267.579363) (xy 364.876109 -267.526797) (xy 364.893636 -267.47645)
			(xy 364.919313 -267.42973) (xy 364.95242 -267.387946) (xy 364.992032 -267.352267) (xy 365.014256 -267.33754)
			(xy 365.02086 -267.333222) (xy 365.03356 -267.317982) (xy 365.034068 -267.317474) (xy 365.035846 -267.31468)
			(xy 365.043466 -267.302996) (xy 365.045244 -267.298424) (xy 365.053605 -267.279005) (xy 365.076805 -267.243668)
			(xy 365.1065 -267.213581) (xy 365.141531 -267.18992) (xy 365.180529 -267.173607) (xy 365.221974 -267.165279)
			(xy 365.24311 -267.16482) (xy 365.333788 -267.16482) (xy 365.341058 -267.164589) (xy 365.354995 -267.160455)
			(xy 365.36122 -267.156692) (xy 365.361474 -267.156692) (xy 365.36727 -267.152621) (xy 365.376541 -267.141919)
			(xy 365.379762 -267.13561) (xy 365.380016 -267.135356) (xy 365.398812 -267.09497) (xy 365.398812 -267.094462)
			(xy 365.417862 -267.054076) (xy 365.420743 -267.047421) (xy 365.422946 -267.033093) (xy 365.42218 -267.025882)
			(xy 365.421418 -267.01877) (xy 365.415576 -267.005816) (xy 365.41075 -266.999974) (xy 365.393382 -266.978312)
			(xy 365.365718 -266.930177) (xy 365.346848 -266.877964) (xy 365.337347 -266.823265) (xy 365.336836 -266.795504)
			(xy 365.336836 -266.790932) (xy 365.337344 -266.780772) (xy 365.337344 -266.779756) (xy 365.338614 -266.762992)
			(xy 365.33963 -266.751562) (xy 365.332518 -266.730734) (xy 365.325406 -266.723114) (xy 365.274352 -266.666726)
			(xy 365.267005 -266.65992) (xy 365.248542 -266.652201) (xy 365.238538 -266.65174) (xy 365.136684 -266.65174)
			(xy 365.13262 -266.651994) (xy 365.119666 -266.653772) (xy 365.111613 -266.655668) (xy 365.097237 -266.663838)
			(xy 365.091472 -266.669774) (xy 365.091218 -266.670028) (xy 365.043974 -266.723114) (xy 365.037624 -266.730226)
			(xy 365.03102 -266.747498) (xy 365.03102 -266.76096) (xy 365.031274 -266.7635) (xy 365.032798 -266.794234)
			(xy 365.032798 -266.796774) (xy 365.032251 -266.821724) (xy 365.024338 -266.870995) (xy 365.008826 -266.918425)
			(xy 364.986097 -266.962851) (xy 364.956707 -267.00318) (xy 364.921378 -267.038425) (xy 364.880978 -267.067718)
			(xy 364.836499 -267.090341) (xy 364.789031 -267.105739) (xy 364.739741 -267.113534) (xy 364.689839 -267.113534)
			(xy 364.640549 -267.105739) (xy 364.593081 -267.090341) (xy 364.548602 -267.067718) (xy 364.508202 -267.038425)
			(xy 364.472873 -267.00318) (xy 364.443483 -266.962851) (xy 364.420754 -266.918425) (xy 364.405242 -266.870995)
			(xy 364.397329 -266.821724) (xy 364.396782 -266.796774) (xy 364.396782 -266.79525) (xy 364.39856 -266.762992)
			(xy 364.399576 -266.751562) (xy 364.392464 -266.730734) (xy 364.385352 -266.723114) (xy 364.334298 -266.666726)
			(xy 364.326954 -266.659913) (xy 364.308491 -266.652177) (xy 364.298484 -266.65174) (xy 364.19663 -266.65174)
			(xy 364.192566 -266.651994) (xy 364.179612 -266.653772) (xy 364.171555 -266.655662) (xy 364.157169 -266.663823)
			(xy 364.151418 -266.669774) (xy 364.151164 -266.670028) (xy 364.10392 -266.723114) (xy 364.09757 -266.730226)
			(xy 364.090966 -266.747498) (xy 364.090966 -266.76096) (xy 364.09122 -266.7635) (xy 364.092744 -266.794234)
			(xy 364.092744 -266.796774) (xy 364.092196 -266.821724) (xy 364.084282 -266.870996) (xy 364.06877 -266.918427)
			(xy 364.04604 -266.962854) (xy 364.01665 -267.003185) (xy 363.981323 -267.038431) (xy 363.940923 -267.067726)
			(xy 363.896445 -267.090353) (xy 363.848978 -267.105755) (xy 363.799688 -267.113555) (xy 363.774736 -267.11402)
			(xy 363.77372 -267.11402) (xy 363.747775 -267.113441) (xy 363.696592 -267.104883) (xy 363.671866 -267.097002)
			(xy 363.670342 -267.096494) (xy 363.662722 -267.094462) (xy 363.655356 -267.093192) (xy 363.645606 -267.092389)
			(xy 363.626701 -267.097354) (xy 363.611042 -267.109052) (xy 363.600919 -267.125771) (xy 363.598968 -267.135356)
			(xy 363.59846 -267.138658) (xy 363.598206 -267.142468) (xy 363.598206 -267.174726) (xy 363.598624 -267.18459)
			(xy 363.606186 -267.202813) (xy 363.620146 -267.216754) (xy 363.638379 -267.224289) (xy 363.648244 -267.224764)
			(xy 363.812328 -267.224764) (xy 363.822335 -267.225256) (xy 363.840823 -267.23292) (xy 363.854976 -267.24707)
			(xy 363.862642 -267.265557) (xy 363.863128 -267.275564) (xy 363.863128 -267.783056) (xy 363.862717 -267.793085)
			(xy 363.855056 -267.811622) (xy 363.840883 -267.825815) (xy 363.822357 -267.833503) (xy 363.812328 -267.833856)
			(xy 363.648244 -267.833856) (xy 363.638367 -267.834262) (xy 363.620111 -267.841808) (xy 363.606137 -267.855769)
			(xy 363.598571 -267.874017) (xy 363.598206 -267.883894) (xy 363.598206 -267.8938) (xy 363.455204 -267.8938)
			(xy 363.444282 -267.89507) (xy 363.435138 -267.897356) (xy 363.42828 -267.899134) (xy 363.425994 -267.90015)
			(xy 363.424978 -267.900658) (xy 363.396458 -267.911488) (xy 363.336604 -267.92325) (xy 363.306106 -267.924026)
			(xy 363.300518 -267.924026) (xy 363.275751 -267.923219) (xy 363.226908 -267.914873) (xy 363.179952 -267.899052)
			(xy 363.136017 -267.876138) (xy 363.09617 -267.846686) (xy 363.061373 -267.811409) (xy 363.032471 -267.77116)
			(xy 363.010162 -267.726916) (xy 362.994987 -267.679746) (xy 362.987313 -267.630793) (xy 362.986828 -267.606018)
			(xy 362.98729 -267.581359) (xy 362.994894 -267.532632) (xy 363.009924 -267.485661) (xy 363.032019 -267.441571)
			(xy 363.06065 -267.401416) (xy 363.095133 -267.366158) (xy 363.11459 -267.351002) (xy 363.119162 -267.3477)
			(xy 363.127544 -267.337794) (xy 363.131097 -267.333513) (xy 363.136473 -267.323775) (xy 363.138212 -267.31849)
			(xy 363.13872 -267.316712) (xy 363.139482 -267.314426) (xy 363.139736 -267.313918) (xy 363.140498 -267.311886)
			(xy 363.141006 -267.310108) (xy 363.148618 -267.289275) (xy 363.171131 -267.25107) (xy 363.201037 -267.218326)
			(xy 363.237051 -267.192452) (xy 363.277625 -267.174558) (xy 363.321017 -267.165414) (xy 363.34319 -267.16482)
			(xy 363.45368 -267.16482) (xy 363.46095 -267.16459) (xy 363.474889 -267.160458) (xy 363.481112 -267.156692)
			(xy 363.481366 -267.156692) (xy 363.487163 -267.152622) (xy 363.496435 -267.14192) (xy 363.499654 -267.13561)
			(xy 363.499908 -267.135356) (xy 363.518704 -267.09497) (xy 363.518704 -267.094462) (xy 363.537754 -267.054076)
			(xy 363.540635 -267.047421) (xy 363.542839 -267.033093) (xy 363.542072 -267.025882) (xy 363.54131 -267.01877)
			(xy 363.535468 -267.005816) (xy 363.530642 -266.999974) (xy 363.513275 -266.978312) (xy 363.485611 -266.930176)
			(xy 363.466742 -266.877963) (xy 363.45724 -266.823265) (xy 363.456728 -266.795504) (xy 363.456728 -266.790932)
			(xy 363.457236 -266.780772) (xy 363.457236 -266.779756) (xy 363.458506 -266.762992) (xy 363.459522 -266.751562)
			(xy 363.45241 -266.730734) (xy 363.445298 -266.723114) (xy 363.394244 -266.666726) (xy 363.386897 -266.659922)
			(xy 363.368434 -266.652205) (xy 363.35843 -266.65174) (xy 362.316776 -266.65174) (xy 362.312712 -266.651994)
			(xy 362.299758 -266.653772) (xy 362.291705 -266.655669) (xy 362.277331 -266.663841) (xy 362.271564 -266.669774)
			(xy 362.27131 -266.670028) (xy 362.224066 -266.723114) (xy 362.217716 -266.730226) (xy 362.211112 -266.747498)
			(xy 362.211112 -266.760198) (xy 362.212058 -266.769121) (xy 362.213075 -266.787039) (xy 362.213144 -266.796012)
			(xy 362.212678 -266.821022) (xy 362.204851 -266.870426) (xy 362.189392 -266.917997) (xy 362.166681 -266.962564)
			(xy 362.137279 -267.00303) (xy 362.101907 -267.038398) (xy 362.061439 -267.067797) (xy 362.016869 -267.090504)
			(xy 361.969297 -267.105958) (xy 361.919892 -267.11378) (xy 361.894882 -267.114274) (xy 361.872077 -267.113881)
			(xy 361.826936 -267.107364) (xy 361.783188 -267.094465) (xy 361.762294 -267.085318) (xy 361.759246 -267.084048)
			(xy 361.743498 -267.084048) (xy 361.731942 -267.085795) (xy 361.712129 -267.098141) (xy 361.699789 -267.117959)
			(xy 361.698032 -267.129514) (xy 361.698032 -267.178282) (xy 361.699003 -267.187238) (xy 361.706435 -267.203633)
			(xy 361.71251 -267.210286) (xy 361.719828 -267.216848) (xy 361.737998 -267.224296) (xy 361.747816 -267.224764)
			(xy 361.932982 -267.224764) (xy 361.9627 -267.254482) (xy 361.9627 -267.269722) (xy 361.962954 -267.271754)
			(xy 361.962954 -267.786866) (xy 361.9627 -267.788898) (xy 361.9627 -267.804138) (xy 361.932982 -267.833856)
			(xy 361.747816 -267.833856) (xy 361.737997 -267.83432) (xy 361.719828 -267.841771) (xy 361.71251 -267.848334)
			(xy 361.706436 -267.854985) (xy 361.699017 -267.871385) (xy 361.698032 -267.880338) (xy 361.698032 -267.8938)
			(xy 361.575096 -267.8938) (xy 361.564174 -267.89507) (xy 361.55503 -267.897356) (xy 361.548172 -267.899134)
			(xy 361.545886 -267.90015) (xy 361.54487 -267.900658) (xy 361.51635 -267.911487) (xy 361.456495 -267.923248)
			(xy 361.425998 -267.924026) (xy 361.42041 -267.924026) (xy 361.395644 -267.923218) (xy 361.346802 -267.914872)
			(xy 361.299846 -267.89905) (xy 361.255913 -267.876135) (xy 361.216066 -267.846683) (xy 361.181271 -267.811406)
			(xy 361.152369 -267.771158) (xy 361.130061 -267.726914) (xy 361.114886 -267.679745) (xy 361.107212 -267.630793)
			(xy 361.10672 -267.606018) (xy 361.107266 -267.579299) (xy 361.116195 -267.526614) (xy 361.133806 -267.476162)
			(xy 361.159602 -267.429364) (xy 361.192858 -267.387536) (xy 361.212384 -267.36929) (xy 361.21848 -267.363956)
			(xy 361.233466 -267.337286) (xy 361.234736 -267.331698) (xy 361.235244 -267.32992) (xy 361.240338 -267.310088)
			(xy 361.257046 -267.27271) (xy 361.280568 -267.2392) (xy 361.310043 -267.210785) (xy 361.344392 -267.188505)
			(xy 361.382356 -267.173176) (xy 361.422545 -267.165361) (xy 361.443016 -267.16482) (xy 361.573826 -267.16482)
			(xy 361.581094 -267.164584) (xy 361.595026 -267.160441) (xy 361.601258 -267.156692) (xy 361.601512 -267.156692)
			(xy 361.607314 -267.152625) (xy 361.616595 -267.141928) (xy 361.6198 -267.13561) (xy 361.620054 -267.135356)
			(xy 361.63885 -267.09497) (xy 361.63885 -267.094462) (xy 361.6579 -267.054076) (xy 361.660779 -267.04742)
			(xy 361.662981 -267.033093) (xy 361.662218 -267.025882) (xy 361.66044 -267.011912) (xy 361.654598 -267.0048)
			(xy 361.639957 -266.987343) (xy 361.615295 -266.949033) (xy 361.596343 -266.9076) (xy 361.583489 -266.863889)
			(xy 361.576995 -266.818793) (xy 361.57662 -266.796012) (xy 361.576672 -266.786273) (xy 361.577818 -266.766828)
			(xy 361.578906 -266.75715) (xy 361.579414 -266.751308) (xy 361.572556 -266.730988) (xy 361.56773 -266.725654)
			(xy 361.565444 -266.723114) (xy 361.540806 -266.695682) (xy 361.514644 -266.666726) (xy 361.507423 -266.660071)
			(xy 361.489392 -266.65234) (xy 361.479592 -266.65174) (xy 358.56291 -266.65174) (xy 358.558846 -266.651994)
			(xy 358.545892 -266.653772) (xy 358.537836 -266.655665) (xy 358.523455 -266.66383) (xy 358.517698 -266.669774)
			(xy 358.517444 -266.670028) (xy 358.4702 -266.723114) (xy 358.46385 -266.730226) (xy 358.457246 -266.747498)
			(xy 358.457246 -266.76096) (xy 358.4575 -266.7635) (xy 358.459024 -266.791694) (xy 358.459024 -266.794996)
			(xy 358.458635 -266.820039) (xy 358.450941 -266.869529) (xy 358.435585 -266.9172) (xy 358.412947 -266.961876)
			(xy 358.383586 -267.002451) (xy 358.348228 -267.037922) (xy 358.307747 -267.067413) (xy 358.263144 -267.090195)
			(xy 358.215522 -267.105703) (xy 358.166058 -267.113556) (xy 358.141016 -267.11402) (xy 358.119787 -267.113669)
			(xy 358.077705 -267.108023) (xy 358.036749 -267.09683) (xy 358.017064 -267.088874) (xy 358.015032 -267.087858)
			(xy 358.011984 -267.086842) (xy 358.002078 -267.08481) (xy 357.990876 -267.083137) (xy 357.968911 -267.088546)
			(xy 357.951387 -267.102849) (xy 357.941686 -267.123284) (xy 357.941118 -267.134594) (xy 357.941118 -267.174726)
			(xy 357.941603 -267.184583) (xy 357.94915 -267.202796) (xy 357.963089 -267.21674) (xy 357.981299 -267.224294)
			(xy 357.991156 -267.224764) (xy 358.176322 -267.224764) (xy 358.20604 -267.254482) (xy 358.20604 -267.269722)
			(xy 358.206294 -267.271754) (xy 358.206294 -267.786866) (xy 358.20604 -267.788898) (xy 358.20604 -267.804138)
			(xy 358.176322 -267.833856) (xy 357.983028 -267.833856) (xy 357.975702 -267.83412) (xy 357.96164 -267.838234)
			(xy 357.955342 -267.841984) (xy 357.942896 -267.850112) (xy 357.941372 -267.853668) (xy 357.941372 -267.864082)
			(xy 357.911654 -267.8938) (xy 357.81742 -267.8938) (xy 357.81226 -267.893896) (xy 357.802147 -267.895948)
			(xy 357.797354 -267.897864) (xy 357.777422 -267.906091) (xy 357.735896 -267.917706) (xy 357.693183 -267.923616)
			(xy 357.671624 -267.924026) (xy 357.670608 -267.924026) (xy 357.645644 -267.923499) (xy 357.596339 -267.91562)
			(xy 357.548871 -267.900132) (xy 357.504407 -267.877417) (xy 357.464039 -267.848032) (xy 357.42876 -267.8127)
			(xy 357.399435 -267.772288) (xy 357.376786 -267.72779) (xy 357.361369 -267.6803) (xy 357.353563 -267.630983)
			(xy 357.353108 -267.606018) (xy 357.352854 -267.606018) (xy 357.353393 -267.579752) (xy 357.362028 -267.527934)
			(xy 357.379066 -267.478241) (xy 357.404043 -267.432027) (xy 357.436279 -267.390548) (xy 357.455216 -267.372338)
			(xy 357.460804 -267.367258) (xy 357.476552 -267.339318) (xy 357.478076 -267.331952) (xy 357.483016 -267.311919)
			(xy 357.499522 -267.274109) (xy 357.522979 -267.240171) (xy 357.552514 -267.211367) (xy 357.58703 -267.188769)
			(xy 357.625242 -267.173217) (xy 357.665728 -267.165289) (xy 357.686356 -267.16482) (xy 357.817674 -267.16482)
			(xy 357.831085 -267.164416) (xy 357.856984 -267.157437) (xy 357.880171 -267.143954) (xy 357.899047 -267.124897)
			(xy 357.912308 -267.101582) (xy 357.919039 -267.075618) (xy 357.919274 -267.062204) (xy 357.919274 -267.061696)
			(xy 357.918428 -267.04609) (xy 357.908458 -267.016487) (xy 357.899716 -267.00353) (xy 357.897684 -267.000736)
			(xy 357.880316 -266.979158) (xy 357.852543 -266.93124) (xy 357.833485 -266.879236) (xy 357.82372 -266.824719)
			(xy 357.823008 -266.797028) (xy 357.823008 -266.796774) (xy 357.823008 -266.795504) (xy 357.824786 -266.762992)
			(xy 357.825802 -266.751562) (xy 357.81869 -266.730734) (xy 357.811578 -266.723114) (xy 357.760524 -266.666726)
			(xy 357.753176 -266.659925) (xy 357.734713 -266.652216) (xy 357.72471 -266.65174) (xy 357.62311 -266.65174)
			(xy 357.619046 -266.651994) (xy 357.606092 -266.653772) (xy 357.598036 -266.655665) (xy 357.583655 -266.66383)
			(xy 357.577898 -266.669774) (xy 357.577644 -266.670028) (xy 357.5304 -266.723114) (xy 357.52405 -266.730226)
			(xy 357.517446 -266.747498) (xy 357.517446 -266.76096) (xy 357.5177 -266.7635) (xy 357.519224 -266.794234)
			(xy 357.519224 -266.796774) (xy 357.518677 -266.821724) (xy 357.510764 -266.870995) (xy 357.495252 -266.918425)
			(xy 357.472523 -266.962851) (xy 357.443133 -267.00318) (xy 357.407804 -267.038425) (xy 357.367404 -267.067718)
			(xy 357.322925 -267.090341) (xy 357.275457 -267.105739) (xy 357.226167 -267.113534) (xy 357.176265 -267.113534)
			(xy 357.126975 -267.105739) (xy 357.079507 -267.090341) (xy 357.035028 -267.067718) (xy 356.994628 -267.038425)
			(xy 356.959299 -267.00318) (xy 356.929909 -266.962851) (xy 356.90718 -266.918425) (xy 356.891668 -266.870995)
			(xy 356.883755 -266.821724) (xy 356.883208 -266.796774) (xy 356.883208 -266.79525) (xy 356.884986 -266.762992)
			(xy 356.886002 -266.751562) (xy 356.87889 -266.730734) (xy 356.871778 -266.723114) (xy 356.820724 -266.666726)
			(xy 356.813376 -266.659925) (xy 356.794913 -266.652216) (xy 356.78491 -266.65174) (xy 355.743002 -266.65174)
			(xy 355.738938 -266.651994) (xy 355.725984 -266.653772) (xy 355.717929 -266.655666) (xy 355.703549 -266.663832)
			(xy 355.69779 -266.669774) (xy 355.697536 -266.670028) (xy 355.650292 -266.723114) (xy 355.643942 -266.730226)
			(xy 355.637338 -266.747498) (xy 355.637338 -266.76096) (xy 355.637592 -266.7635) (xy 355.639116 -266.794234)
			(xy 355.639116 -266.796774) (xy 355.638569 -266.821724) (xy 355.630656 -266.870995) (xy 355.615144 -266.918425)
			(xy 355.592415 -266.962851) (xy 355.563025 -267.00318) (xy 355.527696 -267.038425) (xy 355.487296 -267.067718)
			(xy 355.442817 -267.090341) (xy 355.395349 -267.105739) (xy 355.346059 -267.113534) (xy 355.296157 -267.113534)
			(xy 355.246867 -267.105739) (xy 355.199399 -267.090341) (xy 355.15492 -267.067718) (xy 355.11452 -267.038425)
			(xy 355.079191 -267.00318) (xy 355.049801 -266.962851) (xy 355.027072 -266.918425) (xy 355.01156 -266.870995)
			(xy 355.003647 -266.821724) (xy 355.0031 -266.796774) (xy 355.0031 -266.79525) (xy 355.004878 -266.762992)
			(xy 355.005894 -266.751562) (xy 354.998782 -266.730734) (xy 354.99167 -266.723114) (xy 354.940616 -266.666726)
			(xy 354.933267 -266.659926) (xy 354.914804 -266.65222) (xy 354.904802 -266.65174) (xy 354.802948 -266.65174)
			(xy 354.798884 -266.651994) (xy 354.78593 -266.653772) (xy 354.777871 -266.65566) (xy 354.763482 -266.663817)
			(xy 354.757736 -266.669774) (xy 354.757482 -266.670028) (xy 354.710238 -266.723114) (xy 354.703888 -266.730226)
			(xy 354.697284 -266.747498) (xy 354.697284 -266.76096) (xy 354.697538 -266.7635) (xy 354.699062 -266.794234)
			(xy 354.699062 -266.796774) (xy 354.698515 -266.821724) (xy 354.690602 -266.870995) (xy 354.67509 -266.918425)
			(xy 354.652361 -266.962851) (xy 354.622971 -267.00318) (xy 354.587642 -267.038425) (xy 354.547242 -267.067718)
			(xy 354.502763 -267.090341) (xy 354.455295 -267.105739) (xy 354.406005 -267.113534) (xy 354.356103 -267.113534)
			(xy 354.306813 -267.105739) (xy 354.259345 -267.090341) (xy 354.214866 -267.067718) (xy 354.174466 -267.038425)
			(xy 354.139137 -267.00318) (xy 354.109747 -266.962851) (xy 354.087018 -266.918425) (xy 354.071506 -266.870995)
			(xy 354.063593 -266.821724) (xy 354.063046 -266.796774) (xy 354.063046 -266.79525) (xy 354.064824 -266.762992)
			(xy 354.06584 -266.751562) (xy 354.058728 -266.730734) (xy 354.051616 -266.723114) (xy 354.000562 -266.666726)
			(xy 353.993216 -266.659918) (xy 353.974753 -266.652196) (xy 353.964748 -266.65174) (xy 353.862894 -266.65174)
			(xy 353.85883 -266.651994) (xy 353.845876 -266.653772) (xy 353.837822 -266.655667) (xy 353.823444 -266.663835)
			(xy 353.817682 -266.669774) (xy 353.817428 -266.670028) (xy 353.770184 -266.723114) (xy 353.763834 -266.730226)
			(xy 353.75723 -266.747498) (xy 353.75723 -266.76096) (xy 353.757484 -266.7635) (xy 353.759008 -266.794234)
			(xy 353.759008 -266.796774) (xy 353.758461 -266.821724) (xy 353.750548 -266.870995) (xy 353.735036 -266.918425)
			(xy 353.712307 -266.962851) (xy 353.682917 -267.00318) (xy 353.647588 -267.038425) (xy 353.607188 -267.067718)
			(xy 353.562709 -267.090341) (xy 353.515241 -267.105739) (xy 353.465951 -267.113534) (xy 353.416049 -267.113534)
			(xy 353.366759 -267.105739) (xy 353.319291 -267.090341) (xy 353.274812 -267.067718) (xy 353.234412 -267.038425)
			(xy 353.199083 -267.00318) (xy 353.169693 -266.962851) (xy 353.146964 -266.918425) (xy 353.131452 -266.870995)
			(xy 353.123539 -266.821724) (xy 353.122992 -266.796774) (xy 353.122992 -266.79525) (xy 353.12477 -266.762992)
			(xy 353.125786 -266.751562) (xy 353.118674 -266.730734) (xy 353.111562 -266.723114) (xy 353.060508 -266.666726)
			(xy 353.053164 -266.659912) (xy 353.034702 -266.652172) (xy 353.024694 -266.65174) (xy 351.98304 -266.65174)
			(xy 351.978976 -266.651994) (xy 351.966022 -266.653772) (xy 351.957964 -266.655661) (xy 351.943576 -266.66382)
			(xy 351.937828 -266.669774) (xy 351.937574 -266.670028) (xy 351.89033 -266.723114) (xy 351.88398 -266.730226)
			(xy 351.877376 -266.747498) (xy 351.877376 -266.76096) (xy 351.87763 -266.7635) (xy 351.879154 -266.794234)
			(xy 351.879154 -266.796774) (xy 351.878607 -266.821724) (xy 351.870694 -266.870995) (xy 351.855182 -266.918425)
			(xy 351.832453 -266.962851) (xy 351.803063 -267.00318) (xy 351.767734 -267.038425) (xy 351.727334 -267.067718)
			(xy 351.682855 -267.090341) (xy 351.635387 -267.105739) (xy 351.586097 -267.113534) (xy 351.536195 -267.113534)
			(xy 351.486905 -267.105739) (xy 351.439437 -267.090341) (xy 351.394958 -267.067718) (xy 351.354558 -267.038425)
			(xy 351.319229 -267.00318) (xy 351.289839 -266.962851) (xy 351.26711 -266.918425) (xy 351.251598 -266.870995)
			(xy 351.243685 -266.821724) (xy 351.243138 -266.796774) (xy 351.243138 -266.79525) (xy 351.244916 -266.762992)
			(xy 351.245932 -266.751562) (xy 351.23882 -266.730734) (xy 351.231708 -266.723114) (xy 351.180654 -266.666726)
			(xy 351.173308 -266.65992) (xy 351.154845 -266.6522) (xy 351.14484 -266.65174) (xy 351.042986 -266.65174)
			(xy 351.038922 -266.651994) (xy 351.025968 -266.653772) (xy 351.017914 -266.655668) (xy 351.003538 -266.663838)
			(xy 350.997774 -266.669774) (xy 350.99752 -266.670028) (xy 350.950276 -266.723114) (xy 350.943926 -266.730226)
			(xy 350.937322 -266.747498) (xy 350.937322 -266.76096) (xy 350.937576 -266.7635) (xy 350.9391 -266.794234)
			(xy 350.9391 -266.796774) (xy 350.938553 -266.821724) (xy 350.93064 -266.870995) (xy 350.915128 -266.918425)
			(xy 350.892399 -266.962851) (xy 350.863009 -267.00318) (xy 350.82768 -267.038425) (xy 350.78728 -267.067718)
			(xy 350.742801 -267.090341) (xy 350.695333 -267.105739) (xy 350.646043 -267.113534) (xy 350.596141 -267.113534)
			(xy 350.546851 -267.105739) (xy 350.499383 -267.090341) (xy 350.454904 -267.067718) (xy 350.414504 -267.038425)
			(xy 350.379175 -267.00318) (xy 350.349785 -266.962851) (xy 350.327056 -266.918425) (xy 350.311544 -266.870995)
			(xy 350.303631 -266.821724) (xy 350.303084 -266.796774) (xy 350.303084 -266.79525) (xy 350.304862 -266.762992)
			(xy 350.305878 -266.751562) (xy 350.298766 -266.730734) (xy 350.291654 -266.723114) (xy 350.2406 -266.666726)
			(xy 350.233256 -266.659913) (xy 350.214793 -266.652176) (xy 350.204786 -266.65174) (xy 350.102932 -266.65174)
			(xy 350.098868 -266.651994) (xy 350.085914 -266.653772) (xy 350.077857 -266.655662) (xy 350.063471 -266.663823)
			(xy 350.05772 -266.669774) (xy 350.057466 -266.670028) (xy 350.010222 -266.723114) (xy 350.003872 -266.730226)
			(xy 349.997268 -266.747498) (xy 349.997268 -266.76096) (xy 349.997522 -266.7635) (xy 349.999046 -266.794234)
			(xy 349.999046 -266.796774) (xy 349.998499 -266.821724) (xy 349.990586 -266.870995) (xy 349.975074 -266.918425)
			(xy 349.952345 -266.962851) (xy 349.922955 -267.00318) (xy 349.887626 -267.038425) (xy 349.847226 -267.067718)
			(xy 349.802747 -267.090341) (xy 349.755279 -267.105739) (xy 349.705989 -267.113534) (xy 349.656087 -267.113534)
			(xy 349.606797 -267.105739) (xy 349.559329 -267.090341) (xy 349.51485 -267.067718) (xy 349.47445 -267.038425)
			(xy 349.439121 -267.00318) (xy 349.409731 -266.962851) (xy 349.387002 -266.918425) (xy 349.37149 -266.870995)
			(xy 349.363577 -266.821724) (xy 349.36303 -266.796774) (xy 349.36303 -266.79525) (xy 349.364808 -266.762992)
			(xy 349.365824 -266.751562) (xy 349.358712 -266.730734) (xy 349.3516 -266.723114) (xy 349.300546 -266.666726)
			(xy 349.293199 -266.659921) (xy 349.274736 -266.652204) (xy 349.264732 -266.65174) (xy 349.196152 -266.65174)
			(xy 349.187606 -266.651403) (xy 349.171494 -266.645699) (xy 349.164656 -266.640564) (xy 349.164402 -266.64031)
			(xy 349.158052 -266.63523) (xy 349.150432 -266.632182) (xy 349.145865 -266.630426) (xy 349.136273 -266.628503)
			(xy 349.131382 -266.628372) (xy 348.213934 -266.628372) (xy 348.208854 -266.628626) (xy 348.199482 -266.629948)
			(xy 348.182644 -266.638563) (xy 348.176088 -266.64539) (xy 348.137734 -266.690348) (xy 348.137734 -266.690856)
			(xy 348.125796 -266.70508) (xy 348.120395 -266.712565) (xy 348.114797 -266.73014) (xy 348.114874 -266.73937)
			(xy 348.115128 -266.743434) (xy 348.115382 -266.744704) (xy 348.115636 -266.746482) (xy 348.117368 -266.758726)
			(xy 348.11915 -266.783392) (xy 348.119192 -266.795758) (xy 348.119192 -266.796266) (xy 348.118682 -266.821241)
			(xy 348.11083 -266.870571) (xy 348.095362 -266.918067) (xy 348.072658 -266.96256) (xy 348.043277 -267.002955)
			(xy 348.007941 -267.03826) (xy 347.967519 -267.067606) (xy 347.923006 -267.090271) (xy 347.875496 -267.105696)
			(xy 347.826159 -267.113504) (xy 347.801184 -267.11402) (xy 347.776195 -267.113528) (xy 347.726833 -267.105708)
			(xy 347.679303 -267.090263) (xy 347.634773 -267.067572) (xy 347.594341 -267.038196) (xy 347.559002 -267.002856)
			(xy 347.529625 -266.962424) (xy 347.506936 -266.917894) (xy 347.491491 -266.870363) (xy 347.483671 -266.821001)
			(xy 347.483176 -266.796012) (xy 347.483261 -266.783901) (xy 347.48504 -266.759745) (xy 347.486732 -266.747752)
			(xy 347.486986 -266.746228) (xy 347.48724 -266.743434) (xy 347.487494 -266.738608) (xy 347.487557 -266.72935)
			(xy 347.481816 -266.711768) (xy 347.476318 -266.704318) (xy 347.464634 -266.690602) (xy 347.425264 -266.644374)
			(xy 347.418438 -266.637729) (xy 347.401208 -266.629639) (xy 347.391736 -266.628626) (xy 347.38818 -266.628372)
			(xy 347.325696 -266.628372) (xy 347.316294 -266.628784) (xy 347.298806 -266.635699) (xy 347.285058 -266.648531)
			(xy 347.276956 -266.665502) (xy 347.275912 -266.674854) (xy 347.275912 -266.79017) (xy 347.275404 -266.803124)
			(xy 347.275404 -266.89431) (xy 347.274914 -266.909293) (xy 347.267156 -266.938237) (xy 347.252172 -266.964187)
			(xy 347.230983 -266.985376) (xy 347.205031 -267.000358) (xy 347.176087 -267.008115) (xy 347.161104 -267.00861)
			(xy 347.119448 -267.00861) (xy 347.114557 -267.008747) (xy 347.104965 -267.010665) (xy 347.100398 -267.01242)
			(xy 347.091508 -267.015976) (xy 347.084142 -267.023088) (xy 347.072315 -267.034373) (xy 347.046738 -267.054734)
			(xy 347.033088 -267.063728) (xy 347.032834 -267.063982) (xy 347.0275 -267.067538) (xy 347.024706 -267.070332)
			(xy 347.023436 -267.071856) (xy 347.015308 -267.082778) (xy 347.012768 -267.08735) (xy 347.009065 -267.094642)
			(xy 347.006075 -267.110712) (xy 347.006926 -267.118846) (xy 347.008772 -267.128529) (xy 347.018684 -267.145547)
			(xy 347.034261 -267.157599) (xy 347.053223 -267.162921) (xy 347.06306 -267.16228) (xy 347.06814 -267.161518)
			(xy 347.083126 -267.160502) (xy 347.542104 -267.160502) (xy 347.557159 -267.16095) (xy 347.586243 -267.168744)
			(xy 347.612318 -267.183801) (xy 347.633608 -267.205093) (xy 347.648661 -267.23117) (xy 347.656452 -267.260255)
			(xy 347.656912 -267.27531) (xy 347.656912 -267.606018) (xy 347.953076 -267.606018) (xy 347.953593 -267.578792)
			(xy 347.962858 -267.525133) (xy 347.981138 -267.473841) (xy 348.007895 -267.426416) (xy 348.042348 -267.384249)
			(xy 348.06255 -267.365988) (xy 348.06867 -267.360154) (xy 348.077099 -267.34551) (xy 348.07906 -267.337286)
			(xy 348.083606 -267.316762) (xy 348.099536 -267.277871) (xy 348.122772 -267.242852) (xy 348.152415 -267.213059)
			(xy 348.187316 -267.189645) (xy 348.226126 -267.173518) (xy 348.267342 -267.165301) (xy 348.288356 -267.16482)
			(xy 348.543372 -267.16482) (xy 348.543372 -267.173964) (xy 348.543848 -267.18398) (xy 348.551501 -267.20249)
			(xy 348.565656 -267.216663) (xy 348.584157 -267.224339) (xy 348.594172 -267.224764) (xy 348.75724 -267.224764)
			(xy 348.767246 -267.225254) (xy 348.785732 -267.23292) (xy 348.799882 -267.247072) (xy 348.807546 -267.265558)
			(xy 348.80804 -267.275564) (xy 348.80804 -267.60678) (xy 349.833184 -267.60678) (xy 349.833184 -267.606018)
			(xy 349.833739 -267.579744) (xy 349.842424 -267.527917) (xy 349.850456 -267.502894) (xy 349.852996 -267.494766)
			(xy 349.852996 -267.37945) (xy 349.853388 -267.358403) (xy 349.861386 -267.317082) (xy 349.87732 -267.278127)
			(xy 349.900571 -267.243045) (xy 349.930242 -267.213194) (xy 349.965182 -267.18973) (xy 350.00404 -267.173561)
			(xy 350.045312 -267.165312) (xy 350.066356 -267.16482) (xy 350.321372 -267.16482) (xy 350.321372 -267.173964)
			(xy 350.321848 -267.18398) (xy 350.329501 -267.20249) (xy 350.343656 -267.216663) (xy 350.362157 -267.224339)
			(xy 350.372172 -267.224764) (xy 350.53524 -267.224764) (xy 350.545246 -267.225254) (xy 350.563732 -267.23292)
			(xy 350.577882 -267.247072) (xy 350.585546 -267.265558) (xy 350.58604 -267.275564) (xy 350.58604 -267.606018)
			(xy 351.713038 -267.606018) (xy 351.713574 -267.579556) (xy 351.722375 -267.527367) (xy 351.739687 -267.477354)
			(xy 351.7519 -267.453872) (xy 351.7519 -267.453364) (xy 351.75469 -267.44779) (xy 351.757781 -267.435718)
			(xy 351.757996 -267.429488) (xy 351.757996 -267.37945) (xy 351.758388 -267.358403) (xy 351.766386 -267.317082)
			(xy 351.78232 -267.278127) (xy 351.805571 -267.243045) (xy 351.835242 -267.213194) (xy 351.870182 -267.18973)
			(xy 351.90904 -267.173561) (xy 351.950312 -267.165312) (xy 351.971356 -267.16482) (xy 352.226372 -267.16482)
			(xy 352.226372 -267.173964) (xy 352.226848 -267.18398) (xy 352.234501 -267.20249) (xy 352.248656 -267.216663)
			(xy 352.267157 -267.224339) (xy 352.277172 -267.224764) (xy 352.44024 -267.224764) (xy 352.450246 -267.225254)
			(xy 352.468732 -267.23292) (xy 352.482882 -267.247072) (xy 352.490546 -267.265558) (xy 352.49104 -267.275564)
			(xy 352.49104 -267.606018) (xy 353.593146 -267.606018) (xy 353.593661 -267.581133) (xy 353.601463 -267.531977)
			(xy 353.616831 -267.484638) (xy 353.63939 -267.440272) (xy 353.653598 -267.419836) (xy 353.653598 -267.419328)
			(xy 353.65817 -267.412978) (xy 353.662996 -267.398246) (xy 353.662996 -267.37945) (xy 353.663388 -267.358403)
			(xy 353.671386 -267.317082) (xy 353.68732 -267.278127) (xy 353.710571 -267.243045) (xy 353.740242 -267.213194)
			(xy 353.775182 -267.18973) (xy 353.81404 -267.173561) (xy 353.855312 -267.165312) (xy 353.876356 -267.16482)
			(xy 354.131372 -267.16482) (xy 354.131372 -267.173964) (xy 354.131848 -267.18398) (xy 354.139501 -267.20249)
			(xy 354.153656 -267.216663) (xy 354.172157 -267.224339) (xy 354.182172 -267.224764) (xy 354.34524 -267.224764)
			(xy 354.355246 -267.225254) (xy 354.373732 -267.23292) (xy 354.387882 -267.247072) (xy 354.395546 -267.265558)
			(xy 354.39604 -267.275564) (xy 354.39604 -267.606018) (xy 355.473 -267.606018) (xy 355.4734 -267.582554)
			(xy 355.480289 -267.536134) (xy 355.493921 -267.49123) (xy 355.514001 -267.448814) (xy 355.540092 -267.409807)
			(xy 355.55555 -267.39215) (xy 355.560926 -267.385697) (xy 355.567533 -267.370267) (xy 355.568504 -267.361924)
			(xy 355.570441 -267.342063) (xy 355.580849 -267.303543) (xy 355.598225 -267.267624) (xy 355.621966 -267.235554)
			(xy 355.651246 -267.208446) (xy 355.685049 -267.187244) (xy 355.722198 -267.172683) (xy 355.761405 -267.16527)
			(xy 355.781356 -267.16482) (xy 356.036372 -267.16482) (xy 356.036372 -267.173964) (xy 356.036848 -267.18398)
			(xy 356.044501 -267.20249) (xy 356.058656 -267.216663) (xy 356.077157 -267.224339) (xy 356.087172 -267.224764)
			(xy 356.25024 -267.224764) (xy 356.260246 -267.225254) (xy 356.278732 -267.23292) (xy 356.292882 -267.247072)
			(xy 356.300546 -267.265558) (xy 356.30104 -267.275564) (xy 356.30104 -267.783056) (xy 356.300545 -267.79307)
			(xy 356.292897 -267.811578) (xy 356.278748 -267.82575) (xy 356.260253 -267.833429) (xy 356.25024 -267.833856)
			(xy 356.036372 -267.833856) (xy 356.036372 -267.843) (xy 356.03598 -267.853025) (xy 356.028305 -267.871547)
			(xy 356.014124 -267.88572) (xy 355.995597 -267.893385) (xy 355.985572 -267.8938) (xy 355.92639 -267.8938)
			(xy 355.916738 -267.898118) (xy 355.896799 -267.906306) (xy 355.855268 -267.917844) (xy 355.81256 -267.923667)
			(xy 355.791008 -267.924026) (xy 355.76602 -267.92351) (xy 355.716659 -267.915694) (xy 355.669128 -267.900252)
			(xy 355.624598 -267.877565) (xy 355.584166 -267.848191) (xy 355.548826 -267.812854) (xy 355.519449 -267.772424)
			(xy 355.496758 -267.727896) (xy 355.481312 -267.680366) (xy 355.473492 -267.631006) (xy 355.473 -267.606018)
			(xy 354.39604 -267.606018) (xy 354.39604 -267.783056) (xy 354.395545 -267.79307) (xy 354.387897 -267.811578)
			(xy 354.373748 -267.82575) (xy 354.355253 -267.833429) (xy 354.34524 -267.833856) (xy 354.132896 -267.833856)
			(xy 354.131372 -267.835634) (xy 354.131372 -267.843) (xy 354.13098 -267.853025) (xy 354.123305 -267.871547)
			(xy 354.109124 -267.88572) (xy 354.090597 -267.893385) (xy 354.080572 -267.8938) (xy 354.046536 -267.8938)
			(xy 354.036884 -267.898118) (xy 354.016939 -267.906292) (xy 353.975411 -267.917835) (xy 353.932705 -267.923664)
			(xy 353.911154 -267.924026) (xy 353.886164 -267.92356) (xy 353.836802 -267.915736) (xy 353.78927 -267.900286)
			(xy 353.74474 -267.877592) (xy 353.704308 -267.848213) (xy 353.668969 -267.812871) (xy 353.639593 -267.772436)
			(xy 353.616903 -267.727904) (xy 353.601458 -267.680371) (xy 353.593638 -267.631008) (xy 353.593146 -267.606018)
			(xy 352.49104 -267.606018) (xy 352.49104 -267.783056) (xy 352.490545 -267.79307) (xy 352.482897 -267.811578)
			(xy 352.468748 -267.82575) (xy 352.450253 -267.833429) (xy 352.44024 -267.833856) (xy 352.2726 -267.833856)
			(xy 352.263498 -267.834239) (xy 352.246447 -267.84062) (xy 352.239326 -267.846302) (xy 352.226372 -267.85697)
			(xy 352.226372 -267.864082) (xy 352.196654 -267.8938) (xy 352.166428 -267.8938) (xy 352.156776 -267.898118)
			(xy 352.136832 -267.906294) (xy 352.095304 -267.917836) (xy 352.052597 -267.923664) (xy 352.031046 -267.924026)
			(xy 352.006057 -267.923501) (xy 351.956693 -267.915689) (xy 351.909159 -267.900251) (xy 351.864626 -267.877567)
			(xy 351.82419 -267.848195) (xy 351.788847 -267.812859) (xy 351.759467 -267.772429) (xy 351.736773 -267.7279)
			(xy 351.721326 -267.680369) (xy 351.713504 -267.631007) (xy 351.713038 -267.606018) (xy 350.58604 -267.606018)
			(xy 350.58604 -267.783056) (xy 350.585545 -267.79307) (xy 350.577897 -267.811578) (xy 350.563748 -267.82575)
			(xy 350.545253 -267.833429) (xy 350.53524 -267.833856) (xy 350.392746 -267.833856) (xy 350.383646 -267.834261)
			(xy 350.366595 -267.840627) (xy 350.359472 -267.846302) (xy 350.350418 -267.854024) (xy 350.33135 -267.868265)
			(xy 350.321372 -267.87475) (xy 350.321372 -267.8938) (xy 350.286574 -267.8938) (xy 350.276922 -267.898118)
			(xy 350.256985 -267.906311) (xy 350.215453 -267.917847) (xy 350.172744 -267.923668) (xy 350.151192 -267.924026)
			(xy 350.123225 -267.923437) (xy 350.068151 -267.913667) (xy 350.015636 -267.894411) (xy 349.991172 -267.880846)
			(xy 349.985076 -267.877798) (xy 349.967169 -267.869991) (xy 349.934345 -267.848816) (xy 349.905924 -267.822021)
			(xy 349.882856 -267.790499) (xy 349.865912 -267.755304) (xy 349.860362 -267.736574) (xy 349.85833 -267.72997)
			(xy 349.850426 -267.710401) (xy 349.839263 -267.669701) (xy 349.83358 -267.627881) (xy 349.833184 -267.60678)
			(xy 348.80804 -267.60678) (xy 348.80804 -267.783056) (xy 348.807545 -267.79307) (xy 348.799897 -267.811578)
			(xy 348.785748 -267.82575) (xy 348.767253 -267.833429) (xy 348.75724 -267.833856) (xy 348.543372 -267.833856)
			(xy 348.543372 -267.843) (xy 348.54298 -267.853025) (xy 348.535305 -267.871547) (xy 348.521124 -267.88572)
			(xy 348.502597 -267.893385) (xy 348.492572 -267.8938) (xy 348.406466 -267.8938) (xy 348.396814 -267.898118)
			(xy 348.376878 -267.906313) (xy 348.335346 -267.917848) (xy 348.292636 -267.923668) (xy 348.271084 -267.924026)
			(xy 348.246095 -267.923532) (xy 348.196733 -267.915712) (xy 348.149202 -267.900267) (xy 348.104673 -267.877577)
			(xy 348.06424 -267.848201) (xy 348.028901 -267.812861) (xy 347.999524 -267.772429) (xy 347.976834 -267.727899)
			(xy 347.961388 -267.680369) (xy 347.953568 -267.631007) (xy 347.953076 -267.606018) (xy 347.656912 -267.606018)
			(xy 347.656912 -267.78331) (xy 347.65642 -267.798359) (xy 347.648628 -267.827432) (xy 347.633577 -267.853498)
			(xy 347.612293 -267.874781) (xy 347.586227 -267.88983) (xy 347.557153 -267.897621) (xy 347.542104 -267.898118)
			(xy 347.457522 -267.898118) (xy 347.448632 -267.901674) (xy 347.420373 -267.912185) (xy 347.361172 -267.923568)
			(xy 347.33103 -267.92428) (xy 347.300889 -267.923555) (xy 347.241688 -267.912181) (xy 347.213428 -267.901674)
			(xy 347.204538 -267.898118) (xy 347.084904 -267.898118) (xy 347.067436 -267.897503) (xy 347.034103 -267.887044)
			(xy 347.005431 -267.867084) (xy 346.994226 -267.853668) (xy 346.990463 -267.84903) (xy 346.98122 -267.841472)
			(xy 346.975938 -267.838682) (xy 346.966032 -267.833856) (xy 346.87256 -267.833856) (xy 346.866772 -267.833987)
			(xy 346.855487 -267.836558) (xy 346.850208 -267.838936) (xy 346.845636 -267.841222) (xy 346.836238 -267.848842)
			(xy 346.832682 -267.853668) (xy 346.821489 -267.867092) (xy 346.792803 -267.887033) (xy 346.759471 -267.897496)
			(xy 346.742004 -267.898118) (xy 346.530168 -267.898118) (xy 346.522294 -267.898626) (xy 346.510864 -267.900912)
			(xy 346.507816 -267.902182) (xy 346.47978 -267.912495) (xy 346.421095 -267.923623) (xy 346.39123 -267.92428)
			(xy 346.390722 -267.92428) (xy 346.368662 -267.923881) (xy 346.324968 -267.91775) (xy 346.282536 -267.905658)
			(xy 346.262198 -267.897102) (xy 346.261182 -267.896594) (xy 346.25534 -267.894308) (xy 346.25407 -267.8938)
			(xy 346.253054 -267.893546) (xy 346.252038 -267.893292) (xy 346.238039 -267.888646) (xy 346.212835 -267.873343)
			(xy 346.202254 -267.863066) (xy 346.202 -267.862812) (xy 346.196412 -267.857732) (xy 346.177544 -267.842561)
			(xy 346.144184 -267.807476) (xy 346.116524 -267.767742) (xy 346.095204 -267.724276) (xy 346.080715 -267.678081)
			(xy 346.073392 -267.630225) (xy 346.072968 -267.606018) (xy 346.073372 -267.583003) (xy 346.079993 -267.537451)
			(xy 346.0931 -267.493326) (xy 346.112419 -267.451546) (xy 346.13755 -267.41298) (xy 346.15247 -267.395452)
			(xy 346.157804 -267.389356) (xy 346.165678 -267.371576) (xy 346.167964 -267.365226) (xy 346.169996 -267.351256)
			(xy 346.169996 -267.27531) (xy 346.170434 -267.261566) (xy 346.176985 -267.234868) (xy 346.18295 -267.222478)
			(xy 346.18549 -267.217398) (xy 346.187776 -267.209016) (xy 346.189545 -267.19931) (xy 346.186404 -267.179852)
			(xy 346.176154 -267.163016) (xy 346.16031 -267.151291) (xy 346.141214 -267.146409) (xy 346.131388 -267.147294)
			(xy 346.12453 -267.148564) (xy 346.118588 -267.150493) (xy 346.107805 -267.156795) (xy 346.103194 -267.16101)
			(xy 346.102432 -267.161518) (xy 345.775534 -267.488416) (xy 345.76813 -267.496594) (xy 345.760493 -267.517266)
			(xy 345.760802 -267.528294) (xy 345.76131 -267.53439) (xy 345.762072 -267.537692) (xy 345.765445 -267.554506)
			(xy 345.769006 -267.588616) (xy 345.769184 -267.605764) (xy 345.769184 -267.606018) (xy 345.768748 -267.630078)
			(xy 345.761512 -267.677652) (xy 345.747193 -267.723593) (xy 345.726116 -267.766853) (xy 345.698764 -267.806444)
			(xy 345.665761 -267.841464) (xy 345.627859 -267.871113) (xy 345.585924 -267.894714) (xy 345.540912 -267.911729)
			(xy 345.51747 -267.917168) (xy 345.51239 -267.918184) (xy 345.497242 -267.921002) (xy 345.466582 -267.92406)
			(xy 345.451176 -267.92428) (xy 345.45016 -267.92428) (xy 345.432738 -267.923977) (xy 345.398115 -267.920032)
			(xy 345.381072 -267.916406) (xy 345.374572 -267.915088) (xy 345.361321 -267.91547) (xy 345.35491 -267.917168)
			(xy 345.349322 -267.918946) (xy 345.338654 -267.925296) (xy 345.209622 -268.054328) (xy 345.203176 -268.061626)
			(xy 345.195861 -268.079654) (xy 345.195398 -268.08938) (xy 345.195144 -268.14907) (xy 345.195144 -268.15923)
			(xy 345.209368 -268.194536) (xy 345.215718 -268.201394) (xy 345.230784 -268.218382) (xy 345.256407 -268.255868)
			(xy 345.266772 -268.27607) (xy 345.276745 -268.297427) (xy 345.290972 -268.342361) (xy 345.298393 -268.388906)
			(xy 345.29903 -268.412468) (xy 345.29903 -268.416024) (xy 345.298588 -268.43976) (xy 345.2984 -268.441013)
			(xy 345.603558 -268.441013) (xy 345.603558 -268.391035) (xy 345.611377 -268.341672) (xy 345.626821 -268.29414)
			(xy 345.649511 -268.249608) (xy 345.678887 -268.209175) (xy 345.714227 -268.173835) (xy 345.75466 -268.144459)
			(xy 345.799192 -268.121769) (xy 345.846724 -268.106325) (xy 345.896087 -268.098506) (xy 345.946065 -268.098506)
			(xy 345.995428 -268.106325) (xy 346.04296 -268.121769) (xy 346.087492 -268.144459) (xy 346.127925 -268.173835)
			(xy 346.163265 -268.209175) (xy 346.192641 -268.249608) (xy 346.215331 -268.29414) (xy 346.230775 -268.341672)
			(xy 346.238594 -268.391035) (xy 346.239084 -268.416024) (xy 346.238594 -268.441013) (xy 346.230775 -268.490376)
			(xy 346.215331 -268.537908) (xy 346.192641 -268.58244) (xy 346.163265 -268.622873) (xy 346.127925 -268.658213)
			(xy 346.108872 -268.672056) (xy 347.400372 -268.672056) (xy 347.400372 -268.164564) (xy 347.400858 -268.154557)
			(xy 347.408524 -268.13607) (xy 347.422677 -268.12192) (xy 347.441165 -268.114256) (xy 347.451172 -268.113764)
			(xy 347.66504 -268.113764) (xy 347.66504 -268.10462) (xy 347.665437 -268.094595) (xy 347.673108 -268.076071)
			(xy 347.687288 -268.061897) (xy 347.705815 -268.054233) (xy 347.71584 -268.05382) (xy 347.920056 -268.05382)
			(xy 347.9411 -268.054364) (xy 347.982374 -268.062597) (xy 348.021236 -268.078754) (xy 348.056182 -268.102209)
			(xy 348.085858 -268.132053) (xy 348.109114 -268.167131) (xy 348.125051 -268.206084) (xy 348.133052 -268.247404)
			(xy 348.133416 -268.26845) (xy 348.133416 -268.268704) (xy 348.133416 -268.416024) (xy 349.36303 -268.416024)
			(xy 349.363541 -268.390443) (xy 349.371743 -268.339941) (xy 349.387923 -268.291404) (xy 349.411664 -268.246082)
			(xy 349.442354 -268.205145) (xy 349.4792 -268.169649) (xy 349.499936 -268.154658) (xy 349.503423 -268.152082)
			(xy 349.509555 -268.145955) (xy 349.512128 -268.142466) (xy 349.524368 -268.126368) (xy 349.55377 -268.098612)
			(xy 349.587862 -268.076873) (xy 349.625431 -268.061926) (xy 349.66514 -268.054304) (xy 349.685356 -268.05382)
			(xy 349.940372 -268.05382) (xy 349.940372 -268.062964) (xy 349.940848 -268.07298) (xy 349.948501 -268.09149)
			(xy 349.962656 -268.105663) (xy 349.981157 -268.113339) (xy 349.991172 -268.113764) (xy 350.15424 -268.113764)
			(xy 350.164246 -268.114254) (xy 350.182732 -268.12192) (xy 350.196882 -268.136072) (xy 350.204546 -268.154558)
			(xy 350.20504 -268.164564) (xy 350.20504 -268.416024) (xy 351.243138 -268.416024) (xy 351.243588 -268.390612)
			(xy 351.251654 -268.340432) (xy 351.267603 -268.292174) (xy 351.291025 -268.247069) (xy 351.321327 -268.206265)
			(xy 351.357734 -268.170802) (xy 351.39932 -268.141583) (xy 351.421954 -268.13002) (xy 351.425952 -268.127985)
			(xy 351.433235 -268.122752) (xy 351.436432 -268.119606) (xy 351.451711 -268.104444) (xy 351.487108 -268.079966)
			(xy 351.526683 -268.063052) (xy 351.568838 -268.054387) (xy 351.590356 -268.05382) (xy 351.845372 -268.05382)
			(xy 351.845372 -268.062964) (xy 351.845848 -268.07298) (xy 351.853501 -268.09149) (xy 351.867656 -268.105663)
			(xy 351.886157 -268.113339) (xy 351.896172 -268.113764) (xy 352.05924 -268.113764) (xy 352.069246 -268.114254)
			(xy 352.087732 -268.12192) (xy 352.101882 -268.136072) (xy 352.109546 -268.154558) (xy 352.11004 -268.164564)
			(xy 352.11004 -268.416024) (xy 353.122992 -268.416024) (xy 353.123414 -268.391219) (xy 353.131128 -268.342213)
			(xy 353.146358 -268.294999) (xy 353.168732 -268.250721) (xy 353.19771 -268.210455) (xy 353.232589 -268.175176)
			(xy 353.272522 -268.14574) (xy 353.31654 -268.12286) (xy 353.339908 -268.114526) (xy 353.344529 -268.112823)
			(xy 353.353099 -268.107974) (xy 353.356926 -268.104874) (xy 353.371514 -268.092935) (xy 353.404036 -268.073878)
			(xy 353.439401 -268.060837) (xy 353.476509 -268.054218) (xy 353.495356 -268.05382) (xy 353.750372 -268.05382)
			(xy 353.750372 -268.062964) (xy 353.750848 -268.07298) (xy 353.758501 -268.09149) (xy 353.772656 -268.105663)
			(xy 353.791157 -268.113339) (xy 353.801172 -268.113764) (xy 353.96424 -268.113764) (xy 353.974246 -268.114254)
			(xy 353.992732 -268.12192) (xy 354.006882 -268.136072) (xy 354.014546 -268.154558) (xy 354.01504 -268.164564)
			(xy 354.01504 -268.416024) (xy 355.0031 -268.416024) (xy 355.0031 -268.415516) (xy 355.003539 -268.391909)
			(xy 355.010562 -268.345218) (xy 355.024427 -268.300084) (xy 355.044827 -268.257503) (xy 355.05771 -268.237716)
			(xy 355.060266 -268.23367) (xy 355.063969 -268.224846) (xy 355.065076 -268.22019) (xy 355.070137 -268.20024)
			(xy 355.086753 -268.162592) (xy 355.110261 -268.128816) (xy 355.139794 -268.100159) (xy 355.174263 -268.077678)
			(xy 355.212394 -268.062204) (xy 355.252781 -268.054307) (xy 355.273356 -268.05382) (xy 355.528372 -268.05382)
			(xy 355.528372 -268.062964) (xy 355.528848 -268.07298) (xy 355.536501 -268.09149) (xy 355.550656 -268.105663)
			(xy 355.569157 -268.113339) (xy 355.579172 -268.113764) (xy 355.74224 -268.113764) (xy 355.752246 -268.114254)
			(xy 355.770732 -268.12192) (xy 355.784882 -268.136072) (xy 355.792546 -268.154558) (xy 355.79304 -268.164564)
			(xy 355.79304 -268.416024) (xy 356.883208 -268.416024) (xy 356.883676 -268.391338) (xy 356.891306 -268.342559)
			(xy 356.906373 -268.295542) (xy 356.928514 -268.251412) (xy 356.9572 -268.211229) (xy 356.97414 -268.193266)
			(xy 356.977205 -268.190044) (xy 356.982317 -268.182768) (xy 356.9843 -268.178788) (xy 356.993089 -268.160432)
			(xy 357.016635 -268.127239) (xy 357.046052 -268.099118) (xy 357.08027 -268.07709) (xy 357.118046 -268.061954)
			(xy 357.158008 -268.054261) (xy 357.178356 -268.05382) (xy 357.433372 -268.05382) (xy 357.433372 -268.059408)
			(xy 359.629964 -268.059408) (xy 359.629964 -267.804392) (xy 359.639108 -267.804392) (xy 359.649117 -267.803918)
			(xy 359.667611 -267.796254) (xy 359.681763 -267.782097) (xy 359.689421 -267.763601) (xy 359.689908 -267.753592)
			(xy 359.689908 -267.590524) (xy 359.69034 -267.580503) (xy 359.698003 -267.561985) (xy 359.712172 -267.547812)
			(xy 359.730687 -267.540143) (xy 359.740708 -267.539724) (xy 360.2482 -267.539724) (xy 360.258224 -267.54012)
			(xy 360.276746 -267.547795) (xy 360.290919 -267.561974) (xy 360.298585 -267.5805) (xy 360.299 -267.590524)
			(xy 360.299 -267.804392) (xy 360.308144 -267.804392) (xy 360.318153 -267.804852) (xy 360.336645 -267.812524)
			(xy 360.350796 -267.826686) (xy 360.358455 -267.845182) (xy 360.358944 -267.855192) (xy 360.358944 -268.059408)
			(xy 360.358442 -268.079462) (xy 360.350968 -268.118866) (xy 360.336265 -268.15618) (xy 360.314851 -268.190092)
			(xy 360.28748 -268.219407) (xy 360.271568 -268.23162) (xy 360.263186 -268.23924) (xy 360.244607 -268.259782)
			(xy 360.202216 -268.295426) (xy 360.15482 -268.324081) (xy 360.10356 -268.345057) (xy 360.049672 -268.357848)
			(xy 359.994454 -268.362146) (xy 359.939236 -268.357848) (xy 359.885348 -268.345057) (xy 359.834088 -268.324081)
			(xy 359.786692 -268.295426) (xy 359.744301 -268.259782) (xy 359.725722 -268.23924) (xy 359.71734 -268.23162)
			(xy 359.701421 -268.219413) (xy 359.674046 -268.190096) (xy 359.652625 -268.156184) (xy 359.637911 -268.118869)
			(xy 359.630421 -268.079464) (xy 359.629964 -268.059408) (xy 357.433372 -268.059408) (xy 357.433372 -268.062964)
			(xy 357.433848 -268.07298) (xy 357.441501 -268.09149) (xy 357.455656 -268.105663) (xy 357.474157 -268.113339)
			(xy 357.484172 -268.113764) (xy 357.64724 -268.113764) (xy 357.657246 -268.114254) (xy 357.675732 -268.12192)
			(xy 357.689882 -268.136072) (xy 357.697546 -268.154558) (xy 357.69804 -268.164564) (xy 357.69804 -268.416024)
			(xy 361.576874 -268.416024) (xy 361.57738 -268.390096) (xy 361.585778 -268.338924) (xy 361.602372 -268.289795)
			(xy 361.626722 -268.244012) (xy 361.658181 -268.202788) (xy 361.676696 -268.18463) (xy 361.679834 -268.181569)
			(xy 361.685069 -268.174539) (xy 361.68711 -268.17066) (xy 361.696336 -268.153366) (xy 361.720146 -268.122235)
			(xy 361.74924 -268.095974) (xy 361.78264 -268.075467) (xy 361.819223 -268.061405) (xy 361.857759 -268.054258)
			(xy 361.877356 -268.05382) (xy 362.132372 -268.05382) (xy 362.132372 -268.062964) (xy 362.132848 -268.07298)
			(xy 362.140501 -268.09149) (xy 362.154656 -268.105663) (xy 362.173157 -268.113339) (xy 362.183172 -268.113764)
			(xy 362.34624 -268.113764) (xy 362.356246 -268.114254) (xy 362.374732 -268.12192) (xy 362.388882 -268.136072)
			(xy 362.396546 -268.154558) (xy 362.39704 -268.164564) (xy 362.39704 -268.416024) (xy 363.456728 -268.416024)
			(xy 363.457238 -268.389876) (xy 363.465804 -268.338286) (xy 363.482694 -268.288792) (xy 363.507452 -268.242727)
			(xy 363.539411 -268.201332) (xy 363.57771 -268.165723) (xy 363.599222 -268.150848) (xy 363.60283 -268.148359)
			(xy 363.609218 -268.14236) (xy 363.611922 -268.13891) (xy 363.624152 -268.123377) (xy 363.653311 -268.096689)
			(xy 363.68689 -268.075833) (xy 363.723738 -268.061522) (xy 363.762591 -268.054247) (xy 363.782356 -268.05382)
			(xy 364.037372 -268.05382) (xy 364.037372 -268.062964) (xy 364.037848 -268.07298) (xy 364.045501 -268.09149)
			(xy 364.059656 -268.105663) (xy 364.078157 -268.113339) (xy 364.088172 -268.113764) (xy 364.25124 -268.113764)
			(xy 364.261246 -268.114254) (xy 364.279732 -268.12192) (xy 364.293882 -268.136072) (xy 364.301546 -268.154558)
			(xy 364.30204 -268.164564) (xy 364.30204 -268.416024) (xy 365.336836 -268.416024) (xy 365.337415 -268.390225)
			(xy 365.345755 -268.339304) (xy 365.362205 -268.290398) (xy 365.386333 -268.244788) (xy 365.417506 -268.20367)
			(xy 365.454907 -268.168123) (xy 365.497555 -268.139078) (xy 365.520732 -268.127734) (xy 365.52488 -268.125762)
			(xy 365.532416 -268.120513) (xy 365.535718 -268.11732) (xy 365.550887 -268.102623) (xy 365.585883 -268.078984)
			(xy 365.62484 -268.062678) (xy 365.666241 -268.054338) (xy 365.687356 -268.05382) (xy 365.942372 -268.05382)
			(xy 365.942372 -268.062964) (xy 365.942848 -268.07298) (xy 365.950501 -268.09149) (xy 365.964656 -268.105663)
			(xy 365.983157 -268.113339) (xy 365.993172 -268.113764) (xy 366.15624 -268.113764) (xy 366.166246 -268.114254)
			(xy 366.184732 -268.12192) (xy 366.198882 -268.136072) (xy 366.206546 -268.154558) (xy 366.20704 -268.164564)
			(xy 366.20704 -268.416024) (xy 367.21669 -268.416024) (xy 367.217184 -268.390771) (xy 367.225146 -268.340898)
			(xy 367.240874 -268.292904) (xy 367.251996 -268.270228) (xy 367.251996 -268.268704) (xy 367.252366 -268.247641)
			(xy 367.260327 -268.206281) (xy 367.276238 -268.167282) (xy 367.299481 -268.132156) (xy 367.329156 -268.102265)
			(xy 367.364112 -268.078767) (xy 367.402995 -268.062574) (xy 367.444296 -268.054313) (xy 367.465356 -268.05382)
			(xy 367.720372 -268.05382) (xy 367.720372 -268.062964) (xy 367.720848 -268.07298) (xy 367.728501 -268.09149)
			(xy 367.742656 -268.105663) (xy 367.761157 -268.113339) (xy 367.771172 -268.113764) (xy 367.93424 -268.113764)
			(xy 367.944246 -268.114254) (xy 367.962732 -268.12192) (xy 367.976882 -268.136072) (xy 367.984546 -268.154558)
			(xy 367.98504 -268.164564) (xy 367.98504 -268.416024) (xy 369.096798 -268.416024) (xy 369.097272 -268.391422)
			(xy 369.104847 -268.342805) (xy 369.119821 -268.295935) (xy 369.141836 -268.251931) (xy 369.155726 -268.23162)
			(xy 369.158378 -268.227715) (xy 369.162343 -268.219151) (xy 369.1636 -268.214602) (xy 369.168999 -268.195173)
			(xy 369.186087 -268.158651) (xy 369.209729 -268.125988) (xy 369.239084 -268.098346) (xy 369.273108 -268.076708)
			(xy 369.310589 -268.061844) (xy 369.350195 -268.054283) (xy 369.370356 -268.05382) (xy 369.625372 -268.05382)
			(xy 369.625372 -268.062964) (xy 369.625848 -268.07298) (xy 369.633501 -268.09149) (xy 369.647656 -268.105663)
			(xy 369.666157 -268.113339) (xy 369.676172 -268.113764) (xy 369.83924 -268.113764) (xy 369.849246 -268.114254)
			(xy 369.867732 -268.12192) (xy 369.881882 -268.136072) (xy 369.889546 -268.154558) (xy 369.89004 -268.164564)
			(xy 369.89004 -268.416024) (xy 370.976906 -268.416024) (xy 370.977404 -268.390544) (xy 370.985509 -268.340235)
			(xy 371.001531 -268.29186) (xy 371.025061 -268.246659) (xy 371.055495 -268.205787) (xy 371.073426 -268.187678)
			(xy 371.076478 -268.184587) (xy 371.081589 -268.177565) (xy 371.083586 -268.173708) (xy 371.092665 -268.156015)
			(xy 371.1164 -268.12411) (xy 371.145633 -268.097153) (xy 371.179354 -268.076077) (xy 371.216394 -268.061611)
			(xy 371.255473 -268.054256) (xy 371.275356 -268.05382) (xy 371.530372 -268.05382) (xy 371.530372 -268.062964)
			(xy 371.530848 -268.07298) (xy 371.538501 -268.09149) (xy 371.552656 -268.105663) (xy 371.571157 -268.113339)
			(xy 371.581172 -268.113764) (xy 371.74424 -268.113764) (xy 371.754246 -268.114254) (xy 371.772732 -268.12192)
			(xy 371.786882 -268.136072) (xy 371.794546 -268.154558) (xy 371.79504 -268.164564) (xy 371.79504 -268.478393)
			(xy 372.815167 -268.478393) (xy 372.818269 -268.435958) (xy 372.829704 -268.394975) (xy 372.849022 -268.357064)
			(xy 372.86184 -268.340078) (xy 372.864737 -268.33628) (xy 372.869215 -268.327844) (xy 372.87073 -268.323314)
			(xy 372.878617 -268.29922) (xy 372.90088 -268.253678) (xy 372.930091 -268.212248) (xy 372.965509 -268.175981)
			(xy 373.006236 -268.145797) (xy 373.051237 -268.122461) (xy 373.099373 -268.106565) (xy 373.149422 -268.098512)
			(xy 373.174768 -268.098016) (xy 373.175276 -268.098016) (xy 373.194849 -268.09833) (xy 373.233694 -268.103174)
			(xy 373.252746 -268.107668) (xy 373.256992 -268.108642) (xy 373.265677 -268.109288) (xy 373.270018 -268.108938)
			(xy 373.290364 -268.107383) (xy 373.330986 -268.111192) (xy 373.370147 -268.122643) (xy 373.406422 -268.141322)
			(xy 373.43849 -268.166548) (xy 373.465185 -268.197403) (xy 373.475758 -268.214856) (xy 373.603266 -268.435582)
			(xy 373.595392 -268.440154) (xy 373.586856 -268.445497) (xy 373.574566 -268.461435) (xy 373.569325 -268.480866)
			(xy 373.571934 -268.500822) (xy 373.576596 -268.50975) (xy 373.658384 -268.65072) (xy 373.66297 -268.659617)
			(xy 373.665582 -268.679443) (xy 373.660414 -268.69876) (xy 373.648252 -268.714633) (xy 373.639842 -268.720062)
			(xy 373.199914 -268.974062) (xy 373.191003 -268.97862) (xy 373.171185 -268.981242) (xy 373.151871 -268.976083)
			(xy 373.136 -268.963927) (xy 373.130572 -268.95552) (xy 373.023384 -268.769846) (xy 373.015256 -268.774418)
			(xy 373.006403 -268.779124) (xy 372.986535 -268.781738) (xy 372.96718 -268.776548) (xy 372.951285 -268.764345)
			(xy 372.945914 -268.755876) (xy 372.844314 -268.5796) (xy 372.83412 -268.56092) (xy 372.820521 -268.520603)
			(xy 372.815167 -268.478393) (xy 371.79504 -268.478393) (xy 371.79504 -268.672056) (xy 371.794545 -268.68207)
			(xy 371.786897 -268.700578) (xy 371.772748 -268.71475) (xy 371.754253 -268.722429) (xy 371.74424 -268.722856)
			(xy 371.530372 -268.722856) (xy 371.530372 -268.732) (xy 371.52998 -268.742025) (xy 371.522305 -268.760547)
			(xy 371.508124 -268.77472) (xy 371.489597 -268.782385) (xy 371.479572 -268.7828) (xy 371.275356 -268.7828)
			(xy 371.254855 -268.782305) (xy 371.214609 -268.774466) (xy 371.176601 -268.759084) (xy 371.14223 -268.736727)
			(xy 371.112762 -268.708216) (xy 371.089282 -268.674603) (xy 371.080538 -268.656054) (xy 371.078567 -268.651848)
			(xy 371.073324 -268.644181) (xy 371.070124 -268.640814) (xy 371.052747 -268.622848) (xy 371.023334 -268.582438)
			(xy 371.000621 -268.537915) (xy 370.985169 -268.490382) (xy 370.97736 -268.441015) (xy 370.976906 -268.416024)
			(xy 369.89004 -268.416024) (xy 369.89004 -268.672056) (xy 369.889545 -268.68207) (xy 369.881897 -268.700578)
			(xy 369.867748 -268.71475) (xy 369.849253 -268.722429) (xy 369.83924 -268.722856) (xy 369.625372 -268.722856)
			(xy 369.625372 -268.732) (xy 369.62498 -268.742025) (xy 369.617305 -268.760547) (xy 369.603124 -268.77472)
			(xy 369.584597 -268.782385) (xy 369.574572 -268.7828) (xy 369.370356 -268.7828) (xy 369.349795 -268.782251)
			(xy 369.309438 -268.774357) (xy 369.271337 -268.758887) (xy 369.236898 -268.736415) (xy 369.207395 -268.707769)
			(xy 369.183918 -268.674008) (xy 369.167332 -268.636379) (xy 369.16233 -268.61643) (xy 369.161087 -268.611605)
			(xy 369.156991 -268.602525) (xy 369.154202 -268.598396) (xy 369.140645 -268.57824) (xy 369.119197 -268.534658)
			(xy 369.104619 -268.488323) (xy 369.09725 -268.440311) (xy 369.096798 -268.416024) (xy 367.98504 -268.416024)
			(xy 367.98504 -268.672056) (xy 367.984545 -268.68207) (xy 367.976897 -268.700578) (xy 367.962748 -268.71475)
			(xy 367.944253 -268.722429) (xy 367.93424 -268.722856) (xy 367.720372 -268.722856) (xy 367.720372 -268.732)
			(xy 367.71998 -268.742025) (xy 367.712305 -268.760547) (xy 367.698124 -268.77472) (xy 367.679597 -268.782385)
			(xy 367.669572 -268.7828) (xy 367.465356 -268.7828) (xy 367.444298 -268.782225) (xy 367.402997 -268.773983)
			(xy 367.364112 -268.757806) (xy 367.329151 -268.734322) (xy 367.29947 -268.704442) (xy 367.276221 -268.669325)
			(xy 367.260305 -268.630332) (xy 367.252339 -268.588977) (xy 367.251996 -268.567916) (xy 367.251996 -268.56182)
			(xy 367.240838 -268.539158) (xy 367.225092 -268.491163) (xy 367.217149 -268.44128) (xy 367.21669 -268.416024)
			(xy 366.20704 -268.416024) (xy 366.20704 -268.672056) (xy 366.206545 -268.68207) (xy 366.198897 -268.700578)
			(xy 366.184748 -268.71475) (xy 366.166253 -268.722429) (xy 366.15624 -268.722856) (xy 365.942372 -268.722856)
			(xy 365.942372 -268.732) (xy 365.94198 -268.742025) (xy 365.934305 -268.760547) (xy 365.920124 -268.77472)
			(xy 365.901597 -268.782385) (xy 365.891572 -268.7828) (xy 365.687356 -268.7828) (xy 365.665093 -268.782211)
			(xy 365.621541 -268.772943) (xy 365.580842 -268.75488) (xy 365.544752 -268.728799) (xy 365.529368 -268.712696)
			(xy 365.526062 -268.70917) (xy 365.518393 -268.703287) (xy 365.514128 -268.701012) (xy 365.49165 -268.689447)
			(xy 365.450416 -268.660208) (xy 365.414333 -268.624807) (xy 365.384311 -268.584139) (xy 365.361109 -268.539229)
			(xy 365.345312 -268.491212) (xy 365.337319 -268.441299) (xy 365.336836 -268.416024) (xy 364.30204 -268.416024)
			(xy 364.30204 -268.672056) (xy 364.301545 -268.68207) (xy 364.293897 -268.700578) (xy 364.279748 -268.71475)
			(xy 364.261253 -268.722429) (xy 364.25124 -268.722856) (xy 364.037372 -268.722856) (xy 364.037372 -268.732)
			(xy 364.03698 -268.742025) (xy 364.029305 -268.760547) (xy 364.015124 -268.77472) (xy 363.996597 -268.782385)
			(xy 363.986572 -268.7828) (xy 363.782356 -268.7828) (xy 363.761706 -268.782317) (xy 363.721186 -268.774315)
			(xy 363.682959 -268.758677) (xy 363.648449 -268.735986) (xy 363.618942 -268.707086) (xy 363.606842 -268.690344)
			(xy 363.604135 -268.686613) (xy 363.597621 -268.680093) (xy 363.593888 -268.67739) (xy 363.573113 -268.66243)
			(xy 363.536201 -268.626962) (xy 363.505453 -268.586034) (xy 363.481667 -268.540705) (xy 363.465457 -268.492147)
			(xy 363.457245 -268.44162) (xy 363.456728 -268.416024) (xy 362.39704 -268.416024) (xy 362.39704 -268.672056)
			(xy 362.396545 -268.68207) (xy 362.388897 -268.700578) (xy 362.374748 -268.71475) (xy 362.356253 -268.722429)
			(xy 362.34624 -268.722856) (xy 362.132372 -268.722856) (xy 362.132372 -268.732) (xy 362.13198 -268.742025)
			(xy 362.124305 -268.760547) (xy 362.110124 -268.77472) (xy 362.091597 -268.782385) (xy 362.081572 -268.7828)
			(xy 361.877356 -268.7828) (xy 361.857114 -268.782294) (xy 361.817357 -268.774649) (xy 361.779756 -268.759641)
			(xy 361.745661 -268.737811) (xy 361.716296 -268.709941) (xy 361.692715 -268.677032) (xy 361.683808 -268.658848)
			(xy 361.681776 -268.654687) (xy 361.676406 -268.647144) (xy 361.67314 -268.643862) (xy 361.655278 -268.62577)
			(xy 361.624929 -268.584985) (xy 361.601461 -268.539889) (xy 361.585474 -268.491631) (xy 361.577376 -268.441443)
			(xy 361.576874 -268.416024) (xy 357.69804 -268.416024) (xy 357.69804 -268.672056) (xy 357.697545 -268.68207)
			(xy 357.689897 -268.700578) (xy 357.675748 -268.71475) (xy 357.657253 -268.722429) (xy 357.64724 -268.722856)
			(xy 357.433372 -268.722856) (xy 357.433372 -268.732) (xy 357.43298 -268.742025) (xy 357.425305 -268.760547)
			(xy 357.411124 -268.77472) (xy 357.392597 -268.782385) (xy 357.382572 -268.7828) (xy 357.178356 -268.7828)
			(xy 357.157399 -268.782317) (xy 357.11629 -268.774152) (xy 357.077562 -268.758126) (xy 357.042704 -268.734853)
			(xy 357.013056 -268.705228) (xy 356.989755 -268.670389) (xy 356.981252 -268.651228) (xy 356.979352 -268.64697)
			(xy 356.974241 -268.639173) (xy 356.971092 -268.635734) (xy 356.954702 -268.617847) (xy 356.926957 -268.578053)
			(xy 356.905565 -268.534512) (xy 356.891022 -268.488231) (xy 356.883664 -268.44028) (xy 356.883208 -268.416024)
			(xy 355.79304 -268.416024) (xy 355.79304 -268.672056) (xy 355.792545 -268.68207) (xy 355.784897 -268.700578)
			(xy 355.770748 -268.71475) (xy 355.752253 -268.722429) (xy 355.74224 -268.722856) (xy 355.528372 -268.722856)
			(xy 355.528372 -268.732) (xy 355.52798 -268.742025) (xy 355.520305 -268.760547) (xy 355.506124 -268.77472)
			(xy 355.487597 -268.782385) (xy 355.477572 -268.7828) (xy 355.273356 -268.7828) (xy 355.252398 -268.782212)
			(xy 355.211296 -268.773989) (xy 355.172588 -268.757907) (xy 355.137759 -268.734584) (xy 355.108149 -268.704916)
			(xy 355.084894 -268.670042) (xy 355.068889 -268.631301) (xy 355.064314 -268.610842) (xy 355.063189 -268.605982)
			(xy 355.059359 -268.596771) (xy 355.056694 -268.592554) (xy 355.044032 -268.572862) (xy 355.024029 -268.530535)
			(xy 355.010432 -268.485737) (xy 355.003536 -268.439432) (xy 355.0031 -268.416024) (xy 354.01504 -268.416024)
			(xy 354.01504 -268.672056) (xy 354.014545 -268.68207) (xy 354.006897 -268.700578) (xy 353.992748 -268.71475)
			(xy 353.974253 -268.722429) (xy 353.96424 -268.722856) (xy 353.750372 -268.722856) (xy 353.750372 -268.732)
			(xy 353.74998 -268.742025) (xy 353.742305 -268.760547) (xy 353.728124 -268.77472) (xy 353.709597 -268.782385)
			(xy 353.699572 -268.7828) (xy 353.495356 -268.7828) (xy 353.47536 -268.782367) (xy 353.43607 -268.7749)
			(xy 353.398856 -268.760254) (xy 353.365017 -268.738939) (xy 353.350068 -268.72565) (xy 353.346251 -268.722244)
			(xy 353.337553 -268.716864) (xy 353.332796 -268.714982) (xy 353.310068 -268.706287) (xy 353.267361 -268.682967)
			(xy 353.228707 -268.65341) (xy 353.195011 -268.618305) (xy 353.16706 -268.578474) (xy 353.145507 -268.534848)
			(xy 353.130856 -268.488447) (xy 353.12345 -268.440354) (xy 353.122992 -268.416024) (xy 352.11004 -268.416024)
			(xy 352.11004 -268.672056) (xy 352.109545 -268.68207) (xy 352.101897 -268.700578) (xy 352.087748 -268.71475)
			(xy 352.069253 -268.722429) (xy 352.05924 -268.722856) (xy 351.845372 -268.722856) (xy 351.845372 -268.732)
			(xy 351.84498 -268.742025) (xy 351.837305 -268.760547) (xy 351.823124 -268.77472) (xy 351.804597 -268.782385)
			(xy 351.794572 -268.7828) (xy 351.590356 -268.7828) (xy 351.567663 -268.782188) (xy 351.523304 -268.772579)
			(xy 351.481963 -268.753844) (xy 351.445494 -268.726824) (xy 351.430082 -268.710156) (xy 351.426863 -268.706615)
			(xy 351.419312 -268.700737) (xy 351.415096 -268.698472) (xy 351.393225 -268.686656) (xy 351.353154 -268.657241)
			(xy 351.31815 -268.621947) (xy 351.289067 -268.581634) (xy 351.266614 -268.537286) (xy 351.251338 -268.489983)
			(xy 351.243612 -268.440878) (xy 351.243138 -268.416024) (xy 350.20504 -268.416024) (xy 350.20504 -268.672056)
			(xy 350.204545 -268.68207) (xy 350.196897 -268.700578) (xy 350.182748 -268.71475) (xy 350.164253 -268.722429)
			(xy 350.15424 -268.722856) (xy 349.940372 -268.722856) (xy 349.940372 -268.732) (xy 349.93998 -268.742025)
			(xy 349.932305 -268.760547) (xy 349.918124 -268.77472) (xy 349.899597 -268.782385) (xy 349.889572 -268.7828)
			(xy 349.685356 -268.7828) (xy 349.664273 -268.78232) (xy 349.622925 -268.774057) (xy 349.584002 -268.757843)
			(xy 349.549017 -268.734307) (xy 349.51933 -268.704364) (xy 349.507302 -268.687042) (xy 349.504651 -268.683272)
			(xy 349.49827 -268.676623) (xy 349.494602 -268.673834) (xy 349.474587 -268.658752) (xy 349.439088 -268.623379)
			(xy 349.409581 -268.582874) (xy 349.386797 -268.538238) (xy 349.371302 -268.490581) (xy 349.363479 -268.441081)
			(xy 349.36303 -268.416024) (xy 348.133416 -268.416024) (xy 348.133416 -268.567916) (xy 348.133416 -268.56817)
			(xy 348.13313 -268.589222) (xy 348.125124 -268.630555) (xy 348.109179 -268.669519) (xy 348.085913 -268.704607)
			(xy 348.056226 -268.734459) (xy 348.021269 -268.75792) (xy 347.982394 -268.774081) (xy 347.941106 -268.782317)
			(xy 347.920056 -268.7828) (xy 347.66504 -268.7828) (xy 347.66504 -268.773656) (xy 347.664549 -268.76365)
			(xy 347.656882 -268.745165) (xy 347.642731 -268.731015) (xy 347.624246 -268.72335) (xy 347.61424 -268.722856)
			(xy 347.451172 -268.722856) (xy 347.441143 -268.722503) (xy 347.422617 -268.714815) (xy 347.408444 -268.700622)
			(xy 347.400783 -268.682085) (xy 347.400372 -268.672056) (xy 346.108872 -268.672056) (xy 346.087492 -268.687589)
			(xy 346.04296 -268.710279) (xy 345.995428 -268.725723) (xy 345.946065 -268.733542) (xy 345.896087 -268.733542)
			(xy 345.846724 -268.725723) (xy 345.799192 -268.710279) (xy 345.75466 -268.687589) (xy 345.714227 -268.658213)
			(xy 345.678887 -268.622873) (xy 345.649511 -268.58244) (xy 345.626821 -268.537908) (xy 345.611377 -268.490376)
			(xy 345.603558 -268.441013) (xy 345.2984 -268.441013) (xy 345.291528 -268.486704) (xy 345.277569 -268.532077)
			(xy 345.25702 -268.574872) (xy 345.230337 -268.614136) (xy 345.198115 -268.648998) (xy 345.161069 -268.678682)
			(xy 345.120022 -268.702531) (xy 345.098116 -268.71168) (xy 345.097862 -268.71168) (xy 345.095068 -268.712696)
			(xy 345.086747 -268.717081) (xy 345.073764 -268.730667) (xy 345.066548 -268.748019) (xy 345.065858 -268.7574)
			(xy 345.065858 -269.69339) (xy 345.065858 -269.69466) (xy 345.066522 -269.704046) (xy 345.073741 -269.721404)
			(xy 345.086739 -269.734987) (xy 345.095068 -269.739364) (xy 345.097862 -269.74038) (xy 345.120569 -269.749832)
			(xy 345.162994 -269.774711) (xy 345.201081 -269.805828) (xy 345.233922 -269.842439) (xy 345.260733 -269.883671)
			(xy 345.280873 -269.92854) (xy 345.293863 -269.975976) (xy 345.299392 -270.024846) (xy 345.298922 -270.036036)
			(xy 345.604841 -270.036036) (xy 345.608936 -269.985308) (xy 345.621115 -269.935894) (xy 345.641063 -269.889074)
			(xy 345.668264 -269.84606) (xy 345.702012 -269.807966) (xy 345.741434 -269.775779) (xy 345.785508 -269.750333)
			(xy 345.833094 -269.732286) (xy 345.882958 -269.722106) (xy 345.93381 -269.720057) (xy 345.984331 -269.726191)
			(xy 346.033215 -269.740351) (xy 346.079194 -269.762168) (xy 346.121078 -269.791078) (xy 346.157782 -269.826333)
			(xy 346.188355 -269.867019) (xy 346.212006 -269.912082) (xy 346.228122 -269.960356) (xy 346.236286 -270.01059)
			(xy 346.236302 -270.011386) (xy 346.546441 -270.011386) (xy 346.554166 -269.962429) (xy 346.569454 -269.915282)
			(xy 346.591928 -269.871106) (xy 346.621034 -269.83099) (xy 346.656056 -269.795919) (xy 346.696132 -269.766757)
			(xy 346.740277 -269.744222) (xy 346.787402 -269.728869) (xy 346.836349 -269.721075) (xy 346.86113 -269.720568)
			(xy 346.861892 -269.720568) (xy 346.88764 -269.721103) (xy 346.938443 -269.729523) (xy 346.962984 -269.737332)
			(xy 346.970858 -269.740126) (xy 346.97924 -269.740126) (xy 346.989247 -269.739645) (xy 347.007735 -269.731977)
			(xy 347.021885 -269.717823) (xy 347.029548 -269.699333) (xy 347.03004 -269.689326) (xy 347.03004 -269.662656)
			(xy 347.029549 -269.65265) (xy 347.021882 -269.634165) (xy 347.007731 -269.620015) (xy 346.989246 -269.61235)
			(xy 346.97924 -269.611856) (xy 346.816172 -269.611856) (xy 346.806143 -269.611503) (xy 346.787617 -269.603815)
			(xy 346.773444 -269.589622) (xy 346.765783 -269.571085) (xy 346.765372 -269.561056) (xy 346.765372 -269.053564)
			(xy 346.765858 -269.043557) (xy 346.773524 -269.02507) (xy 346.787677 -269.01092) (xy 346.806165 -269.003256)
			(xy 346.816172 -269.002764) (xy 347.03004 -269.002764) (xy 347.03004 -268.99362) (xy 347.030437 -268.983595)
			(xy 347.038108 -268.965071) (xy 347.052288 -268.950897) (xy 347.070815 -268.943233) (xy 347.08084 -268.94282)
			(xy 347.18625 -268.94282) (xy 347.19641 -268.937994) (xy 347.21759 -268.928567) (xy 347.261989 -268.915231)
			(xy 347.307851 -268.908465) (xy 347.33103 -268.908022) (xy 347.356021 -268.908455) (xy 347.405388 -268.916279)
			(xy 347.452924 -268.931729) (xy 347.497457 -268.954425) (xy 347.537891 -268.983808) (xy 347.573231 -269.019154)
			(xy 347.602607 -269.059594) (xy 347.625294 -269.104132) (xy 347.640736 -269.15167) (xy 347.64855 -269.201038)
			(xy 347.649038 -269.22603) (xy 349.833184 -269.22603) (xy 349.833685 -269.20104) (xy 349.841499 -269.151675)
			(xy 349.85694 -269.10414) (xy 349.879627 -269.059606) (xy 349.909001 -269.019169) (xy 349.94434 -268.983826)
			(xy 349.984773 -268.954447) (xy 350.029305 -268.931754) (xy 350.076838 -268.916308) (xy 350.126202 -268.908488)
			(xy 350.151192 -268.908022) (xy 350.174374 -268.908435) (xy 350.220243 -268.915184) (xy 350.264642 -268.928539)
			(xy 350.285812 -268.937994) (xy 350.295972 -268.94282) (xy 350.448372 -268.94282) (xy 350.448372 -268.951964)
			(xy 350.448848 -268.96198) (xy 350.456501 -268.98049) (xy 350.470656 -268.994663) (xy 350.489157 -269.002339)
			(xy 350.499172 -269.002764) (xy 350.66224 -269.002764) (xy 350.672246 -269.003254) (xy 350.690732 -269.01092)
			(xy 350.704882 -269.025072) (xy 350.712546 -269.043558) (xy 350.71304 -269.053564) (xy 350.71304 -269.22603)
			(xy 352.653092 -269.22603) (xy 352.653585 -269.20104) (xy 352.661399 -269.151674) (xy 352.67684 -269.104138)
			(xy 352.699528 -269.059603) (xy 352.728904 -269.019167) (xy 352.764244 -268.983823) (xy 352.804678 -268.954444)
			(xy 352.84921 -268.931752) (xy 352.896744 -268.916306) (xy 352.94611 -268.908487) (xy 352.9711 -268.908022)
			(xy 352.994282 -268.908433) (xy 353.040152 -268.915182) (xy 353.08455 -268.928538) (xy 353.10572 -268.937994)
			(xy 353.11588 -268.94282) (xy 353.242372 -268.94282) (xy 353.242372 -268.951964) (xy 353.242848 -268.96198)
			(xy 353.250501 -268.98049) (xy 353.264656 -268.994663) (xy 353.283157 -269.002339) (xy 353.293172 -269.002764)
			(xy 353.45624 -269.002764) (xy 353.466246 -269.003254) (xy 353.484732 -269.01092) (xy 353.498882 -269.025072)
			(xy 353.506546 -269.043558) (xy 353.50704 -269.053564) (xy 353.50704 -269.561056) (xy 355.305868 -269.561056)
			(xy 355.305868 -269.053564) (xy 355.306358 -269.043558) (xy 355.314023 -269.025072) (xy 355.328175 -269.010921)
			(xy 355.346662 -269.003257) (xy 355.356668 -269.002764) (xy 355.564694 -269.002764) (xy 355.570536 -268.996668)
			(xy 355.570536 -268.99362) (xy 355.570937 -268.983596) (xy 355.578607 -268.965072) (xy 355.592786 -268.950898)
			(xy 355.611311 -268.943234) (xy 355.621336 -268.94282) (xy 355.646228 -268.94282) (xy 355.656388 -268.937994)
			(xy 355.677571 -268.928574) (xy 355.721968 -268.915235) (xy 355.76783 -268.908466) (xy 355.791008 -268.908022)
			(xy 355.816001 -268.908449) (xy 355.865371 -268.91627) (xy 355.91291 -268.931719) (xy 355.957447 -268.954414)
			(xy 355.997885 -268.983797) (xy 356.033228 -269.019144) (xy 356.062606 -269.059586) (xy 356.085296 -269.104125)
			(xy 356.100739 -269.151666) (xy 356.108554 -269.201037) (xy 356.109016 -269.22603) (xy 356.414827 -269.22603)
			(xy 356.418922 -269.175302) (xy 356.431101 -269.125888) (xy 356.451049 -269.079068) (xy 356.47825 -269.036054)
			(xy 356.511998 -268.99796) (xy 356.55142 -268.965773) (xy 356.595494 -268.940327) (xy 356.64308 -268.92228)
			(xy 356.692944 -268.9121) (xy 356.743796 -268.910051) (xy 356.794317 -268.916185) (xy 356.843201 -268.930345)
			(xy 356.88918 -268.952162) (xy 356.931064 -268.981072) (xy 356.967768 -269.016327) (xy 356.998341 -269.057013)
			(xy 357.021992 -269.102076) (xy 357.038108 -269.15035) (xy 357.046272 -269.200584) (xy 357.046784 -269.22603)
			(xy 357.354881 -269.22603) (xy 357.358976 -269.175302) (xy 357.371155 -269.125888) (xy 357.391103 -269.079068)
			(xy 357.418304 -269.036054) (xy 357.452052 -268.99796) (xy 357.491474 -268.965773) (xy 357.535548 -268.940327)
			(xy 357.583134 -268.92228) (xy 357.632998 -268.9121) (xy 357.68385 -268.910051) (xy 357.734371 -268.916185)
			(xy 357.783255 -268.930345) (xy 357.829234 -268.952162) (xy 357.871118 -268.981072) (xy 357.907822 -269.016327)
			(xy 357.938395 -269.057013) (xy 357.962046 -269.102076) (xy 357.978162 -269.15035) (xy 357.986326 -269.200584)
			(xy 357.986838 -269.22603) (xy 357.986335 -269.251019) (xy 358.293652 -269.251019) (xy 358.293652 -269.201041)
			(xy 358.301471 -269.151678) (xy 358.316915 -269.104146) (xy 358.339605 -269.059614) (xy 358.368981 -269.019181)
			(xy 358.404321 -268.983841) (xy 358.444754 -268.954465) (xy 358.489286 -268.931775) (xy 358.536818 -268.916331)
			(xy 358.586181 -268.908512) (xy 358.636159 -268.908512) (xy 358.685522 -268.916331) (xy 358.733054 -268.931775)
			(xy 358.777586 -268.954465) (xy 358.818019 -268.983841) (xy 358.853359 -269.019181) (xy 358.882735 -269.059614)
			(xy 358.905425 -269.104146) (xy 358.920869 -269.151678) (xy 358.928688 -269.201041) (xy 358.929178 -269.22603)
			(xy 358.928688 -269.251019) (xy 361.10721 -269.251019) (xy 361.10721 -269.201041) (xy 361.115029 -269.151678)
			(xy 361.130473 -269.104146) (xy 361.153163 -269.059614) (xy 361.182539 -269.019181) (xy 361.217879 -268.983841)
			(xy 361.258312 -268.954465) (xy 361.302844 -268.931775) (xy 361.350376 -268.916331) (xy 361.399739 -268.908512)
			(xy 361.449717 -268.908512) (xy 361.49908 -268.916331) (xy 361.546612 -268.931775) (xy 361.591144 -268.954465)
			(xy 361.631577 -268.983841) (xy 361.666917 -269.019181) (xy 361.696293 -269.059614) (xy 361.718983 -269.104146)
			(xy 361.734427 -269.151678) (xy 361.742246 -269.201041) (xy 361.742736 -269.22603) (xy 362.048547 -269.22603)
			(xy 362.052642 -269.175302) (xy 362.064821 -269.125888) (xy 362.084769 -269.079068) (xy 362.11197 -269.036054)
			(xy 362.145718 -268.99796) (xy 362.18514 -268.965773) (xy 362.229214 -268.940327) (xy 362.2768 -268.92228)
			(xy 362.326664 -268.9121) (xy 362.377516 -268.910051) (xy 362.428037 -268.916185) (xy 362.476921 -268.930345)
			(xy 362.5229 -268.952162) (xy 362.564784 -268.981072) (xy 362.601488 -269.016327) (xy 362.632061 -269.057013)
			(xy 362.655712 -269.102076) (xy 362.671828 -269.15035) (xy 362.679992 -269.200584) (xy 362.680504 -269.22603)
			(xy 362.988601 -269.22603) (xy 362.992696 -269.175302) (xy 363.004875 -269.125888) (xy 363.024823 -269.079068)
			(xy 363.052024 -269.036054) (xy 363.085772 -268.99796) (xy 363.125194 -268.965773) (xy 363.169268 -268.940327)
			(xy 363.216854 -268.92228) (xy 363.266718 -268.9121) (xy 363.31757 -268.910051) (xy 363.368091 -268.916185)
			(xy 363.416975 -268.930345) (xy 363.462954 -268.952162) (xy 363.504838 -268.981072) (xy 363.541542 -269.016327)
			(xy 363.572115 -269.057013) (xy 363.595766 -269.102076) (xy 363.611882 -269.15035) (xy 363.620046 -269.200584)
			(xy 363.620558 -269.22603) (xy 363.926882 -269.22603) (xy 363.927385 -269.20104) (xy 363.935199 -269.151675)
			(xy 363.950639 -269.10414) (xy 363.973326 -269.059606) (xy 364.002701 -269.01917) (xy 364.03804 -268.983827)
			(xy 364.078472 -268.954447) (xy 364.123003 -268.931755) (xy 364.170536 -268.916308) (xy 364.2199 -268.908488)
			(xy 364.24489 -268.908022) (xy 364.268072 -268.908436) (xy 364.313941 -268.915185) (xy 364.35834 -268.928539)
			(xy 364.37951 -268.937994) (xy 364.38967 -268.94282) (xy 364.545372 -268.94282) (xy 364.545372 -268.951964)
			(xy 364.545848 -268.96198) (xy 364.553501 -268.98049) (xy 364.567656 -268.994663) (xy 364.586157 -269.002339)
			(xy 364.596172 -269.002764) (xy 364.75924 -269.002764) (xy 364.769246 -269.003254) (xy 364.787732 -269.01092)
			(xy 364.801882 -269.025072) (xy 364.809546 -269.043558) (xy 364.81004 -269.053564) (xy 364.81004 -269.561056)
			(xy 366.608868 -269.561056) (xy 366.608868 -269.053564) (xy 366.609358 -269.043558) (xy 366.617023 -269.025072)
			(xy 366.631175 -269.010921) (xy 366.649662 -269.003257) (xy 366.659668 -269.002764) (xy 366.81791 -269.002764)
			(xy 366.827355 -269.002451) (xy 366.844976 -268.995651) (xy 366.8522 -268.989556) (xy 366.856264 -268.986)
			(xy 366.864147 -268.978448) (xy 366.873087 -268.958555) (xy 366.873536 -268.947646) (xy 366.873536 -268.94282)
			(xy 366.920018 -268.94282) (xy 366.930178 -268.937994) (xy 366.951362 -268.928577) (xy 366.995759 -268.915238)
			(xy 367.04162 -268.908467) (xy 367.064798 -268.908022) (xy 367.089791 -268.908458) (xy 367.139161 -268.916278)
			(xy 367.186699 -268.931725) (xy 367.231236 -268.954419) (xy 367.271674 -268.983801) (xy 367.307017 -269.019147)
			(xy 367.336396 -269.059588) (xy 367.359086 -269.104127) (xy 367.374529 -269.151667) (xy 367.382344 -269.201037)
			(xy 367.382806 -269.22603) (xy 369.566698 -269.22603) (xy 369.567185 -269.201039) (xy 369.574999 -269.151673)
			(xy 369.590441 -269.104137) (xy 369.613129 -269.059602) (xy 369.642506 -269.019165) (xy 369.677846 -268.983821)
			(xy 369.718281 -268.954442) (xy 369.762814 -268.93175) (xy 369.810349 -268.916305) (xy 369.859715 -268.908486)
			(xy 369.884706 -268.908022) (xy 369.907888 -268.90843) (xy 369.953758 -268.915181) (xy 369.998156 -268.928538)
			(xy 370.019326 -268.937994) (xy 370.029486 -268.94282) (xy 370.152676 -268.94282) (xy 370.152676 -268.951964)
			(xy 370.153149 -268.96198) (xy 370.160802 -268.980492) (xy 370.174958 -268.994664) (xy 370.193461 -269.00234)
			(xy 370.203476 -269.002764) (xy 370.366544 -269.002764) (xy 370.37655 -269.003251) (xy 370.395036 -269.010919)
			(xy 370.409186 -269.025071) (xy 370.41685 -269.043558) (xy 370.417344 -269.053564) (xy 370.417344 -269.561056)
			(xy 370.416777 -269.571055) (xy 370.40914 -269.589538) (xy 370.395012 -269.603691) (xy 370.376543 -269.61136)
			(xy 370.366544 -269.611856) (xy 370.203476 -269.611856) (xy 370.193472 -269.612367) (xy 370.174988 -269.620026)
			(xy 370.160838 -269.634171) (xy 370.153171 -269.652652) (xy 370.152676 -269.662656) (xy 370.152676 -269.702534)
			(xy 370.15316 -269.712541) (xy 370.160826 -269.731029) (xy 370.17498 -269.74518) (xy 370.193469 -269.752842)
			(xy 370.203476 -269.753334) (xy 370.214398 -269.753334) (xy 370.224304 -269.748762) (xy 370.244854 -269.739843)
			(xy 370.287858 -269.727288) (xy 370.332207 -269.720955) (xy 370.354606 -269.720568) (xy 370.35486 -269.720568)
			(xy 370.379655 -269.72095) (xy 370.428635 -269.728701) (xy 370.475799 -269.744019) (xy 370.519987 -269.766527)
			(xy 370.560109 -269.79567) (xy 370.595179 -269.830731) (xy 370.624332 -269.870846) (xy 370.64685 -269.915028)
			(xy 370.66218 -269.962189) (xy 370.669944 -270.011167) (xy 370.669947 -270.036036) (xy 370.978679 -270.036036)
			(xy 370.982774 -269.985308) (xy 370.994953 -269.935894) (xy 371.014901 -269.889074) (xy 371.042102 -269.84606)
			(xy 371.07585 -269.807966) (xy 371.115272 -269.775779) (xy 371.159346 -269.750333) (xy 371.206932 -269.732286)
			(xy 371.256796 -269.722106) (xy 371.307648 -269.720057) (xy 371.358169 -269.726191) (xy 371.407053 -269.740351)
			(xy 371.453032 -269.762168) (xy 371.494916 -269.791078) (xy 371.53162 -269.826333) (xy 371.562193 -269.867019)
			(xy 371.585844 -269.912082) (xy 371.60196 -269.960356) (xy 371.610124 -270.01059) (xy 371.610636 -270.036036)
			(xy 371.610134 -270.060965) (xy 371.917217 -270.060965) (xy 371.91722 -270.010993) (xy 371.92504 -269.961636)
			(xy 371.940486 -269.914111) (xy 371.963175 -269.869587) (xy 371.99255 -269.829161) (xy 372.027888 -269.793827)
			(xy 372.068317 -269.764457) (xy 372.112844 -269.741772) (xy 372.160371 -269.726332) (xy 372.209728 -269.718517)
			(xy 372.234714 -269.718028) (xy 372.262338 -269.718633) (xy 372.316749 -269.728213) (xy 372.342918 -269.737078)
			(xy 372.351046 -269.739872) (xy 372.359936 -269.739872) (xy 372.369949 -269.739441) (xy 372.388447 -269.731764)
			(xy 372.4026 -269.717594) (xy 372.410253 -269.699086) (xy 372.410736 -269.689072) (xy 372.410736 -269.662656)
			(xy 372.410249 -269.65265) (xy 372.402581 -269.634164) (xy 372.388429 -269.620014) (xy 372.369942 -269.61235)
			(xy 372.359936 -269.611856) (xy 372.196868 -269.611856) (xy 372.186839 -269.611506) (xy 372.168313 -269.603817)
			(xy 372.15414 -269.589623) (xy 372.146479 -269.571085) (xy 372.146068 -269.561056) (xy 372.146068 -269.053564)
			(xy 372.146558 -269.043558) (xy 372.154223 -269.025072) (xy 372.168375 -269.010921) (xy 372.186862 -269.003257)
			(xy 372.196868 -269.002764) (xy 372.410736 -269.002764) (xy 372.410736 -268.99362) (xy 372.411137 -268.983596)
			(xy 372.418807 -268.965072) (xy 372.432986 -268.950898) (xy 372.451511 -268.943234) (xy 372.461536 -268.94282)
			(xy 372.560088 -268.94282) (xy 372.570248 -268.937994) (xy 372.591423 -268.928554) (xy 372.635824 -268.915223)
			(xy 372.681689 -268.908462) (xy 372.704868 -268.908022) (xy 372.72986 -268.908487) (xy 372.779229 -268.916302)
			(xy 372.826767 -268.931745) (xy 372.871303 -268.954435) (xy 372.911742 -268.983813) (xy 372.947085 -269.019157)
			(xy 372.976464 -269.059595) (xy 372.999155 -269.104131) (xy 373.014598 -269.151669) (xy 373.022413 -269.201038)
			(xy 373.022876 -269.22603) (xy 373.022414 -269.251035) (xy 373.014577 -269.300427) (xy 372.999099 -269.347982)
			(xy 372.976365 -269.392526) (xy 372.946933 -269.432958) (xy 372.911533 -269.468282) (xy 372.891558 -269.483332)
			(xy 372.884688 -269.488826) (xy 372.87481 -269.503364) (xy 372.872254 -269.51178) (xy 372.866798 -269.531132)
			(xy 372.849656 -269.567496) (xy 372.826005 -269.600006) (xy 372.796684 -269.62751) (xy 372.76273 -269.649036)
			(xy 372.725346 -269.663821) (xy 372.685853 -269.671342) (xy 372.665752 -269.6718) (xy 372.56212 -269.6718)
			(xy 372.552576 -269.672219) (xy 372.53484 -269.679288) (xy 372.520884 -269.692319) (xy 372.5164 -269.700756)
			(xy 372.470172 -269.796768) (xy 372.473728 -269.825724) (xy 372.482872 -269.837154) (xy 372.499218 -269.858491)
			(xy 372.5253 -269.905481) (xy 372.543115 -269.956186) (xy 372.552157 -270.009164) (xy 372.552722 -270.036036)
			(xy 372.858533 -270.036036) (xy 372.862628 -269.985308) (xy 372.874807 -269.935894) (xy 372.894755 -269.889074)
			(xy 372.921956 -269.84606) (xy 372.955704 -269.807966) (xy 372.995126 -269.775779) (xy 373.0392 -269.750333)
			(xy 373.086786 -269.732286) (xy 373.13665 -269.722106) (xy 373.187502 -269.720057) (xy 373.238023 -269.726191)
			(xy 373.286907 -269.740351) (xy 373.332886 -269.762168) (xy 373.37477 -269.791078) (xy 373.411474 -269.826333)
			(xy 373.442047 -269.867019) (xy 373.465698 -269.912082) (xy 373.481814 -269.960356) (xy 373.489978 -270.01059)
			(xy 373.49049 -270.036036) (xy 373.798587 -270.036036) (xy 373.802682 -269.985308) (xy 373.814861 -269.935894)
			(xy 373.834809 -269.889074) (xy 373.86201 -269.84606) (xy 373.895758 -269.807966) (xy 373.93518 -269.775779)
			(xy 373.979254 -269.750333) (xy 374.02684 -269.732286) (xy 374.076704 -269.722106) (xy 374.127556 -269.720057)
			(xy 374.178077 -269.726191) (xy 374.226961 -269.740351) (xy 374.27294 -269.762168) (xy 374.314824 -269.791078)
			(xy 374.351528 -269.826333) (xy 374.382101 -269.867019) (xy 374.405752 -269.912082) (xy 374.421868 -269.960356)
			(xy 374.430032 -270.01059) (xy 374.430544 -270.036036) (xy 374.430032 -270.061482) (xy 374.421868 -270.111716)
			(xy 374.405752 -270.15999) (xy 374.382101 -270.205053) (xy 374.351528 -270.245739) (xy 374.314824 -270.280994)
			(xy 374.27294 -270.309904) (xy 374.226961 -270.331721) (xy 374.178077 -270.345881) (xy 374.127556 -270.352015)
			(xy 374.076704 -270.349966) (xy 374.02684 -270.339786) (xy 373.979254 -270.321739) (xy 373.93518 -270.296293)
			(xy 373.895758 -270.264106) (xy 373.86201 -270.226012) (xy 373.834809 -270.182998) (xy 373.814861 -270.136178)
			(xy 373.802682 -270.086764) (xy 373.798587 -270.036036) (xy 373.49049 -270.036036) (xy 373.489978 -270.061482)
			(xy 373.481814 -270.111716) (xy 373.465698 -270.15999) (xy 373.442047 -270.205053) (xy 373.411474 -270.245739)
			(xy 373.37477 -270.280994) (xy 373.332886 -270.309904) (xy 373.286907 -270.331721) (xy 373.238023 -270.345881)
			(xy 373.187502 -270.352015) (xy 373.13665 -270.349966) (xy 373.086786 -270.339786) (xy 373.0392 -270.321739)
			(xy 372.995126 -270.296293) (xy 372.955704 -270.264106) (xy 372.921956 -270.226012) (xy 372.894755 -270.182998)
			(xy 372.874807 -270.136178) (xy 372.862628 -270.086764) (xy 372.858533 -270.036036) (xy 372.552722 -270.036036)
			(xy 372.552179 -270.061022) (xy 372.544356 -270.110378) (xy 372.528909 -270.157902) (xy 372.506217 -270.202425)
			(xy 372.47684 -270.24285) (xy 372.441501 -270.278182) (xy 372.40107 -270.307551) (xy 372.356542 -270.330234)
			(xy 372.309015 -270.345671) (xy 372.259657 -270.353484) (xy 372.209685 -270.35348) (xy 372.160329 -270.345658)
			(xy 372.112804 -270.330212) (xy 372.068281 -270.307521) (xy 372.027855 -270.278145) (xy 371.992522 -270.242807)
			(xy 371.963153 -270.202376) (xy 371.940469 -270.157849) (xy 371.92503 -270.110322) (xy 371.917217 -270.060965)
			(xy 371.610134 -270.060965) (xy 371.610124 -270.061482) (xy 371.60196 -270.111716) (xy 371.585844 -270.15999)
			(xy 371.562193 -270.205053) (xy 371.53162 -270.245739) (xy 371.494916 -270.280994) (xy 371.453032 -270.309904)
			(xy 371.407053 -270.331721) (xy 371.358169 -270.345881) (xy 371.307648 -270.352015) (xy 371.256796 -270.349966)
			(xy 371.206932 -270.339786) (xy 371.159346 -270.321739) (xy 371.115272 -270.296293) (xy 371.07585 -270.264106)
			(xy 371.042102 -270.226012) (xy 371.014901 -270.182998) (xy 370.994953 -270.136178) (xy 370.982774 -270.086764)
			(xy 370.978679 -270.036036) (xy 370.669947 -270.036036) (xy 370.66995 -270.060756) (xy 370.662198 -270.109736)
			(xy 370.64688 -270.156901) (xy 370.624372 -270.201088) (xy 370.595229 -270.24121) (xy 370.560168 -270.27628)
			(xy 370.520053 -270.305432) (xy 370.475871 -270.327951) (xy 370.42871 -270.343281) (xy 370.379732 -270.351044)
			(xy 370.330142 -270.35105) (xy 370.281163 -270.343298) (xy 370.233998 -270.32798) (xy 370.189811 -270.305471)
			(xy 370.149689 -270.276328) (xy 370.11462 -270.241267) (xy 370.085467 -270.201152) (xy 370.062949 -270.15697)
			(xy 370.047619 -270.109809) (xy 370.039856 -270.060831) (xy 370.039392 -270.036036) (xy 370.039392 -270.035528)
			(xy 370.039947 -270.008727) (xy 370.049013 -269.955897) (xy 370.06689 -269.905364) (xy 370.09306 -269.858584)
			(xy 370.109496 -269.837408) (xy 370.118894 -269.825978) (xy 370.12245 -269.797022) (xy 370.076476 -269.700756)
			(xy 370.071974 -269.692334) (xy 370.058023 -269.679314) (xy 370.040294 -269.672256) (xy 370.030756 -269.6718)
			(xy 369.89766 -269.6718) (xy 369.876075 -269.671177) (xy 369.833792 -269.66246) (xy 369.79412 -269.64543)
			(xy 369.758677 -269.62078) (xy 369.728905 -269.589515) (xy 369.706019 -269.552909) (xy 369.690949 -269.512452)
			(xy 369.687094 -269.491206) (xy 369.685401 -269.482743) (xy 369.677231 -269.467554) (xy 369.671092 -269.461488)
			(xy 369.651805 -269.443255) (xy 369.618939 -269.401586) (xy 369.593454 -269.355035) (xy 369.576057 -269.304897)
			(xy 369.567234 -269.252565) (xy 369.566698 -269.22603) (xy 367.382806 -269.22603) (xy 367.382806 -269.226284)
			(xy 367.382316 -269.251495) (xy 367.374333 -269.301281) (xy 367.35861 -269.349189) (xy 367.3475 -269.371826)
			(xy 367.344907 -269.37725) (xy 367.34208 -269.388931) (xy 367.341912 -269.39494) (xy 367.341912 -269.456916)
			(xy 367.341912 -269.45717) (xy 367.34163 -269.478223) (xy 367.333624 -269.519555) (xy 367.317679 -269.55852)
			(xy 367.294412 -269.593608) (xy 367.264725 -269.62346) (xy 367.229766 -269.646921) (xy 367.19089 -269.663082)
			(xy 367.149603 -269.671317) (xy 367.128552 -269.6718) (xy 366.873536 -269.6718) (xy 366.873536 -269.662656)
			(xy 366.873049 -269.65265) (xy 366.865381 -269.634164) (xy 366.851229 -269.620014) (xy 366.832742 -269.61235)
			(xy 366.822736 -269.611856) (xy 366.659668 -269.611856) (xy 366.649639 -269.611506) (xy 366.631113 -269.603817)
			(xy 366.61694 -269.589623) (xy 366.609279 -269.571085) (xy 366.608868 -269.561056) (xy 364.81004 -269.561056)
			(xy 364.809545 -269.57107) (xy 364.801897 -269.589578) (xy 364.787748 -269.60375) (xy 364.769253 -269.611429)
			(xy 364.75924 -269.611856) (xy 364.596172 -269.611856) (xy 364.586168 -269.612364) (xy 364.567684 -269.620025)
			(xy 364.553534 -269.634171) (xy 364.545867 -269.652652) (xy 364.545372 -269.662656) (xy 364.545372 -269.689326)
			(xy 364.545866 -269.699332) (xy 364.553529 -269.717819) (xy 364.567679 -269.73197) (xy 364.586166 -269.739634)
			(xy 364.596172 -269.740126) (xy 364.604554 -269.740126) (xy 364.612428 -269.737586) (xy 364.637197 -269.729614)
			(xy 364.68852 -269.721066) (xy 364.714536 -269.720568) (xy 364.71479 -269.720568) (xy 364.739596 -269.721054)
			(xy 364.788599 -269.728812) (xy 364.835785 -269.744139) (xy 364.879993 -269.766659) (xy 364.920134 -269.795815)
			(xy 364.955221 -269.830891) (xy 364.98439 -269.871024) (xy 365.006923 -269.915224) (xy 365.022265 -269.962406)
			(xy 365.030039 -270.011406) (xy 365.030046 -270.036036) (xy 365.338609 -270.036036) (xy 365.342704 -269.985308)
			(xy 365.354883 -269.935894) (xy 365.374831 -269.889074) (xy 365.402032 -269.84606) (xy 365.43578 -269.807966)
			(xy 365.475202 -269.775779) (xy 365.519276 -269.750333) (xy 365.566862 -269.732286) (xy 365.616726 -269.722106)
			(xy 365.667578 -269.720057) (xy 365.718099 -269.726191) (xy 365.766983 -269.740351) (xy 365.812962 -269.762168)
			(xy 365.854846 -269.791078) (xy 365.89155 -269.826333) (xy 365.922123 -269.867019) (xy 365.945774 -269.912082)
			(xy 365.96189 -269.960356) (xy 365.970054 -270.01059) (xy 365.970566 -270.036036) (xy 365.970063 -270.061025)
			(xy 366.27738 -270.061025) (xy 366.27738 -270.011047) (xy 366.285199 -269.961684) (xy 366.300643 -269.914152)
			(xy 366.323333 -269.86962) (xy 366.352709 -269.829187) (xy 366.388049 -269.793847) (xy 366.428482 -269.764471)
			(xy 366.473014 -269.741781) (xy 366.520546 -269.726337) (xy 366.569909 -269.718518) (xy 366.619887 -269.718518)
			(xy 366.66925 -269.726337) (xy 366.716782 -269.741781) (xy 366.761314 -269.764471) (xy 366.801747 -269.793847)
			(xy 366.837087 -269.829187) (xy 366.866463 -269.86962) (xy 366.889153 -269.914152) (xy 366.904597 -269.961684)
			(xy 366.912416 -270.011047) (xy 366.912906 -270.036036) (xy 367.218463 -270.036036) (xy 367.222558 -269.985308)
			(xy 367.234737 -269.935894) (xy 367.254685 -269.889074) (xy 367.281886 -269.84606) (xy 367.315634 -269.807966)
			(xy 367.355056 -269.775779) (xy 367.39913 -269.750333) (xy 367.446716 -269.732286) (xy 367.49658 -269.722106)
			(xy 367.547432 -269.720057) (xy 367.597953 -269.726191) (xy 367.646837 -269.740351) (xy 367.692816 -269.762168)
			(xy 367.7347 -269.791078) (xy 367.771404 -269.826333) (xy 367.801977 -269.867019) (xy 367.825628 -269.912082)
			(xy 367.841744 -269.960356) (xy 367.849908 -270.01059) (xy 367.85042 -270.036036) (xy 368.158517 -270.036036)
			(xy 368.162612 -269.985308) (xy 368.174791 -269.935894) (xy 368.194739 -269.889074) (xy 368.22194 -269.84606)
			(xy 368.255688 -269.807966) (xy 368.29511 -269.775779) (xy 368.339184 -269.750333) (xy 368.38677 -269.732286)
			(xy 368.436634 -269.722106) (xy 368.487486 -269.720057) (xy 368.538007 -269.726191) (xy 368.586891 -269.740351)
			(xy 368.63287 -269.762168) (xy 368.674754 -269.791078) (xy 368.711458 -269.826333) (xy 368.742031 -269.867019)
			(xy 368.765682 -269.912082) (xy 368.781798 -269.960356) (xy 368.789962 -270.01059) (xy 368.790474 -270.036036)
			(xy 368.789971 -270.061025) (xy 369.097288 -270.061025) (xy 369.097288 -270.011047) (xy 369.105107 -269.961684)
			(xy 369.120551 -269.914152) (xy 369.143241 -269.86962) (xy 369.172617 -269.829187) (xy 369.207957 -269.793847)
			(xy 369.24839 -269.764471) (xy 369.292922 -269.741781) (xy 369.340454 -269.726337) (xy 369.389817 -269.718518)
			(xy 369.439795 -269.718518) (xy 369.489158 -269.726337) (xy 369.53669 -269.741781) (xy 369.581222 -269.764471)
			(xy 369.621655 -269.793847) (xy 369.656995 -269.829187) (xy 369.686371 -269.86962) (xy 369.709061 -269.914152)
			(xy 369.724505 -269.961684) (xy 369.732324 -270.011047) (xy 369.732814 -270.036036) (xy 369.732324 -270.061025)
			(xy 369.724505 -270.110388) (xy 369.709061 -270.15792) (xy 369.686371 -270.202452) (xy 369.656995 -270.242885)
			(xy 369.621655 -270.278225) (xy 369.581222 -270.307601) (xy 369.53669 -270.330291) (xy 369.489158 -270.345735)
			(xy 369.439795 -270.353554) (xy 369.389817 -270.353554) (xy 369.340454 -270.345735) (xy 369.292922 -270.330291)
			(xy 369.24839 -270.307601) (xy 369.207957 -270.278225) (xy 369.172617 -270.242885) (xy 369.143241 -270.202452)
			(xy 369.120551 -270.15792) (xy 369.105107 -270.110388) (xy 369.097288 -270.061025) (xy 368.789971 -270.061025)
			(xy 368.789962 -270.061482) (xy 368.781798 -270.111716) (xy 368.765682 -270.15999) (xy 368.742031 -270.205053)
			(xy 368.711458 -270.245739) (xy 368.674754 -270.280994) (xy 368.63287 -270.309904) (xy 368.586891 -270.331721)
			(xy 368.538007 -270.345881) (xy 368.487486 -270.352015) (xy 368.436634 -270.349966) (xy 368.38677 -270.339786)
			(xy 368.339184 -270.321739) (xy 368.29511 -270.296293) (xy 368.255688 -270.264106) (xy 368.22194 -270.226012)
			(xy 368.194739 -270.182998) (xy 368.174791 -270.136178) (xy 368.162612 -270.086764) (xy 368.158517 -270.036036)
			(xy 367.85042 -270.036036) (xy 367.849908 -270.061482) (xy 367.841744 -270.111716) (xy 367.825628 -270.15999)
			(xy 367.801977 -270.205053) (xy 367.771404 -270.245739) (xy 367.7347 -270.280994) (xy 367.692816 -270.309904)
			(xy 367.646837 -270.331721) (xy 367.597953 -270.345881) (xy 367.547432 -270.352015) (xy 367.49658 -270.349966)
			(xy 367.446716 -270.339786) (xy 367.39913 -270.321739) (xy 367.355056 -270.296293) (xy 367.315634 -270.264106)
			(xy 367.281886 -270.226012) (xy 367.254685 -270.182998) (xy 367.234737 -270.136178) (xy 367.222558 -270.086764)
			(xy 367.218463 -270.036036) (xy 366.912906 -270.036036) (xy 366.912416 -270.061025) (xy 366.904597 -270.110388)
			(xy 366.889153 -270.15792) (xy 366.866463 -270.202452) (xy 366.837087 -270.242885) (xy 366.801747 -270.278225)
			(xy 366.761314 -270.307601) (xy 366.716782 -270.330291) (xy 366.66925 -270.345735) (xy 366.619887 -270.353554)
			(xy 366.569909 -270.353554) (xy 366.520546 -270.345735) (xy 366.473014 -270.330291) (xy 366.428482 -270.307601)
			(xy 366.388049 -270.278225) (xy 366.352709 -270.242885) (xy 366.323333 -270.202452) (xy 366.300643 -270.15792)
			(xy 366.285199 -270.110388) (xy 366.27738 -270.061025) (xy 365.970063 -270.061025) (xy 365.970054 -270.061482)
			(xy 365.96189 -270.111716) (xy 365.945774 -270.15999) (xy 365.922123 -270.205053) (xy 365.89155 -270.245739)
			(xy 365.854846 -270.280994) (xy 365.812962 -270.309904) (xy 365.766983 -270.331721) (xy 365.718099 -270.345881)
			(xy 365.667578 -270.352015) (xy 365.616726 -270.349966) (xy 365.566862 -270.339786) (xy 365.519276 -270.321739)
			(xy 365.475202 -270.296293) (xy 365.43578 -270.264106) (xy 365.402032 -270.226012) (xy 365.374831 -270.182998)
			(xy 365.354883 -270.136178) (xy 365.342704 -270.086764) (xy 365.338609 -270.036036) (xy 365.030046 -270.036036)
			(xy 365.030053 -270.061019) (xy 365.022306 -270.110023) (xy 365.00699 -270.157213) (xy 364.984482 -270.201426)
			(xy 364.955336 -270.241575) (xy 364.920268 -270.27667) (xy 364.880143 -270.305849) (xy 364.835948 -270.328393)
			(xy 364.78877 -270.343747) (xy 364.739772 -270.351533) (xy 364.690159 -270.351559) (xy 364.641153 -270.343824)
			(xy 364.593959 -270.32852) (xy 364.549741 -270.306023) (xy 364.509585 -270.276886) (xy 364.47448 -270.241828)
			(xy 364.445292 -270.20171) (xy 364.422737 -270.15752) (xy 364.407371 -270.110346) (xy 364.399574 -270.06135)
			(xy 364.399068 -270.036544) (xy 364.399068 -270.036036) (xy 364.399581 -270.009159) (xy 364.408687 -269.956183)
			(xy 364.42664 -269.905517) (xy 364.452923 -269.858628) (xy 364.469426 -269.837408) (xy 364.478824 -269.825978)
			(xy 364.48238 -269.797022) (xy 364.436406 -269.700756) (xy 364.431884 -269.692346) (xy 364.417942 -269.679326)
			(xy 364.400221 -269.672261) (xy 364.390686 -269.6718) (xy 364.290356 -269.6718) (xy 364.2706 -269.671368)
			(xy 364.231768 -269.664059) (xy 364.194943 -269.649736) (xy 364.161378 -269.628886) (xy 364.132218 -269.602221)
			(xy 364.108458 -269.57065) (xy 364.090908 -269.535248) (xy 364.085124 -269.516352) (xy 364.082359 -269.507942)
			(xy 364.071955 -269.493631) (xy 364.064804 -269.488412) (xy 364.043924 -269.473405) (xy 364.006801 -269.437831)
			(xy 363.975874 -269.396756) (xy 363.951946 -269.351247) (xy 363.935639 -269.302486) (xy 363.927376 -269.251738)
			(xy 363.926882 -269.22603) (xy 363.620558 -269.22603) (xy 363.620046 -269.251476) (xy 363.611882 -269.30171)
			(xy 363.595766 -269.349984) (xy 363.572115 -269.395047) (xy 363.541542 -269.435733) (xy 363.504838 -269.470988)
			(xy 363.462954 -269.499898) (xy 363.416975 -269.521715) (xy 363.368091 -269.535875) (xy 363.31757 -269.542009)
			(xy 363.266718 -269.53996) (xy 363.216854 -269.52978) (xy 363.169268 -269.511733) (xy 363.125194 -269.486287)
			(xy 363.085772 -269.4541) (xy 363.052024 -269.416006) (xy 363.024823 -269.372992) (xy 363.004875 -269.326172)
			(xy 362.992696 -269.276758) (xy 362.988601 -269.22603) (xy 362.680504 -269.22603) (xy 362.679992 -269.251476)
			(xy 362.671828 -269.30171) (xy 362.655712 -269.349984) (xy 362.632061 -269.395047) (xy 362.601488 -269.435733)
			(xy 362.564784 -269.470988) (xy 362.5229 -269.499898) (xy 362.476921 -269.521715) (xy 362.428037 -269.535875)
			(xy 362.377516 -269.542009) (xy 362.326664 -269.53996) (xy 362.2768 -269.52978) (xy 362.229214 -269.511733)
			(xy 362.18514 -269.486287) (xy 362.145718 -269.4541) (xy 362.11197 -269.416006) (xy 362.084769 -269.372992)
			(xy 362.064821 -269.326172) (xy 362.052642 -269.276758) (xy 362.048547 -269.22603) (xy 361.742736 -269.22603)
			(xy 361.742246 -269.251019) (xy 361.734427 -269.300382) (xy 361.718983 -269.347914) (xy 361.696293 -269.392446)
			(xy 361.666917 -269.432879) (xy 361.631577 -269.468219) (xy 361.591144 -269.497595) (xy 361.546612 -269.520285)
			(xy 361.49908 -269.535729) (xy 361.449717 -269.543548) (xy 361.399739 -269.543548) (xy 361.350376 -269.535729)
			(xy 361.302844 -269.520285) (xy 361.258312 -269.497595) (xy 361.217879 -269.468219) (xy 361.182539 -269.432879)
			(xy 361.153163 -269.392446) (xy 361.130473 -269.347914) (xy 361.115029 -269.300382) (xy 361.10721 -269.251019)
			(xy 358.928688 -269.251019) (xy 358.920869 -269.300382) (xy 358.905425 -269.347914) (xy 358.882735 -269.392446)
			(xy 358.853359 -269.432879) (xy 358.818019 -269.468219) (xy 358.777586 -269.497595) (xy 358.733054 -269.520285)
			(xy 358.685522 -269.535729) (xy 358.636159 -269.543548) (xy 358.586181 -269.543548) (xy 358.536818 -269.535729)
			(xy 358.489286 -269.520285) (xy 358.444754 -269.497595) (xy 358.404321 -269.468219) (xy 358.368981 -269.432879)
			(xy 358.339605 -269.392446) (xy 358.316915 -269.347914) (xy 358.301471 -269.300382) (xy 358.293652 -269.251019)
			(xy 357.986335 -269.251019) (xy 357.986326 -269.251476) (xy 357.978162 -269.30171) (xy 357.962046 -269.349984)
			(xy 357.938395 -269.395047) (xy 357.907822 -269.435733) (xy 357.871118 -269.470988) (xy 357.829234 -269.499898)
			(xy 357.783255 -269.521715) (xy 357.734371 -269.535875) (xy 357.68385 -269.542009) (xy 357.632998 -269.53996)
			(xy 357.583134 -269.52978) (xy 357.535548 -269.511733) (xy 357.491474 -269.486287) (xy 357.452052 -269.4541)
			(xy 357.418304 -269.416006) (xy 357.391103 -269.372992) (xy 357.371155 -269.326172) (xy 357.358976 -269.276758)
			(xy 357.354881 -269.22603) (xy 357.046784 -269.22603) (xy 357.046272 -269.251476) (xy 357.038108 -269.30171)
			(xy 357.021992 -269.349984) (xy 356.998341 -269.395047) (xy 356.967768 -269.435733) (xy 356.931064 -269.470988)
			(xy 356.88918 -269.499898) (xy 356.843201 -269.521715) (xy 356.794317 -269.535875) (xy 356.743796 -269.542009)
			(xy 356.692944 -269.53996) (xy 356.64308 -269.52978) (xy 356.595494 -269.511733) (xy 356.55142 -269.486287)
			(xy 356.511998 -269.4541) (xy 356.47825 -269.416006) (xy 356.451049 -269.372992) (xy 356.431101 -269.326172)
			(xy 356.418922 -269.276758) (xy 356.414827 -269.22603) (xy 356.109016 -269.22603) (xy 356.109016 -269.226284)
			(xy 356.108526 -269.2512) (xy 356.100721 -269.300418) (xy 356.085348 -269.347821) (xy 356.062779 -269.392251)
			(xy 356.048564 -269.41272) (xy 356.043738 -269.41907) (xy 356.038912 -269.43431) (xy 356.038912 -269.456916)
			(xy 356.038912 -269.45717) (xy 356.03863 -269.478223) (xy 356.030624 -269.519555) (xy 356.014679 -269.55852)
			(xy 355.991412 -269.593608) (xy 355.961725 -269.62346) (xy 355.926766 -269.646921) (xy 355.88789 -269.663082)
			(xy 355.846603 -269.671317) (xy 355.825552 -269.6718) (xy 355.570536 -269.6718) (xy 355.570536 -269.662656)
			(xy 355.570049 -269.65265) (xy 355.562381 -269.634164) (xy 355.548229 -269.620014) (xy 355.529742 -269.61235)
			(xy 355.519736 -269.611856) (xy 355.356668 -269.611856) (xy 355.346639 -269.611506) (xy 355.328113 -269.603817)
			(xy 355.31394 -269.589623) (xy 355.306279 -269.571085) (xy 355.305868 -269.561056) (xy 353.50704 -269.561056)
			(xy 353.506545 -269.57107) (xy 353.498897 -269.589578) (xy 353.484748 -269.60375) (xy 353.466253 -269.611429)
			(xy 353.45624 -269.611856) (xy 353.293172 -269.611856) (xy 353.283168 -269.612364) (xy 353.264684 -269.620025)
			(xy 353.250534 -269.634171) (xy 353.242867 -269.652652) (xy 353.242372 -269.662656) (xy 353.242372 -269.698216)
			(xy 353.242874 -269.708221) (xy 353.250534 -269.726708) (xy 353.264682 -269.74086) (xy 353.283167 -269.748524)
			(xy 353.293172 -269.749016) (xy 353.303586 -269.749016) (xy 353.313492 -269.744698) (xy 353.333683 -269.736273)
			(xy 353.375788 -269.72439) (xy 353.419125 -269.718392) (xy 353.441 -269.718028) (xy 353.465989 -269.718482)
			(xy 353.51535 -269.7263) (xy 353.562882 -269.741744) (xy 353.607412 -269.764432) (xy 353.647845 -269.793808)
			(xy 353.683185 -269.829146) (xy 353.712561 -269.869578) (xy 353.735252 -269.914107) (xy 353.750697 -269.961638)
			(xy 353.758517 -270.010999) (xy 353.758518 -270.036036) (xy 354.064819 -270.036036) (xy 354.068914 -269.985308)
			(xy 354.081093 -269.935894) (xy 354.101041 -269.889074) (xy 354.128242 -269.84606) (xy 354.16199 -269.807966)
			(xy 354.201412 -269.775779) (xy 354.245486 -269.750333) (xy 354.293072 -269.732286) (xy 354.342936 -269.722106)
			(xy 354.393788 -269.720057) (xy 354.444309 -269.726191) (xy 354.493193 -269.740351) (xy 354.539172 -269.762168)
			(xy 354.581056 -269.791078) (xy 354.61776 -269.826333) (xy 354.648333 -269.867019) (xy 354.671984 -269.912082)
			(xy 354.6881 -269.960356) (xy 354.696264 -270.01059) (xy 354.696776 -270.036036) (xy 355.004873 -270.036036)
			(xy 355.008968 -269.985308) (xy 355.021147 -269.935894) (xy 355.041095 -269.889074) (xy 355.068296 -269.84606)
			(xy 355.102044 -269.807966) (xy 355.141466 -269.775779) (xy 355.18554 -269.750333) (xy 355.233126 -269.732286)
			(xy 355.28299 -269.722106) (xy 355.333842 -269.720057) (xy 355.384363 -269.726191) (xy 355.433247 -269.740351)
			(xy 355.479226 -269.762168) (xy 355.52111 -269.791078) (xy 355.557814 -269.826333) (xy 355.588387 -269.867019)
			(xy 355.612038 -269.912082) (xy 355.628154 -269.960356) (xy 355.636318 -270.01059) (xy 355.63683 -270.036036)
			(xy 355.636327 -270.061025) (xy 355.943644 -270.061025) (xy 355.943644 -270.011047) (xy 355.951463 -269.961684)
			(xy 355.966907 -269.914152) (xy 355.989597 -269.86962) (xy 356.018973 -269.829187) (xy 356.054313 -269.793847)
			(xy 356.094746 -269.764471) (xy 356.139278 -269.741781) (xy 356.18681 -269.726337) (xy 356.236173 -269.718518)
			(xy 356.286151 -269.718518) (xy 356.335514 -269.726337) (xy 356.383046 -269.741781) (xy 356.427578 -269.764471)
			(xy 356.468011 -269.793847) (xy 356.503351 -269.829187) (xy 356.532727 -269.86962) (xy 356.555417 -269.914152)
			(xy 356.570861 -269.961684) (xy 356.57868 -270.011047) (xy 356.57917 -270.036036) (xy 356.57868 -270.061025)
			(xy 356.883698 -270.061025) (xy 356.883698 -270.011047) (xy 356.891517 -269.961684) (xy 356.906961 -269.914152)
			(xy 356.929651 -269.86962) (xy 356.959027 -269.829187) (xy 356.994367 -269.793847) (xy 357.0348 -269.764471)
			(xy 357.079332 -269.741781) (xy 357.126864 -269.726337) (xy 357.176227 -269.718518) (xy 357.226205 -269.718518)
			(xy 357.275568 -269.726337) (xy 357.3231 -269.741781) (xy 357.367632 -269.764471) (xy 357.408065 -269.793847)
			(xy 357.443405 -269.829187) (xy 357.472781 -269.86962) (xy 357.495471 -269.914152) (xy 357.510915 -269.961684)
			(xy 357.518734 -270.011047) (xy 357.519224 -270.036036) (xy 357.518734 -270.061025) (xy 357.823498 -270.061025)
			(xy 357.823498 -270.011047) (xy 357.831317 -269.961684) (xy 357.846761 -269.914152) (xy 357.869451 -269.86962)
			(xy 357.898827 -269.829187) (xy 357.934167 -269.793847) (xy 357.9746 -269.764471) (xy 358.019132 -269.741781)
			(xy 358.066664 -269.726337) (xy 358.116027 -269.718518) (xy 358.166005 -269.718518) (xy 358.215368 -269.726337)
			(xy 358.2629 -269.741781) (xy 358.307432 -269.764471) (xy 358.347865 -269.793847) (xy 358.383205 -269.829187)
			(xy 358.412581 -269.86962) (xy 358.435271 -269.914152) (xy 358.450715 -269.961684) (xy 358.458534 -270.011047)
			(xy 358.459024 -270.036036) (xy 358.458534 -270.061025) (xy 361.577364 -270.061025) (xy 361.577364 -270.011047)
			(xy 361.585183 -269.961684) (xy 361.600627 -269.914152) (xy 361.623317 -269.86962) (xy 361.652693 -269.829187)
			(xy 361.688033 -269.793847) (xy 361.728466 -269.764471) (xy 361.772998 -269.741781) (xy 361.82053 -269.726337)
			(xy 361.869893 -269.718518) (xy 361.919871 -269.718518) (xy 361.969234 -269.726337) (xy 362.016766 -269.741781)
			(xy 362.061298 -269.764471) (xy 362.101731 -269.793847) (xy 362.137071 -269.829187) (xy 362.166447 -269.86962)
			(xy 362.189137 -269.914152) (xy 362.204581 -269.961684) (xy 362.2124 -270.011047) (xy 362.21289 -270.036036)
			(xy 362.2124 -270.061025) (xy 362.517164 -270.061025) (xy 362.517164 -270.011047) (xy 362.524983 -269.961684)
			(xy 362.540427 -269.914152) (xy 362.563117 -269.86962) (xy 362.592493 -269.829187) (xy 362.627833 -269.793847)
			(xy 362.668266 -269.764471) (xy 362.712798 -269.741781) (xy 362.76033 -269.726337) (xy 362.809693 -269.718518)
			(xy 362.859671 -269.718518) (xy 362.909034 -269.726337) (xy 362.956566 -269.741781) (xy 363.001098 -269.764471)
			(xy 363.041531 -269.793847) (xy 363.076871 -269.829187) (xy 363.106247 -269.86962) (xy 363.128937 -269.914152)
			(xy 363.144381 -269.961684) (xy 363.1522 -270.011047) (xy 363.15269 -270.036036) (xy 363.1522 -270.061025)
			(xy 363.457218 -270.061025) (xy 363.457218 -270.011047) (xy 363.465037 -269.961684) (xy 363.480481 -269.914152)
			(xy 363.503171 -269.86962) (xy 363.532547 -269.829187) (xy 363.567887 -269.793847) (xy 363.60832 -269.764471)
			(xy 363.652852 -269.741781) (xy 363.700384 -269.726337) (xy 363.749747 -269.718518) (xy 363.799725 -269.718518)
			(xy 363.849088 -269.726337) (xy 363.89662 -269.741781) (xy 363.941152 -269.764471) (xy 363.981585 -269.793847)
			(xy 364.016925 -269.829187) (xy 364.046301 -269.86962) (xy 364.068991 -269.914152) (xy 364.084435 -269.961684)
			(xy 364.092254 -270.011047) (xy 364.092744 -270.036036) (xy 364.092254 -270.061025) (xy 364.084435 -270.110388)
			(xy 364.068991 -270.15792) (xy 364.046301 -270.202452) (xy 364.016925 -270.242885) (xy 363.981585 -270.278225)
			(xy 363.941152 -270.307601) (xy 363.89662 -270.330291) (xy 363.849088 -270.345735) (xy 363.799725 -270.353554)
			(xy 363.749747 -270.353554) (xy 363.700384 -270.345735) (xy 363.652852 -270.330291) (xy 363.60832 -270.307601)
			(xy 363.567887 -270.278225) (xy 363.532547 -270.242885) (xy 363.503171 -270.202452) (xy 363.480481 -270.15792)
			(xy 363.465037 -270.110388) (xy 363.457218 -270.061025) (xy 363.1522 -270.061025) (xy 363.144381 -270.110388)
			(xy 363.128937 -270.15792) (xy 363.106247 -270.202452) (xy 363.076871 -270.242885) (xy 363.041531 -270.278225)
			(xy 363.001098 -270.307601) (xy 362.956566 -270.330291) (xy 362.909034 -270.345735) (xy 362.859671 -270.353554)
			(xy 362.809693 -270.353554) (xy 362.76033 -270.345735) (xy 362.712798 -270.330291) (xy 362.668266 -270.307601)
			(xy 362.627833 -270.278225) (xy 362.592493 -270.242885) (xy 362.563117 -270.202452) (xy 362.540427 -270.15792)
			(xy 362.524983 -270.110388) (xy 362.517164 -270.061025) (xy 362.2124 -270.061025) (xy 362.204581 -270.110388)
			(xy 362.189137 -270.15792) (xy 362.166447 -270.202452) (xy 362.137071 -270.242885) (xy 362.101731 -270.278225)
			(xy 362.061298 -270.307601) (xy 362.016766 -270.330291) (xy 361.969234 -270.345735) (xy 361.919871 -270.353554)
			(xy 361.869893 -270.353554) (xy 361.82053 -270.345735) (xy 361.772998 -270.330291) (xy 361.728466 -270.307601)
			(xy 361.688033 -270.278225) (xy 361.652693 -270.242885) (xy 361.623317 -270.202452) (xy 361.600627 -270.15792)
			(xy 361.585183 -270.110388) (xy 361.577364 -270.061025) (xy 358.458534 -270.061025) (xy 358.450715 -270.110388)
			(xy 358.435271 -270.15792) (xy 358.412581 -270.202452) (xy 358.383205 -270.242885) (xy 358.347865 -270.278225)
			(xy 358.307432 -270.307601) (xy 358.2629 -270.330291) (xy 358.215368 -270.345735) (xy 358.166005 -270.353554)
			(xy 358.116027 -270.353554) (xy 358.066664 -270.345735) (xy 358.019132 -270.330291) (xy 357.9746 -270.307601)
			(xy 357.934167 -270.278225) (xy 357.898827 -270.242885) (xy 357.869451 -270.202452) (xy 357.846761 -270.15792)
			(xy 357.831317 -270.110388) (xy 357.823498 -270.061025) (xy 357.518734 -270.061025) (xy 357.510915 -270.110388)
			(xy 357.495471 -270.15792) (xy 357.472781 -270.202452) (xy 357.443405 -270.242885) (xy 357.408065 -270.278225)
			(xy 357.367632 -270.307601) (xy 357.3231 -270.330291) (xy 357.275568 -270.345735) (xy 357.226205 -270.353554)
			(xy 357.176227 -270.353554) (xy 357.126864 -270.345735) (xy 357.079332 -270.330291) (xy 357.0348 -270.307601)
			(xy 356.994367 -270.278225) (xy 356.959027 -270.242885) (xy 356.929651 -270.202452) (xy 356.906961 -270.15792)
			(xy 356.891517 -270.110388) (xy 356.883698 -270.061025) (xy 356.57868 -270.061025) (xy 356.570861 -270.110388)
			(xy 356.555417 -270.15792) (xy 356.532727 -270.202452) (xy 356.503351 -270.242885) (xy 356.468011 -270.278225)
			(xy 356.427578 -270.307601) (xy 356.383046 -270.330291) (xy 356.335514 -270.345735) (xy 356.286151 -270.353554)
			(xy 356.236173 -270.353554) (xy 356.18681 -270.345735) (xy 356.139278 -270.330291) (xy 356.094746 -270.307601)
			(xy 356.054313 -270.278225) (xy 356.018973 -270.242885) (xy 355.989597 -270.202452) (xy 355.966907 -270.15792)
			(xy 355.951463 -270.110388) (xy 355.943644 -270.061025) (xy 355.636327 -270.061025) (xy 355.636318 -270.061482)
			(xy 355.628154 -270.111716) (xy 355.612038 -270.15999) (xy 355.588387 -270.205053) (xy 355.557814 -270.245739)
			(xy 355.52111 -270.280994) (xy 355.479226 -270.309904) (xy 355.433247 -270.331721) (xy 355.384363 -270.345881)
			(xy 355.333842 -270.352015) (xy 355.28299 -270.349966) (xy 355.233126 -270.339786) (xy 355.18554 -270.321739)
			(xy 355.141466 -270.296293) (xy 355.102044 -270.264106) (xy 355.068296 -270.226012) (xy 355.041095 -270.182998)
			(xy 355.021147 -270.136178) (xy 355.008968 -270.086764) (xy 355.004873 -270.036036) (xy 354.696776 -270.036036)
			(xy 354.696264 -270.061482) (xy 354.6881 -270.111716) (xy 354.671984 -270.15999) (xy 354.648333 -270.205053)
			(xy 354.61776 -270.245739) (xy 354.581056 -270.280994) (xy 354.539172 -270.309904) (xy 354.493193 -270.331721)
			(xy 354.444309 -270.345881) (xy 354.393788 -270.352015) (xy 354.342936 -270.349966) (xy 354.293072 -270.339786)
			(xy 354.245486 -270.321739) (xy 354.201412 -270.296293) (xy 354.16199 -270.264106) (xy 354.128242 -270.226012)
			(xy 354.101041 -270.182998) (xy 354.081093 -270.136178) (xy 354.068914 -270.086764) (xy 354.064819 -270.036036)
			(xy 353.758518 -270.036036) (xy 353.758519 -270.060977) (xy 353.750703 -270.110339) (xy 353.735261 -270.157871)
			(xy 353.712574 -270.202402) (xy 353.6832 -270.242836) (xy 353.647863 -270.278177) (xy 353.607432 -270.307555)
			(xy 353.562904 -270.330247) (xy 353.515374 -270.345694) (xy 353.466013 -270.353516) (xy 353.416035 -270.35352)
			(xy 353.366673 -270.345705) (xy 353.319141 -270.330266) (xy 353.274609 -270.30758) (xy 353.234174 -270.278208)
			(xy 353.198831 -270.242872) (xy 353.169451 -270.202443) (xy 353.146757 -270.157915) (xy 353.131309 -270.110386)
			(xy 353.123485 -270.061025) (xy 353.122992 -270.036036) (xy 353.123539 -270.009162) (xy 353.132571 -269.956178)
			(xy 353.150384 -269.905467) (xy 353.176471 -269.858474) (xy 353.192842 -269.837154) (xy 353.201986 -269.825724)
			(xy 353.205542 -269.796768) (xy 353.159314 -269.700756) (xy 353.154872 -269.692284) (xy 353.140933 -269.679205)
			(xy 353.123152 -269.672192) (xy 353.113594 -269.6718) (xy 352.987356 -269.6718) (xy 352.965954 -269.671309)
			(xy 352.92401 -269.662761) (xy 352.884607 -269.646036) (xy 352.849321 -269.621804) (xy 352.819563 -269.591034)
			(xy 352.796526 -269.554957) (xy 352.781129 -269.515016) (xy 352.777044 -269.494) (xy 352.775268 -269.485484)
			(xy 352.766826 -269.470289) (xy 352.760534 -269.464282) (xy 352.740691 -269.446035) (xy 352.706887 -269.404046)
			(xy 352.680652 -269.356957) (xy 352.662736 -269.306116) (xy 352.653654 -269.252982) (xy 352.653092 -269.22603)
			(xy 350.71304 -269.22603) (xy 350.71304 -269.561056) (xy 350.712545 -269.57107) (xy 350.704897 -269.589578)
			(xy 350.690748 -269.60375) (xy 350.672253 -269.611429) (xy 350.66224 -269.611856) (xy 350.499172 -269.611856)
			(xy 350.489168 -269.612364) (xy 350.470684 -269.620025) (xy 350.456534 -269.634171) (xy 350.448867 -269.652652)
			(xy 350.448372 -269.662656) (xy 350.448372 -269.688056) (xy 350.448855 -269.698071) (xy 350.456505 -269.716582)
			(xy 350.470658 -269.730754) (xy 350.489158 -269.738431) (xy 350.499172 -269.738856) (xy 350.507808 -269.738856)
			(xy 350.515936 -269.736062) (xy 350.541419 -269.727696) (xy 350.594278 -269.718629) (xy 350.621092 -269.718028)
			(xy 350.646081 -269.718474) (xy 350.695445 -269.726291) (xy 350.742978 -269.741733) (xy 350.78751 -269.764422)
			(xy 350.827945 -269.793797) (xy 350.863286 -269.829136) (xy 350.892665 -269.869568) (xy 350.915357 -269.914099)
			(xy 350.930803 -269.96163) (xy 350.938624 -270.010993) (xy 350.938626 -270.036036) (xy 351.244911 -270.036036)
			(xy 351.249006 -269.985308) (xy 351.261185 -269.935894) (xy 351.281133 -269.889074) (xy 351.308334 -269.84606)
			(xy 351.342082 -269.807966) (xy 351.381504 -269.775779) (xy 351.425578 -269.750333) (xy 351.473164 -269.732286)
			(xy 351.523028 -269.722106) (xy 351.57388 -269.720057) (xy 351.624401 -269.726191) (xy 351.673285 -269.740351)
			(xy 351.719264 -269.762168) (xy 351.761148 -269.791078) (xy 351.797852 -269.826333) (xy 351.828425 -269.867019)
			(xy 351.852076 -269.912082) (xy 351.868192 -269.960356) (xy 351.876356 -270.01059) (xy 351.876868 -270.036036)
			(xy 352.184965 -270.036036) (xy 352.18906 -269.985308) (xy 352.201239 -269.935894) (xy 352.221187 -269.889074)
			(xy 352.248388 -269.84606) (xy 352.282136 -269.807966) (xy 352.321558 -269.775779) (xy 352.365632 -269.750333)
			(xy 352.413218 -269.732286) (xy 352.463082 -269.722106) (xy 352.513934 -269.720057) (xy 352.564455 -269.726191)
			(xy 352.613339 -269.740351) (xy 352.659318 -269.762168) (xy 352.701202 -269.791078) (xy 352.737906 -269.826333)
			(xy 352.768479 -269.867019) (xy 352.79213 -269.912082) (xy 352.808246 -269.960356) (xy 352.81641 -270.01059)
			(xy 352.816922 -270.036036) (xy 352.81641 -270.061482) (xy 352.808246 -270.111716) (xy 352.79213 -270.15999)
			(xy 352.768479 -270.205053) (xy 352.737906 -270.245739) (xy 352.701202 -270.280994) (xy 352.659318 -270.309904)
			(xy 352.613339 -270.331721) (xy 352.564455 -270.345881) (xy 352.513934 -270.352015) (xy 352.463082 -270.349966)
			(xy 352.413218 -270.339786) (xy 352.365632 -270.321739) (xy 352.321558 -270.296293) (xy 352.282136 -270.264106)
			(xy 352.248388 -270.226012) (xy 352.221187 -270.182998) (xy 352.201239 -270.136178) (xy 352.18906 -270.086764)
			(xy 352.184965 -270.036036) (xy 351.876868 -270.036036) (xy 351.876356 -270.061482) (xy 351.868192 -270.111716)
			(xy 351.852076 -270.15999) (xy 351.828425 -270.205053) (xy 351.797852 -270.245739) (xy 351.761148 -270.280994)
			(xy 351.719264 -270.309904) (xy 351.673285 -270.331721) (xy 351.624401 -270.345881) (xy 351.57388 -270.352015)
			(xy 351.523028 -270.349966) (xy 351.473164 -270.339786) (xy 351.425578 -270.321739) (xy 351.381504 -270.296293)
			(xy 351.342082 -270.264106) (xy 351.308334 -270.226012) (xy 351.281133 -270.182998) (xy 351.261185 -270.136178)
			(xy 351.249006 -270.086764) (xy 351.244911 -270.036036) (xy 350.938626 -270.036036) (xy 350.938627 -270.060972)
			(xy 350.930811 -270.110336) (xy 350.91537 -270.157869) (xy 350.892683 -270.202402) (xy 350.863309 -270.242838)
			(xy 350.827971 -270.27818) (xy 350.78754 -270.30756) (xy 350.74301 -270.330253) (xy 350.695479 -270.345701)
			(xy 350.646116 -270.353524) (xy 350.596137 -270.353528) (xy 350.546773 -270.345714) (xy 350.499239 -270.330274)
			(xy 350.454706 -270.307588) (xy 350.414269 -270.278215) (xy 350.378926 -270.242878) (xy 350.349545 -270.202448)
			(xy 350.32685 -270.157919) (xy 350.311401 -270.110388) (xy 350.303577 -270.061025) (xy 350.303084 -270.036036)
			(xy 350.303633 -270.009162) (xy 350.312665 -269.956178) (xy 350.330477 -269.905467) (xy 350.356564 -269.858474)
			(xy 350.372934 -269.837154) (xy 350.382078 -269.825724) (xy 350.385634 -269.796768) (xy 350.339406 -269.700756)
			(xy 350.33497 -269.69228) (xy 350.321028 -269.679202) (xy 350.303245 -269.67219) (xy 350.293686 -269.6718)
			(xy 350.193356 -269.6718) (xy 350.173435 -269.671379) (xy 350.134293 -269.663943) (xy 350.09721 -269.649375)
			(xy 350.063473 -269.62818) (xy 350.034254 -269.601094) (xy 350.010567 -269.569058) (xy 349.993234 -269.533184)
			(xy 349.987616 -269.514066) (xy 349.984939 -269.50566) (xy 349.974807 -269.491236) (xy 349.967804 -269.485872)
			(xy 349.947382 -269.470836) (xy 349.911123 -269.435386) (xy 349.880947 -269.394632) (xy 349.857619 -269.349607)
			(xy 349.841729 -269.301451) (xy 349.833679 -269.251385) (xy 349.833184 -269.22603) (xy 347.649038 -269.22603)
			(xy 347.648526 -269.251797) (xy 347.640225 -269.302659) (xy 347.623829 -269.351516) (xy 347.599768 -269.397089)
			(xy 347.568671 -269.438184) (xy 347.531353 -269.473725) (xy 347.510354 -269.488666) (xy 347.50327 -269.493954)
			(xy 347.492875 -269.508236) (xy 347.490034 -269.516606) (xy 347.484248 -269.53547) (xy 347.466707 -269.570811)
			(xy 347.442971 -269.602326) (xy 347.413847 -269.628943) (xy 347.380329 -269.649755) (xy 347.343556 -269.664052)
			(xy 347.304783 -269.671349) (xy 347.285056 -269.6718) (xy 347.185234 -269.6718) (xy 347.175684 -269.672246)
			(xy 347.157918 -269.679253) (xy 347.143969 -269.6923) (xy 347.139514 -269.700756) (xy 347.09354 -269.797022)
			(xy 347.097096 -269.825978) (xy 347.106494 -269.837408) (xy 347.122975 -269.858642) (xy 347.149244 -269.905532)
			(xy 347.167194 -269.956193) (xy 347.176306 -270.009163) (xy 347.176852 -270.036036) (xy 347.176343 -270.060818)
			(xy 347.17631 -270.061025) (xy 347.483666 -270.061025) (xy 347.483666 -270.011047) (xy 347.491485 -269.961684)
			(xy 347.506929 -269.914152) (xy 347.529619 -269.86962) (xy 347.558995 -269.829187) (xy 347.594335 -269.793847)
			(xy 347.634768 -269.764471) (xy 347.6793 -269.741781) (xy 347.726832 -269.726337) (xy 347.776195 -269.718518)
			(xy 347.826173 -269.718518) (xy 347.875536 -269.726337) (xy 347.923068 -269.741781) (xy 347.9676 -269.764471)
			(xy 348.008033 -269.793847) (xy 348.043373 -269.829187) (xy 348.072749 -269.86962) (xy 348.095439 -269.914152)
			(xy 348.110883 -269.961684) (xy 348.118702 -270.011047) (xy 348.119192 -270.036036) (xy 348.425003 -270.036036)
			(xy 348.429098 -269.985308) (xy 348.441277 -269.935894) (xy 348.461225 -269.889074) (xy 348.488426 -269.84606)
			(xy 348.522174 -269.807966) (xy 348.561596 -269.775779) (xy 348.60567 -269.750333) (xy 348.653256 -269.732286)
			(xy 348.70312 -269.722106) (xy 348.753972 -269.720057) (xy 348.804493 -269.726191) (xy 348.853377 -269.740351)
			(xy 348.899356 -269.762168) (xy 348.94124 -269.791078) (xy 348.977944 -269.826333) (xy 349.008517 -269.867019)
			(xy 349.032168 -269.912082) (xy 349.048284 -269.960356) (xy 349.056448 -270.01059) (xy 349.05696 -270.036036)
			(xy 349.364803 -270.036036) (xy 349.368898 -269.985308) (xy 349.381077 -269.935894) (xy 349.401025 -269.889074)
			(xy 349.428226 -269.84606) (xy 349.461974 -269.807966) (xy 349.501396 -269.775779) (xy 349.54547 -269.750333)
			(xy 349.593056 -269.732286) (xy 349.64292 -269.722106) (xy 349.693772 -269.720057) (xy 349.744293 -269.726191)
			(xy 349.793177 -269.740351) (xy 349.839156 -269.762168) (xy 349.88104 -269.791078) (xy 349.917744 -269.826333)
			(xy 349.948317 -269.867019) (xy 349.971968 -269.912082) (xy 349.988084 -269.960356) (xy 349.996248 -270.01059)
			(xy 349.99676 -270.036036) (xy 349.996248 -270.061482) (xy 349.988084 -270.111716) (xy 349.971968 -270.15999)
			(xy 349.948317 -270.205053) (xy 349.917744 -270.245739) (xy 349.88104 -270.280994) (xy 349.839156 -270.309904)
			(xy 349.793177 -270.331721) (xy 349.744293 -270.345881) (xy 349.693772 -270.352015) (xy 349.64292 -270.349966)
			(xy 349.593056 -270.339786) (xy 349.54547 -270.321739) (xy 349.501396 -270.296293) (xy 349.461974 -270.264106)
			(xy 349.428226 -270.226012) (xy 349.401025 -270.182998) (xy 349.381077 -270.136178) (xy 349.368898 -270.086764)
			(xy 349.364803 -270.036036) (xy 349.05696 -270.036036) (xy 349.056448 -270.061482) (xy 349.048284 -270.111716)
			(xy 349.032168 -270.15999) (xy 349.008517 -270.205053) (xy 348.977944 -270.245739) (xy 348.94124 -270.280994)
			(xy 348.899356 -270.309904) (xy 348.853377 -270.331721) (xy 348.804493 -270.345881) (xy 348.753972 -270.352015)
			(xy 348.70312 -270.349966) (xy 348.653256 -270.339786) (xy 348.60567 -270.321739) (xy 348.561596 -270.296293)
			(xy 348.522174 -270.264106) (xy 348.488426 -270.226012) (xy 348.461225 -270.182998) (xy 348.441277 -270.136178)
			(xy 348.429098 -270.086764) (xy 348.425003 -270.036036) (xy 348.119192 -270.036036) (xy 348.118702 -270.061025)
			(xy 348.110883 -270.110388) (xy 348.095439 -270.15792) (xy 348.072749 -270.202452) (xy 348.043373 -270.242885)
			(xy 348.008033 -270.278225) (xy 347.9676 -270.307601) (xy 347.923068 -270.330291) (xy 347.875536 -270.345735)
			(xy 347.826173 -270.353554) (xy 347.776195 -270.353554) (xy 347.726832 -270.345735) (xy 347.6793 -270.330291)
			(xy 347.634768 -270.307601) (xy 347.594335 -270.278225) (xy 347.558995 -270.242885) (xy 347.529619 -270.202452)
			(xy 347.506929 -270.15792) (xy 347.491485 -270.110388) (xy 347.483666 -270.061025) (xy 347.17631 -270.061025)
			(xy 347.168586 -270.10977) (xy 347.153268 -270.156907) (xy 347.130766 -270.201068) (xy 347.101634 -270.241166)
			(xy 347.066589 -270.276214) (xy 347.026493 -270.30535) (xy 346.982335 -270.327856) (xy 346.935199 -270.343179)
			(xy 346.886248 -270.350941) (xy 346.836684 -270.350951) (xy 346.787729 -270.34321) (xy 346.740587 -270.327907)
			(xy 346.696419 -270.305419) (xy 346.656312 -270.2763) (xy 346.621252 -270.241266) (xy 346.592104 -270.201181)
			(xy 346.569583 -270.157029) (xy 346.554245 -270.109899) (xy 346.546467 -270.060949) (xy 346.546441 -270.011386)
			(xy 346.236302 -270.011386) (xy 346.236798 -270.036036) (xy 346.236286 -270.061482) (xy 346.228122 -270.111716)
			(xy 346.212006 -270.15999) (xy 346.188355 -270.205053) (xy 346.157782 -270.245739) (xy 346.121078 -270.280994)
			(xy 346.079194 -270.309904) (xy 346.033215 -270.331721) (xy 345.984331 -270.345881) (xy 345.93381 -270.352015)
			(xy 345.882958 -270.349966) (xy 345.833094 -270.339786) (xy 345.785508 -270.321739) (xy 345.741434 -270.296293)
			(xy 345.702012 -270.264106) (xy 345.668264 -270.226012) (xy 345.641063 -270.182998) (xy 345.621115 -270.136178)
			(xy 345.608936 -270.086764) (xy 345.604841 -270.036036) (xy 345.298922 -270.036036) (xy 345.297329 -270.073985)
			(xy 345.287723 -270.12222) (xy 345.270803 -270.1684) (xy 345.246972 -270.211423) (xy 345.232228 -270.231108)
			(xy 345.21439 -270.25308) (xy 345.172317 -270.290926) (xy 345.124201 -270.320712) (xy 345.098116 -270.331692)
			(xy 345.097862 -270.331692) (xy 345.095068 -270.332708) (xy 345.086749 -270.337094) (xy 345.073769 -270.350681)
			(xy 345.066557 -270.368032) (xy 345.065858 -270.377412) (xy 345.065858 -270.539972) (xy 345.066314 -270.549809)
			(xy 345.073745 -270.568024) (xy 345.087514 -270.582076) (xy 345.096338 -270.586454) (xy 345.14155 -270.606266)
			(xy 345.17965 -270.622776) (xy 345.186544 -270.625504) (xy 345.201255 -270.627303) (xy 345.208606 -270.626332)
			(xy 345.215464 -270.625062) (xy 345.228672 -270.618712) (xy 345.23426 -270.613378) (xy 345.252025 -270.597417)
			(xy 345.291444 -270.570458) (xy 345.33445 -270.549693) (xy 345.380076 -270.535589) (xy 345.427298 -270.528462)
			(xy 345.451176 -270.528034) (xy 345.476165 -270.528497) (xy 345.525529 -270.536312) (xy 345.573062 -270.551753)
			(xy 345.617594 -270.57444) (xy 345.658028 -270.603815) (xy 345.693369 -270.639154) (xy 345.722747 -270.679586)
			(xy 345.745438 -270.724116) (xy 345.760882 -270.771648) (xy 345.768701 -270.821011) (xy 345.768701 -270.870989)
			(xy 345.768694 -270.871031) (xy 346.073712 -270.871031) (xy 346.073712 -270.821053) (xy 346.081531 -270.77169)
			(xy 346.096975 -270.724158) (xy 346.119665 -270.679626) (xy 346.149041 -270.639193) (xy 346.184381 -270.603853)
			(xy 346.224814 -270.574477) (xy 346.269346 -270.551787) (xy 346.316878 -270.536343) (xy 346.366241 -270.528524)
			(xy 346.416219 -270.528524) (xy 346.465582 -270.536343) (xy 346.513114 -270.551787) (xy 346.557646 -270.574477)
			(xy 346.598079 -270.603853) (xy 346.633419 -270.639193) (xy 346.662795 -270.679626) (xy 346.685485 -270.724158)
			(xy 346.700929 -270.77169) (xy 346.708748 -270.821053) (xy 346.709238 -270.846042) (xy 346.708748 -270.871031)
			(xy 347.013512 -270.871031) (xy 347.013512 -270.821053) (xy 347.021331 -270.77169) (xy 347.036775 -270.724158)
			(xy 347.059465 -270.679626) (xy 347.088841 -270.639193) (xy 347.124181 -270.603853) (xy 347.164614 -270.574477)
			(xy 347.209146 -270.551787) (xy 347.256678 -270.536343) (xy 347.306041 -270.528524) (xy 347.356019 -270.528524)
			(xy 347.405382 -270.536343) (xy 347.452914 -270.551787) (xy 347.497446 -270.574477) (xy 347.537879 -270.603853)
			(xy 347.573219 -270.639193) (xy 347.602595 -270.679626) (xy 347.625285 -270.724158) (xy 347.640729 -270.77169)
			(xy 347.648548 -270.821053) (xy 347.649038 -270.846042) (xy 347.648548 -270.871031) (xy 347.640729 -270.920394)
			(xy 347.625285 -270.967926) (xy 347.602595 -271.012458) (xy 347.573219 -271.052891) (xy 347.537879 -271.088231)
			(xy 347.497446 -271.117607) (xy 347.452914 -271.140297) (xy 347.405382 -271.155741) (xy 347.356019 -271.16356)
			(xy 347.306041 -271.16356) (xy 347.256678 -271.155741) (xy 347.209146 -271.140297) (xy 347.164614 -271.117607)
			(xy 347.124181 -271.088231) (xy 347.088841 -271.052891) (xy 347.059465 -271.012458) (xy 347.036775 -270.967926)
			(xy 347.021331 -270.920394) (xy 347.013512 -270.871031) (xy 346.708748 -270.871031) (xy 346.700929 -270.920394)
			(xy 346.685485 -270.967926) (xy 346.662795 -271.012458) (xy 346.633419 -271.052891) (xy 346.598079 -271.088231)
			(xy 346.557646 -271.117607) (xy 346.513114 -271.140297) (xy 346.465582 -271.155741) (xy 346.416219 -271.16356)
			(xy 346.366241 -271.16356) (xy 346.316878 -271.155741) (xy 346.269346 -271.140297) (xy 346.224814 -271.117607)
			(xy 346.184381 -271.088231) (xy 346.149041 -271.052891) (xy 346.119665 -271.012458) (xy 346.096975 -270.967926)
			(xy 346.081531 -270.920394) (xy 346.073712 -270.871031) (xy 345.768694 -270.871031) (xy 345.760882 -270.920352)
			(xy 345.745438 -270.967884) (xy 345.722747 -271.012414) (xy 345.693369 -271.052846) (xy 345.658028 -271.088185)
			(xy 345.617594 -271.11756) (xy 345.573062 -271.140247) (xy 345.525529 -271.155688) (xy 345.476165 -271.163503)
			(xy 345.451176 -271.16405) (xy 345.427299 -271.163621) (xy 345.38008 -271.156485) (xy 345.334458 -271.142376)
			(xy 345.291454 -271.12161) (xy 345.252035 -271.094655) (xy 345.23426 -271.078706) (xy 345.22866 -271.073834)
			(xy 345.21537 -271.067237) (xy 345.208098 -271.065752) (xy 345.20124 -271.064482) (xy 345.186508 -271.06626)
			(xy 345.14155 -271.085818) (xy 345.096338 -271.10563) (xy 345.087511 -271.109991) (xy 345.073776 -271.124072)
			(xy 345.066328 -271.142278) (xy 345.065858 -271.152112) (xy 345.065858 -271.313402) (xy 345.065858 -271.314672)
			(xy 345.066524 -271.324057) (xy 345.073745 -271.341412) (xy 345.086744 -271.354991) (xy 345.095068 -271.359376)
			(xy 345.097862 -271.360392) (xy 345.120568 -271.369844) (xy 345.162992 -271.394723) (xy 345.201078 -271.42584)
			(xy 345.233917 -271.46245) (xy 345.260726 -271.503682) (xy 345.280865 -271.54855) (xy 345.293853 -271.595985)
			(xy 345.299382 -271.644854) (xy 345.298912 -271.656048) (xy 345.604841 -271.656048) (xy 345.608936 -271.60532)
			(xy 345.621115 -271.555906) (xy 345.641063 -271.509086) (xy 345.668264 -271.466072) (xy 345.702012 -271.427978)
			(xy 345.741434 -271.395791) (xy 345.785508 -271.370345) (xy 345.833094 -271.352298) (xy 345.882958 -271.342118)
			(xy 345.93381 -271.340069) (xy 345.984331 -271.346203) (xy 346.033215 -271.360363) (xy 346.079194 -271.38218)
			(xy 346.121078 -271.41109) (xy 346.157782 -271.446345) (xy 346.188355 -271.487031) (xy 346.212006 -271.532094)
			(xy 346.228122 -271.580368) (xy 346.236286 -271.630602) (xy 346.236798 -271.656048) (xy 346.544895 -271.656048)
			(xy 346.54899 -271.60532) (xy 346.561169 -271.555906) (xy 346.581117 -271.509086) (xy 346.608318 -271.466072)
			(xy 346.642066 -271.427978) (xy 346.681488 -271.395791) (xy 346.725562 -271.370345) (xy 346.773148 -271.352298)
			(xy 346.823012 -271.342118) (xy 346.873864 -271.340069) (xy 346.924385 -271.346203) (xy 346.973269 -271.360363)
			(xy 347.019248 -271.38218) (xy 347.061132 -271.41109) (xy 347.097836 -271.446345) (xy 347.128409 -271.487031)
			(xy 347.15206 -271.532094) (xy 347.168176 -271.580368) (xy 347.17634 -271.630602) (xy 347.176852 -271.656048)
			(xy 347.318076 -271.656048) (xy 347.318583 -271.624415) (xy 347.326825 -271.561688) (xy 347.343188 -271.500574)
			(xy 347.367392 -271.44212) (xy 347.399021 -271.387328) (xy 347.437535 -271.337135) (xy 347.459554 -271.314418)
			(xy 347.629988 -271.143984) (xy 347.630496 -271.143476) (xy 347.651695 -271.12209) (xy 347.698525 -271.08423)
			(xy 347.749693 -271.052478) (xy 347.804409 -271.027327) (xy 347.861824 -271.009166) (xy 347.891354 -271.003268)
			(xy 347.896942 -271.001998) (xy 347.953584 -270.920718) (xy 347.957902 -270.901668) (xy 347.956378 -270.89227)
			(xy 347.95481 -270.880778) (xy 347.953161 -270.85764) (xy 347.953076 -270.846042) (xy 347.953566 -270.821053)
			(xy 347.961385 -270.77169) (xy 347.976829 -270.724158) (xy 347.999519 -270.679626) (xy 348.028895 -270.639193)
			(xy 348.064235 -270.603853) (xy 348.104668 -270.574477) (xy 348.1492 -270.551787) (xy 348.196732 -270.536343)
			(xy 348.246095 -270.528524) (xy 348.296073 -270.528524) (xy 348.345436 -270.536343) (xy 348.392968 -270.551787)
			(xy 348.4375 -270.574477) (xy 348.477933 -270.603853) (xy 348.513273 -270.639193) (xy 348.542649 -270.679626)
			(xy 348.565339 -270.724158) (xy 348.580783 -270.77169) (xy 348.588602 -270.821053) (xy 348.589092 -270.846042)
			(xy 348.588622 -270.870275) (xy 348.588506 -270.871031) (xy 348.89362 -270.871031) (xy 348.89362 -270.821053)
			(xy 348.901439 -270.77169) (xy 348.916883 -270.724158) (xy 348.939573 -270.679626) (xy 348.968949 -270.639193)
			(xy 349.004289 -270.603853) (xy 349.044722 -270.574477) (xy 349.089254 -270.551787) (xy 349.136786 -270.536343)
			(xy 349.186149 -270.528524) (xy 349.236127 -270.528524) (xy 349.28549 -270.536343) (xy 349.333022 -270.551787)
			(xy 349.377554 -270.574477) (xy 349.417987 -270.603853) (xy 349.453327 -270.639193) (xy 349.482703 -270.679626)
			(xy 349.505393 -270.724158) (xy 349.520837 -270.77169) (xy 349.528656 -270.821053) (xy 349.529146 -270.846042)
			(xy 349.528656 -270.871031) (xy 349.833674 -270.871031) (xy 349.833674 -270.821053) (xy 349.841493 -270.77169)
			(xy 349.856937 -270.724158) (xy 349.879627 -270.679626) (xy 349.909003 -270.639193) (xy 349.944343 -270.603853)
			(xy 349.984776 -270.574477) (xy 350.029308 -270.551787) (xy 350.07684 -270.536343) (xy 350.126203 -270.528524)
			(xy 350.176181 -270.528524) (xy 350.225544 -270.536343) (xy 350.273076 -270.551787) (xy 350.317608 -270.574477)
			(xy 350.358041 -270.603853) (xy 350.393381 -270.639193) (xy 350.422757 -270.679626) (xy 350.445447 -270.724158)
			(xy 350.460891 -270.77169) (xy 350.46871 -270.821053) (xy 350.4692 -270.846042) (xy 350.46871 -270.871031)
			(xy 350.773728 -270.871031) (xy 350.773728 -270.821053) (xy 350.781547 -270.77169) (xy 350.796991 -270.724158)
			(xy 350.819681 -270.679626) (xy 350.849057 -270.639193) (xy 350.884397 -270.603853) (xy 350.92483 -270.574477)
			(xy 350.969362 -270.551787) (xy 351.016894 -270.536343) (xy 351.066257 -270.528524) (xy 351.116235 -270.528524)
			(xy 351.165598 -270.536343) (xy 351.21313 -270.551787) (xy 351.257662 -270.574477) (xy 351.298095 -270.603853)
			(xy 351.333435 -270.639193) (xy 351.362811 -270.679626) (xy 351.385501 -270.724158) (xy 351.400945 -270.77169)
			(xy 351.408764 -270.821053) (xy 351.409254 -270.846042) (xy 351.408764 -270.871031) (xy 351.713528 -270.871031)
			(xy 351.713528 -270.821053) (xy 351.721347 -270.77169) (xy 351.736791 -270.724158) (xy 351.759481 -270.679626)
			(xy 351.788857 -270.639193) (xy 351.824197 -270.603853) (xy 351.86463 -270.574477) (xy 351.909162 -270.551787)
			(xy 351.956694 -270.536343) (xy 352.006057 -270.528524) (xy 352.056035 -270.528524) (xy 352.105398 -270.536343)
			(xy 352.15293 -270.551787) (xy 352.197462 -270.574477) (xy 352.237895 -270.603853) (xy 352.273235 -270.639193)
			(xy 352.302611 -270.679626) (xy 352.325301 -270.724158) (xy 352.340745 -270.77169) (xy 352.348564 -270.821053)
			(xy 352.349054 -270.846042) (xy 352.348564 -270.871031) (xy 352.653582 -270.871031) (xy 352.653582 -270.821053)
			(xy 352.661401 -270.77169) (xy 352.676845 -270.724158) (xy 352.699535 -270.679626) (xy 352.728911 -270.639193)
			(xy 352.764251 -270.603853) (xy 352.804684 -270.574477) (xy 352.849216 -270.551787) (xy 352.896748 -270.536343)
			(xy 352.946111 -270.528524) (xy 352.996089 -270.528524) (xy 353.045452 -270.536343) (xy 353.092984 -270.551787)
			(xy 353.137516 -270.574477) (xy 353.177949 -270.603853) (xy 353.213289 -270.639193) (xy 353.242665 -270.679626)
			(xy 353.265355 -270.724158) (xy 353.280799 -270.77169) (xy 353.288618 -270.821053) (xy 353.289108 -270.846042)
			(xy 353.288618 -270.871031) (xy 353.593636 -270.871031) (xy 353.593636 -270.821053) (xy 353.601455 -270.77169)
			(xy 353.616899 -270.724158) (xy 353.639589 -270.679626) (xy 353.668965 -270.639193) (xy 353.704305 -270.603853)
			(xy 353.744738 -270.574477) (xy 353.78927 -270.551787) (xy 353.836802 -270.536343) (xy 353.886165 -270.528524)
			(xy 353.936143 -270.528524) (xy 353.985506 -270.536343) (xy 354.033038 -270.551787) (xy 354.07757 -270.574477)
			(xy 354.118003 -270.603853) (xy 354.153343 -270.639193) (xy 354.182719 -270.679626) (xy 354.205409 -270.724158)
			(xy 354.220853 -270.77169) (xy 354.228672 -270.821053) (xy 354.229162 -270.846042) (xy 354.228672 -270.871031)
			(xy 354.53369 -270.871031) (xy 354.53369 -270.821053) (xy 354.541509 -270.77169) (xy 354.556953 -270.724158)
			(xy 354.579643 -270.679626) (xy 354.609019 -270.639193) (xy 354.644359 -270.603853) (xy 354.684792 -270.574477)
			(xy 354.729324 -270.551787) (xy 354.776856 -270.536343) (xy 354.826219 -270.528524) (xy 354.876197 -270.528524)
			(xy 354.92556 -270.536343) (xy 354.973092 -270.551787) (xy 355.017624 -270.574477) (xy 355.058057 -270.603853)
			(xy 355.093397 -270.639193) (xy 355.122773 -270.679626) (xy 355.145463 -270.724158) (xy 355.160907 -270.77169)
			(xy 355.168726 -270.821053) (xy 355.169216 -270.846042) (xy 355.168726 -270.871031) (xy 355.160907 -270.920394)
			(xy 355.145463 -270.967926) (xy 355.122773 -271.012458) (xy 355.093397 -271.052891) (xy 355.058057 -271.088231)
			(xy 355.017624 -271.117607) (xy 354.973092 -271.140297) (xy 354.92556 -271.155741) (xy 354.876197 -271.16356)
			(xy 354.826219 -271.16356) (xy 354.776856 -271.155741) (xy 354.729324 -271.140297) (xy 354.684792 -271.117607)
			(xy 354.644359 -271.088231) (xy 354.609019 -271.052891) (xy 354.579643 -271.012458) (xy 354.556953 -270.967926)
			(xy 354.541509 -270.920394) (xy 354.53369 -270.871031) (xy 354.228672 -270.871031) (xy 354.220853 -270.920394)
			(xy 354.205409 -270.967926) (xy 354.182719 -271.012458) (xy 354.153343 -271.052891) (xy 354.118003 -271.088231)
			(xy 354.07757 -271.117607) (xy 354.033038 -271.140297) (xy 353.985506 -271.155741) (xy 353.936143 -271.16356)
			(xy 353.886165 -271.16356) (xy 353.836802 -271.155741) (xy 353.78927 -271.140297) (xy 353.744738 -271.117607)
			(xy 353.704305 -271.088231) (xy 353.668965 -271.052891) (xy 353.639589 -271.012458) (xy 353.616899 -270.967926)
			(xy 353.601455 -270.920394) (xy 353.593636 -270.871031) (xy 353.288618 -270.871031) (xy 353.280799 -270.920394)
			(xy 353.265355 -270.967926) (xy 353.242665 -271.012458) (xy 353.213289 -271.052891) (xy 353.177949 -271.088231)
			(xy 353.137516 -271.117607) (xy 353.092984 -271.140297) (xy 353.045452 -271.155741) (xy 352.996089 -271.16356)
			(xy 352.946111 -271.16356) (xy 352.896748 -271.155741) (xy 352.849216 -271.140297) (xy 352.804684 -271.117607)
			(xy 352.764251 -271.088231) (xy 352.728911 -271.052891) (xy 352.699535 -271.012458) (xy 352.676845 -270.967926)
			(xy 352.661401 -270.920394) (xy 352.653582 -270.871031) (xy 352.348564 -270.871031) (xy 352.340745 -270.920394)
			(xy 352.325301 -270.967926) (xy 352.302611 -271.012458) (xy 352.273235 -271.052891) (xy 352.237895 -271.088231)
			(xy 352.197462 -271.117607) (xy 352.15293 -271.140297) (xy 352.105398 -271.155741) (xy 352.056035 -271.16356)
			(xy 352.006057 -271.16356) (xy 351.956694 -271.155741) (xy 351.909162 -271.140297) (xy 351.86463 -271.117607)
			(xy 351.824197 -271.088231) (xy 351.788857 -271.052891) (xy 351.759481 -271.012458) (xy 351.736791 -270.967926)
			(xy 351.721347 -270.920394) (xy 351.713528 -270.871031) (xy 351.408764 -270.871031) (xy 351.400945 -270.920394)
			(xy 351.385501 -270.967926) (xy 351.362811 -271.012458) (xy 351.333435 -271.052891) (xy 351.298095 -271.088231)
			(xy 351.257662 -271.117607) (xy 351.21313 -271.140297) (xy 351.165598 -271.155741) (xy 351.116235 -271.16356)
			(xy 351.066257 -271.16356) (xy 351.016894 -271.155741) (xy 350.969362 -271.140297) (xy 350.92483 -271.117607)
			(xy 350.884397 -271.088231) (xy 350.849057 -271.052891) (xy 350.819681 -271.012458) (xy 350.796991 -270.967926)
			(xy 350.781547 -270.920394) (xy 350.773728 -270.871031) (xy 350.46871 -270.871031) (xy 350.460891 -270.920394)
			(xy 350.445447 -270.967926) (xy 350.422757 -271.012458) (xy 350.393381 -271.052891) (xy 350.358041 -271.088231)
			(xy 350.317608 -271.117607) (xy 350.273076 -271.140297) (xy 350.225544 -271.155741) (xy 350.176181 -271.16356)
			(xy 350.126203 -271.16356) (xy 350.07684 -271.155741) (xy 350.029308 -271.140297) (xy 349.984776 -271.117607)
			(xy 349.944343 -271.088231) (xy 349.909003 -271.052891) (xy 349.879627 -271.012458) (xy 349.856937 -270.967926)
			(xy 349.841493 -270.920394) (xy 349.833674 -270.871031) (xy 349.528656 -270.871031) (xy 349.520837 -270.920394)
			(xy 349.505393 -270.967926) (xy 349.482703 -271.012458) (xy 349.453327 -271.052891) (xy 349.417987 -271.088231)
			(xy 349.377554 -271.117607) (xy 349.333022 -271.140297) (xy 349.28549 -271.155741) (xy 349.236127 -271.16356)
			(xy 349.186149 -271.16356) (xy 349.136786 -271.155741) (xy 349.089254 -271.140297) (xy 349.044722 -271.117607)
			(xy 349.004289 -271.088231) (xy 348.968949 -271.052891) (xy 348.939573 -271.012458) (xy 348.916883 -270.967926)
			(xy 348.901439 -270.920394) (xy 348.89362 -270.871031) (xy 348.588506 -270.871031) (xy 348.581263 -270.918178)
			(xy 348.566723 -270.96441) (xy 348.545337 -271.007902) (xy 348.517601 -271.047646) (xy 348.501208 -271.065498)
			(xy 348.500954 -271.065752) (xy 348.495169 -271.072378) (xy 348.488163 -271.0885) (xy 348.487238 -271.097248)
			(xy 348.48165 -271.180306) (xy 348.48419 -271.183862) (xy 348.504767 -271.211605) (xy 348.538676 -271.27178)
			(xy 348.551754 -271.30375) (xy 348.553532 -271.308068) (xy 348.629478 -271.346168) (xy 348.637717 -271.349895)
			(xy 348.655682 -271.351845) (xy 348.66453 -271.349978) (xy 348.683275 -271.345595) (xy 348.721482 -271.340883)
			(xy 348.74073 -271.34058) (xy 348.741238 -271.34058) (xy 348.766029 -271.340973) (xy 348.815001 -271.348735)
			(xy 348.862156 -271.364061) (xy 348.906333 -271.386575) (xy 348.946444 -271.415722) (xy 348.981502 -271.450785)
			(xy 349.010645 -271.4909) (xy 349.033153 -271.535079) (xy 349.048474 -271.582236) (xy 349.05623 -271.631209)
			(xy 349.05623 -271.656048) (xy 349.365316 -271.656048) (xy 349.365803 -271.631238) (xy 349.373565 -271.58223)
			(xy 349.388898 -271.53504) (xy 349.411425 -271.490829) (xy 349.44059 -271.450686) (xy 349.475676 -271.4156)
			(xy 349.515819 -271.386435) (xy 349.56003 -271.363908) (xy 349.60722 -271.348575) (xy 349.656228 -271.340813)
			(xy 349.705848 -271.340813) (xy 349.754856 -271.348575) (xy 349.802046 -271.363908) (xy 349.846257 -271.386435)
			(xy 349.8864 -271.4156) (xy 349.921486 -271.450686) (xy 349.950651 -271.490829) (xy 349.973178 -271.53504)
			(xy 349.988511 -271.58223) (xy 349.996273 -271.631238) (xy 349.99676 -271.656048) (xy 349.996383 -271.677151)
			(xy 349.99072 -271.718977) (xy 349.97954 -271.759676) (xy 349.971614 -271.779238) (xy 349.966534 -271.790922)
			(xy 349.96882 -271.816322) (xy 350.022922 -271.897602) (xy 350.030398 -271.907708) (xy 350.052531 -271.919564)
			(xy 350.065086 -271.920208) (xy 350.206056 -271.920208) (xy 350.225614 -271.921224) (xy 350.238822 -271.922494)
			(xy 350.26346 -271.911572) (xy 350.322896 -271.830038) (xy 350.327695 -271.822763) (xy 350.332573 -271.806047)
			(xy 350.331554 -271.788663) (xy 350.328484 -271.780508) (xy 350.328484 -271.780254) (xy 350.320449 -271.760545)
			(xy 350.309149 -271.719508) (xy 350.303437 -271.67733) (xy 350.303084 -271.656048) (xy 350.303505 -271.631052)
			(xy 350.311318 -271.581675) (xy 350.32676 -271.534127) (xy 350.34945 -271.489581) (xy 350.378829 -271.449133)
			(xy 350.414174 -271.413779) (xy 350.454615 -271.38439) (xy 350.499156 -271.361689) (xy 350.546699 -271.346236)
			(xy 350.596075 -271.338411) (xy 350.646067 -271.338406) (xy 350.695444 -271.346223) (xy 350.74299 -271.361667)
			(xy 350.787535 -271.38436) (xy 350.827981 -271.413741) (xy 350.863333 -271.449089) (xy 350.89272 -271.489531)
			(xy 350.915418 -271.534073) (xy 350.930868 -271.581617) (xy 350.938691 -271.630993) (xy 350.938692 -271.656048)
			(xy 351.244911 -271.656048) (xy 351.249006 -271.60532) (xy 351.261185 -271.555906) (xy 351.281133 -271.509086)
			(xy 351.308334 -271.466072) (xy 351.342082 -271.427978) (xy 351.381504 -271.395791) (xy 351.425578 -271.370345)
			(xy 351.473164 -271.352298) (xy 351.523028 -271.342118) (xy 351.57388 -271.340069) (xy 351.624401 -271.346203)
			(xy 351.673285 -271.360363) (xy 351.719264 -271.38218) (xy 351.761148 -271.41109) (xy 351.797852 -271.446345)
			(xy 351.828425 -271.487031) (xy 351.852076 -271.532094) (xy 351.868192 -271.580368) (xy 351.876356 -271.630602)
			(xy 351.876868 -271.656048) (xy 352.184965 -271.656048) (xy 352.18906 -271.60532) (xy 352.201239 -271.555906)
			(xy 352.221187 -271.509086) (xy 352.248388 -271.466072) (xy 352.282136 -271.427978) (xy 352.321558 -271.395791)
			(xy 352.365632 -271.370345) (xy 352.413218 -271.352298) (xy 352.463082 -271.342118) (xy 352.513934 -271.340069)
			(xy 352.564455 -271.346203) (xy 352.613339 -271.360363) (xy 352.659318 -271.38218) (xy 352.701202 -271.41109)
			(xy 352.737906 -271.446345) (xy 352.768479 -271.487031) (xy 352.79213 -271.532094) (xy 352.808246 -271.580368)
			(xy 352.81641 -271.630602) (xy 352.816922 -271.656048) (xy 352.81641 -271.681494) (xy 352.808246 -271.731728)
			(xy 352.79213 -271.780002) (xy 352.768479 -271.825065) (xy 352.737906 -271.865751) (xy 352.701202 -271.901006)
			(xy 352.659318 -271.929916) (xy 352.613339 -271.951733) (xy 352.564455 -271.965893) (xy 352.513934 -271.972027)
			(xy 352.463082 -271.969978) (xy 352.413218 -271.959798) (xy 352.365632 -271.941751) (xy 352.321558 -271.916305)
			(xy 352.282136 -271.884118) (xy 352.248388 -271.846024) (xy 352.221187 -271.80301) (xy 352.201239 -271.75619)
			(xy 352.18906 -271.706776) (xy 352.184965 -271.656048) (xy 351.876868 -271.656048) (xy 351.876356 -271.681494)
			(xy 351.868192 -271.731728) (xy 351.852076 -271.780002) (xy 351.828425 -271.825065) (xy 351.797852 -271.865751)
			(xy 351.761148 -271.901006) (xy 351.719264 -271.929916) (xy 351.673285 -271.951733) (xy 351.624401 -271.965893)
			(xy 351.57388 -271.972027) (xy 351.523028 -271.969978) (xy 351.473164 -271.959798) (xy 351.425578 -271.941751)
			(xy 351.381504 -271.916305) (xy 351.342082 -271.884118) (xy 351.308334 -271.846024) (xy 351.281133 -271.80301)
			(xy 351.261185 -271.75619) (xy 351.249006 -271.706776) (xy 351.244911 -271.656048) (xy 350.938692 -271.656048)
			(xy 350.938692 -271.680985) (xy 350.930873 -271.730362) (xy 350.915426 -271.777907) (xy 350.892731 -271.822451)
			(xy 350.863347 -271.862895) (xy 350.827997 -271.898245) (xy 350.787553 -271.927629) (xy 350.74301 -271.950325)
			(xy 350.695464 -271.965773) (xy 350.646088 -271.973592) (xy 350.621092 -271.974056) (xy 350.600271 -271.973692)
			(xy 350.558992 -271.968211) (xy 350.538796 -271.963134) (xy 350.538542 -271.963134) (xy 350.53002 -271.961255)
			(xy 350.512646 -271.962764) (xy 350.496785 -271.970014) (xy 350.490282 -271.975834) (xy 350.427544 -272.03654)
			(xy 350.421557 -272.042913) (xy 350.413869 -272.058601) (xy 350.411919 -272.075962) (xy 350.413574 -272.084546)
			(xy 350.413574 -272.0848) (xy 350.416347 -272.097186) (xy 350.419278 -272.1224) (xy 350.419416 -272.135092)
			(xy 350.419416 -272.280888) (xy 350.419701 -272.287482) (xy 350.423162 -272.300214) (xy 350.426274 -272.306034)
			(xy 350.426274 -272.306288) (xy 350.439731 -272.330654) (xy 350.458864 -272.382919) (xy 350.468601 -272.437718)
			(xy 350.4692 -272.465546) (xy 350.4692 -272.466054) (xy 352.653092 -272.466054) (xy 352.653092 -272.4658)
			(xy 352.653737 -272.437511) (xy 352.663768 -272.381829) (xy 352.683494 -272.328802) (xy 352.712293 -272.280102)
			(xy 352.730308 -272.258282) (xy 352.735909 -272.251205) (xy 352.742147 -272.234281) (xy 352.7425 -272.225262)
			(xy 352.7425 -272.134838) (xy 352.742877 -272.113791) (xy 352.750878 -272.072469) (xy 352.766813 -272.033513)
			(xy 352.790067 -271.998431) (xy 352.81974 -271.96858) (xy 352.854682 -271.945116) (xy 352.893542 -271.928947)
			(xy 352.934815 -271.9207) (xy 352.95586 -271.920208) (xy 353.054412 -271.920208) (xy 353.066953 -271.919523)
			(xy 353.089062 -271.907666) (xy 353.096576 -271.897602) (xy 353.150424 -271.816322) (xy 353.152964 -271.791176)
			(xy 353.147884 -271.779238) (xy 353.140024 -271.759661) (xy 353.128959 -271.718953) (xy 353.123355 -271.677141)
			(xy 353.122992 -271.656048) (xy 353.123482 -271.631059) (xy 353.131301 -271.581696) (xy 353.146745 -271.534164)
			(xy 353.169435 -271.489632) (xy 353.198811 -271.449199) (xy 353.234151 -271.413859) (xy 353.274584 -271.384483)
			(xy 353.319116 -271.361793) (xy 353.366648 -271.346349) (xy 353.416011 -271.33853) (xy 353.465989 -271.33853)
			(xy 353.515352 -271.346349) (xy 353.562884 -271.361793) (xy 353.607416 -271.384483) (xy 353.647849 -271.413859)
			(xy 353.683189 -271.449199) (xy 353.712565 -271.489632) (xy 353.735255 -271.534164) (xy 353.750699 -271.581696)
			(xy 353.758518 -271.631059) (xy 353.759008 -271.656048) (xy 354.064819 -271.656048) (xy 354.068914 -271.60532)
			(xy 354.081093 -271.555906) (xy 354.101041 -271.509086) (xy 354.128242 -271.466072) (xy 354.16199 -271.427978)
			(xy 354.201412 -271.395791) (xy 354.245486 -271.370345) (xy 354.293072 -271.352298) (xy 354.342936 -271.342118)
			(xy 354.393788 -271.340069) (xy 354.444309 -271.346203) (xy 354.493193 -271.360363) (xy 354.539172 -271.38218)
			(xy 354.581056 -271.41109) (xy 354.61776 -271.446345) (xy 354.648333 -271.487031) (xy 354.671984 -271.532094)
			(xy 354.6881 -271.580368) (xy 354.696264 -271.630602) (xy 354.696776 -271.656048) (xy 355.00564 -271.656048)
			(xy 355.006126 -271.631258) (xy 355.013882 -271.58229) (xy 355.029203 -271.535137) (xy 355.051712 -271.490962)
			(xy 355.080854 -271.450851) (xy 355.115911 -271.415794) (xy 355.156022 -271.386652) (xy 355.200197 -271.364143)
			(xy 355.24735 -271.348822) (xy 355.296318 -271.341066) (xy 355.345898 -271.341066) (xy 355.394866 -271.348822)
			(xy 355.442019 -271.364143) (xy 355.486194 -271.386652) (xy 355.526305 -271.415794) (xy 355.561362 -271.450851)
			(xy 355.590504 -271.490962) (xy 355.613013 -271.535137) (xy 355.628334 -271.58229) (xy 355.63609 -271.631258)
			(xy 355.636576 -271.656048) (xy 355.636576 -271.65681) (xy 355.636221 -271.677779) (xy 355.630619 -271.719343)
			(xy 355.619542 -271.759793) (xy 355.611684 -271.779238) (xy 355.606604 -271.790922) (xy 355.60889 -271.816322)
			(xy 355.662992 -271.897602) (xy 355.670483 -271.907694) (xy 355.692605 -271.919557) (xy 355.705156 -271.920208)
			(xy 355.794056 -271.920208) (xy 355.802438 -271.920462) (xy 355.814933 -271.920338) (xy 355.83744 -271.90955)
			(xy 355.845364 -271.899888) (xy 355.902768 -271.821402) (xy 355.906578 -271.797018) (xy 355.90226 -271.78508)
			(xy 355.90226 -271.784572) (xy 355.891836 -271.753468) (xy 355.880592 -271.688845) (xy 355.879908 -271.656048)
			(xy 355.880505 -271.624971) (xy 355.890528 -271.563632) (xy 355.910349 -271.504724) (xy 355.924358 -271.476978)
			(xy 355.927083 -271.471458) (xy 355.930032 -271.45951) (xy 355.9302 -271.453356) (xy 355.9302 -271.395952)
			(xy 355.930718 -271.368456) (xy 355.93869 -271.314044) (xy 355.95439 -271.26134) (xy 355.965506 -271.236186)
			(xy 355.967143 -271.232423) (xy 355.969315 -271.22451) (xy 355.969824 -271.220438) (xy 355.972872 -271.201134)
			(xy 355.972872 -271.20088) (xy 355.974585 -271.190048) (xy 355.969845 -271.168668) (xy 355.956619 -271.151213)
			(xy 355.937317 -271.140868) (xy 355.91546 -271.139518) (xy 355.905054 -271.142968) (xy 355.877634 -271.152783)
			(xy 355.820378 -271.163397) (xy 355.791262 -271.16405) (xy 355.791008 -271.16405) (xy 355.766015 -271.163552)
			(xy 355.716645 -271.155734) (xy 355.669106 -271.140288) (xy 355.624569 -271.117596) (xy 355.584129 -271.088215)
			(xy 355.548784 -271.05287) (xy 355.519404 -271.012431) (xy 355.496712 -270.967893) (xy 355.481266 -270.920354)
			(xy 355.473448 -270.870984) (xy 355.473449 -270.820999) (xy 355.48127 -270.771629) (xy 355.496718 -270.724091)
			(xy 355.519413 -270.679554) (xy 355.548796 -270.639117) (xy 355.584143 -270.603774) (xy 355.624583 -270.574395)
			(xy 355.669122 -270.551705) (xy 355.716662 -270.536262) (xy 355.766033 -270.528447) (xy 355.816018 -270.52845)
			(xy 355.865387 -270.536274) (xy 355.912925 -270.551725) (xy 355.95746 -270.574422) (xy 355.997896 -270.603807)
			(xy 356.033237 -270.639155) (xy 356.062613 -270.679598) (xy 356.085301 -270.724138) (xy 356.100742 -270.771678)
			(xy 356.108555 -270.821049) (xy 356.109016 -270.846042) (xy 356.108244 -270.876805) (xy 356.09635 -270.937174)
			(xy 356.085394 -270.96593) (xy 356.084632 -270.968216) (xy 356.081554 -270.978464) (xy 356.083342 -270.999771)
			(xy 356.093622 -271.018519) (xy 356.110624 -271.031484) (xy 356.131425 -271.036434) (xy 356.142036 -271.035018)
			(xy 356.151848 -271.03326) (xy 356.171692 -271.031349) (xy 356.18166 -271.031208) (xy 356.199694 -271.031208)
			(xy 356.206552 -271.02943) (xy 356.232038 -271.022536) (xy 356.284296 -271.015015) (xy 356.310692 -271.014444)
			(xy 356.312724 -271.014444) (xy 356.317804 -271.014698) (xy 356.328924 -271.014279) (xy 356.349211 -271.005196)
			(xy 356.35692 -270.997172) (xy 356.41534 -270.929608) (xy 356.421436 -270.908018) (xy 356.419658 -270.896842)
			(xy 356.417675 -270.884235) (xy 356.415516 -270.858803) (xy 356.41534 -270.846042) (xy 356.415827 -270.821232)
			(xy 356.423589 -270.772224) (xy 356.438922 -270.725034) (xy 356.461449 -270.680823) (xy 356.490614 -270.64068)
			(xy 356.5257 -270.605594) (xy 356.565843 -270.576429) (xy 356.610054 -270.553902) (xy 356.657244 -270.538569)
			(xy 356.706252 -270.530807) (xy 356.755872 -270.530807) (xy 356.80488 -270.538569) (xy 356.85207 -270.553902)
			(xy 356.896281 -270.576429) (xy 356.936424 -270.605594) (xy 356.97151 -270.64068) (xy 357.000675 -270.680823)
			(xy 357.023202 -270.725034) (xy 357.038535 -270.772224) (xy 357.046297 -270.821232) (xy 357.046784 -270.846042)
			(xy 357.354881 -270.846042) (xy 357.358976 -270.795314) (xy 357.371155 -270.7459) (xy 357.391103 -270.69908)
			(xy 357.418304 -270.656066) (xy 357.452052 -270.617972) (xy 357.491474 -270.585785) (xy 357.535548 -270.560339)
			(xy 357.583134 -270.542292) (xy 357.632998 -270.532112) (xy 357.68385 -270.530063) (xy 357.734371 -270.536197)
			(xy 357.783255 -270.550357) (xy 357.829234 -270.572174) (xy 357.871118 -270.601084) (xy 357.907822 -270.636339)
			(xy 357.938395 -270.677025) (xy 357.962046 -270.722088) (xy 357.978162 -270.770362) (xy 357.986326 -270.820596)
			(xy 357.986838 -270.846042) (xy 357.986335 -270.871031) (xy 358.293652 -270.871031) (xy 358.293652 -270.821053)
			(xy 358.301471 -270.77169) (xy 358.316915 -270.724158) (xy 358.339605 -270.679626) (xy 358.368981 -270.639193)
			(xy 358.404321 -270.603853) (xy 358.444754 -270.574477) (xy 358.489286 -270.551787) (xy 358.536818 -270.536343)
			(xy 358.586181 -270.528524) (xy 358.636159 -270.528524) (xy 358.685522 -270.536343) (xy 358.733054 -270.551787)
			(xy 358.777586 -270.574477) (xy 358.818019 -270.603853) (xy 358.853359 -270.639193) (xy 358.882735 -270.679626)
			(xy 358.905425 -270.724158) (xy 358.920869 -270.77169) (xy 358.928688 -270.821053) (xy 358.929178 -270.846042)
			(xy 358.928688 -270.871031) (xy 361.10721 -270.871031) (xy 361.10721 -270.821053) (xy 361.115029 -270.77169)
			(xy 361.130473 -270.724158) (xy 361.153163 -270.679626) (xy 361.182539 -270.639193) (xy 361.217879 -270.603853)
			(xy 361.258312 -270.574477) (xy 361.302844 -270.551787) (xy 361.350376 -270.536343) (xy 361.399739 -270.528524)
			(xy 361.449717 -270.528524) (xy 361.49908 -270.536343) (xy 361.546612 -270.551787) (xy 361.591144 -270.574477)
			(xy 361.631577 -270.603853) (xy 361.666917 -270.639193) (xy 361.696293 -270.679626) (xy 361.718983 -270.724158)
			(xy 361.734427 -270.77169) (xy 361.742246 -270.821053) (xy 361.742736 -270.846042) (xy 362.048547 -270.846042)
			(xy 362.052642 -270.795314) (xy 362.064821 -270.7459) (xy 362.084769 -270.69908) (xy 362.11197 -270.656066)
			(xy 362.145718 -270.617972) (xy 362.18514 -270.585785) (xy 362.229214 -270.560339) (xy 362.2768 -270.542292)
			(xy 362.326664 -270.532112) (xy 362.377516 -270.530063) (xy 362.428037 -270.536197) (xy 362.476921 -270.550357)
			(xy 362.5229 -270.572174) (xy 362.564784 -270.601084) (xy 362.601488 -270.636339) (xy 362.632061 -270.677025)
			(xy 362.655712 -270.722088) (xy 362.671828 -270.770362) (xy 362.679992 -270.820596) (xy 362.680504 -270.846042)
			(xy 362.989368 -270.846042) (xy 362.989902 -270.821247) (xy 362.99765 -270.772265) (xy 363.012961 -270.725098)
			(xy 363.03546 -270.680905) (xy 363.064592 -270.640773) (xy 363.09964 -270.605691) (xy 363.139744 -270.57652)
			(xy 363.183915 -270.553979) (xy 363.231067 -270.538622) (xy 363.280041 -270.530827) (xy 363.304836 -270.53032)
			(xy 363.330956 -270.530872) (xy 363.382485 -270.539468) (xy 363.431893 -270.556436) (xy 363.47783 -270.581312)
			(xy 363.519041 -270.613417) (xy 363.5544 -270.651872) (xy 363.582941 -270.695627) (xy 363.603882 -270.743487)
			(xy 363.616653 -270.794142) (xy 363.619288 -270.820134) (xy 363.619288 -270.820388) (xy 363.620529 -270.829952)
			(xy 363.629142 -270.847189) (xy 363.636052 -270.853916) (xy 363.695996 -270.907256) (xy 363.714284 -270.913606)
			(xy 363.723936 -270.913352) (xy 363.724444 -270.913352) (xy 363.7407 -270.912844) (xy 363.741716 -270.912844)
			(xy 363.759246 -270.913066) (xy 363.794206 -270.915734) (xy 363.811566 -270.918178) (xy 363.821936 -270.919151)
			(xy 363.842 -270.913632) (xy 363.850428 -270.90751) (xy 363.91723 -270.853662) (xy 363.926882 -270.83512)
			(xy 363.927644 -270.824452) (xy 363.929999 -270.797984) (xy 363.94236 -270.74631) (xy 363.96314 -270.697409)
			(xy 363.991758 -270.652642) (xy 364.027419 -270.613254) (xy 364.069132 -270.580343) (xy 364.115734 -270.554822)
			(xy 364.16593 -270.537403) (xy 364.218324 -270.52857) (xy 364.24489 -270.528034) (xy 364.269883 -270.528466)
			(xy 364.319254 -270.536285) (xy 364.366793 -270.551731) (xy 364.411331 -270.574425) (xy 364.451769 -270.603808)
			(xy 364.487113 -270.639155) (xy 364.516492 -270.679596) (xy 364.539181 -270.724136) (xy 364.554623 -270.771677)
			(xy 364.562437 -270.821049) (xy 364.562898 -270.846042) (xy 364.562418 -270.871031) (xy 364.867172 -270.871031)
			(xy 364.867172 -270.821053) (xy 364.874991 -270.77169) (xy 364.890435 -270.724158) (xy 364.913125 -270.679626)
			(xy 364.942501 -270.639193) (xy 364.977841 -270.603853) (xy 365.018274 -270.574477) (xy 365.062806 -270.551787)
			(xy 365.110338 -270.536343) (xy 365.159701 -270.528524) (xy 365.209679 -270.528524) (xy 365.259042 -270.536343)
			(xy 365.306574 -270.551787) (xy 365.351106 -270.574477) (xy 365.391539 -270.603853) (xy 365.426879 -270.639193)
			(xy 365.456255 -270.679626) (xy 365.478945 -270.724158) (xy 365.494389 -270.77169) (xy 365.502208 -270.821053)
			(xy 365.502698 -270.846042) (xy 365.502208 -270.871031) (xy 365.807226 -270.871031) (xy 365.807226 -270.821053)
			(xy 365.815045 -270.77169) (xy 365.830489 -270.724158) (xy 365.853179 -270.679626) (xy 365.882555 -270.639193)
			(xy 365.917895 -270.603853) (xy 365.958328 -270.574477) (xy 366.00286 -270.551787) (xy 366.050392 -270.536343)
			(xy 366.099755 -270.528524) (xy 366.149733 -270.528524) (xy 366.199096 -270.536343) (xy 366.246628 -270.551787)
			(xy 366.29116 -270.574477) (xy 366.331593 -270.603853) (xy 366.366933 -270.639193) (xy 366.396309 -270.679626)
			(xy 366.418999 -270.724158) (xy 366.434443 -270.77169) (xy 366.442262 -270.821053) (xy 366.442752 -270.846042)
			(xy 366.442262 -270.871031) (xy 366.74728 -270.871031) (xy 366.74728 -270.821053) (xy 366.755099 -270.77169)
			(xy 366.770543 -270.724158) (xy 366.793233 -270.679626) (xy 366.822609 -270.639193) (xy 366.857949 -270.603853)
			(xy 366.898382 -270.574477) (xy 366.942914 -270.551787) (xy 366.990446 -270.536343) (xy 367.039809 -270.528524)
			(xy 367.089787 -270.528524) (xy 367.13915 -270.536343) (xy 367.186682 -270.551787) (xy 367.231214 -270.574477)
			(xy 367.271647 -270.603853) (xy 367.306987 -270.639193) (xy 367.336363 -270.679626) (xy 367.359053 -270.724158)
			(xy 367.374497 -270.77169) (xy 367.382316 -270.821053) (xy 367.382806 -270.846042) (xy 367.382316 -270.871031)
			(xy 367.687334 -270.871031) (xy 367.687334 -270.821053) (xy 367.695153 -270.77169) (xy 367.710597 -270.724158)
			(xy 367.733287 -270.679626) (xy 367.762663 -270.639193) (xy 367.798003 -270.603853) (xy 367.838436 -270.574477)
			(xy 367.882968 -270.551787) (xy 367.9305 -270.536343) (xy 367.979863 -270.528524) (xy 368.029841 -270.528524)
			(xy 368.079204 -270.536343) (xy 368.126736 -270.551787) (xy 368.171268 -270.574477) (xy 368.211701 -270.603853)
			(xy 368.247041 -270.639193) (xy 368.276417 -270.679626) (xy 368.299107 -270.724158) (xy 368.314551 -270.77169)
			(xy 368.32237 -270.821053) (xy 368.32286 -270.846042) (xy 368.32237 -270.871031) (xy 368.627388 -270.871031)
			(xy 368.627388 -270.821053) (xy 368.635207 -270.77169) (xy 368.650651 -270.724158) (xy 368.673341 -270.679626)
			(xy 368.702717 -270.639193) (xy 368.738057 -270.603853) (xy 368.77849 -270.574477) (xy 368.823022 -270.551787)
			(xy 368.870554 -270.536343) (xy 368.919917 -270.528524) (xy 368.969895 -270.528524) (xy 369.019258 -270.536343)
			(xy 369.06679 -270.551787) (xy 369.111322 -270.574477) (xy 369.151755 -270.603853) (xy 369.187095 -270.639193)
			(xy 369.216471 -270.679626) (xy 369.239161 -270.724158) (xy 369.254605 -270.77169) (xy 369.262424 -270.821053)
			(xy 369.262914 -270.846042) (xy 369.262424 -270.871031) (xy 369.567188 -270.871031) (xy 369.567188 -270.821053)
			(xy 369.575007 -270.77169) (xy 369.590451 -270.724158) (xy 369.613141 -270.679626) (xy 369.642517 -270.639193)
			(xy 369.677857 -270.603853) (xy 369.71829 -270.574477) (xy 369.762822 -270.551787) (xy 369.810354 -270.536343)
			(xy 369.859717 -270.528524) (xy 369.909695 -270.528524) (xy 369.959058 -270.536343) (xy 370.00659 -270.551787)
			(xy 370.051122 -270.574477) (xy 370.091555 -270.603853) (xy 370.126895 -270.639193) (xy 370.156271 -270.679626)
			(xy 370.178961 -270.724158) (xy 370.194405 -270.77169) (xy 370.202224 -270.821053) (xy 370.202714 -270.846042)
			(xy 370.202224 -270.871031) (xy 370.507242 -270.871031) (xy 370.507242 -270.821053) (xy 370.515061 -270.77169)
			(xy 370.530505 -270.724158) (xy 370.553195 -270.679626) (xy 370.582571 -270.639193) (xy 370.617911 -270.603853)
			(xy 370.658344 -270.574477) (xy 370.702876 -270.551787) (xy 370.750408 -270.536343) (xy 370.799771 -270.528524)
			(xy 370.849749 -270.528524) (xy 370.899112 -270.536343) (xy 370.946644 -270.551787) (xy 370.991176 -270.574477)
			(xy 371.031609 -270.603853) (xy 371.066949 -270.639193) (xy 371.096325 -270.679626) (xy 371.119015 -270.724158)
			(xy 371.134459 -270.77169) (xy 371.142278 -270.821053) (xy 371.142768 -270.846042) (xy 371.142278 -270.871031)
			(xy 371.134459 -270.920394) (xy 371.119015 -270.967926) (xy 371.096325 -271.012458) (xy 371.066949 -271.052891)
			(xy 371.031609 -271.088231) (xy 370.991176 -271.117607) (xy 370.946644 -271.140297) (xy 370.899112 -271.155741)
			(xy 370.849749 -271.16356) (xy 370.799771 -271.16356) (xy 370.750408 -271.155741) (xy 370.702876 -271.140297)
			(xy 370.658344 -271.117607) (xy 370.617911 -271.088231) (xy 370.582571 -271.052891) (xy 370.553195 -271.012458)
			(xy 370.530505 -270.967926) (xy 370.515061 -270.920394) (xy 370.507242 -270.871031) (xy 370.202224 -270.871031)
			(xy 370.194405 -270.920394) (xy 370.178961 -270.967926) (xy 370.156271 -271.012458) (xy 370.126895 -271.052891)
			(xy 370.091555 -271.088231) (xy 370.051122 -271.117607) (xy 370.00659 -271.140297) (xy 369.959058 -271.155741)
			(xy 369.909695 -271.16356) (xy 369.859717 -271.16356) (xy 369.810354 -271.155741) (xy 369.762822 -271.140297)
			(xy 369.71829 -271.117607) (xy 369.677857 -271.088231) (xy 369.642517 -271.052891) (xy 369.613141 -271.012458)
			(xy 369.590451 -270.967926) (xy 369.575007 -270.920394) (xy 369.567188 -270.871031) (xy 369.262424 -270.871031)
			(xy 369.254605 -270.920394) (xy 369.239161 -270.967926) (xy 369.216471 -271.012458) (xy 369.187095 -271.052891)
			(xy 369.151755 -271.088231) (xy 369.111322 -271.117607) (xy 369.06679 -271.140297) (xy 369.019258 -271.155741)
			(xy 368.969895 -271.16356) (xy 368.919917 -271.16356) (xy 368.870554 -271.155741) (xy 368.823022 -271.140297)
			(xy 368.77849 -271.117607) (xy 368.738057 -271.088231) (xy 368.702717 -271.052891) (xy 368.673341 -271.012458)
			(xy 368.650651 -270.967926) (xy 368.635207 -270.920394) (xy 368.627388 -270.871031) (xy 368.32237 -270.871031)
			(xy 368.314551 -270.920394) (xy 368.299107 -270.967926) (xy 368.276417 -271.012458) (xy 368.247041 -271.052891)
			(xy 368.211701 -271.088231) (xy 368.171268 -271.117607) (xy 368.126736 -271.140297) (xy 368.079204 -271.155741)
			(xy 368.029841 -271.16356) (xy 367.979863 -271.16356) (xy 367.9305 -271.155741) (xy 367.882968 -271.140297)
			(xy 367.838436 -271.117607) (xy 367.798003 -271.088231) (xy 367.762663 -271.052891) (xy 367.733287 -271.012458)
			(xy 367.710597 -270.967926) (xy 367.695153 -270.920394) (xy 367.687334 -270.871031) (xy 367.382316 -270.871031)
			(xy 367.374497 -270.920394) (xy 367.359053 -270.967926) (xy 367.336363 -271.012458) (xy 367.306987 -271.052891)
			(xy 367.271647 -271.088231) (xy 367.231214 -271.117607) (xy 367.186682 -271.140297) (xy 367.13915 -271.155741)
			(xy 367.089787 -271.16356) (xy 367.039809 -271.16356) (xy 366.990446 -271.155741) (xy 366.942914 -271.140297)
			(xy 366.898382 -271.117607) (xy 366.857949 -271.088231) (xy 366.822609 -271.052891) (xy 366.793233 -271.012458)
			(xy 366.770543 -270.967926) (xy 366.755099 -270.920394) (xy 366.74728 -270.871031) (xy 366.442262 -270.871031)
			(xy 366.434443 -270.920394) (xy 366.418999 -270.967926) (xy 366.396309 -271.012458) (xy 366.366933 -271.052891)
			(xy 366.331593 -271.088231) (xy 366.29116 -271.117607) (xy 366.246628 -271.140297) (xy 366.199096 -271.155741)
			(xy 366.149733 -271.16356) (xy 366.099755 -271.16356) (xy 366.050392 -271.155741) (xy 366.00286 -271.140297)
			(xy 365.958328 -271.117607) (xy 365.917895 -271.088231) (xy 365.882555 -271.052891) (xy 365.853179 -271.012458)
			(xy 365.830489 -270.967926) (xy 365.815045 -270.920394) (xy 365.807226 -270.871031) (xy 365.502208 -270.871031)
			(xy 365.494389 -270.920394) (xy 365.478945 -270.967926) (xy 365.456255 -271.012458) (xy 365.426879 -271.052891)
			(xy 365.391539 -271.088231) (xy 365.351106 -271.117607) (xy 365.306574 -271.140297) (xy 365.259042 -271.155741)
			(xy 365.209679 -271.16356) (xy 365.159701 -271.16356) (xy 365.110338 -271.155741) (xy 365.062806 -271.140297)
			(xy 365.018274 -271.117607) (xy 364.977841 -271.088231) (xy 364.942501 -271.052891) (xy 364.913125 -271.012458)
			(xy 364.890435 -270.967926) (xy 364.874991 -270.920394) (xy 364.867172 -270.871031) (xy 364.562418 -270.871031)
			(xy 364.562417 -270.871061) (xy 364.554589 -270.920483) (xy 364.539117 -270.968069) (xy 364.516383 -271.012644)
			(xy 364.486949 -271.053109) (xy 364.451539 -271.088464) (xy 364.41103 -271.117837) (xy 364.36642 -271.140503)
			(xy 364.31881 -271.155902) (xy 364.294166 -271.16024) (xy 364.283752 -271.161764) (xy 364.265718 -271.173194)
			(xy 364.212378 -271.253204) (xy 364.208568 -271.273778) (xy 364.211108 -271.284192) (xy 364.217271 -271.31172)
			(xy 364.223889 -271.367745) (xy 364.224316 -271.395952) (xy 364.224316 -271.47901) (xy 364.227364 -271.487646)
			(xy 364.236997 -271.514666) (xy 364.250546 -271.57041) (xy 364.257402 -271.627365) (xy 364.257844 -271.656048)
			(xy 364.25719 -271.690111) (xy 364.247505 -271.757546) (xy 364.23854 -271.790414) (xy 364.23854 -271.790668)
			(xy 364.235947 -271.802095) (xy 364.240169 -271.825115) (xy 364.246668 -271.834864) (xy 364.29569 -271.899888)
			(xy 364.303278 -271.909009) (xy 364.32448 -271.919596) (xy 364.33633 -271.920208) (xy 364.386114 -271.920208)
			(xy 364.395437 -271.919776) (xy 364.412846 -271.913099) (xy 364.426712 -271.900634) (xy 364.431326 -271.892522)
			(xy 364.444788 -271.866106) (xy 364.448412 -271.858347) (xy 364.450742 -271.841389) (xy 364.447349 -271.824612)
			(xy 364.443264 -271.817084) (xy 364.429413 -271.792527) (xy 364.409698 -271.739713) (xy 364.399687 -271.684235)
			(xy 364.399068 -271.656048) (xy 364.399555 -271.631238) (xy 364.407317 -271.58223) (xy 364.42265 -271.53504)
			(xy 364.445177 -271.490829) (xy 364.474342 -271.450686) (xy 364.509428 -271.4156) (xy 364.549571 -271.386435)
			(xy 364.593782 -271.363908) (xy 364.640972 -271.348575) (xy 364.68998 -271.340813) (xy 364.7396 -271.340813)
			(xy 364.788608 -271.348575) (xy 364.835798 -271.363908) (xy 364.880009 -271.386435) (xy 364.920152 -271.4156)
			(xy 364.955238 -271.450686) (xy 364.984403 -271.490829) (xy 365.00693 -271.53504) (xy 365.022263 -271.58223)
			(xy 365.030025 -271.631238) (xy 365.030512 -271.656048) (xy 365.338609 -271.656048) (xy 365.342704 -271.60532)
			(xy 365.354883 -271.555906) (xy 365.374831 -271.509086) (xy 365.402032 -271.466072) (xy 365.43578 -271.427978)
			(xy 365.475202 -271.395791) (xy 365.519276 -271.370345) (xy 365.566862 -271.352298) (xy 365.616726 -271.342118)
			(xy 365.667578 -271.340069) (xy 365.718099 -271.346203) (xy 365.766983 -271.360363) (xy 365.812962 -271.38218)
			(xy 365.854846 -271.41109) (xy 365.89155 -271.446345) (xy 365.922123 -271.487031) (xy 365.945774 -271.532094)
			(xy 365.96189 -271.580368) (xy 365.970054 -271.630602) (xy 365.970566 -271.656048) (xy 366.27689 -271.656048)
			(xy 366.27738 -271.631059) (xy 366.285199 -271.581696) (xy 366.300643 -271.534164) (xy 366.323333 -271.489632)
			(xy 366.352709 -271.449199) (xy 366.388049 -271.413859) (xy 366.428482 -271.384483) (xy 366.473014 -271.361793)
			(xy 366.520546 -271.346349) (xy 366.569909 -271.33853) (xy 366.619887 -271.33853) (xy 366.66925 -271.346349)
			(xy 366.716782 -271.361793) (xy 366.761314 -271.384483) (xy 366.801747 -271.413859) (xy 366.837087 -271.449199)
			(xy 366.866463 -271.489632) (xy 366.889153 -271.534164) (xy 366.904597 -271.581696) (xy 366.912416 -271.631059)
			(xy 366.912906 -271.656048) (xy 367.218463 -271.656048) (xy 367.222558 -271.60532) (xy 367.234737 -271.555906)
			(xy 367.254685 -271.509086) (xy 367.281886 -271.466072) (xy 367.315634 -271.427978) (xy 367.355056 -271.395791)
			(xy 367.39913 -271.370345) (xy 367.446716 -271.352298) (xy 367.49658 -271.342118) (xy 367.547432 -271.340069)
			(xy 367.597953 -271.346203) (xy 367.646837 -271.360363) (xy 367.692816 -271.38218) (xy 367.7347 -271.41109)
			(xy 367.771404 -271.446345) (xy 367.801977 -271.487031) (xy 367.825628 -271.532094) (xy 367.841744 -271.580368)
			(xy 367.849908 -271.630602) (xy 367.85042 -271.656048) (xy 368.158517 -271.656048) (xy 368.162612 -271.60532)
			(xy 368.174791 -271.555906) (xy 368.194739 -271.509086) (xy 368.22194 -271.466072) (xy 368.255688 -271.427978)
			(xy 368.29511 -271.395791) (xy 368.339184 -271.370345) (xy 368.38677 -271.352298) (xy 368.436634 -271.342118)
			(xy 368.487486 -271.340069) (xy 368.538007 -271.346203) (xy 368.586891 -271.360363) (xy 368.63287 -271.38218)
			(xy 368.674754 -271.41109) (xy 368.711458 -271.446345) (xy 368.742031 -271.487031) (xy 368.765682 -271.532094)
			(xy 368.781798 -271.580368) (xy 368.789962 -271.630602) (xy 368.790474 -271.656048) (xy 368.789971 -271.681037)
			(xy 369.097288 -271.681037) (xy 369.097288 -271.631059) (xy 369.105107 -271.581696) (xy 369.120551 -271.534164)
			(xy 369.143241 -271.489632) (xy 369.172617 -271.449199) (xy 369.207957 -271.413859) (xy 369.24839 -271.384483)
			(xy 369.292922 -271.361793) (xy 369.340454 -271.346349) (xy 369.389817 -271.33853) (xy 369.439795 -271.33853)
			(xy 369.489158 -271.346349) (xy 369.53669 -271.361793) (xy 369.581222 -271.384483) (xy 369.621655 -271.413859)
			(xy 369.656995 -271.449199) (xy 369.686371 -271.489632) (xy 369.709061 -271.534164) (xy 369.724505 -271.581696)
			(xy 369.732324 -271.631059) (xy 369.732814 -271.656048) (xy 369.732324 -271.681037) (xy 369.724505 -271.7304)
			(xy 369.709061 -271.777932) (xy 369.686371 -271.822464) (xy 369.656995 -271.862897) (xy 369.621655 -271.898237)
			(xy 369.581222 -271.927613) (xy 369.53669 -271.950303) (xy 369.489158 -271.965747) (xy 369.439795 -271.973566)
			(xy 369.389817 -271.973566) (xy 369.340454 -271.965747) (xy 369.292922 -271.950303) (xy 369.24839 -271.927613)
			(xy 369.207957 -271.898237) (xy 369.172617 -271.862897) (xy 369.143241 -271.822464) (xy 369.120551 -271.777932)
			(xy 369.105107 -271.7304) (xy 369.097288 -271.681037) (xy 368.789971 -271.681037) (xy 368.789962 -271.681494)
			(xy 368.781798 -271.731728) (xy 368.765682 -271.780002) (xy 368.742031 -271.825065) (xy 368.711458 -271.865751)
			(xy 368.674754 -271.901006) (xy 368.63287 -271.929916) (xy 368.586891 -271.951733) (xy 368.538007 -271.965893)
			(xy 368.487486 -271.972027) (xy 368.436634 -271.969978) (xy 368.38677 -271.959798) (xy 368.339184 -271.941751)
			(xy 368.29511 -271.916305) (xy 368.255688 -271.884118) (xy 368.22194 -271.846024) (xy 368.194739 -271.80301)
			(xy 368.174791 -271.75619) (xy 368.162612 -271.706776) (xy 368.158517 -271.656048) (xy 367.85042 -271.656048)
			(xy 367.849908 -271.681494) (xy 367.841744 -271.731728) (xy 367.825628 -271.780002) (xy 367.801977 -271.825065)
			(xy 367.771404 -271.865751) (xy 367.7347 -271.901006) (xy 367.692816 -271.929916) (xy 367.646837 -271.951733)
			(xy 367.597953 -271.965893) (xy 367.547432 -271.972027) (xy 367.49658 -271.969978) (xy 367.446716 -271.959798)
			(xy 367.39913 -271.941751) (xy 367.355056 -271.916305) (xy 367.315634 -271.884118) (xy 367.281886 -271.846024)
			(xy 367.254685 -271.80301) (xy 367.234737 -271.75619) (xy 367.222558 -271.706776) (xy 367.218463 -271.656048)
			(xy 366.912906 -271.656048) (xy 366.912563 -271.677142) (xy 366.906974 -271.718959) (xy 366.895888 -271.759665)
			(xy 366.888014 -271.779238) (xy 366.882934 -271.791176) (xy 366.885474 -271.816322) (xy 366.939322 -271.897602)
			(xy 366.946798 -271.907708) (xy 366.968931 -271.919564) (xy 366.981486 -271.920208) (xy 367.097056 -271.920208)
			(xy 367.118099 -271.920764) (xy 367.159371 -271.928997) (xy 367.198233 -271.945153) (xy 367.233178 -271.968606)
			(xy 367.262853 -271.998448) (xy 367.28611 -272.033524) (xy 367.302049 -272.072475) (xy 367.31005 -272.113793)
			(xy 367.310416 -272.134838) (xy 367.310416 -272.135346) (xy 367.310416 -272.246344) (xy 367.310699 -272.254455)
			(xy 367.315741 -272.269871) (xy 367.320322 -272.27657) (xy 367.335043 -272.297217) (xy 367.358385 -272.342231)
			(xy 367.374278 -272.390382) (xy 367.382319 -272.440447) (xy 367.382806 -272.4658) (xy 367.382806 -272.466054)
			(xy 369.566698 -272.466054) (xy 369.56716 -272.441725) (xy 369.574567 -272.393635) (xy 369.589215 -272.347236)
			(xy 369.610763 -272.30361) (xy 369.624356 -272.283428) (xy 369.628616 -272.276895) (xy 369.633266 -272.262015)
			(xy 369.6335 -272.254218) (xy 369.6335 -272.134838) (xy 369.633877 -272.113791) (xy 369.641878 -272.072469)
			(xy 369.657813 -272.033513) (xy 369.681067 -271.998431) (xy 369.71074 -271.96858) (xy 369.745682 -271.945116)
			(xy 369.784542 -271.928947) (xy 369.825815 -271.9207) (xy 369.84686 -271.920208) (xy 369.970812 -271.920208)
			(xy 369.983353 -271.919523) (xy 370.005462 -271.907666) (xy 370.012976 -271.897602) (xy 370.067078 -271.816322)
			(xy 370.069364 -271.790922) (xy 370.064284 -271.779238) (xy 370.052737 -271.749955) (xy 370.0402 -271.688278)
			(xy 370.039392 -271.65681) (xy 370.039392 -271.656048) (xy 370.039878 -271.631258) (xy 370.047634 -271.58229)
			(xy 370.062955 -271.535137) (xy 370.085464 -271.490962) (xy 370.114606 -271.450851) (xy 370.149663 -271.415794)
			(xy 370.189774 -271.386652) (xy 370.233949 -271.364143) (xy 370.281102 -271.348822) (xy 370.33007 -271.341066)
			(xy 370.37965 -271.341066) (xy 370.428618 -271.348822) (xy 370.475771 -271.364143) (xy 370.519946 -271.386652)
			(xy 370.560057 -271.415794) (xy 370.595114 -271.450851) (xy 370.624256 -271.490962) (xy 370.646765 -271.535137)
			(xy 370.662086 -271.58229) (xy 370.669842 -271.631258) (xy 370.670328 -271.656048) (xy 370.669813 -271.680587)
			(xy 370.669781 -271.680789) (xy 370.979941 -271.680789) (xy 370.979941 -271.631211) (xy 370.987697 -271.582245)
			(xy 371.003017 -271.535094) (xy 371.025525 -271.490921) (xy 371.054667 -271.450813) (xy 371.089724 -271.415758)
			(xy 371.129833 -271.386618) (xy 371.174007 -271.364112) (xy 371.221158 -271.348793) (xy 371.270125 -271.34104)
			(xy 371.294914 -271.34058) (xy 371.310836 -271.340766) (xy 371.342519 -271.343946) (xy 371.35816 -271.34693)
			(xy 371.367089 -271.348304) (xy 371.384913 -271.34545) (xy 371.392958 -271.341342) (xy 371.420136 -271.326356)
			(xy 371.42811 -271.321378) (xy 371.440099 -271.306923) (xy 371.443504 -271.298162) (xy 371.453041 -271.271319)
			(xy 371.477547 -271.219894) (xy 371.507941 -271.171713) (xy 371.525546 -271.149318) (xy 371.530866 -271.14214)
			(xy 371.5366 -271.125231) (xy 371.536722 -271.116298) (xy 371.536214 -271.085564) (xy 371.535596 -271.0768)
			(xy 371.529239 -271.060435) (xy 371.523768 -271.05356) (xy 371.505787 -271.031724) (xy 371.477027 -270.983023)
			(xy 371.457355 -270.929996) (xy 371.447394 -270.874322) (xy 371.446806 -270.846042) (xy 371.447296 -270.821053)
			(xy 371.455115 -270.77169) (xy 371.470559 -270.724158) (xy 371.493249 -270.679626) (xy 371.522625 -270.639193)
			(xy 371.557965 -270.603853) (xy 371.598398 -270.574477) (xy 371.64293 -270.551787) (xy 371.690462 -270.536343)
			(xy 371.739825 -270.528524) (xy 371.789803 -270.528524) (xy 371.839166 -270.536343) (xy 371.886698 -270.551787)
			(xy 371.93123 -270.574477) (xy 371.971663 -270.603853) (xy 372.007003 -270.639193) (xy 372.036379 -270.679626)
			(xy 372.059069 -270.724158) (xy 372.074513 -270.77169) (xy 372.082332 -270.821053) (xy 372.082822 -270.846042)
			(xy 372.081632 -270.871031) (xy 372.38735 -270.871031) (xy 372.38735 -270.821053) (xy 372.395169 -270.77169)
			(xy 372.410613 -270.724158) (xy 372.433303 -270.679626) (xy 372.462679 -270.639193) (xy 372.498019 -270.603853)
			(xy 372.538452 -270.574477) (xy 372.582984 -270.551787) (xy 372.630516 -270.536343) (xy 372.679879 -270.528524)
			(xy 372.729857 -270.528524) (xy 372.77922 -270.536343) (xy 372.826752 -270.551787) (xy 372.871284 -270.574477)
			(xy 372.911717 -270.603853) (xy 372.947057 -270.639193) (xy 372.976433 -270.679626) (xy 372.999123 -270.724158)
			(xy 373.014567 -270.77169) (xy 373.022386 -270.821053) (xy 373.022876 -270.846042) (xy 373.022386 -270.871031)
			(xy 373.327404 -270.871031) (xy 373.327404 -270.821053) (xy 373.335223 -270.77169) (xy 373.350667 -270.724158)
			(xy 373.373357 -270.679626) (xy 373.402733 -270.639193) (xy 373.438073 -270.603853) (xy 373.478506 -270.574477)
			(xy 373.523038 -270.551787) (xy 373.57057 -270.536343) (xy 373.619933 -270.528524) (xy 373.669911 -270.528524)
			(xy 373.719274 -270.536343) (xy 373.766806 -270.551787) (xy 373.811338 -270.574477) (xy 373.851771 -270.603853)
			(xy 373.887111 -270.639193) (xy 373.916487 -270.679626) (xy 373.939177 -270.724158) (xy 373.954621 -270.77169)
			(xy 373.96244 -270.821053) (xy 373.96293 -270.846042) (xy 373.96244 -270.871031) (xy 373.954621 -270.920394)
			(xy 373.939177 -270.967926) (xy 373.916487 -271.012458) (xy 373.887111 -271.052891) (xy 373.851771 -271.088231)
			(xy 373.811338 -271.117607) (xy 373.766806 -271.140297) (xy 373.719274 -271.155741) (xy 373.669911 -271.16356)
			(xy 373.619933 -271.16356) (xy 373.57057 -271.155741) (xy 373.523038 -271.140297) (xy 373.478506 -271.117607)
			(xy 373.438073 -271.088231) (xy 373.402733 -271.052891) (xy 373.373357 -271.012458) (xy 373.350667 -270.967926)
			(xy 373.335223 -270.920394) (xy 373.327404 -270.871031) (xy 373.022386 -270.871031) (xy 373.014567 -270.920394)
			(xy 372.999123 -270.967926) (xy 372.976433 -271.012458) (xy 372.947057 -271.052891) (xy 372.911717 -271.088231)
			(xy 372.871284 -271.117607) (xy 372.826752 -271.140297) (xy 372.77922 -271.155741) (xy 372.729857 -271.16356)
			(xy 372.679879 -271.16356) (xy 372.630516 -271.155741) (xy 372.582984 -271.140297) (xy 372.538452 -271.117607)
			(xy 372.498019 -271.088231) (xy 372.462679 -271.052891) (xy 372.433303 -271.012458) (xy 372.410613 -270.967926)
			(xy 372.395169 -270.920394) (xy 372.38735 -270.871031) (xy 372.081632 -270.871031) (xy 372.081298 -270.878046)
			(xy 372.080282 -270.886936) (xy 372.084854 -270.904462) (xy 372.127272 -270.966184) (xy 372.132735 -270.97342)
			(xy 372.147566 -270.983827) (xy 372.156228 -270.986504) (xy 372.186739 -270.995104) (xy 372.24535 -271.019258)
			(xy 372.300292 -271.05088) (xy 372.35062 -271.089425) (xy 372.373398 -271.111472) (xy 372.576344 -271.314418)
			(xy 372.598285 -271.337108) (xy 372.636678 -271.387208) (xy 372.668221 -271.441879) (xy 372.692379 -271.500193)
			(xy 372.708738 -271.561154) (xy 372.717022 -271.623727) (xy 372.717568 -271.655286) (xy 372.717568 -271.656048)
			(xy 372.858533 -271.656048) (xy 372.862628 -271.60532) (xy 372.874807 -271.555906) (xy 372.894755 -271.509086)
			(xy 372.921956 -271.466072) (xy 372.955704 -271.427978) (xy 372.995126 -271.395791) (xy 373.0392 -271.370345)
			(xy 373.086786 -271.352298) (xy 373.13665 -271.342118) (xy 373.187502 -271.340069) (xy 373.238023 -271.346203)
			(xy 373.286907 -271.360363) (xy 373.332886 -271.38218) (xy 373.37477 -271.41109) (xy 373.411474 -271.446345)
			(xy 373.442047 -271.487031) (xy 373.465698 -271.532094) (xy 373.481814 -271.580368) (xy 373.489978 -271.630602)
			(xy 373.49049 -271.656048) (xy 373.798587 -271.656048) (xy 373.802682 -271.60532) (xy 373.814861 -271.555906)
			(xy 373.834809 -271.509086) (xy 373.86201 -271.466072) (xy 373.895758 -271.427978) (xy 373.93518 -271.395791)
			(xy 373.979254 -271.370345) (xy 374.02684 -271.352298) (xy 374.076704 -271.342118) (xy 374.127556 -271.340069)
			(xy 374.178077 -271.346203) (xy 374.226961 -271.360363) (xy 374.27294 -271.38218) (xy 374.314824 -271.41109)
			(xy 374.351528 -271.446345) (xy 374.382101 -271.487031) (xy 374.405752 -271.532094) (xy 374.421868 -271.580368)
			(xy 374.430032 -271.630602) (xy 374.430544 -271.656048) (xy 374.430032 -271.681494) (xy 374.421868 -271.731728)
			(xy 374.405752 -271.780002) (xy 374.382101 -271.825065) (xy 374.351528 -271.865751) (xy 374.314824 -271.901006)
			(xy 374.27294 -271.929916) (xy 374.226961 -271.951733) (xy 374.178077 -271.965893) (xy 374.127556 -271.972027)
			(xy 374.076704 -271.969978) (xy 374.02684 -271.959798) (xy 373.979254 -271.941751) (xy 373.93518 -271.916305)
			(xy 373.895758 -271.884118) (xy 373.86201 -271.846024) (xy 373.834809 -271.80301) (xy 373.814861 -271.75619)
			(xy 373.802682 -271.706776) (xy 373.798587 -271.656048) (xy 373.49049 -271.656048) (xy 373.489978 -271.681494)
			(xy 373.481814 -271.731728) (xy 373.465698 -271.780002) (xy 373.442047 -271.825065) (xy 373.411474 -271.865751)
			(xy 373.37477 -271.901006) (xy 373.332886 -271.929916) (xy 373.286907 -271.951733) (xy 373.238023 -271.965893)
			(xy 373.187502 -271.972027) (xy 373.13665 -271.969978) (xy 373.086786 -271.959798) (xy 373.0392 -271.941751)
			(xy 372.995126 -271.916305) (xy 372.955704 -271.884118) (xy 372.921956 -271.846024) (xy 372.894755 -271.80301)
			(xy 372.874807 -271.75619) (xy 372.862628 -271.706776) (xy 372.858533 -271.656048) (xy 372.717568 -271.656048)
			(xy 372.717137 -271.687671) (xy 372.708878 -271.750375) (xy 372.692508 -271.811466) (xy 372.668307 -271.869898)
			(xy 372.636689 -271.924673) (xy 372.598193 -271.974855) (xy 372.553479 -272.019584) (xy 372.503312 -272.058096)
			(xy 372.448547 -272.089734) (xy 372.390123 -272.113955) (xy 372.329038 -272.130345) (xy 372.266337 -272.138626)
			(xy 372.234714 -272.139156) (xy 372.20308 -272.138662) (xy 372.140353 -272.130415) (xy 372.07924 -272.114049)
			(xy 372.020786 -272.089843) (xy 371.965994 -272.058212) (xy 371.915801 -272.019697) (xy 371.893084 -271.997678)
			(xy 371.83695 -271.941544) (xy 371.831488 -271.936426) (xy 371.818318 -271.929328) (xy 371.811042 -271.927574)
			(xy 371.810788 -271.927574) (xy 371.778264 -271.920818) (xy 371.715323 -271.899585) (xy 371.655883 -271.869931)
			(xy 371.628162 -271.851628) (xy 371.627908 -271.851628) (xy 371.621552 -271.847636) (xy 371.607214 -271.843231)
			(xy 371.599714 -271.842992) (xy 371.56263 -271.842992) (xy 371.542564 -271.852136) (xy 371.535198 -271.860772)
			(xy 371.517083 -271.881164) (xy 371.475078 -271.915952) (xy 371.427718 -271.943002) (xy 371.376414 -271.961508)
			(xy 371.322692 -271.970921) (xy 371.295422 -271.971516) (xy 371.294914 -271.971516) (xy 371.270125 -271.97096)
			(xy 371.221158 -271.963207) (xy 371.174007 -271.947888) (xy 371.129833 -271.925382) (xy 371.089724 -271.896242)
			(xy 371.054667 -271.861187) (xy 371.025525 -271.821079) (xy 371.003017 -271.776906) (xy 370.987697 -271.729755)
			(xy 370.979941 -271.680789) (xy 370.669781 -271.680789) (xy 370.662234 -271.729075) (xy 370.647235 -271.775805)
			(xy 370.625178 -271.819646) (xy 370.596596 -271.859542) (xy 370.562179 -271.894528) (xy 370.522758 -271.923761)
			(xy 370.479284 -271.946533) (xy 370.432807 -271.962297) (xy 370.408708 -271.966944) (xy 370.399984 -271.968822)
			(xy 370.384509 -271.977684) (xy 370.373013 -271.991317) (xy 370.36689 -272.008066) (xy 370.366544 -272.016982)
			(xy 370.366544 -272.491043) (xy 372.38735 -272.491043) (xy 372.38735 -272.441065) (xy 372.395169 -272.391702)
			(xy 372.410613 -272.34417) (xy 372.433303 -272.299638) (xy 372.462679 -272.259205) (xy 372.498019 -272.223865)
			(xy 372.538452 -272.194489) (xy 372.582984 -272.171799) (xy 372.630516 -272.156355) (xy 372.679879 -272.148536)
			(xy 372.729857 -272.148536) (xy 372.77922 -272.156355) (xy 372.826752 -272.171799) (xy 372.871284 -272.194489)
			(xy 372.911717 -272.223865) (xy 372.947057 -272.259205) (xy 372.976433 -272.299638) (xy 372.999123 -272.34417)
			(xy 373.014567 -272.391702) (xy 373.022386 -272.441065) (xy 373.022876 -272.466054) (xy 373.022386 -272.491043)
			(xy 373.014567 -272.540406) (xy 372.999123 -272.587938) (xy 372.976433 -272.63247) (xy 372.947057 -272.672903)
			(xy 372.911717 -272.708243) (xy 372.871284 -272.737619) (xy 372.826752 -272.760309) (xy 372.77922 -272.775753)
			(xy 372.729857 -272.783572) (xy 372.679879 -272.783572) (xy 372.630516 -272.775753) (xy 372.582984 -272.760309)
			(xy 372.538452 -272.737619) (xy 372.498019 -272.708243) (xy 372.462679 -272.672903) (xy 372.433303 -272.63247)
			(xy 372.410613 -272.587938) (xy 372.395169 -272.540406) (xy 372.38735 -272.491043) (xy 370.366544 -272.491043)
			(xy 370.366544 -272.538952) (xy 370.366042 -272.548965) (xy 370.358396 -272.567472) (xy 370.34425 -272.581645)
			(xy 370.325756 -272.589324) (xy 370.315744 -272.589752) (xy 370.195348 -272.589752) (xy 370.171726 -272.603722)
			(xy 370.164868 -272.616422) (xy 370.152856 -272.637784) (xy 370.123345 -272.676907) (xy 370.088179 -272.711037)
			(xy 370.048191 -272.739366) (xy 370.00433 -272.761222) (xy 369.957633 -272.776087) (xy 369.909209 -272.783609)
			(xy 369.884706 -272.784062) (xy 369.859713 -272.783638) (xy 369.810341 -272.775818) (xy 369.762801 -272.760371)
			(xy 369.718264 -272.737676) (xy 369.677825 -272.708293) (xy 369.642481 -272.672945) (xy 369.613103 -272.632502)
			(xy 369.590414 -272.587962) (xy 369.574972 -272.54042) (xy 369.567159 -272.491047) (xy 369.566698 -272.466054)
			(xy 367.382806 -272.466054) (xy 367.382301 -272.491044) (xy 367.374488 -272.54041) (xy 367.359049 -272.587945)
			(xy 367.336363 -272.63248) (xy 367.306989 -272.672917) (xy 367.27165 -272.708261) (xy 367.231217 -272.73764)
			(xy 367.186686 -272.760332) (xy 367.139153 -272.775778) (xy 367.089788 -272.783597) (xy 367.064798 -272.784062)
			(xy 367.040298 -272.783568) (xy 366.991878 -272.776038) (xy 366.945186 -272.761174) (xy 366.901325 -272.739325)
			(xy 366.861333 -272.71101) (xy 366.826156 -272.676897) (xy 366.796626 -272.637793) (xy 366.784636 -272.616422)
			(xy 366.779954 -272.608566) (xy 366.76618 -272.596556) (xy 366.749069 -272.590138) (xy 366.739932 -272.589752)
			(xy 366.628172 -272.589752) (xy 366.618143 -272.589402) (xy 366.599616 -272.581714) (xy 366.585443 -272.56752)
			(xy 366.577783 -272.548982) (xy 366.577372 -272.538952) (xy 366.577372 -272.018506) (xy 366.576817 -272.006684)
			(xy 366.566331 -271.985497) (xy 366.547477 -271.971237) (xy 366.53597 -271.968468) (xy 366.512011 -271.963473)
			(xy 366.46587 -271.947165) (xy 366.422774 -271.923975) (xy 366.383742 -271.894454) (xy 366.349697 -271.859298)
			(xy 366.321444 -271.819338) (xy 366.29965 -271.77552) (xy 366.284831 -271.728879) (xy 366.277336 -271.680517)
			(xy 366.27689 -271.656048) (xy 365.970566 -271.656048) (xy 365.970054 -271.681494) (xy 365.96189 -271.731728)
			(xy 365.945774 -271.780002) (xy 365.922123 -271.825065) (xy 365.89155 -271.865751) (xy 365.854846 -271.901006)
			(xy 365.812962 -271.929916) (xy 365.766983 -271.951733) (xy 365.718099 -271.965893) (xy 365.667578 -271.972027)
			(xy 365.616726 -271.969978) (xy 365.566862 -271.959798) (xy 365.519276 -271.941751) (xy 365.475202 -271.916305)
			(xy 365.43578 -271.884118) (xy 365.402032 -271.846024) (xy 365.374831 -271.80301) (xy 365.354883 -271.75619)
			(xy 365.342704 -271.706776) (xy 365.338609 -271.656048) (xy 365.030512 -271.656048) (xy 365.030063 -271.680772)
			(xy 365.022355 -271.729615) (xy 365.007121 -271.776657) (xy 364.984733 -271.820746) (xy 364.95574 -271.860801)
			(xy 364.920852 -271.895842) (xy 364.880924 -271.92501) (xy 364.836933 -271.947591) (xy 364.813596 -271.955768)
			(xy 364.803589 -271.959542) (xy 364.787702 -271.973827) (xy 364.779011 -271.993345) (xy 364.778544 -272.004028)
			(xy 364.778544 -272.538952) (xy 364.778042 -272.548965) (xy 364.770396 -272.567472) (xy 364.75625 -272.581645)
			(xy 364.737756 -272.589324) (xy 364.727744 -272.589752) (xy 364.569756 -272.589752) (xy 364.560617 -272.590126)
			(xy 364.543505 -272.596548) (xy 364.529731 -272.608562) (xy 364.525052 -272.616422) (xy 364.52048 -272.62455)
			(xy 364.513876 -272.636488) (xy 364.513876 -272.649696) (xy 364.504478 -272.649696) (xy 364.489439 -272.670077)
			(xy 364.454015 -272.706275) (xy 364.413299 -272.736398) (xy 364.368322 -272.759683) (xy 364.320221 -272.775541)
			(xy 364.270214 -272.783571) (xy 364.24489 -272.784062) (xy 364.219896 -272.783653) (xy 364.170524 -272.775831)
			(xy 364.122984 -272.760381) (xy 364.078446 -272.737684) (xy 364.038008 -272.708299) (xy 364.002664 -272.67295)
			(xy 363.973286 -272.632506) (xy 363.950597 -272.587964) (xy 363.935156 -272.540421) (xy 363.927343 -272.491048)
			(xy 363.926882 -272.466054) (xy 363.927399 -272.439764) (xy 363.936041 -272.3879) (xy 363.953083 -272.338159)
			(xy 363.978062 -272.291892) (xy 364.010299 -272.250355) (xy 364.029244 -272.23212) (xy 364.036547 -272.224628)
			(xy 364.044938 -272.205484) (xy 364.0455 -272.195036) (xy 364.0455 -272.142458) (xy 364.045046 -272.132448)
			(xy 364.037373 -272.113955) (xy 364.02321 -272.099804) (xy 364.004711 -272.092145) (xy 363.9947 -272.091658)
			(xy 363.983778 -272.091658) (xy 363.973872 -272.095976) (xy 363.94245 -272.109573) (xy 363.876736 -272.128782)
			(xy 363.808968 -272.138522) (xy 363.774736 -272.139156) (xy 363.743103 -272.138648) (xy 363.680376 -272.130404)
			(xy 363.619263 -272.114041) (xy 363.56081 -272.089837) (xy 363.506017 -272.058209) (xy 363.455824 -272.019696)
			(xy 363.433106 -271.997678) (xy 363.399578 -271.96415) (xy 363.377574 -271.941421) (xy 363.339072 -271.891223)
			(xy 363.307449 -271.836431) (xy 363.283245 -271.777981) (xy 363.266875 -271.716873) (xy 363.258618 -271.654151)
			(xy 363.2581 -271.62252) (xy 363.2581 -271.395952) (xy 363.258684 -271.364003) (xy 363.267219 -271.300676)
			(xy 363.275118 -271.269714) (xy 363.277658 -271.260316) (xy 363.275372 -271.241012) (xy 363.232446 -271.161764)
			(xy 363.21746 -271.149572) (xy 363.208062 -271.146524) (xy 363.184562 -271.13844) (xy 363.140252 -271.115938)
			(xy 363.100013 -271.086776) (xy 363.064838 -271.051671) (xy 363.035594 -271.011491) (xy 363.013004 -270.967227)
			(xy 362.997624 -270.919971) (xy 362.989835 -270.87089) (xy 362.989368 -270.846042) (xy 362.680504 -270.846042)
			(xy 362.679992 -270.871488) (xy 362.671828 -270.921722) (xy 362.655712 -270.969996) (xy 362.632061 -271.015059)
			(xy 362.601488 -271.055745) (xy 362.564784 -271.091) (xy 362.5229 -271.11991) (xy 362.476921 -271.141727)
			(xy 362.428037 -271.155887) (xy 362.377516 -271.162021) (xy 362.326664 -271.159972) (xy 362.2768 -271.149792)
			(xy 362.229214 -271.131745) (xy 362.18514 -271.106299) (xy 362.145718 -271.074112) (xy 362.11197 -271.036018)
			(xy 362.084769 -270.993004) (xy 362.064821 -270.946184) (xy 362.052642 -270.89677) (xy 362.048547 -270.846042)
			(xy 361.742736 -270.846042) (xy 361.742246 -270.871031) (xy 361.734427 -270.920394) (xy 361.718983 -270.967926)
			(xy 361.696293 -271.012458) (xy 361.666917 -271.052891) (xy 361.631577 -271.088231) (xy 361.591144 -271.117607)
			(xy 361.546612 -271.140297) (xy 361.49908 -271.155741) (xy 361.449717 -271.16356) (xy 361.399739 -271.16356)
			(xy 361.350376 -271.155741) (xy 361.302844 -271.140297) (xy 361.258312 -271.117607) (xy 361.217879 -271.088231)
			(xy 361.182539 -271.052891) (xy 361.153163 -271.012458) (xy 361.130473 -270.967926) (xy 361.115029 -270.920394)
			(xy 361.10721 -270.871031) (xy 358.928688 -270.871031) (xy 358.920869 -270.920394) (xy 358.905425 -270.967926)
			(xy 358.882735 -271.012458) (xy 358.853359 -271.052891) (xy 358.818019 -271.088231) (xy 358.777586 -271.117607)
			(xy 358.733054 -271.140297) (xy 358.685522 -271.155741) (xy 358.636159 -271.16356) (xy 358.586181 -271.16356)
			(xy 358.536818 -271.155741) (xy 358.489286 -271.140297) (xy 358.444754 -271.117607) (xy 358.404321 -271.088231)
			(xy 358.368981 -271.052891) (xy 358.339605 -271.012458) (xy 358.316915 -270.967926) (xy 358.301471 -270.920394)
			(xy 358.293652 -270.871031) (xy 357.986335 -270.871031) (xy 357.986326 -270.871488) (xy 357.978162 -270.921722)
			(xy 357.962046 -270.969996) (xy 357.938395 -271.015059) (xy 357.907822 -271.055745) (xy 357.871118 -271.091)
			(xy 357.829234 -271.11991) (xy 357.783255 -271.141727) (xy 357.734371 -271.155887) (xy 357.68385 -271.162021)
			(xy 357.632998 -271.159972) (xy 357.583134 -271.149792) (xy 357.535548 -271.131745) (xy 357.491474 -271.106299)
			(xy 357.452052 -271.074112) (xy 357.418304 -271.036018) (xy 357.391103 -270.993004) (xy 357.371155 -270.946184)
			(xy 357.358976 -270.89677) (xy 357.354881 -270.846042) (xy 357.046784 -270.846042) (xy 357.04623 -270.871592)
			(xy 357.038002 -270.922025) (xy 357.021752 -270.970471) (xy 356.997905 -271.015665) (xy 356.967085 -271.056424)
			(xy 356.930098 -271.091681) (xy 356.887911 -271.120516) (xy 356.841627 -271.142172) (xy 356.792458 -271.156085)
			(xy 356.76713 -271.159478) (xy 356.758373 -271.160882) (xy 356.742525 -271.168815) (xy 356.736142 -271.174972)
			(xy 356.715314 -271.19707) (xy 356.70897 -271.204417) (xy 356.701779 -271.222426) (xy 356.701344 -271.232122)
			(xy 356.701344 -271.674336) (xy 356.700646 -271.686597) (xy 356.689379 -271.708368) (xy 356.679754 -271.715992)
			(xy 356.676452 -271.718278) (xy 356.67061 -271.73428) (xy 356.660714 -271.760521) (xy 356.634298 -271.809991)
			(xy 356.600917 -271.855056) (xy 356.581456 -271.87525) (xy 356.53091 -271.925796) (xy 356.509326 -271.946612)
			(xy 356.460821 -271.981865) (xy 356.407396 -272.009092) (xy 356.350368 -272.027623) (xy 356.291143 -272.037001)
			(xy 356.261162 -272.037556) (xy 356.230445 -272.036915) (xy 356.169819 -272.026965) (xy 356.140512 -272.017744)
			(xy 356.140258 -272.017744) (xy 356.128253 -272.014625) (xy 356.103834 -272.018728) (xy 356.093522 -272.025618)
			(xy 356.02672 -272.076926) (xy 356.01713 -272.085096) (xy 356.006741 -272.108016) (xy 356.006908 -272.120614)
			(xy 356.007416 -272.135092) (xy 356.007416 -272.2118) (xy 356.00786 -272.221438) (xy 356.015041 -272.239329)
			(xy 356.021386 -272.246598) (xy 356.037737 -272.264472) (xy 356.065399 -272.304238) (xy 356.086725 -272.347732)
			(xy 356.101224 -272.393952) (xy 356.108561 -272.441834) (xy 356.109016 -272.466054) (xy 356.414827 -272.466054)
			(xy 356.418922 -272.415326) (xy 356.431101 -272.365912) (xy 356.451049 -272.319092) (xy 356.47825 -272.276078)
			(xy 356.511998 -272.237984) (xy 356.55142 -272.205797) (xy 356.595494 -272.180351) (xy 356.64308 -272.162304)
			(xy 356.692944 -272.152124) (xy 356.743796 -272.150075) (xy 356.794317 -272.156209) (xy 356.843201 -272.170369)
			(xy 356.88918 -272.192186) (xy 356.931064 -272.221096) (xy 356.967768 -272.256351) (xy 356.998341 -272.297037)
			(xy 357.021992 -272.3421) (xy 357.038108 -272.390374) (xy 357.046272 -272.440608) (xy 357.046784 -272.466054)
			(xy 357.354881 -272.466054) (xy 357.358976 -272.415326) (xy 357.371155 -272.365912) (xy 357.391103 -272.319092)
			(xy 357.418304 -272.276078) (xy 357.452052 -272.237984) (xy 357.491474 -272.205797) (xy 357.535548 -272.180351)
			(xy 357.583134 -272.162304) (xy 357.632998 -272.152124) (xy 357.68385 -272.150075) (xy 357.734371 -272.156209)
			(xy 357.783255 -272.170369) (xy 357.829234 -272.192186) (xy 357.871118 -272.221096) (xy 357.907822 -272.256351)
			(xy 357.938395 -272.297037) (xy 357.962046 -272.3421) (xy 357.978162 -272.390374) (xy 357.986326 -272.440608)
			(xy 357.986838 -272.466054) (xy 357.986335 -272.491043) (xy 358.293652 -272.491043) (xy 358.293652 -272.441065)
			(xy 358.301471 -272.391702) (xy 358.316915 -272.34417) (xy 358.339605 -272.299638) (xy 358.368981 -272.259205)
			(xy 358.404321 -272.223865) (xy 358.444754 -272.194489) (xy 358.489286 -272.171799) (xy 358.536818 -272.156355)
			(xy 358.586181 -272.148536) (xy 358.636159 -272.148536) (xy 358.685522 -272.156355) (xy 358.733054 -272.171799)
			(xy 358.777586 -272.194489) (xy 358.818019 -272.223865) (xy 358.853359 -272.259205) (xy 358.882735 -272.299638)
			(xy 358.905425 -272.34417) (xy 358.920869 -272.391702) (xy 358.928688 -272.441065) (xy 358.929178 -272.466054)
			(xy 358.928688 -272.491043) (xy 361.10721 -272.491043) (xy 361.10721 -272.441065) (xy 361.115029 -272.391702)
			(xy 361.130473 -272.34417) (xy 361.153163 -272.299638) (xy 361.182539 -272.259205) (xy 361.217879 -272.223865)
			(xy 361.258312 -272.194489) (xy 361.302844 -272.171799) (xy 361.350376 -272.156355) (xy 361.399739 -272.148536)
			(xy 361.449717 -272.148536) (xy 361.49908 -272.156355) (xy 361.546612 -272.171799) (xy 361.591144 -272.194489)
			(xy 361.631577 -272.223865) (xy 361.666917 -272.259205) (xy 361.696293 -272.299638) (xy 361.718983 -272.34417)
			(xy 361.734427 -272.391702) (xy 361.742246 -272.441065) (xy 361.742736 -272.466054) (xy 362.048547 -272.466054)
			(xy 362.052642 -272.415326) (xy 362.064821 -272.365912) (xy 362.084769 -272.319092) (xy 362.11197 -272.276078)
			(xy 362.145718 -272.237984) (xy 362.18514 -272.205797) (xy 362.229214 -272.180351) (xy 362.2768 -272.162304)
			(xy 362.326664 -272.152124) (xy 362.377516 -272.150075) (xy 362.428037 -272.156209) (xy 362.476921 -272.170369)
			(xy 362.5229 -272.192186) (xy 362.564784 -272.221096) (xy 362.601488 -272.256351) (xy 362.632061 -272.297037)
			(xy 362.655712 -272.3421) (xy 362.671828 -272.390374) (xy 362.679992 -272.440608) (xy 362.680504 -272.466054)
			(xy 362.988601 -272.466054) (xy 362.992696 -272.415326) (xy 363.004875 -272.365912) (xy 363.024823 -272.319092)
			(xy 363.052024 -272.276078) (xy 363.085772 -272.237984) (xy 363.125194 -272.205797) (xy 363.169268 -272.180351)
			(xy 363.216854 -272.162304) (xy 363.266718 -272.152124) (xy 363.31757 -272.150075) (xy 363.368091 -272.156209)
			(xy 363.416975 -272.170369) (xy 363.462954 -272.192186) (xy 363.504838 -272.221096) (xy 363.541542 -272.256351)
			(xy 363.572115 -272.297037) (xy 363.595766 -272.3421) (xy 363.611882 -272.390374) (xy 363.620046 -272.440608)
			(xy 363.620558 -272.466054) (xy 363.620046 -272.4915) (xy 363.611882 -272.541734) (xy 363.595766 -272.590008)
			(xy 363.572115 -272.635071) (xy 363.541542 -272.675757) (xy 363.504838 -272.711012) (xy 363.462954 -272.739922)
			(xy 363.416975 -272.761739) (xy 363.368091 -272.775899) (xy 363.31757 -272.782033) (xy 363.266718 -272.779984)
			(xy 363.216854 -272.769804) (xy 363.169268 -272.751757) (xy 363.125194 -272.726311) (xy 363.085772 -272.694124)
			(xy 363.052024 -272.65603) (xy 363.024823 -272.613016) (xy 363.004875 -272.566196) (xy 362.992696 -272.516782)
			(xy 362.988601 -272.466054) (xy 362.680504 -272.466054) (xy 362.679992 -272.4915) (xy 362.671828 -272.541734)
			(xy 362.655712 -272.590008) (xy 362.632061 -272.635071) (xy 362.601488 -272.675757) (xy 362.564784 -272.711012)
			(xy 362.5229 -272.739922) (xy 362.476921 -272.761739) (xy 362.428037 -272.775899) (xy 362.377516 -272.782033)
			(xy 362.326664 -272.779984) (xy 362.2768 -272.769804) (xy 362.229214 -272.751757) (xy 362.18514 -272.726311)
			(xy 362.145718 -272.694124) (xy 362.11197 -272.65603) (xy 362.084769 -272.613016) (xy 362.064821 -272.566196)
			(xy 362.052642 -272.516782) (xy 362.048547 -272.466054) (xy 361.742736 -272.466054) (xy 361.742246 -272.491043)
			(xy 361.734427 -272.540406) (xy 361.718983 -272.587938) (xy 361.696293 -272.63247) (xy 361.666917 -272.672903)
			(xy 361.631577 -272.708243) (xy 361.591144 -272.737619) (xy 361.546612 -272.760309) (xy 361.49908 -272.775753)
			(xy 361.449717 -272.783572) (xy 361.399739 -272.783572) (xy 361.350376 -272.775753) (xy 361.302844 -272.760309)
			(xy 361.258312 -272.737619) (xy 361.217879 -272.708243) (xy 361.182539 -272.672903) (xy 361.153163 -272.63247)
			(xy 361.130473 -272.587938) (xy 361.115029 -272.540406) (xy 361.10721 -272.491043) (xy 358.928688 -272.491043)
			(xy 358.920869 -272.540406) (xy 358.905425 -272.587938) (xy 358.882735 -272.63247) (xy 358.853359 -272.672903)
			(xy 358.818019 -272.708243) (xy 358.777586 -272.737619) (xy 358.733054 -272.760309) (xy 358.685522 -272.775753)
			(xy 358.636159 -272.783572) (xy 358.586181 -272.783572) (xy 358.536818 -272.775753) (xy 358.489286 -272.760309)
			(xy 358.444754 -272.737619) (xy 358.404321 -272.708243) (xy 358.368981 -272.672903) (xy 358.339605 -272.63247)
			(xy 358.316915 -272.587938) (xy 358.301471 -272.540406) (xy 358.293652 -272.491043) (xy 357.986335 -272.491043)
			(xy 357.986326 -272.4915) (xy 357.978162 -272.541734) (xy 357.962046 -272.590008) (xy 357.938395 -272.635071)
			(xy 357.907822 -272.675757) (xy 357.871118 -272.711012) (xy 357.829234 -272.739922) (xy 357.783255 -272.761739)
			(xy 357.734371 -272.775899) (xy 357.68385 -272.782033) (xy 357.632998 -272.779984) (xy 357.583134 -272.769804)
			(xy 357.535548 -272.751757) (xy 357.491474 -272.726311) (xy 357.452052 -272.694124) (xy 357.418304 -272.65603)
			(xy 357.391103 -272.613016) (xy 357.371155 -272.566196) (xy 357.358976 -272.516782) (xy 357.354881 -272.466054)
			(xy 357.046784 -272.466054) (xy 357.046272 -272.4915) (xy 357.038108 -272.541734) (xy 357.021992 -272.590008)
			(xy 356.998341 -272.635071) (xy 356.967768 -272.675757) (xy 356.931064 -272.711012) (xy 356.88918 -272.739922)
			(xy 356.843201 -272.761739) (xy 356.794317 -272.775899) (xy 356.743796 -272.782033) (xy 356.692944 -272.779984)
			(xy 356.64308 -272.769804) (xy 356.595494 -272.751757) (xy 356.55142 -272.726311) (xy 356.511998 -272.694124)
			(xy 356.47825 -272.65603) (xy 356.451049 -272.613016) (xy 356.431101 -272.566196) (xy 356.418922 -272.516782)
			(xy 356.414827 -272.466054) (xy 356.109016 -272.466054) (xy 356.108501 -272.491044) (xy 356.100689 -272.540408)
			(xy 356.08525 -272.587943) (xy 356.062565 -272.632477) (xy 356.033192 -272.672914) (xy 355.997855 -272.708257)
			(xy 355.957423 -272.737637) (xy 355.912893 -272.76033) (xy 355.865361 -272.775776) (xy 355.815997 -272.783596)
			(xy 355.791008 -272.784062) (xy 355.766508 -272.78356) (xy 355.718089 -272.776032) (xy 355.671397 -272.761169)
			(xy 355.627536 -272.739321) (xy 355.587544 -272.711007) (xy 355.552367 -272.676895) (xy 355.522836 -272.637793)
			(xy 355.510846 -272.616422) (xy 355.506158 -272.60857) (xy 355.492386 -272.59656) (xy 355.475278 -272.590139)
			(xy 355.466142 -272.589752) (xy 355.325172 -272.589752) (xy 355.315143 -272.589402) (xy 355.296616 -272.581714)
			(xy 355.282443 -272.56752) (xy 355.274783 -272.548982) (xy 355.274372 -272.538952) (xy 355.274372 -271.99209)
			(xy 355.253544 -271.964912) (xy 355.237034 -271.96034) (xy 355.212421 -271.953005) (xy 355.16581 -271.931446)
			(xy 355.1233 -271.902631) (xy 355.086012 -271.867318) (xy 355.054928 -271.826438) (xy 355.030867 -271.781068)
			(xy 355.014462 -271.732403) (xy 355.006146 -271.681726) (xy 355.00564 -271.656048) (xy 354.696776 -271.656048)
			(xy 354.696264 -271.681494) (xy 354.6881 -271.731728) (xy 354.671984 -271.780002) (xy 354.648333 -271.825065)
			(xy 354.61776 -271.865751) (xy 354.581056 -271.901006) (xy 354.539172 -271.929916) (xy 354.493193 -271.951733)
			(xy 354.444309 -271.965893) (xy 354.393788 -271.972027) (xy 354.342936 -271.969978) (xy 354.293072 -271.959798)
			(xy 354.245486 -271.941751) (xy 354.201412 -271.916305) (xy 354.16199 -271.884118) (xy 354.128242 -271.846024)
			(xy 354.101041 -271.80301) (xy 354.081093 -271.75619) (xy 354.068914 -271.706776) (xy 354.064819 -271.656048)
			(xy 353.759008 -271.656048) (xy 353.758437 -271.682639) (xy 353.749598 -271.735081) (xy 353.732157 -271.785322)
			(xy 353.7066 -271.831961) (xy 353.673641 -271.873698) (xy 353.634197 -271.90937) (xy 353.589368 -271.937982)
			(xy 353.540403 -271.958738) (xy 353.51466 -271.96542) (xy 353.514406 -271.96542) (xy 353.503482 -271.968659)
			(xy 353.485811 -271.982993) (xy 353.476095 -272.003569) (xy 353.475544 -272.01495) (xy 353.475544 -272.538952)
			(xy 353.475042 -272.548965) (xy 353.467396 -272.567472) (xy 353.45325 -272.581645) (xy 353.434756 -272.589324)
			(xy 353.424744 -272.589752) (xy 353.281742 -272.589752) (xy 353.25812 -272.603722) (xy 353.251262 -272.616422)
			(xy 353.239255 -272.637787) (xy 353.209743 -272.67691) (xy 353.174576 -272.71104) (xy 353.134587 -272.739368)
			(xy 353.090725 -272.761223) (xy 353.044028 -272.776088) (xy 352.995603 -272.783609) (xy 352.9711 -272.784062)
			(xy 352.946106 -272.783643) (xy 352.896735 -272.775823) (xy 352.849195 -272.760375) (xy 352.804657 -272.737679)
			(xy 352.764218 -272.708295) (xy 352.728875 -272.672946) (xy 352.699497 -272.632504) (xy 352.676808 -272.587963)
			(xy 352.661366 -272.54042) (xy 352.653553 -272.491048) (xy 352.653092 -272.466054) (xy 350.4692 -272.466054)
			(xy 350.468701 -272.491044) (xy 350.460888 -272.540411) (xy 350.445449 -272.587947) (xy 350.422762 -272.632482)
			(xy 350.393387 -272.672919) (xy 350.358048 -272.708263) (xy 350.317614 -272.737642) (xy 350.273082 -272.760334)
			(xy 350.225548 -272.775779) (xy 350.176182 -272.783598) (xy 350.151192 -272.784062) (xy 350.126691 -272.783573)
			(xy 350.078272 -272.776042) (xy 350.031579 -272.761177) (xy 349.987719 -272.739328) (xy 349.947727 -272.711011)
			(xy 349.91255 -272.676897) (xy 349.88302 -272.637793) (xy 349.87103 -272.616422) (xy 349.866352 -272.608563)
			(xy 349.852576 -272.596554) (xy 349.835464 -272.590137) (xy 349.826326 -272.589752) (xy 349.737172 -272.589752)
			(xy 349.727143 -272.589402) (xy 349.708616 -272.581714) (xy 349.694443 -272.56752) (xy 349.686783 -272.548982)
			(xy 349.686372 -272.538952) (xy 349.686372 -272.019776) (xy 349.685995 -272.010552) (xy 349.679498 -271.993287)
			(xy 349.667316 -271.979435) (xy 349.651022 -271.970786) (xy 349.641922 -271.96923) (xy 349.641668 -271.96923)
			(xy 349.616556 -271.965579) (xy 349.567864 -271.951296) (xy 349.522086 -271.929405) (xy 349.4804 -271.900472)
			(xy 349.443882 -271.865241) (xy 349.413471 -271.82462) (xy 349.389951 -271.779657) (xy 349.373929 -271.73151)
			(xy 349.365818 -271.68142) (xy 349.365316 -271.656048) (xy 349.05623 -271.656048) (xy 349.05623 -271.680791)
			(xy 349.048474 -271.729764) (xy 349.033153 -271.776921) (xy 349.010645 -271.8211) (xy 348.981502 -271.861215)
			(xy 348.946444 -271.896278) (xy 348.906333 -271.925425) (xy 348.862156 -271.947939) (xy 348.815001 -271.963265)
			(xy 348.766029 -271.971027) (xy 348.741238 -271.971516) (xy 348.717834 -271.971101) (xy 348.67154 -271.96419)
			(xy 348.626775 -271.950512) (xy 348.584523 -271.93037) (xy 348.545712 -271.904205) (xy 348.511193 -271.872591)
			(xy 348.496128 -271.854676) (xy 348.488762 -271.845786) (xy 348.468188 -271.83588) (xy 348.445582 -271.83588)
			(xy 348.43665 -271.836219) (xy 348.419865 -271.842324) (xy 348.412816 -271.847818) (xy 348.405704 -271.85366)
			(xy 348.405704 -271.868392) (xy 348.386908 -271.868392) (xy 348.383606 -271.870424) (xy 348.354021 -271.890971)
			(xy 348.29002 -271.924012) (xy 348.221824 -271.94719) (xy 348.186502 -271.954244) (xy 348.185994 -271.954244)
			(xy 348.142814 -271.997678) (xy 348.120049 -272.019644) (xy 348.06986 -272.058151) (xy 348.015076 -272.08978)
			(xy 347.956633 -272.113991) (xy 347.89553 -272.130369) (xy 347.832814 -272.138634) (xy 347.801184 -272.139156)
			(xy 347.769555 -272.138606) (xy 347.706838 -272.130348) (xy 347.645736 -272.113975) (xy 347.587293 -272.089767)
			(xy 347.532509 -272.058138) (xy 347.482322 -272.01963) (xy 347.437591 -271.974902) (xy 347.399079 -271.924717)
			(xy 347.367447 -271.869936) (xy 347.343235 -271.811495) (xy 347.326858 -271.750393) (xy 347.318596 -271.687677)
			(xy 347.318076 -271.656048) (xy 347.176852 -271.656048) (xy 347.17634 -271.681494) (xy 347.168176 -271.731728)
			(xy 347.15206 -271.780002) (xy 347.128409 -271.825065) (xy 347.097836 -271.865751) (xy 347.061132 -271.901006)
			(xy 347.019248 -271.929916) (xy 346.973269 -271.951733) (xy 346.924385 -271.965893) (xy 346.873864 -271.972027)
			(xy 346.823012 -271.969978) (xy 346.773148 -271.959798) (xy 346.725562 -271.941751) (xy 346.681488 -271.916305)
			(xy 346.642066 -271.884118) (xy 346.608318 -271.846024) (xy 346.581117 -271.80301) (xy 346.561169 -271.75619)
			(xy 346.54899 -271.706776) (xy 346.544895 -271.656048) (xy 346.236798 -271.656048) (xy 346.236286 -271.681494)
			(xy 346.228122 -271.731728) (xy 346.212006 -271.780002) (xy 346.188355 -271.825065) (xy 346.157782 -271.865751)
			(xy 346.121078 -271.901006) (xy 346.079194 -271.929916) (xy 346.033215 -271.951733) (xy 345.984331 -271.965893)
			(xy 345.93381 -271.972027) (xy 345.882958 -271.969978) (xy 345.833094 -271.959798) (xy 345.785508 -271.941751)
			(xy 345.741434 -271.916305) (xy 345.702012 -271.884118) (xy 345.668264 -271.846024) (xy 345.641063 -271.80301)
			(xy 345.621115 -271.75619) (xy 345.608936 -271.706776) (xy 345.604841 -271.656048) (xy 345.298912 -271.656048)
			(xy 345.297317 -271.693991) (xy 345.28771 -271.742225) (xy 345.270789 -271.788403) (xy 345.246958 -271.831424)
			(xy 345.232228 -271.85112) (xy 345.214389 -271.873092) (xy 345.172316 -271.910936) (xy 345.1242 -271.940721)
			(xy 345.098116 -271.951704) (xy 345.097862 -271.951704) (xy 345.095068 -271.95272) (xy 345.086739 -271.957102)
			(xy 345.073736 -271.970684) (xy 345.066495 -271.988036) (xy 345.065858 -271.997424) (xy 345.065858 -272.491043)
			(xy 347.013512 -272.491043) (xy 347.013512 -272.441065) (xy 347.021331 -272.391702) (xy 347.036775 -272.34417)
			(xy 347.059465 -272.299638) (xy 347.088841 -272.259205) (xy 347.124181 -272.223865) (xy 347.164614 -272.194489)
			(xy 347.209146 -272.171799) (xy 347.256678 -272.156355) (xy 347.306041 -272.148536) (xy 347.356019 -272.148536)
			(xy 347.405382 -272.156355) (xy 347.452914 -272.171799) (xy 347.497446 -272.194489) (xy 347.537879 -272.223865)
			(xy 347.573219 -272.259205) (xy 347.602595 -272.299638) (xy 347.625285 -272.34417) (xy 347.640729 -272.391702)
			(xy 347.648548 -272.441065) (xy 347.649038 -272.466054) (xy 347.648548 -272.491043) (xy 347.640729 -272.540406)
			(xy 347.625285 -272.587938) (xy 347.602595 -272.63247) (xy 347.573219 -272.672903) (xy 347.537879 -272.708243)
			(xy 347.497446 -272.737619) (xy 347.452914 -272.760309) (xy 347.405382 -272.775753) (xy 347.356019 -272.783572)
			(xy 347.306041 -272.783572) (xy 347.256678 -272.775753) (xy 347.209146 -272.760309) (xy 347.164614 -272.737619)
			(xy 347.124181 -272.708243) (xy 347.088841 -272.672903) (xy 347.059465 -272.63247) (xy 347.036775 -272.587938)
			(xy 347.021331 -272.540406) (xy 347.013512 -272.491043) (xy 345.065858 -272.491043) (xy 345.065858 -272.933414)
			(xy 345.065858 -272.934684) (xy 345.066526 -272.944068) (xy 345.07375 -272.961419) (xy 345.086748 -272.974994)
			(xy 345.095068 -272.979388) (xy 345.097862 -272.980404) (xy 345.120567 -272.989856) (xy 345.162989 -273.014735)
			(xy 345.201074 -273.045851) (xy 345.233911 -273.082462) (xy 345.260719 -273.123693) (xy 345.280857 -273.16856)
			(xy 345.293844 -273.215994) (xy 345.299371 -273.264862) (xy 345.2989 -273.27606) (xy 345.604841 -273.27606)
			(xy 345.608936 -273.225332) (xy 345.621115 -273.175918) (xy 345.641063 -273.129098) (xy 345.668264 -273.086084)
			(xy 345.702012 -273.04799) (xy 345.741434 -273.015803) (xy 345.785508 -272.990357) (xy 345.833094 -272.97231)
			(xy 345.882958 -272.96213) (xy 345.93381 -272.960081) (xy 345.984331 -272.966215) (xy 346.033215 -272.980375)
			(xy 346.079194 -273.002192) (xy 346.121078 -273.031102) (xy 346.157782 -273.066357) (xy 346.188355 -273.107043)
			(xy 346.212006 -273.152106) (xy 346.228122 -273.20038) (xy 346.236286 -273.250614) (xy 346.236798 -273.27606)
			(xy 346.544895 -273.27606) (xy 346.54899 -273.225332) (xy 346.561169 -273.175918) (xy 346.581117 -273.129098)
			(xy 346.608318 -273.086084) (xy 346.642066 -273.04799) (xy 346.681488 -273.015803) (xy 346.725562 -272.990357)
			(xy 346.773148 -272.97231) (xy 346.823012 -272.96213) (xy 346.873864 -272.960081) (xy 346.924385 -272.966215)
			(xy 346.973269 -272.980375) (xy 347.019248 -273.002192) (xy 347.061132 -273.031102) (xy 347.097836 -273.066357)
			(xy 347.128409 -273.107043) (xy 347.15206 -273.152106) (xy 347.168176 -273.20038) (xy 347.17634 -273.250614)
			(xy 347.176852 -273.27606) (xy 347.176349 -273.301049) (xy 347.483666 -273.301049) (xy 347.483666 -273.251071)
			(xy 347.491485 -273.201708) (xy 347.506929 -273.154176) (xy 347.529619 -273.109644) (xy 347.558995 -273.069211)
			(xy 347.594335 -273.033871) (xy 347.634768 -273.004495) (xy 347.6793 -272.981805) (xy 347.726832 -272.966361)
			(xy 347.776195 -272.958542) (xy 347.826173 -272.958542) (xy 347.875536 -272.966361) (xy 347.923068 -272.981805)
			(xy 347.9676 -273.004495) (xy 348.008033 -273.033871) (xy 348.043373 -273.069211) (xy 348.072749 -273.109644)
			(xy 348.095439 -273.154176) (xy 348.110883 -273.201708) (xy 348.118702 -273.251071) (xy 348.119192 -273.27606)
			(xy 348.425003 -273.27606) (xy 348.429098 -273.225332) (xy 348.441277 -273.175918) (xy 348.461225 -273.129098)
			(xy 348.488426 -273.086084) (xy 348.522174 -273.04799) (xy 348.561596 -273.015803) (xy 348.60567 -272.990357)
			(xy 348.653256 -272.97231) (xy 348.70312 -272.96213) (xy 348.753972 -272.960081) (xy 348.804493 -272.966215)
			(xy 348.853377 -272.980375) (xy 348.899356 -273.002192) (xy 348.94124 -273.031102) (xy 348.977944 -273.066357)
			(xy 349.008517 -273.107043) (xy 349.032168 -273.152106) (xy 349.048284 -273.20038) (xy 349.056448 -273.250614)
			(xy 349.05696 -273.27606) (xy 349.364803 -273.27606) (xy 349.368898 -273.225332) (xy 349.381077 -273.175918)
			(xy 349.401025 -273.129098) (xy 349.428226 -273.086084) (xy 349.461974 -273.04799) (xy 349.501396 -273.015803)
			(xy 349.54547 -272.990357) (xy 349.593056 -272.97231) (xy 349.64292 -272.96213) (xy 349.693772 -272.960081)
			(xy 349.744293 -272.966215) (xy 349.793177 -272.980375) (xy 349.839156 -273.002192) (xy 349.88104 -273.031102)
			(xy 349.917744 -273.066357) (xy 349.948317 -273.107043) (xy 349.971968 -273.152106) (xy 349.988084 -273.20038)
			(xy 349.996248 -273.250614) (xy 349.99676 -273.27606) (xy 349.996257 -273.301049) (xy 350.303574 -273.301049)
			(xy 350.303574 -273.251071) (xy 350.311393 -273.201708) (xy 350.326837 -273.154176) (xy 350.349527 -273.109644)
			(xy 350.378903 -273.069211) (xy 350.414243 -273.033871) (xy 350.454676 -273.004495) (xy 350.499208 -272.981805)
			(xy 350.54674 -272.966361) (xy 350.596103 -272.958542) (xy 350.646081 -272.958542) (xy 350.695444 -272.966361)
			(xy 350.742976 -272.981805) (xy 350.787508 -273.004495) (xy 350.827941 -273.033871) (xy 350.863281 -273.069211)
			(xy 350.892657 -273.109644) (xy 350.915347 -273.154176) (xy 350.930791 -273.201708) (xy 350.93861 -273.251071)
			(xy 350.9391 -273.27606) (xy 351.244911 -273.27606) (xy 351.249006 -273.225332) (xy 351.261185 -273.175918)
			(xy 351.281133 -273.129098) (xy 351.308334 -273.086084) (xy 351.342082 -273.04799) (xy 351.381504 -273.015803)
			(xy 351.425578 -272.990357) (xy 351.473164 -272.97231) (xy 351.523028 -272.96213) (xy 351.57388 -272.960081)
			(xy 351.624401 -272.966215) (xy 351.673285 -272.980375) (xy 351.719264 -273.002192) (xy 351.761148 -273.031102)
			(xy 351.797852 -273.066357) (xy 351.828425 -273.107043) (xy 351.852076 -273.152106) (xy 351.868192 -273.20038)
			(xy 351.876356 -273.250614) (xy 351.876868 -273.27606) (xy 352.184965 -273.27606) (xy 352.18906 -273.225332)
			(xy 352.201239 -273.175918) (xy 352.221187 -273.129098) (xy 352.248388 -273.086084) (xy 352.282136 -273.04799)
			(xy 352.321558 -273.015803) (xy 352.365632 -272.990357) (xy 352.413218 -272.97231) (xy 352.463082 -272.96213)
			(xy 352.513934 -272.960081) (xy 352.564455 -272.966215) (xy 352.613339 -272.980375) (xy 352.659318 -273.002192)
			(xy 352.701202 -273.031102) (xy 352.737906 -273.066357) (xy 352.768479 -273.107043) (xy 352.79213 -273.152106)
			(xy 352.808246 -273.20038) (xy 352.81641 -273.250614) (xy 352.816922 -273.27606) (xy 352.816419 -273.301049)
			(xy 353.123482 -273.301049) (xy 353.123482 -273.251071) (xy 353.131301 -273.201708) (xy 353.146745 -273.154176)
			(xy 353.169435 -273.109644) (xy 353.198811 -273.069211) (xy 353.234151 -273.033871) (xy 353.274584 -273.004495)
			(xy 353.319116 -272.981805) (xy 353.366648 -272.966361) (xy 353.416011 -272.958542) (xy 353.465989 -272.958542)
			(xy 353.515352 -272.966361) (xy 353.562884 -272.981805) (xy 353.607416 -273.004495) (xy 353.647849 -273.033871)
			(xy 353.683189 -273.069211) (xy 353.712565 -273.109644) (xy 353.735255 -273.154176) (xy 353.750699 -273.201708)
			(xy 353.758518 -273.251071) (xy 353.759008 -273.27606) (xy 354.064819 -273.27606) (xy 354.068914 -273.225332)
			(xy 354.081093 -273.175918) (xy 354.101041 -273.129098) (xy 354.128242 -273.086084) (xy 354.16199 -273.04799)
			(xy 354.201412 -273.015803) (xy 354.245486 -272.990357) (xy 354.293072 -272.97231) (xy 354.342936 -272.96213)
			(xy 354.393788 -272.960081) (xy 354.444309 -272.966215) (xy 354.493193 -272.980375) (xy 354.539172 -273.002192)
			(xy 354.581056 -273.031102) (xy 354.61776 -273.066357) (xy 354.648333 -273.107043) (xy 354.671984 -273.152106)
			(xy 354.6881 -273.20038) (xy 354.696264 -273.250614) (xy 354.696776 -273.27606) (xy 355.004873 -273.27606)
			(xy 355.008968 -273.225332) (xy 355.021147 -273.175918) (xy 355.041095 -273.129098) (xy 355.068296 -273.086084)
			(xy 355.102044 -273.04799) (xy 355.141466 -273.015803) (xy 355.18554 -272.990357) (xy 355.233126 -272.97231)
			(xy 355.28299 -272.96213) (xy 355.333842 -272.960081) (xy 355.384363 -272.966215) (xy 355.433247 -272.980375)
			(xy 355.479226 -273.002192) (xy 355.52111 -273.031102) (xy 355.557814 -273.066357) (xy 355.588387 -273.107043)
			(xy 355.612038 -273.152106) (xy 355.628154 -273.20038) (xy 355.636318 -273.250614) (xy 355.63683 -273.27606)
			(xy 355.636327 -273.301049) (xy 355.943644 -273.301049) (xy 355.943644 -273.251071) (xy 355.951463 -273.201708)
			(xy 355.966907 -273.154176) (xy 355.989597 -273.109644) (xy 356.018973 -273.069211) (xy 356.054313 -273.033871)
			(xy 356.094746 -273.004495) (xy 356.139278 -272.981805) (xy 356.18681 -272.966361) (xy 356.236173 -272.958542)
			(xy 356.286151 -272.958542) (xy 356.335514 -272.966361) (xy 356.383046 -272.981805) (xy 356.427578 -273.004495)
			(xy 356.468011 -273.033871) (xy 356.503351 -273.069211) (xy 356.532727 -273.109644) (xy 356.555417 -273.154176)
			(xy 356.570861 -273.201708) (xy 356.57868 -273.251071) (xy 356.57917 -273.27606) (xy 356.57868 -273.301049)
			(xy 356.883698 -273.301049) (xy 356.883698 -273.251071) (xy 356.891517 -273.201708) (xy 356.906961 -273.154176)
			(xy 356.929651 -273.109644) (xy 356.959027 -273.069211) (xy 356.994367 -273.033871) (xy 357.0348 -273.004495)
			(xy 357.079332 -272.981805) (xy 357.126864 -272.966361) (xy 357.176227 -272.958542) (xy 357.226205 -272.958542)
			(xy 357.275568 -272.966361) (xy 357.3231 -272.981805) (xy 357.367632 -273.004495) (xy 357.408065 -273.033871)
			(xy 357.443405 -273.069211) (xy 357.472781 -273.109644) (xy 357.495471 -273.154176) (xy 357.510915 -273.201708)
			(xy 357.518734 -273.251071) (xy 357.519224 -273.27606) (xy 357.518734 -273.301049) (xy 357.823498 -273.301049)
			(xy 357.823498 -273.251071) (xy 357.831317 -273.201708) (xy 357.846761 -273.154176) (xy 357.869451 -273.109644)
			(xy 357.898827 -273.069211) (xy 357.934167 -273.033871) (xy 357.9746 -273.004495) (xy 358.019132 -272.981805)
			(xy 358.066664 -272.966361) (xy 358.116027 -272.958542) (xy 358.166005 -272.958542) (xy 358.215368 -272.966361)
			(xy 358.2629 -272.981805) (xy 358.307432 -273.004495) (xy 358.347865 -273.033871) (xy 358.383205 -273.069211)
			(xy 358.412581 -273.109644) (xy 358.435271 -273.154176) (xy 358.450715 -273.201708) (xy 358.458534 -273.251071)
			(xy 358.459024 -273.27606) (xy 358.458534 -273.301049) (xy 361.577364 -273.301049) (xy 361.577364 -273.251071)
			(xy 361.585183 -273.201708) (xy 361.600627 -273.154176) (xy 361.623317 -273.109644) (xy 361.652693 -273.069211)
			(xy 361.688033 -273.033871) (xy 361.728466 -273.004495) (xy 361.772998 -272.981805) (xy 361.82053 -272.966361)
			(xy 361.869893 -272.958542) (xy 361.919871 -272.958542) (xy 361.969234 -272.966361) (xy 362.016766 -272.981805)
			(xy 362.061298 -273.004495) (xy 362.101731 -273.033871) (xy 362.137071 -273.069211) (xy 362.166447 -273.109644)
			(xy 362.189137 -273.154176) (xy 362.204581 -273.201708) (xy 362.2124 -273.251071) (xy 362.21289 -273.27606)
			(xy 362.2124 -273.301049) (xy 362.517164 -273.301049) (xy 362.517164 -273.251071) (xy 362.524983 -273.201708)
			(xy 362.540427 -273.154176) (xy 362.563117 -273.109644) (xy 362.592493 -273.069211) (xy 362.627833 -273.033871)
			(xy 362.668266 -273.004495) (xy 362.712798 -272.981805) (xy 362.76033 -272.966361) (xy 362.809693 -272.958542)
			(xy 362.859671 -272.958542) (xy 362.909034 -272.966361) (xy 362.956566 -272.981805) (xy 363.001098 -273.004495)
			(xy 363.041531 -273.033871) (xy 363.076871 -273.069211) (xy 363.106247 -273.109644) (xy 363.128937 -273.154176)
			(xy 363.144381 -273.201708) (xy 363.1522 -273.251071) (xy 363.15269 -273.27606) (xy 363.1522 -273.301049)
			(xy 363.457218 -273.301049) (xy 363.457218 -273.251071) (xy 363.465037 -273.201708) (xy 363.480481 -273.154176)
			(xy 363.503171 -273.109644) (xy 363.532547 -273.069211) (xy 363.567887 -273.033871) (xy 363.60832 -273.004495)
			(xy 363.652852 -272.981805) (xy 363.700384 -272.966361) (xy 363.749747 -272.958542) (xy 363.799725 -272.958542)
			(xy 363.849088 -272.966361) (xy 363.89662 -272.981805) (xy 363.941152 -273.004495) (xy 363.981585 -273.033871)
			(xy 364.016925 -273.069211) (xy 364.046301 -273.109644) (xy 364.068991 -273.154176) (xy 364.084435 -273.201708)
			(xy 364.092254 -273.251071) (xy 364.092744 -273.27606) (xy 364.398555 -273.27606) (xy 364.40265 -273.225332)
			(xy 364.414829 -273.175918) (xy 364.434777 -273.129098) (xy 364.461978 -273.086084) (xy 364.495726 -273.04799)
			(xy 364.535148 -273.015803) (xy 364.579222 -272.990357) (xy 364.626808 -272.97231) (xy 364.676672 -272.96213)
			(xy 364.727524 -272.960081) (xy 364.778045 -272.966215) (xy 364.826929 -272.980375) (xy 364.872908 -273.002192)
			(xy 364.914792 -273.031102) (xy 364.951496 -273.066357) (xy 364.982069 -273.107043) (xy 365.00572 -273.152106)
			(xy 365.021836 -273.20038) (xy 365.03 -273.250614) (xy 365.030512 -273.27606) (xy 365.338609 -273.27606)
			(xy 365.342704 -273.225332) (xy 365.354883 -273.175918) (xy 365.374831 -273.129098) (xy 365.402032 -273.086084)
			(xy 365.43578 -273.04799) (xy 365.475202 -273.015803) (xy 365.519276 -272.990357) (xy 365.566862 -272.97231)
			(xy 365.616726 -272.96213) (xy 365.667578 -272.960081) (xy 365.718099 -272.966215) (xy 365.766983 -272.980375)
			(xy 365.812962 -273.002192) (xy 365.854846 -273.031102) (xy 365.89155 -273.066357) (xy 365.922123 -273.107043)
			(xy 365.945774 -273.152106) (xy 365.96189 -273.20038) (xy 365.970054 -273.250614) (xy 365.970566 -273.27606)
			(xy 365.970063 -273.301049) (xy 366.27738 -273.301049) (xy 366.27738 -273.251071) (xy 366.285199 -273.201708)
			(xy 366.300643 -273.154176) (xy 366.323333 -273.109644) (xy 366.352709 -273.069211) (xy 366.388049 -273.033871)
			(xy 366.428482 -273.004495) (xy 366.473014 -272.981805) (xy 366.520546 -272.966361) (xy 366.569909 -272.958542)
			(xy 366.619887 -272.958542) (xy 366.66925 -272.966361) (xy 366.716782 -272.981805) (xy 366.761314 -273.004495)
			(xy 366.801747 -273.033871) (xy 366.837087 -273.069211) (xy 366.866463 -273.109644) (xy 366.889153 -273.154176)
			(xy 366.904597 -273.201708) (xy 366.912416 -273.251071) (xy 366.912906 -273.27606) (xy 367.218463 -273.27606)
			(xy 367.222558 -273.225332) (xy 367.234737 -273.175918) (xy 367.254685 -273.129098) (xy 367.281886 -273.086084)
			(xy 367.315634 -273.04799) (xy 367.355056 -273.015803) (xy 367.39913 -272.990357) (xy 367.446716 -272.97231)
			(xy 367.49658 -272.96213) (xy 367.547432 -272.960081) (xy 367.597953 -272.966215) (xy 367.646837 -272.980375)
			(xy 367.692816 -273.002192) (xy 367.7347 -273.031102) (xy 367.771404 -273.066357) (xy 367.801977 -273.107043)
			(xy 367.825628 -273.152106) (xy 367.841744 -273.20038) (xy 367.849908 -273.250614) (xy 367.85042 -273.27606)
			(xy 368.158517 -273.27606) (xy 368.162612 -273.225332) (xy 368.174791 -273.175918) (xy 368.194739 -273.129098)
			(xy 368.22194 -273.086084) (xy 368.255688 -273.04799) (xy 368.29511 -273.015803) (xy 368.339184 -272.990357)
			(xy 368.38677 -272.97231) (xy 368.436634 -272.96213) (xy 368.487486 -272.960081) (xy 368.538007 -272.966215)
			(xy 368.586891 -272.980375) (xy 368.63287 -273.002192) (xy 368.674754 -273.031102) (xy 368.711458 -273.066357)
			(xy 368.742031 -273.107043) (xy 368.765682 -273.152106) (xy 368.781798 -273.20038) (xy 368.789962 -273.250614)
			(xy 368.790474 -273.27606) (xy 368.789971 -273.301049) (xy 369.097288 -273.301049) (xy 369.097288 -273.251071)
			(xy 369.105107 -273.201708) (xy 369.120551 -273.154176) (xy 369.143241 -273.109644) (xy 369.172617 -273.069211)
			(xy 369.207957 -273.033871) (xy 369.24839 -273.004495) (xy 369.292922 -272.981805) (xy 369.340454 -272.966361)
			(xy 369.389817 -272.958542) (xy 369.439795 -272.958542) (xy 369.489158 -272.966361) (xy 369.53669 -272.981805)
			(xy 369.581222 -273.004495) (xy 369.621655 -273.033871) (xy 369.656995 -273.069211) (xy 369.686371 -273.109644)
			(xy 369.709061 -273.154176) (xy 369.724505 -273.201708) (xy 369.732324 -273.251071) (xy 369.732814 -273.27606)
			(xy 370.038625 -273.27606) (xy 370.04272 -273.225332) (xy 370.054899 -273.175918) (xy 370.074847 -273.129098)
			(xy 370.102048 -273.086084) (xy 370.135796 -273.04799) (xy 370.175218 -273.015803) (xy 370.219292 -272.990357)
			(xy 370.266878 -272.97231) (xy 370.316742 -272.96213) (xy 370.367594 -272.960081) (xy 370.418115 -272.966215)
			(xy 370.466999 -272.980375) (xy 370.512978 -273.002192) (xy 370.554862 -273.031102) (xy 370.591566 -273.066357)
			(xy 370.622139 -273.107043) (xy 370.64579 -273.152106) (xy 370.661906 -273.20038) (xy 370.67007 -273.250614)
			(xy 370.670582 -273.27606) (xy 370.978679 -273.27606) (xy 370.982774 -273.225332) (xy 370.994953 -273.175918)
			(xy 371.014901 -273.129098) (xy 371.042102 -273.086084) (xy 371.07585 -273.04799) (xy 371.115272 -273.015803)
			(xy 371.159346 -272.990357) (xy 371.206932 -272.97231) (xy 371.256796 -272.96213) (xy 371.307648 -272.960081)
			(xy 371.358169 -272.966215) (xy 371.407053 -272.980375) (xy 371.453032 -273.002192) (xy 371.494916 -273.031102)
			(xy 371.53162 -273.066357) (xy 371.562193 -273.107043) (xy 371.585844 -273.152106) (xy 371.60196 -273.20038)
			(xy 371.610124 -273.250614) (xy 371.610636 -273.27606) (xy 371.610133 -273.301049) (xy 371.917196 -273.301049)
			(xy 371.917196 -273.251071) (xy 371.925015 -273.201708) (xy 371.940459 -273.154176) (xy 371.963149 -273.109644)
			(xy 371.992525 -273.069211) (xy 372.027865 -273.033871) (xy 372.068298 -273.004495) (xy 372.11283 -272.981805)
			(xy 372.160362 -272.966361) (xy 372.209725 -272.958542) (xy 372.259703 -272.958542) (xy 372.309066 -272.966361)
			(xy 372.356598 -272.981805) (xy 372.40113 -273.004495) (xy 372.441563 -273.033871) (xy 372.476903 -273.069211)
			(xy 372.506279 -273.109644) (xy 372.528969 -273.154176) (xy 372.544413 -273.201708) (xy 372.552232 -273.251071)
			(xy 372.552722 -273.27606) (xy 372.858533 -273.27606) (xy 372.862628 -273.225332) (xy 372.874807 -273.175918)
			(xy 372.894755 -273.129098) (xy 372.921956 -273.086084) (xy 372.955704 -273.04799) (xy 372.995126 -273.015803)
			(xy 373.0392 -272.990357) (xy 373.086786 -272.97231) (xy 373.13665 -272.96213) (xy 373.187502 -272.960081)
			(xy 373.238023 -272.966215) (xy 373.286907 -272.980375) (xy 373.332886 -273.002192) (xy 373.37477 -273.031102)
			(xy 373.411474 -273.066357) (xy 373.442047 -273.107043) (xy 373.465698 -273.152106) (xy 373.481814 -273.20038)
			(xy 373.489978 -273.250614) (xy 373.49049 -273.27606) (xy 373.798587 -273.27606) (xy 373.802682 -273.225332)
			(xy 373.814861 -273.175918) (xy 373.834809 -273.129098) (xy 373.86201 -273.086084) (xy 373.895758 -273.04799)
			(xy 373.93518 -273.015803) (xy 373.979254 -272.990357) (xy 374.02684 -272.97231) (xy 374.076704 -272.96213)
			(xy 374.127556 -272.960081) (xy 374.178077 -272.966215) (xy 374.226961 -272.980375) (xy 374.27294 -273.002192)
			(xy 374.314824 -273.031102) (xy 374.351528 -273.066357) (xy 374.382101 -273.107043) (xy 374.405752 -273.152106)
			(xy 374.421868 -273.20038) (xy 374.430032 -273.250614) (xy 374.430544 -273.27606) (xy 374.430032 -273.301506)
			(xy 374.421868 -273.35174) (xy 374.405752 -273.400014) (xy 374.382101 -273.445077) (xy 374.351528 -273.485763)
			(xy 374.314824 -273.521018) (xy 374.27294 -273.549928) (xy 374.226961 -273.571745) (xy 374.178077 -273.585905)
			(xy 374.127556 -273.592039) (xy 374.076704 -273.58999) (xy 374.02684 -273.57981) (xy 373.979254 -273.561763)
			(xy 373.93518 -273.536317) (xy 373.895758 -273.50413) (xy 373.86201 -273.466036) (xy 373.834809 -273.423022)
			(xy 373.814861 -273.376202) (xy 373.802682 -273.326788) (xy 373.798587 -273.27606) (xy 373.49049 -273.27606)
			(xy 373.489978 -273.301506) (xy 373.481814 -273.35174) (xy 373.465698 -273.400014) (xy 373.442047 -273.445077)
			(xy 373.411474 -273.485763) (xy 373.37477 -273.521018) (xy 373.332886 -273.549928) (xy 373.286907 -273.571745)
			(xy 373.238023 -273.585905) (xy 373.187502 -273.592039) (xy 373.13665 -273.58999) (xy 373.086786 -273.57981)
			(xy 373.0392 -273.561763) (xy 372.995126 -273.536317) (xy 372.955704 -273.50413) (xy 372.921956 -273.466036)
			(xy 372.894755 -273.423022) (xy 372.874807 -273.376202) (xy 372.862628 -273.326788) (xy 372.858533 -273.27606)
			(xy 372.552722 -273.27606) (xy 372.552232 -273.301049) (xy 372.544413 -273.350412) (xy 372.528969 -273.397944)
			(xy 372.506279 -273.442476) (xy 372.476903 -273.482909) (xy 372.441563 -273.518249) (xy 372.40113 -273.547625)
			(xy 372.356598 -273.570315) (xy 372.309066 -273.585759) (xy 372.259703 -273.593578) (xy 372.209725 -273.593578)
			(xy 372.160362 -273.585759) (xy 372.11283 -273.570315) (xy 372.068298 -273.547625) (xy 372.027865 -273.518249)
			(xy 371.992525 -273.482909) (xy 371.963149 -273.442476) (xy 371.940459 -273.397944) (xy 371.925015 -273.350412)
			(xy 371.917196 -273.301049) (xy 371.610133 -273.301049) (xy 371.610124 -273.301506) (xy 371.60196 -273.35174)
			(xy 371.585844 -273.400014) (xy 371.562193 -273.445077) (xy 371.53162 -273.485763) (xy 371.494916 -273.521018)
			(xy 371.453032 -273.549928) (xy 371.407053 -273.571745) (xy 371.358169 -273.585905) (xy 371.307648 -273.592039)
			(xy 371.256796 -273.58999) (xy 371.206932 -273.57981) (xy 371.159346 -273.561763) (xy 371.115272 -273.536317)
			(xy 371.07585 -273.50413) (xy 371.042102 -273.466036) (xy 371.014901 -273.423022) (xy 370.994953 -273.376202)
			(xy 370.982774 -273.326788) (xy 370.978679 -273.27606) (xy 370.670582 -273.27606) (xy 370.67007 -273.301506)
			(xy 370.661906 -273.35174) (xy 370.64579 -273.400014) (xy 370.622139 -273.445077) (xy 370.591566 -273.485763)
			(xy 370.554862 -273.521018) (xy 370.512978 -273.549928) (xy 370.466999 -273.571745) (xy 370.418115 -273.585905)
			(xy 370.367594 -273.592039) (xy 370.316742 -273.58999) (xy 370.266878 -273.57981) (xy 370.219292 -273.561763)
			(xy 370.175218 -273.536317) (xy 370.135796 -273.50413) (xy 370.102048 -273.466036) (xy 370.074847 -273.423022)
			(xy 370.054899 -273.376202) (xy 370.04272 -273.326788) (xy 370.038625 -273.27606) (xy 369.732814 -273.27606)
			(xy 369.732324 -273.301049) (xy 369.724505 -273.350412) (xy 369.709061 -273.397944) (xy 369.686371 -273.442476)
			(xy 369.656995 -273.482909) (xy 369.621655 -273.518249) (xy 369.581222 -273.547625) (xy 369.53669 -273.570315)
			(xy 369.489158 -273.585759) (xy 369.439795 -273.593578) (xy 369.389817 -273.593578) (xy 369.340454 -273.585759)
			(xy 369.292922 -273.570315) (xy 369.24839 -273.547625) (xy 369.207957 -273.518249) (xy 369.172617 -273.482909)
			(xy 369.143241 -273.442476) (xy 369.120551 -273.397944) (xy 369.105107 -273.350412) (xy 369.097288 -273.301049)
			(xy 368.789971 -273.301049) (xy 368.789962 -273.301506) (xy 368.781798 -273.35174) (xy 368.765682 -273.400014)
			(xy 368.742031 -273.445077) (xy 368.711458 -273.485763) (xy 368.674754 -273.521018) (xy 368.63287 -273.549928)
			(xy 368.586891 -273.571745) (xy 368.538007 -273.585905) (xy 368.487486 -273.592039) (xy 368.436634 -273.58999)
			(xy 368.38677 -273.57981) (xy 368.339184 -273.561763) (xy 368.29511 -273.536317) (xy 368.255688 -273.50413)
			(xy 368.22194 -273.466036) (xy 368.194739 -273.423022) (xy 368.174791 -273.376202) (xy 368.162612 -273.326788)
			(xy 368.158517 -273.27606) (xy 367.85042 -273.27606) (xy 367.849908 -273.301506) (xy 367.841744 -273.35174)
			(xy 367.825628 -273.400014) (xy 367.801977 -273.445077) (xy 367.771404 -273.485763) (xy 367.7347 -273.521018)
			(xy 367.692816 -273.549928) (xy 367.646837 -273.571745) (xy 367.597953 -273.585905) (xy 367.547432 -273.592039)
			(xy 367.49658 -273.58999) (xy 367.446716 -273.57981) (xy 367.39913 -273.561763) (xy 367.355056 -273.536317)
			(xy 367.315634 -273.50413) (xy 367.281886 -273.466036) (xy 367.254685 -273.423022) (xy 367.234737 -273.376202)
			(xy 367.222558 -273.326788) (xy 367.218463 -273.27606) (xy 366.912906 -273.27606) (xy 366.912416 -273.301049)
			(xy 366.904597 -273.350412) (xy 366.889153 -273.397944) (xy 366.866463 -273.442476) (xy 366.837087 -273.482909)
			(xy 366.801747 -273.518249) (xy 366.761314 -273.547625) (xy 366.716782 -273.570315) (xy 366.66925 -273.585759)
			(xy 366.619887 -273.593578) (xy 366.569909 -273.593578) (xy 366.520546 -273.585759) (xy 366.473014 -273.570315)
			(xy 366.428482 -273.547625) (xy 366.388049 -273.518249) (xy 366.352709 -273.482909) (xy 366.323333 -273.442476)
			(xy 366.300643 -273.397944) (xy 366.285199 -273.350412) (xy 366.27738 -273.301049) (xy 365.970063 -273.301049)
			(xy 365.970054 -273.301506) (xy 365.96189 -273.35174) (xy 365.945774 -273.400014) (xy 365.922123 -273.445077)
			(xy 365.89155 -273.485763) (xy 365.854846 -273.521018) (xy 365.812962 -273.549928) (xy 365.766983 -273.571745)
			(xy 365.718099 -273.585905) (xy 365.667578 -273.592039) (xy 365.616726 -273.58999) (xy 365.566862 -273.57981)
			(xy 365.519276 -273.561763) (xy 365.475202 -273.536317) (xy 365.43578 -273.50413) (xy 365.402032 -273.466036)
			(xy 365.374831 -273.423022) (xy 365.354883 -273.376202) (xy 365.342704 -273.326788) (xy 365.338609 -273.27606)
			(xy 365.030512 -273.27606) (xy 365.03 -273.301506) (xy 365.021836 -273.35174) (xy 365.00572 -273.400014)
			(xy 364.982069 -273.445077) (xy 364.951496 -273.485763) (xy 364.914792 -273.521018) (xy 364.872908 -273.549928)
			(xy 364.826929 -273.571745) (xy 364.778045 -273.585905) (xy 364.727524 -273.592039) (xy 364.676672 -273.58999)
			(xy 364.626808 -273.57981) (xy 364.579222 -273.561763) (xy 364.535148 -273.536317) (xy 364.495726 -273.50413)
			(xy 364.461978 -273.466036) (xy 364.434777 -273.423022) (xy 364.414829 -273.376202) (xy 364.40265 -273.326788)
			(xy 364.398555 -273.27606) (xy 364.092744 -273.27606) (xy 364.092254 -273.301049) (xy 364.084435 -273.350412)
			(xy 364.068991 -273.397944) (xy 364.046301 -273.442476) (xy 364.016925 -273.482909) (xy 363.981585 -273.518249)
			(xy 363.941152 -273.547625) (xy 363.89662 -273.570315) (xy 363.849088 -273.585759) (xy 363.799725 -273.593578)
			(xy 363.749747 -273.593578) (xy 363.700384 -273.585759) (xy 363.652852 -273.570315) (xy 363.60832 -273.547625)
			(xy 363.567887 -273.518249) (xy 363.532547 -273.482909) (xy 363.503171 -273.442476) (xy 363.480481 -273.397944)
			(xy 363.465037 -273.350412) (xy 363.457218 -273.301049) (xy 363.1522 -273.301049) (xy 363.144381 -273.350412)
			(xy 363.128937 -273.397944) (xy 363.106247 -273.442476) (xy 363.076871 -273.482909) (xy 363.041531 -273.518249)
			(xy 363.001098 -273.547625) (xy 362.956566 -273.570315) (xy 362.909034 -273.585759) (xy 362.859671 -273.593578)
			(xy 362.809693 -273.593578) (xy 362.76033 -273.585759) (xy 362.712798 -273.570315) (xy 362.668266 -273.547625)
			(xy 362.627833 -273.518249) (xy 362.592493 -273.482909) (xy 362.563117 -273.442476) (xy 362.540427 -273.397944)
			(xy 362.524983 -273.350412) (xy 362.517164 -273.301049) (xy 362.2124 -273.301049) (xy 362.204581 -273.350412)
			(xy 362.189137 -273.397944) (xy 362.166447 -273.442476) (xy 362.137071 -273.482909) (xy 362.101731 -273.518249)
			(xy 362.061298 -273.547625) (xy 362.016766 -273.570315) (xy 361.969234 -273.585759) (xy 361.919871 -273.593578)
			(xy 361.869893 -273.593578) (xy 361.82053 -273.585759) (xy 361.772998 -273.570315) (xy 361.728466 -273.547625)
			(xy 361.688033 -273.518249) (xy 361.652693 -273.482909) (xy 361.623317 -273.442476) (xy 361.600627 -273.397944)
			(xy 361.585183 -273.350412) (xy 361.577364 -273.301049) (xy 358.458534 -273.301049) (xy 358.450715 -273.350412)
			(xy 358.435271 -273.397944) (xy 358.412581 -273.442476) (xy 358.383205 -273.482909) (xy 358.347865 -273.518249)
			(xy 358.307432 -273.547625) (xy 358.2629 -273.570315) (xy 358.215368 -273.585759) (xy 358.166005 -273.593578)
			(xy 358.116027 -273.593578) (xy 358.066664 -273.585759) (xy 358.019132 -273.570315) (xy 357.9746 -273.547625)
			(xy 357.934167 -273.518249) (xy 357.898827 -273.482909) (xy 357.869451 -273.442476) (xy 357.846761 -273.397944)
			(xy 357.831317 -273.350412) (xy 357.823498 -273.301049) (xy 357.518734 -273.301049) (xy 357.510915 -273.350412)
			(xy 357.495471 -273.397944) (xy 357.472781 -273.442476) (xy 357.443405 -273.482909) (xy 357.408065 -273.518249)
			(xy 357.367632 -273.547625) (xy 357.3231 -273.570315) (xy 357.275568 -273.585759) (xy 357.226205 -273.593578)
			(xy 357.176227 -273.593578) (xy 357.126864 -273.585759) (xy 357.079332 -273.570315) (xy 357.0348 -273.547625)
			(xy 356.994367 -273.518249) (xy 356.959027 -273.482909) (xy 356.929651 -273.442476) (xy 356.906961 -273.397944)
			(xy 356.891517 -273.350412) (xy 356.883698 -273.301049) (xy 356.57868 -273.301049) (xy 356.570861 -273.350412)
			(xy 356.555417 -273.397944) (xy 356.532727 -273.442476) (xy 356.503351 -273.482909) (xy 356.468011 -273.518249)
			(xy 356.427578 -273.547625) (xy 356.383046 -273.570315) (xy 356.335514 -273.585759) (xy 356.286151 -273.593578)
			(xy 356.236173 -273.593578) (xy 356.18681 -273.585759) (xy 356.139278 -273.570315) (xy 356.094746 -273.547625)
			(xy 356.054313 -273.518249) (xy 356.018973 -273.482909) (xy 355.989597 -273.442476) (xy 355.966907 -273.397944)
			(xy 355.951463 -273.350412) (xy 355.943644 -273.301049) (xy 355.636327 -273.301049) (xy 355.636318 -273.301506)
			(xy 355.628154 -273.35174) (xy 355.612038 -273.400014) (xy 355.588387 -273.445077) (xy 355.557814 -273.485763)
			(xy 355.52111 -273.521018) (xy 355.479226 -273.549928) (xy 355.433247 -273.571745) (xy 355.384363 -273.585905)
			(xy 355.333842 -273.592039) (xy 355.28299 -273.58999) (xy 355.233126 -273.57981) (xy 355.18554 -273.561763)
			(xy 355.141466 -273.536317) (xy 355.102044 -273.50413) (xy 355.068296 -273.466036) (xy 355.041095 -273.423022)
			(xy 355.021147 -273.376202) (xy 355.008968 -273.326788) (xy 355.004873 -273.27606) (xy 354.696776 -273.27606)
			(xy 354.696264 -273.301506) (xy 354.6881 -273.35174) (xy 354.671984 -273.400014) (xy 354.648333 -273.445077)
			(xy 354.61776 -273.485763) (xy 354.581056 -273.521018) (xy 354.539172 -273.549928) (xy 354.493193 -273.571745)
			(xy 354.444309 -273.585905) (xy 354.393788 -273.592039) (xy 354.342936 -273.58999) (xy 354.293072 -273.57981)
			(xy 354.245486 -273.561763) (xy 354.201412 -273.536317) (xy 354.16199 -273.50413) (xy 354.128242 -273.466036)
			(xy 354.101041 -273.423022) (xy 354.081093 -273.376202) (xy 354.068914 -273.326788) (xy 354.064819 -273.27606)
			(xy 353.759008 -273.27606) (xy 353.758518 -273.301049) (xy 353.750699 -273.350412) (xy 353.735255 -273.397944)
			(xy 353.712565 -273.442476) (xy 353.683189 -273.482909) (xy 353.647849 -273.518249) (xy 353.607416 -273.547625)
			(xy 353.562884 -273.570315) (xy 353.515352 -273.585759) (xy 353.465989 -273.593578) (xy 353.416011 -273.593578)
			(xy 353.366648 -273.585759) (xy 353.319116 -273.570315) (xy 353.274584 -273.547625) (xy 353.234151 -273.518249)
			(xy 353.198811 -273.482909) (xy 353.169435 -273.442476) (xy 353.146745 -273.397944) (xy 353.131301 -273.350412)
			(xy 353.123482 -273.301049) (xy 352.816419 -273.301049) (xy 352.81641 -273.301506) (xy 352.808246 -273.35174)
			(xy 352.79213 -273.400014) (xy 352.768479 -273.445077) (xy 352.737906 -273.485763) (xy 352.701202 -273.521018)
			(xy 352.659318 -273.549928) (xy 352.613339 -273.571745) (xy 352.564455 -273.585905) (xy 352.513934 -273.592039)
			(xy 352.463082 -273.58999) (xy 352.413218 -273.57981) (xy 352.365632 -273.561763) (xy 352.321558 -273.536317)
			(xy 352.282136 -273.50413) (xy 352.248388 -273.466036) (xy 352.221187 -273.423022) (xy 352.201239 -273.376202)
			(xy 352.18906 -273.326788) (xy 352.184965 -273.27606) (xy 351.876868 -273.27606) (xy 351.876356 -273.301506)
			(xy 351.868192 -273.35174) (xy 351.852076 -273.400014) (xy 351.828425 -273.445077) (xy 351.797852 -273.485763)
			(xy 351.761148 -273.521018) (xy 351.719264 -273.549928) (xy 351.673285 -273.571745) (xy 351.624401 -273.585905)
			(xy 351.57388 -273.592039) (xy 351.523028 -273.58999) (xy 351.473164 -273.57981) (xy 351.425578 -273.561763)
			(xy 351.381504 -273.536317) (xy 351.342082 -273.50413) (xy 351.308334 -273.466036) (xy 351.281133 -273.423022)
			(xy 351.261185 -273.376202) (xy 351.249006 -273.326788) (xy 351.244911 -273.27606) (xy 350.9391 -273.27606)
			(xy 350.93861 -273.301049) (xy 350.930791 -273.350412) (xy 350.915347 -273.397944) (xy 350.892657 -273.442476)
			(xy 350.863281 -273.482909) (xy 350.827941 -273.518249) (xy 350.787508 -273.547625) (xy 350.742976 -273.570315)
			(xy 350.695444 -273.585759) (xy 350.646081 -273.593578) (xy 350.596103 -273.593578) (xy 350.54674 -273.585759)
			(xy 350.499208 -273.570315) (xy 350.454676 -273.547625) (xy 350.414243 -273.518249) (xy 350.378903 -273.482909)
			(xy 350.349527 -273.442476) (xy 350.326837 -273.397944) (xy 350.311393 -273.350412) (xy 350.303574 -273.301049)
			(xy 349.996257 -273.301049) (xy 349.996248 -273.301506) (xy 349.988084 -273.35174) (xy 349.971968 -273.400014)
			(xy 349.948317 -273.445077) (xy 349.917744 -273.485763) (xy 349.88104 -273.521018) (xy 349.839156 -273.549928)
			(xy 349.793177 -273.571745) (xy 349.744293 -273.585905) (xy 349.693772 -273.592039) (xy 349.64292 -273.58999)
			(xy 349.593056 -273.57981) (xy 349.54547 -273.561763) (xy 349.501396 -273.536317) (xy 349.461974 -273.50413)
			(xy 349.428226 -273.466036) (xy 349.401025 -273.423022) (xy 349.381077 -273.376202) (xy 349.368898 -273.326788)
			(xy 349.364803 -273.27606) (xy 349.05696 -273.27606) (xy 349.056448 -273.301506) (xy 349.048284 -273.35174)
			(xy 349.032168 -273.400014) (xy 349.008517 -273.445077) (xy 348.977944 -273.485763) (xy 348.94124 -273.521018)
			(xy 348.899356 -273.549928) (xy 348.853377 -273.571745) (xy 348.804493 -273.585905) (xy 348.753972 -273.592039)
			(xy 348.70312 -273.58999) (xy 348.653256 -273.57981) (xy 348.60567 -273.561763) (xy 348.561596 -273.536317)
			(xy 348.522174 -273.50413) (xy 348.488426 -273.466036) (xy 348.461225 -273.423022) (xy 348.441277 -273.376202)
			(xy 348.429098 -273.326788) (xy 348.425003 -273.27606) (xy 348.119192 -273.27606) (xy 348.118702 -273.301049)
			(xy 348.110883 -273.350412) (xy 348.095439 -273.397944) (xy 348.072749 -273.442476) (xy 348.043373 -273.482909)
			(xy 348.008033 -273.518249) (xy 347.9676 -273.547625) (xy 347.923068 -273.570315) (xy 347.875536 -273.585759)
			(xy 347.826173 -273.593578) (xy 347.776195 -273.593578) (xy 347.726832 -273.585759) (xy 347.6793 -273.570315)
			(xy 347.634768 -273.547625) (xy 347.594335 -273.518249) (xy 347.558995 -273.482909) (xy 347.529619 -273.442476)
			(xy 347.506929 -273.397944) (xy 347.491485 -273.350412) (xy 347.483666 -273.301049) (xy 347.176349 -273.301049)
			(xy 347.17634 -273.301506) (xy 347.168176 -273.35174) (xy 347.15206 -273.400014) (xy 347.128409 -273.445077)
			(xy 347.097836 -273.485763) (xy 347.061132 -273.521018) (xy 347.019248 -273.549928) (xy 346.973269 -273.571745)
			(xy 346.924385 -273.585905) (xy 346.873864 -273.592039) (xy 346.823012 -273.58999) (xy 346.773148 -273.57981)
			(xy 346.725562 -273.561763) (xy 346.681488 -273.536317) (xy 346.642066 -273.50413) (xy 346.608318 -273.466036)
			(xy 346.581117 -273.423022) (xy 346.561169 -273.376202) (xy 346.54899 -273.326788) (xy 346.544895 -273.27606)
			(xy 346.236798 -273.27606) (xy 346.236286 -273.301506) (xy 346.228122 -273.35174) (xy 346.212006 -273.400014)
			(xy 346.188355 -273.445077) (xy 346.157782 -273.485763) (xy 346.121078 -273.521018) (xy 346.079194 -273.549928)
			(xy 346.033215 -273.571745) (xy 345.984331 -273.585905) (xy 345.93381 -273.592039) (xy 345.882958 -273.58999)
			(xy 345.833094 -273.57981) (xy 345.785508 -273.561763) (xy 345.741434 -273.536317) (xy 345.702012 -273.50413)
			(xy 345.668264 -273.466036) (xy 345.641063 -273.423022) (xy 345.621115 -273.376202) (xy 345.608936 -273.326788)
			(xy 345.604841 -273.27606) (xy 345.2989 -273.27606) (xy 345.297305 -273.313998) (xy 345.287697 -273.36223)
			(xy 345.270775 -273.408406) (xy 345.246944 -273.451426) (xy 345.232228 -273.471132) (xy 345.214389 -273.493103)
			(xy 345.172315 -273.530946) (xy 345.124198 -273.56073) (xy 345.098116 -273.571716) (xy 345.097862 -273.571716)
			(xy 345.095068 -273.572732) (xy 345.08674 -273.577114) (xy 345.073741 -273.590697) (xy 345.066503 -273.608049)
			(xy 345.065858 -273.617436) (xy 345.065858 -273.779996) (xy 345.066301 -273.789841) (xy 345.073716 -273.80808)
			(xy 345.087483 -273.822154) (xy 345.096338 -273.826478) (xy 345.14155 -273.84629) (xy 345.17965 -273.8628)
			(xy 345.186544 -273.865531) (xy 345.201255 -273.867333) (xy 345.208606 -273.866356) (xy 345.215464 -273.865086)
			(xy 345.228672 -273.858736) (xy 345.23426 -273.853402) (xy 345.252025 -273.83744) (xy 345.291443 -273.810479)
			(xy 345.334449 -273.789712) (xy 345.380075 -273.775607) (xy 345.427297 -273.76848) (xy 345.451176 -273.768058)
			(xy 345.476171 -273.768521) (xy 345.525546 -273.776338) (xy 345.573091 -273.791782) (xy 345.617634 -273.814475)
			(xy 345.658078 -273.843857) (xy 345.693428 -273.879204) (xy 345.722812 -273.919646) (xy 345.745508 -273.964187)
			(xy 345.760957 -274.01173) (xy 345.768777 -274.061105) (xy 345.768777 -274.111055) (xy 346.073712 -274.111055)
			(xy 346.073712 -274.061077) (xy 346.081531 -274.011714) (xy 346.096975 -273.964182) (xy 346.119665 -273.91965)
			(xy 346.149041 -273.879217) (xy 346.184381 -273.843877) (xy 346.224814 -273.814501) (xy 346.269346 -273.791811)
			(xy 346.316878 -273.776367) (xy 346.366241 -273.768548) (xy 346.416219 -273.768548) (xy 346.465582 -273.776367)
			(xy 346.513114 -273.791811) (xy 346.557646 -273.814501) (xy 346.598079 -273.843877) (xy 346.633419 -273.879217)
			(xy 346.662795 -273.91965) (xy 346.685485 -273.964182) (xy 346.700929 -274.011714) (xy 346.708748 -274.061077)
			(xy 346.709238 -274.086066) (xy 346.708748 -274.111055) (xy 347.013512 -274.111055) (xy 347.013512 -274.061077)
			(xy 347.021331 -274.011714) (xy 347.036775 -273.964182) (xy 347.059465 -273.91965) (xy 347.088841 -273.879217)
			(xy 347.124181 -273.843877) (xy 347.164614 -273.814501) (xy 347.209146 -273.791811) (xy 347.256678 -273.776367)
			(xy 347.306041 -273.768548) (xy 347.356019 -273.768548) (xy 347.405382 -273.776367) (xy 347.452914 -273.791811)
			(xy 347.497446 -273.814501) (xy 347.537879 -273.843877) (xy 347.573219 -273.879217) (xy 347.602595 -273.91965)
			(xy 347.625285 -273.964182) (xy 347.640729 -274.011714) (xy 347.648548 -274.061077) (xy 347.649038 -274.086066)
			(xy 347.648548 -274.111055) (xy 347.953566 -274.111055) (xy 347.953566 -274.061077) (xy 347.961385 -274.011714)
			(xy 347.976829 -273.964182) (xy 347.999519 -273.91965) (xy 348.028895 -273.879217) (xy 348.064235 -273.843877)
			(xy 348.104668 -273.814501) (xy 348.1492 -273.791811) (xy 348.196732 -273.776367) (xy 348.246095 -273.768548)
			(xy 348.296073 -273.768548) (xy 348.345436 -273.776367) (xy 348.392968 -273.791811) (xy 348.4375 -273.814501)
			(xy 348.477933 -273.843877) (xy 348.513273 -273.879217) (xy 348.542649 -273.91965) (xy 348.565339 -273.964182)
			(xy 348.580783 -274.011714) (xy 348.588602 -274.061077) (xy 348.589092 -274.086066) (xy 348.588602 -274.111055)
			(xy 348.89362 -274.111055) (xy 348.89362 -274.061077) (xy 348.901439 -274.011714) (xy 348.916883 -273.964182)
			(xy 348.939573 -273.91965) (xy 348.968949 -273.879217) (xy 349.004289 -273.843877) (xy 349.044722 -273.814501)
			(xy 349.089254 -273.791811) (xy 349.136786 -273.776367) (xy 349.186149 -273.768548) (xy 349.236127 -273.768548)
			(xy 349.28549 -273.776367) (xy 349.333022 -273.791811) (xy 349.377554 -273.814501) (xy 349.417987 -273.843877)
			(xy 349.453327 -273.879217) (xy 349.482703 -273.91965) (xy 349.505393 -273.964182) (xy 349.520837 -274.011714)
			(xy 349.528656 -274.061077) (xy 349.529146 -274.086066) (xy 349.528656 -274.111055) (xy 349.833674 -274.111055)
			(xy 349.833674 -274.061077) (xy 349.841493 -274.011714) (xy 349.856937 -273.964182) (xy 349.879627 -273.91965)
			(xy 349.909003 -273.879217) (xy 349.944343 -273.843877) (xy 349.984776 -273.814501) (xy 350.029308 -273.791811)
			(xy 350.07684 -273.776367) (xy 350.126203 -273.768548) (xy 350.176181 -273.768548) (xy 350.225544 -273.776367)
			(xy 350.273076 -273.791811) (xy 350.317608 -273.814501) (xy 350.358041 -273.843877) (xy 350.393381 -273.879217)
			(xy 350.422757 -273.91965) (xy 350.445447 -273.964182) (xy 350.460891 -274.011714) (xy 350.46871 -274.061077)
			(xy 350.4692 -274.086066) (xy 350.46871 -274.111055) (xy 350.773728 -274.111055) (xy 350.773728 -274.061077)
			(xy 350.781547 -274.011714) (xy 350.796991 -273.964182) (xy 350.819681 -273.91965) (xy 350.849057 -273.879217)
			(xy 350.884397 -273.843877) (xy 350.92483 -273.814501) (xy 350.969362 -273.791811) (xy 351.016894 -273.776367)
			(xy 351.066257 -273.768548) (xy 351.116235 -273.768548) (xy 351.165598 -273.776367) (xy 351.21313 -273.791811)
			(xy 351.257662 -273.814501) (xy 351.298095 -273.843877) (xy 351.333435 -273.879217) (xy 351.362811 -273.91965)
			(xy 351.385501 -273.964182) (xy 351.400945 -274.011714) (xy 351.408764 -274.061077) (xy 351.409254 -274.086066)
			(xy 351.408764 -274.111055) (xy 351.713528 -274.111055) (xy 351.713528 -274.061077) (xy 351.721347 -274.011714)
			(xy 351.736791 -273.964182) (xy 351.759481 -273.91965) (xy 351.788857 -273.879217) (xy 351.824197 -273.843877)
			(xy 351.86463 -273.814501) (xy 351.909162 -273.791811) (xy 351.956694 -273.776367) (xy 352.006057 -273.768548)
			(xy 352.056035 -273.768548) (xy 352.105398 -273.776367) (xy 352.15293 -273.791811) (xy 352.197462 -273.814501)
			(xy 352.237895 -273.843877) (xy 352.273235 -273.879217) (xy 352.302611 -273.91965) (xy 352.325301 -273.964182)
			(xy 352.340745 -274.011714) (xy 352.348564 -274.061077) (xy 352.349054 -274.086066) (xy 352.348564 -274.111055)
			(xy 352.653582 -274.111055) (xy 352.653582 -274.061077) (xy 352.661401 -274.011714) (xy 352.676845 -273.964182)
			(xy 352.699535 -273.91965) (xy 352.728911 -273.879217) (xy 352.764251 -273.843877) (xy 352.804684 -273.814501)
			(xy 352.849216 -273.791811) (xy 352.896748 -273.776367) (xy 352.946111 -273.768548) (xy 352.996089 -273.768548)
			(xy 353.045452 -273.776367) (xy 353.092984 -273.791811) (xy 353.137516 -273.814501) (xy 353.177949 -273.843877)
			(xy 353.213289 -273.879217) (xy 353.242665 -273.91965) (xy 353.265355 -273.964182) (xy 353.280799 -274.011714)
			(xy 353.288618 -274.061077) (xy 353.289108 -274.086066) (xy 353.288618 -274.111055) (xy 353.593636 -274.111055)
			(xy 353.593636 -274.061077) (xy 353.601455 -274.011714) (xy 353.616899 -273.964182) (xy 353.639589 -273.91965)
			(xy 353.668965 -273.879217) (xy 353.704305 -273.843877) (xy 353.744738 -273.814501) (xy 353.78927 -273.791811)
			(xy 353.836802 -273.776367) (xy 353.886165 -273.768548) (xy 353.936143 -273.768548) (xy 353.985506 -273.776367)
			(xy 354.033038 -273.791811) (xy 354.07757 -273.814501) (xy 354.118003 -273.843877) (xy 354.153343 -273.879217)
			(xy 354.182719 -273.91965) (xy 354.205409 -273.964182) (xy 354.220853 -274.011714) (xy 354.228672 -274.061077)
			(xy 354.229162 -274.086066) (xy 354.228672 -274.111055) (xy 354.53369 -274.111055) (xy 354.53369 -274.061077)
			(xy 354.541509 -274.011714) (xy 354.556953 -273.964182) (xy 354.579643 -273.91965) (xy 354.609019 -273.879217)
			(xy 354.644359 -273.843877) (xy 354.684792 -273.814501) (xy 354.729324 -273.791811) (xy 354.776856 -273.776367)
			(xy 354.826219 -273.768548) (xy 354.876197 -273.768548) (xy 354.92556 -273.776367) (xy 354.973092 -273.791811)
			(xy 355.017624 -273.814501) (xy 355.058057 -273.843877) (xy 355.093397 -273.879217) (xy 355.122773 -273.91965)
			(xy 355.145463 -273.964182) (xy 355.160907 -274.011714) (xy 355.168726 -274.061077) (xy 355.169216 -274.086066)
			(xy 355.168726 -274.111055) (xy 355.47349 -274.111055) (xy 355.47349 -274.061077) (xy 355.481309 -274.011714)
			(xy 355.496753 -273.964182) (xy 355.519443 -273.91965) (xy 355.548819 -273.879217) (xy 355.584159 -273.843877)
			(xy 355.624592 -273.814501) (xy 355.669124 -273.791811) (xy 355.716656 -273.776367) (xy 355.766019 -273.768548)
			(xy 355.815997 -273.768548) (xy 355.86536 -273.776367) (xy 355.912892 -273.791811) (xy 355.957424 -273.814501)
			(xy 355.997857 -273.843877) (xy 356.033197 -273.879217) (xy 356.062573 -273.91965) (xy 356.085263 -273.964182)
			(xy 356.100707 -274.011714) (xy 356.108526 -274.061077) (xy 356.109016 -274.086066) (xy 356.414827 -274.086066)
			(xy 356.418922 -274.035338) (xy 356.431101 -273.985924) (xy 356.451049 -273.939104) (xy 356.47825 -273.89609)
			(xy 356.511998 -273.857996) (xy 356.55142 -273.825809) (xy 356.595494 -273.800363) (xy 356.64308 -273.782316)
			(xy 356.692944 -273.772136) (xy 356.743796 -273.770087) (xy 356.794317 -273.776221) (xy 356.843201 -273.790381)
			(xy 356.88918 -273.812198) (xy 356.931064 -273.841108) (xy 356.967768 -273.876363) (xy 356.998341 -273.917049)
			(xy 357.021992 -273.962112) (xy 357.038108 -274.010386) (xy 357.046272 -274.06062) (xy 357.046784 -274.086066)
			(xy 357.354881 -274.086066) (xy 357.358976 -274.035338) (xy 357.371155 -273.985924) (xy 357.391103 -273.939104)
			(xy 357.418304 -273.89609) (xy 357.452052 -273.857996) (xy 357.491474 -273.825809) (xy 357.535548 -273.800363)
			(xy 357.583134 -273.782316) (xy 357.632998 -273.772136) (xy 357.68385 -273.770087) (xy 357.734371 -273.776221)
			(xy 357.783255 -273.790381) (xy 357.829234 -273.812198) (xy 357.871118 -273.841108) (xy 357.907822 -273.876363)
			(xy 357.938395 -273.917049) (xy 357.962046 -273.962112) (xy 357.978162 -274.010386) (xy 357.986326 -274.06062)
			(xy 357.986838 -274.086066) (xy 357.986335 -274.111055) (xy 358.293652 -274.111055) (xy 358.293652 -274.061077)
			(xy 358.301471 -274.011714) (xy 358.316915 -273.964182) (xy 358.339605 -273.91965) (xy 358.368981 -273.879217)
			(xy 358.404321 -273.843877) (xy 358.444754 -273.814501) (xy 358.489286 -273.791811) (xy 358.536818 -273.776367)
			(xy 358.586181 -273.768548) (xy 358.636159 -273.768548) (xy 358.685522 -273.776367) (xy 358.733054 -273.791811)
			(xy 358.777586 -273.814501) (xy 358.818019 -273.843877) (xy 358.853359 -273.879217) (xy 358.882735 -273.91965)
			(xy 358.905425 -273.964182) (xy 358.920869 -274.011714) (xy 358.928688 -274.061077) (xy 358.929178 -274.086066)
			(xy 358.928688 -274.111055) (xy 361.10721 -274.111055) (xy 361.10721 -274.061077) (xy 361.115029 -274.011714)
			(xy 361.130473 -273.964182) (xy 361.153163 -273.91965) (xy 361.182539 -273.879217) (xy 361.217879 -273.843877)
			(xy 361.258312 -273.814501) (xy 361.302844 -273.791811) (xy 361.350376 -273.776367) (xy 361.399739 -273.768548)
			(xy 361.449717 -273.768548) (xy 361.49908 -273.776367) (xy 361.546612 -273.791811) (xy 361.591144 -273.814501)
			(xy 361.631577 -273.843877) (xy 361.666917 -273.879217) (xy 361.696293 -273.91965) (xy 361.718983 -273.964182)
			(xy 361.734427 -274.011714) (xy 361.742246 -274.061077) (xy 361.742736 -274.086066) (xy 362.048547 -274.086066)
			(xy 362.052642 -274.035338) (xy 362.064821 -273.985924) (xy 362.084769 -273.939104) (xy 362.11197 -273.89609)
			(xy 362.145718 -273.857996) (xy 362.18514 -273.825809) (xy 362.229214 -273.800363) (xy 362.2768 -273.782316)
			(xy 362.326664 -273.772136) (xy 362.377516 -273.770087) (xy 362.428037 -273.776221) (xy 362.476921 -273.790381)
			(xy 362.5229 -273.812198) (xy 362.564784 -273.841108) (xy 362.601488 -273.876363) (xy 362.632061 -273.917049)
			(xy 362.655712 -273.962112) (xy 362.671828 -274.010386) (xy 362.679992 -274.06062) (xy 362.680504 -274.086066)
			(xy 362.988601 -274.086066) (xy 362.992696 -274.035338) (xy 363.004875 -273.985924) (xy 363.024823 -273.939104)
			(xy 363.052024 -273.89609) (xy 363.085772 -273.857996) (xy 363.125194 -273.825809) (xy 363.169268 -273.800363)
			(xy 363.216854 -273.782316) (xy 363.266718 -273.772136) (xy 363.31757 -273.770087) (xy 363.368091 -273.776221)
			(xy 363.416975 -273.790381) (xy 363.462954 -273.812198) (xy 363.504838 -273.841108) (xy 363.541542 -273.876363)
			(xy 363.572115 -273.917049) (xy 363.595766 -273.962112) (xy 363.611882 -274.010386) (xy 363.620046 -274.06062)
			(xy 363.620558 -274.086066) (xy 363.620055 -274.111055) (xy 363.927372 -274.111055) (xy 363.927372 -274.061077)
			(xy 363.935191 -274.011714) (xy 363.950635 -273.964182) (xy 363.973325 -273.91965) (xy 364.002701 -273.879217)
			(xy 364.038041 -273.843877) (xy 364.078474 -273.814501) (xy 364.123006 -273.791811) (xy 364.170538 -273.776367)
			(xy 364.219901 -273.768548) (xy 364.269879 -273.768548) (xy 364.319242 -273.776367) (xy 364.366774 -273.791811)
			(xy 364.411306 -273.814501) (xy 364.451739 -273.843877) (xy 364.487079 -273.879217) (xy 364.516455 -273.91965)
			(xy 364.539145 -273.964182) (xy 364.554589 -274.011714) (xy 364.562408 -274.061077) (xy 364.562898 -274.086066)
			(xy 364.562408 -274.111055) (xy 364.867172 -274.111055) (xy 364.867172 -274.061077) (xy 364.874991 -274.011714)
			(xy 364.890435 -273.964182) (xy 364.913125 -273.91965) (xy 364.942501 -273.879217) (xy 364.977841 -273.843877)
			(xy 365.018274 -273.814501) (xy 365.062806 -273.791811) (xy 365.110338 -273.776367) (xy 365.159701 -273.768548)
			(xy 365.209679 -273.768548) (xy 365.259042 -273.776367) (xy 365.306574 -273.791811) (xy 365.351106 -273.814501)
			(xy 365.391539 -273.843877) (xy 365.426879 -273.879217) (xy 365.456255 -273.91965) (xy 365.478945 -273.964182)
			(xy 365.494389 -274.011714) (xy 365.502208 -274.061077) (xy 365.502698 -274.086066) (xy 365.502208 -274.111055)
			(xy 365.807226 -274.111055) (xy 365.807226 -274.061077) (xy 365.815045 -274.011714) (xy 365.830489 -273.964182)
			(xy 365.853179 -273.91965) (xy 365.882555 -273.879217) (xy 365.917895 -273.843877) (xy 365.958328 -273.814501)
			(xy 366.00286 -273.791811) (xy 366.050392 -273.776367) (xy 366.099755 -273.768548) (xy 366.149733 -273.768548)
			(xy 366.199096 -273.776367) (xy 366.246628 -273.791811) (xy 366.29116 -273.814501) (xy 366.331593 -273.843877)
			(xy 366.366933 -273.879217) (xy 366.396309 -273.91965) (xy 366.418999 -273.964182) (xy 366.434443 -274.011714)
			(xy 366.442262 -274.061077) (xy 366.442752 -274.086066) (xy 366.442262 -274.111055) (xy 366.74728 -274.111055)
			(xy 366.74728 -274.061077) (xy 366.755099 -274.011714) (xy 366.770543 -273.964182) (xy 366.793233 -273.91965)
			(xy 366.822609 -273.879217) (xy 366.857949 -273.843877) (xy 366.898382 -273.814501) (xy 366.942914 -273.791811)
			(xy 366.990446 -273.776367) (xy 367.039809 -273.768548) (xy 367.089787 -273.768548) (xy 367.13915 -273.776367)
			(xy 367.186682 -273.791811) (xy 367.231214 -273.814501) (xy 367.271647 -273.843877) (xy 367.306987 -273.879217)
			(xy 367.336363 -273.91965) (xy 367.359053 -273.964182) (xy 367.374497 -274.011714) (xy 367.382316 -274.061077)
			(xy 367.382806 -274.086066) (xy 367.382316 -274.111055) (xy 367.687334 -274.111055) (xy 367.687334 -274.061077)
			(xy 367.695153 -274.011714) (xy 367.710597 -273.964182) (xy 367.733287 -273.91965) (xy 367.762663 -273.879217)
			(xy 367.798003 -273.843877) (xy 367.838436 -273.814501) (xy 367.882968 -273.791811) (xy 367.9305 -273.776367)
			(xy 367.979863 -273.768548) (xy 368.029841 -273.768548) (xy 368.079204 -273.776367) (xy 368.126736 -273.791811)
			(xy 368.171268 -273.814501) (xy 368.211701 -273.843877) (xy 368.247041 -273.879217) (xy 368.276417 -273.91965)
			(xy 368.299107 -273.964182) (xy 368.314551 -274.011714) (xy 368.32237 -274.061077) (xy 368.32286 -274.086066)
			(xy 368.32237 -274.111055) (xy 368.627388 -274.111055) (xy 368.627388 -274.061077) (xy 368.635207 -274.011714)
			(xy 368.650651 -273.964182) (xy 368.673341 -273.91965) (xy 368.702717 -273.879217) (xy 368.738057 -273.843877)
			(xy 368.77849 -273.814501) (xy 368.823022 -273.791811) (xy 368.870554 -273.776367) (xy 368.919917 -273.768548)
			(xy 368.969895 -273.768548) (xy 369.019258 -273.776367) (xy 369.06679 -273.791811) (xy 369.111322 -273.814501)
			(xy 369.151755 -273.843877) (xy 369.187095 -273.879217) (xy 369.216471 -273.91965) (xy 369.239161 -273.964182)
			(xy 369.254605 -274.011714) (xy 369.262424 -274.061077) (xy 369.262914 -274.086066) (xy 369.262424 -274.111055)
			(xy 369.567188 -274.111055) (xy 369.567188 -274.061077) (xy 369.575007 -274.011714) (xy 369.590451 -273.964182)
			(xy 369.613141 -273.91965) (xy 369.642517 -273.879217) (xy 369.677857 -273.843877) (xy 369.71829 -273.814501)
			(xy 369.762822 -273.791811) (xy 369.810354 -273.776367) (xy 369.859717 -273.768548) (xy 369.909695 -273.768548)
			(xy 369.959058 -273.776367) (xy 370.00659 -273.791811) (xy 370.051122 -273.814501) (xy 370.091555 -273.843877)
			(xy 370.126895 -273.879217) (xy 370.156271 -273.91965) (xy 370.178961 -273.964182) (xy 370.194405 -274.011714)
			(xy 370.202224 -274.061077) (xy 370.202714 -274.086066) (xy 370.202224 -274.111055) (xy 370.507242 -274.111055)
			(xy 370.507242 -274.061077) (xy 370.515061 -274.011714) (xy 370.530505 -273.964182) (xy 370.553195 -273.91965)
			(xy 370.582571 -273.879217) (xy 370.617911 -273.843877) (xy 370.658344 -273.814501) (xy 370.702876 -273.791811)
			(xy 370.750408 -273.776367) (xy 370.799771 -273.768548) (xy 370.849749 -273.768548) (xy 370.899112 -273.776367)
			(xy 370.946644 -273.791811) (xy 370.991176 -273.814501) (xy 371.031609 -273.843877) (xy 371.066949 -273.879217)
			(xy 371.096325 -273.91965) (xy 371.119015 -273.964182) (xy 371.134459 -274.011714) (xy 371.142278 -274.061077)
			(xy 371.142768 -274.086066) (xy 371.142278 -274.111055) (xy 371.447296 -274.111055) (xy 371.447296 -274.061077)
			(xy 371.455115 -274.011714) (xy 371.470559 -273.964182) (xy 371.493249 -273.91965) (xy 371.522625 -273.879217)
			(xy 371.557965 -273.843877) (xy 371.598398 -273.814501) (xy 371.64293 -273.791811) (xy 371.690462 -273.776367)
			(xy 371.739825 -273.768548) (xy 371.789803 -273.768548) (xy 371.839166 -273.776367) (xy 371.886698 -273.791811)
			(xy 371.93123 -273.814501) (xy 371.971663 -273.843877) (xy 372.007003 -273.879217) (xy 372.036379 -273.91965)
			(xy 372.059069 -273.964182) (xy 372.074513 -274.011714) (xy 372.082332 -274.061077) (xy 372.082822 -274.086066)
			(xy 372.082332 -274.111055) (xy 372.38735 -274.111055) (xy 372.38735 -274.061077) (xy 372.395169 -274.011714)
			(xy 372.410613 -273.964182) (xy 372.433303 -273.91965) (xy 372.462679 -273.879217) (xy 372.498019 -273.843877)
			(xy 372.538452 -273.814501) (xy 372.582984 -273.791811) (xy 372.630516 -273.776367) (xy 372.679879 -273.768548)
			(xy 372.729857 -273.768548) (xy 372.77922 -273.776367) (xy 372.826752 -273.791811) (xy 372.871284 -273.814501)
			(xy 372.911717 -273.843877) (xy 372.947057 -273.879217) (xy 372.976433 -273.91965) (xy 372.999123 -273.964182)
			(xy 373.014567 -274.011714) (xy 373.022386 -274.061077) (xy 373.022876 -274.086066) (xy 373.022386 -274.111055)
			(xy 373.327404 -274.111055) (xy 373.327404 -274.061077) (xy 373.335223 -274.011714) (xy 373.350667 -273.964182)
			(xy 373.373357 -273.91965) (xy 373.402733 -273.879217) (xy 373.438073 -273.843877) (xy 373.478506 -273.814501)
			(xy 373.523038 -273.791811) (xy 373.57057 -273.776367) (xy 373.619933 -273.768548) (xy 373.669911 -273.768548)
			(xy 373.719274 -273.776367) (xy 373.766806 -273.791811) (xy 373.811338 -273.814501) (xy 373.851771 -273.843877)
			(xy 373.887111 -273.879217) (xy 373.916487 -273.91965) (xy 373.939177 -273.964182) (xy 373.954621 -274.011714)
			(xy 373.96244 -274.061077) (xy 373.96293 -274.086066) (xy 373.96244 -274.111055) (xy 373.954621 -274.160418)
			(xy 373.939177 -274.20795) (xy 373.916487 -274.252482) (xy 373.887111 -274.292915) (xy 373.851771 -274.328255)
			(xy 373.811338 -274.357631) (xy 373.766806 -274.380321) (xy 373.719274 -274.395765) (xy 373.669911 -274.403584)
			(xy 373.619933 -274.403584) (xy 373.57057 -274.395765) (xy 373.523038 -274.380321) (xy 373.478506 -274.357631)
			(xy 373.438073 -274.328255) (xy 373.402733 -274.292915) (xy 373.373357 -274.252482) (xy 373.350667 -274.20795)
			(xy 373.335223 -274.160418) (xy 373.327404 -274.111055) (xy 373.022386 -274.111055) (xy 373.014567 -274.160418)
			(xy 372.999123 -274.20795) (xy 372.976433 -274.252482) (xy 372.947057 -274.292915) (xy 372.911717 -274.328255)
			(xy 372.871284 -274.357631) (xy 372.826752 -274.380321) (xy 372.77922 -274.395765) (xy 372.729857 -274.403584)
			(xy 372.679879 -274.403584) (xy 372.630516 -274.395765) (xy 372.582984 -274.380321) (xy 372.538452 -274.357631)
			(xy 372.498019 -274.328255) (xy 372.462679 -274.292915) (xy 372.433303 -274.252482) (xy 372.410613 -274.20795)
			(xy 372.395169 -274.160418) (xy 372.38735 -274.111055) (xy 372.082332 -274.111055) (xy 372.074513 -274.160418)
			(xy 372.059069 -274.20795) (xy 372.036379 -274.252482) (xy 372.007003 -274.292915) (xy 371.971663 -274.328255)
			(xy 371.93123 -274.357631) (xy 371.886698 -274.380321) (xy 371.839166 -274.395765) (xy 371.789803 -274.403584)
			(xy 371.739825 -274.403584) (xy 371.690462 -274.395765) (xy 371.64293 -274.380321) (xy 371.598398 -274.357631)
			(xy 371.557965 -274.328255) (xy 371.522625 -274.292915) (xy 371.493249 -274.252482) (xy 371.470559 -274.20795)
			(xy 371.455115 -274.160418) (xy 371.447296 -274.111055) (xy 371.142278 -274.111055) (xy 371.134459 -274.160418)
			(xy 371.119015 -274.20795) (xy 371.096325 -274.252482) (xy 371.066949 -274.292915) (xy 371.031609 -274.328255)
			(xy 370.991176 -274.357631) (xy 370.946644 -274.380321) (xy 370.899112 -274.395765) (xy 370.849749 -274.403584)
			(xy 370.799771 -274.403584) (xy 370.750408 -274.395765) (xy 370.702876 -274.380321) (xy 370.658344 -274.357631)
			(xy 370.617911 -274.328255) (xy 370.582571 -274.292915) (xy 370.553195 -274.252482) (xy 370.530505 -274.20795)
			(xy 370.515061 -274.160418) (xy 370.507242 -274.111055) (xy 370.202224 -274.111055) (xy 370.194405 -274.160418)
			(xy 370.178961 -274.20795) (xy 370.156271 -274.252482) (xy 370.126895 -274.292915) (xy 370.091555 -274.328255)
			(xy 370.051122 -274.357631) (xy 370.00659 -274.380321) (xy 369.959058 -274.395765) (xy 369.909695 -274.403584)
			(xy 369.859717 -274.403584) (xy 369.810354 -274.395765) (xy 369.762822 -274.380321) (xy 369.71829 -274.357631)
			(xy 369.677857 -274.328255) (xy 369.642517 -274.292915) (xy 369.613141 -274.252482) (xy 369.590451 -274.20795)
			(xy 369.575007 -274.160418) (xy 369.567188 -274.111055) (xy 369.262424 -274.111055) (xy 369.254605 -274.160418)
			(xy 369.239161 -274.20795) (xy 369.216471 -274.252482) (xy 369.187095 -274.292915) (xy 369.151755 -274.328255)
			(xy 369.111322 -274.357631) (xy 369.06679 -274.380321) (xy 369.019258 -274.395765) (xy 368.969895 -274.403584)
			(xy 368.919917 -274.403584) (xy 368.870554 -274.395765) (xy 368.823022 -274.380321) (xy 368.77849 -274.357631)
			(xy 368.738057 -274.328255) (xy 368.702717 -274.292915) (xy 368.673341 -274.252482) (xy 368.650651 -274.20795)
			(xy 368.635207 -274.160418) (xy 368.627388 -274.111055) (xy 368.32237 -274.111055) (xy 368.314551 -274.160418)
			(xy 368.299107 -274.20795) (xy 368.276417 -274.252482) (xy 368.247041 -274.292915) (xy 368.211701 -274.328255)
			(xy 368.171268 -274.357631) (xy 368.126736 -274.380321) (xy 368.079204 -274.395765) (xy 368.029841 -274.403584)
			(xy 367.979863 -274.403584) (xy 367.9305 -274.395765) (xy 367.882968 -274.380321) (xy 367.838436 -274.357631)
			(xy 367.798003 -274.328255) (xy 367.762663 -274.292915) (xy 367.733287 -274.252482) (xy 367.710597 -274.20795)
			(xy 367.695153 -274.160418) (xy 367.687334 -274.111055) (xy 367.382316 -274.111055) (xy 367.374497 -274.160418)
			(xy 367.359053 -274.20795) (xy 367.336363 -274.252482) (xy 367.306987 -274.292915) (xy 367.271647 -274.328255)
			(xy 367.231214 -274.357631) (xy 367.186682 -274.380321) (xy 367.13915 -274.395765) (xy 367.089787 -274.403584)
			(xy 367.039809 -274.403584) (xy 366.990446 -274.395765) (xy 366.942914 -274.380321) (xy 366.898382 -274.357631)
			(xy 366.857949 -274.328255) (xy 366.822609 -274.292915) (xy 366.793233 -274.252482) (xy 366.770543 -274.20795)
			(xy 366.755099 -274.160418) (xy 366.74728 -274.111055) (xy 366.442262 -274.111055) (xy 366.434443 -274.160418)
			(xy 366.418999 -274.20795) (xy 366.396309 -274.252482) (xy 366.366933 -274.292915) (xy 366.331593 -274.328255)
			(xy 366.29116 -274.357631) (xy 366.246628 -274.380321) (xy 366.199096 -274.395765) (xy 366.149733 -274.403584)
			(xy 366.099755 -274.403584) (xy 366.050392 -274.395765) (xy 366.00286 -274.380321) (xy 365.958328 -274.357631)
			(xy 365.917895 -274.328255) (xy 365.882555 -274.292915) (xy 365.853179 -274.252482) (xy 365.830489 -274.20795)
			(xy 365.815045 -274.160418) (xy 365.807226 -274.111055) (xy 365.502208 -274.111055) (xy 365.494389 -274.160418)
			(xy 365.478945 -274.20795) (xy 365.456255 -274.252482) (xy 365.426879 -274.292915) (xy 365.391539 -274.328255)
			(xy 365.351106 -274.357631) (xy 365.306574 -274.380321) (xy 365.259042 -274.395765) (xy 365.209679 -274.403584)
			(xy 365.159701 -274.403584) (xy 365.110338 -274.395765) (xy 365.062806 -274.380321) (xy 365.018274 -274.357631)
			(xy 364.977841 -274.328255) (xy 364.942501 -274.292915) (xy 364.913125 -274.252482) (xy 364.890435 -274.20795)
			(xy 364.874991 -274.160418) (xy 364.867172 -274.111055) (xy 364.562408 -274.111055) (xy 364.554589 -274.160418)
			(xy 364.539145 -274.20795) (xy 364.516455 -274.252482) (xy 364.487079 -274.292915) (xy 364.451739 -274.328255)
			(xy 364.411306 -274.357631) (xy 364.366774 -274.380321) (xy 364.319242 -274.395765) (xy 364.269879 -274.403584)
			(xy 364.219901 -274.403584) (xy 364.170538 -274.395765) (xy 364.123006 -274.380321) (xy 364.078474 -274.357631)
			(xy 364.038041 -274.328255) (xy 364.002701 -274.292915) (xy 363.973325 -274.252482) (xy 363.950635 -274.20795)
			(xy 363.935191 -274.160418) (xy 363.927372 -274.111055) (xy 363.620055 -274.111055) (xy 363.620046 -274.111512)
			(xy 363.611882 -274.161746) (xy 363.595766 -274.21002) (xy 363.572115 -274.255083) (xy 363.541542 -274.295769)
			(xy 363.504838 -274.331024) (xy 363.462954 -274.359934) (xy 363.416975 -274.381751) (xy 363.368091 -274.395911)
			(xy 363.31757 -274.402045) (xy 363.266718 -274.399996) (xy 363.216854 -274.389816) (xy 363.169268 -274.371769)
			(xy 363.125194 -274.346323) (xy 363.085772 -274.314136) (xy 363.052024 -274.276042) (xy 363.024823 -274.233028)
			(xy 363.004875 -274.186208) (xy 362.992696 -274.136794) (xy 362.988601 -274.086066) (xy 362.680504 -274.086066)
			(xy 362.679992 -274.111512) (xy 362.671828 -274.161746) (xy 362.655712 -274.21002) (xy 362.632061 -274.255083)
			(xy 362.601488 -274.295769) (xy 362.564784 -274.331024) (xy 362.5229 -274.359934) (xy 362.476921 -274.381751)
			(xy 362.428037 -274.395911) (xy 362.377516 -274.402045) (xy 362.326664 -274.399996) (xy 362.2768 -274.389816)
			(xy 362.229214 -274.371769) (xy 362.18514 -274.346323) (xy 362.145718 -274.314136) (xy 362.11197 -274.276042)
			(xy 362.084769 -274.233028) (xy 362.064821 -274.186208) (xy 362.052642 -274.136794) (xy 362.048547 -274.086066)
			(xy 361.742736 -274.086066) (xy 361.742246 -274.111055) (xy 361.734427 -274.160418) (xy 361.718983 -274.20795)
			(xy 361.696293 -274.252482) (xy 361.666917 -274.292915) (xy 361.631577 -274.328255) (xy 361.591144 -274.357631)
			(xy 361.546612 -274.380321) (xy 361.49908 -274.395765) (xy 361.449717 -274.403584) (xy 361.399739 -274.403584)
			(xy 361.350376 -274.395765) (xy 361.302844 -274.380321) (xy 361.258312 -274.357631) (xy 361.217879 -274.328255)
			(xy 361.182539 -274.292915) (xy 361.153163 -274.252482) (xy 361.130473 -274.20795) (xy 361.115029 -274.160418)
			(xy 361.10721 -274.111055) (xy 358.928688 -274.111055) (xy 358.920869 -274.160418) (xy 358.905425 -274.20795)
			(xy 358.882735 -274.252482) (xy 358.853359 -274.292915) (xy 358.818019 -274.328255) (xy 358.777586 -274.357631)
			(xy 358.733054 -274.380321) (xy 358.685522 -274.395765) (xy 358.636159 -274.403584) (xy 358.586181 -274.403584)
			(xy 358.536818 -274.395765) (xy 358.489286 -274.380321) (xy 358.444754 -274.357631) (xy 358.404321 -274.328255)
			(xy 358.368981 -274.292915) (xy 358.339605 -274.252482) (xy 358.316915 -274.20795) (xy 358.301471 -274.160418)
			(xy 358.293652 -274.111055) (xy 357.986335 -274.111055) (xy 357.986326 -274.111512) (xy 357.978162 -274.161746)
			(xy 357.962046 -274.21002) (xy 357.938395 -274.255083) (xy 357.907822 -274.295769) (xy 357.871118 -274.331024)
			(xy 357.829234 -274.359934) (xy 357.783255 -274.381751) (xy 357.734371 -274.395911) (xy 357.68385 -274.402045)
			(xy 357.632998 -274.399996) (xy 357.583134 -274.389816) (xy 357.535548 -274.371769) (xy 357.491474 -274.346323)
			(xy 357.452052 -274.314136) (xy 357.418304 -274.276042) (xy 357.391103 -274.233028) (xy 357.371155 -274.186208)
			(xy 357.358976 -274.136794) (xy 357.354881 -274.086066) (xy 357.046784 -274.086066) (xy 357.046272 -274.111512)
			(xy 357.038108 -274.161746) (xy 357.021992 -274.21002) (xy 356.998341 -274.255083) (xy 356.967768 -274.295769)
			(xy 356.931064 -274.331024) (xy 356.88918 -274.359934) (xy 356.843201 -274.381751) (xy 356.794317 -274.395911)
			(xy 356.743796 -274.402045) (xy 356.692944 -274.399996) (xy 356.64308 -274.389816) (xy 356.595494 -274.371769)
			(xy 356.55142 -274.346323) (xy 356.511998 -274.314136) (xy 356.47825 -274.276042) (xy 356.451049 -274.233028)
			(xy 356.431101 -274.186208) (xy 356.418922 -274.136794) (xy 356.414827 -274.086066) (xy 356.109016 -274.086066)
			(xy 356.108526 -274.111055) (xy 356.100707 -274.160418) (xy 356.085263 -274.20795) (xy 356.062573 -274.252482)
			(xy 356.033197 -274.292915) (xy 355.997857 -274.328255) (xy 355.957424 -274.357631) (xy 355.912892 -274.380321)
			(xy 355.86536 -274.395765) (xy 355.815997 -274.403584) (xy 355.766019 -274.403584) (xy 355.716656 -274.395765)
			(xy 355.669124 -274.380321) (xy 355.624592 -274.357631) (xy 355.584159 -274.328255) (xy 355.548819 -274.292915)
			(xy 355.519443 -274.252482) (xy 355.496753 -274.20795) (xy 355.481309 -274.160418) (xy 355.47349 -274.111055)
			(xy 355.168726 -274.111055) (xy 355.160907 -274.160418) (xy 355.145463 -274.20795) (xy 355.122773 -274.252482)
			(xy 355.093397 -274.292915) (xy 355.058057 -274.328255) (xy 355.017624 -274.357631) (xy 354.973092 -274.380321)
			(xy 354.92556 -274.395765) (xy 354.876197 -274.403584) (xy 354.826219 -274.403584) (xy 354.776856 -274.395765)
			(xy 354.729324 -274.380321) (xy 354.684792 -274.357631) (xy 354.644359 -274.328255) (xy 354.609019 -274.292915)
			(xy 354.579643 -274.252482) (xy 354.556953 -274.20795) (xy 354.541509 -274.160418) (xy 354.53369 -274.111055)
			(xy 354.228672 -274.111055) (xy 354.220853 -274.160418) (xy 354.205409 -274.20795) (xy 354.182719 -274.252482)
			(xy 354.153343 -274.292915) (xy 354.118003 -274.328255) (xy 354.07757 -274.357631) (xy 354.033038 -274.380321)
			(xy 353.985506 -274.395765) (xy 353.936143 -274.403584) (xy 353.886165 -274.403584) (xy 353.836802 -274.395765)
			(xy 353.78927 -274.380321) (xy 353.744738 -274.357631) (xy 353.704305 -274.328255) (xy 353.668965 -274.292915)
			(xy 353.639589 -274.252482) (xy 353.616899 -274.20795) (xy 353.601455 -274.160418) (xy 353.593636 -274.111055)
			(xy 353.288618 -274.111055) (xy 353.280799 -274.160418) (xy 353.265355 -274.20795) (xy 353.242665 -274.252482)
			(xy 353.213289 -274.292915) (xy 353.177949 -274.328255) (xy 353.137516 -274.357631) (xy 353.092984 -274.380321)
			(xy 353.045452 -274.395765) (xy 352.996089 -274.403584) (xy 352.946111 -274.403584) (xy 352.896748 -274.395765)
			(xy 352.849216 -274.380321) (xy 352.804684 -274.357631) (xy 352.764251 -274.328255) (xy 352.728911 -274.292915)
			(xy 352.699535 -274.252482) (xy 352.676845 -274.20795) (xy 352.661401 -274.160418) (xy 352.653582 -274.111055)
			(xy 352.348564 -274.111055) (xy 352.340745 -274.160418) (xy 352.325301 -274.20795) (xy 352.302611 -274.252482)
			(xy 352.273235 -274.292915) (xy 352.237895 -274.328255) (xy 352.197462 -274.357631) (xy 352.15293 -274.380321)
			(xy 352.105398 -274.395765) (xy 352.056035 -274.403584) (xy 352.006057 -274.403584) (xy 351.956694 -274.395765)
			(xy 351.909162 -274.380321) (xy 351.86463 -274.357631) (xy 351.824197 -274.328255) (xy 351.788857 -274.292915)
			(xy 351.759481 -274.252482) (xy 351.736791 -274.20795) (xy 351.721347 -274.160418) (xy 351.713528 -274.111055)
			(xy 351.408764 -274.111055) (xy 351.400945 -274.160418) (xy 351.385501 -274.20795) (xy 351.362811 -274.252482)
			(xy 351.333435 -274.292915) (xy 351.298095 -274.328255) (xy 351.257662 -274.357631) (xy 351.21313 -274.380321)
			(xy 351.165598 -274.395765) (xy 351.116235 -274.403584) (xy 351.066257 -274.403584) (xy 351.016894 -274.395765)
			(xy 350.969362 -274.380321) (xy 350.92483 -274.357631) (xy 350.884397 -274.328255) (xy 350.849057 -274.292915)
			(xy 350.819681 -274.252482) (xy 350.796991 -274.20795) (xy 350.781547 -274.160418) (xy 350.773728 -274.111055)
			(xy 350.46871 -274.111055) (xy 350.460891 -274.160418) (xy 350.445447 -274.20795) (xy 350.422757 -274.252482)
			(xy 350.393381 -274.292915) (xy 350.358041 -274.328255) (xy 350.317608 -274.357631) (xy 350.273076 -274.380321)
			(xy 350.225544 -274.395765) (xy 350.176181 -274.403584) (xy 350.126203 -274.403584) (xy 350.07684 -274.395765)
			(xy 350.029308 -274.380321) (xy 349.984776 -274.357631) (xy 349.944343 -274.328255) (xy 349.909003 -274.292915)
			(xy 349.879627 -274.252482) (xy 349.856937 -274.20795) (xy 349.841493 -274.160418) (xy 349.833674 -274.111055)
			(xy 349.528656 -274.111055) (xy 349.520837 -274.160418) (xy 349.505393 -274.20795) (xy 349.482703 -274.252482)
			(xy 349.453327 -274.292915) (xy 349.417987 -274.328255) (xy 349.377554 -274.357631) (xy 349.333022 -274.380321)
			(xy 349.28549 -274.395765) (xy 349.236127 -274.403584) (xy 349.186149 -274.403584) (xy 349.136786 -274.395765)
			(xy 349.089254 -274.380321) (xy 349.044722 -274.357631) (xy 349.004289 -274.328255) (xy 348.968949 -274.292915)
			(xy 348.939573 -274.252482) (xy 348.916883 -274.20795) (xy 348.901439 -274.160418) (xy 348.89362 -274.111055)
			(xy 348.588602 -274.111055) (xy 348.580783 -274.160418) (xy 348.565339 -274.20795) (xy 348.542649 -274.252482)
			(xy 348.513273 -274.292915) (xy 348.477933 -274.328255) (xy 348.4375 -274.357631) (xy 348.392968 -274.380321)
			(xy 348.345436 -274.395765) (xy 348.296073 -274.403584) (xy 348.246095 -274.403584) (xy 348.196732 -274.395765)
			(xy 348.1492 -274.380321) (xy 348.104668 -274.357631) (xy 348.064235 -274.328255) (xy 348.028895 -274.292915)
			(xy 347.999519 -274.252482) (xy 347.976829 -274.20795) (xy 347.961385 -274.160418) (xy 347.953566 -274.111055)
			(xy 347.648548 -274.111055) (xy 347.640729 -274.160418) (xy 347.625285 -274.20795) (xy 347.602595 -274.252482)
			(xy 347.573219 -274.292915) (xy 347.537879 -274.328255) (xy 347.497446 -274.357631) (xy 347.452914 -274.380321)
			(xy 347.405382 -274.395765) (xy 347.356019 -274.403584) (xy 347.306041 -274.403584) (xy 347.256678 -274.395765)
			(xy 347.209146 -274.380321) (xy 347.164614 -274.357631) (xy 347.124181 -274.328255) (xy 347.088841 -274.292915)
			(xy 347.059465 -274.252482) (xy 347.036775 -274.20795) (xy 347.021331 -274.160418) (xy 347.013512 -274.111055)
			(xy 346.708748 -274.111055) (xy 346.700929 -274.160418) (xy 346.685485 -274.20795) (xy 346.662795 -274.252482)
			(xy 346.633419 -274.292915) (xy 346.598079 -274.328255) (xy 346.557646 -274.357631) (xy 346.513114 -274.380321)
			(xy 346.465582 -274.395765) (xy 346.416219 -274.403584) (xy 346.366241 -274.403584) (xy 346.316878 -274.395765)
			(xy 346.269346 -274.380321) (xy 346.224814 -274.357631) (xy 346.184381 -274.328255) (xy 346.149041 -274.292915)
			(xy 346.119665 -274.252482) (xy 346.096975 -274.20795) (xy 346.081531 -274.160418) (xy 346.073712 -274.111055)
			(xy 345.768777 -274.111055) (xy 345.768777 -274.111095) (xy 345.760957 -274.16047) (xy 345.745508 -274.208013)
			(xy 345.722812 -274.252554) (xy 345.693428 -274.292996) (xy 345.658078 -274.328343) (xy 345.617634 -274.357725)
			(xy 345.573091 -274.380418) (xy 345.525546 -274.395862) (xy 345.476171 -274.403679) (xy 345.451176 -274.404074)
			(xy 345.427299 -274.403645) (xy 345.38008 -274.396509) (xy 345.334457 -274.382401) (xy 345.291452 -274.361637)
			(xy 345.252031 -274.334683) (xy 345.23426 -274.31873) (xy 345.228657 -274.313864) (xy 345.215365 -274.307277)
			(xy 345.208098 -274.305776) (xy 345.20124 -274.304506) (xy 345.186508 -274.306284) (xy 345.14155 -274.325842)
			(xy 345.096338 -274.345654) (xy 345.087513 -274.350016) (xy 345.073785 -274.364099) (xy 345.066345 -274.382304)
			(xy 345.065858 -274.392136) (xy 345.065858 -274.553426) (xy 345.065858 -274.554696) (xy 345.066511 -274.564089)
			(xy 345.073717 -274.581465) (xy 345.086712 -274.595066) (xy 345.095068 -274.5994) (xy 345.097862 -274.600416)
			(xy 345.120567 -274.609868) (xy 345.162987 -274.634747) (xy 345.20107 -274.665863) (xy 345.233906 -274.702473)
			(xy 345.260712 -274.743703) (xy 345.280848 -274.78857) (xy 345.293834 -274.836003) (xy 345.29936 -274.88487)
			(xy 345.298889 -274.896072) (xy 345.604841 -274.896072) (xy 345.608936 -274.845344) (xy 345.621115 -274.79593)
			(xy 345.641063 -274.74911) (xy 345.668264 -274.706096) (xy 345.702012 -274.668002) (xy 345.741434 -274.635815)
			(xy 345.785508 -274.610369) (xy 345.833094 -274.592322) (xy 345.882958 -274.582142) (xy 345.93381 -274.580093)
			(xy 345.984331 -274.586227) (xy 346.033215 -274.600387) (xy 346.079194 -274.622204) (xy 346.121078 -274.651114)
			(xy 346.157782 -274.686369) (xy 346.188355 -274.727055) (xy 346.212006 -274.772118) (xy 346.228122 -274.820392)
			(xy 346.236286 -274.870626) (xy 346.236798 -274.896072) (xy 346.544895 -274.896072) (xy 346.54899 -274.845344)
			(xy 346.561169 -274.79593) (xy 346.581117 -274.74911) (xy 346.608318 -274.706096) (xy 346.642066 -274.668002)
			(xy 346.681488 -274.635815) (xy 346.725562 -274.610369) (xy 346.773148 -274.592322) (xy 346.823012 -274.582142)
			(xy 346.873864 -274.580093) (xy 346.924385 -274.586227) (xy 346.973269 -274.600387) (xy 347.019248 -274.622204)
			(xy 347.061132 -274.651114) (xy 347.097836 -274.686369) (xy 347.128409 -274.727055) (xy 347.15206 -274.772118)
			(xy 347.168176 -274.820392) (xy 347.17634 -274.870626) (xy 347.176852 -274.896072) (xy 347.176349 -274.921061)
			(xy 347.483666 -274.921061) (xy 347.483666 -274.871083) (xy 347.491485 -274.82172) (xy 347.506929 -274.774188)
			(xy 347.529619 -274.729656) (xy 347.558995 -274.689223) (xy 347.594335 -274.653883) (xy 347.634768 -274.624507)
			(xy 347.6793 -274.601817) (xy 347.726832 -274.586373) (xy 347.776195 -274.578554) (xy 347.826173 -274.578554)
			(xy 347.875536 -274.586373) (xy 347.923068 -274.601817) (xy 347.9676 -274.624507) (xy 348.008033 -274.653883)
			(xy 348.043373 -274.689223) (xy 348.072749 -274.729656) (xy 348.095439 -274.774188) (xy 348.110883 -274.82172)
			(xy 348.118702 -274.871083) (xy 348.119192 -274.896072) (xy 348.425003 -274.896072) (xy 348.429098 -274.845344)
			(xy 348.441277 -274.79593) (xy 348.461225 -274.74911) (xy 348.488426 -274.706096) (xy 348.522174 -274.668002)
			(xy 348.561596 -274.635815) (xy 348.60567 -274.610369) (xy 348.653256 -274.592322) (xy 348.70312 -274.582142)
			(xy 348.753972 -274.580093) (xy 348.804493 -274.586227) (xy 348.853377 -274.600387) (xy 348.899356 -274.622204)
			(xy 348.94124 -274.651114) (xy 348.977944 -274.686369) (xy 349.008517 -274.727055) (xy 349.032168 -274.772118)
			(xy 349.048284 -274.820392) (xy 349.056448 -274.870626) (xy 349.05696 -274.896072) (xy 349.364803 -274.896072)
			(xy 349.368898 -274.845344) (xy 349.381077 -274.79593) (xy 349.401025 -274.74911) (xy 349.428226 -274.706096)
			(xy 349.461974 -274.668002) (xy 349.501396 -274.635815) (xy 349.54547 -274.610369) (xy 349.593056 -274.592322)
			(xy 349.64292 -274.582142) (xy 349.693772 -274.580093) (xy 349.744293 -274.586227) (xy 349.793177 -274.600387)
			(xy 349.839156 -274.622204) (xy 349.88104 -274.651114) (xy 349.917744 -274.686369) (xy 349.948317 -274.727055)
			(xy 349.971968 -274.772118) (xy 349.988084 -274.820392) (xy 349.996248 -274.870626) (xy 349.99676 -274.896072)
			(xy 349.996257 -274.921061) (xy 350.303574 -274.921061) (xy 350.303574 -274.871083) (xy 350.311393 -274.82172)
			(xy 350.326837 -274.774188) (xy 350.349527 -274.729656) (xy 350.378903 -274.689223) (xy 350.414243 -274.653883)
			(xy 350.454676 -274.624507) (xy 350.499208 -274.601817) (xy 350.54674 -274.586373) (xy 350.596103 -274.578554)
			(xy 350.646081 -274.578554) (xy 350.695444 -274.586373) (xy 350.742976 -274.601817) (xy 350.787508 -274.624507)
			(xy 350.827941 -274.653883) (xy 350.863281 -274.689223) (xy 350.892657 -274.729656) (xy 350.915347 -274.774188)
			(xy 350.930791 -274.82172) (xy 350.93861 -274.871083) (xy 350.9391 -274.896072) (xy 351.244911 -274.896072)
			(xy 351.249006 -274.845344) (xy 351.261185 -274.79593) (xy 351.281133 -274.74911) (xy 351.308334 -274.706096)
			(xy 351.342082 -274.668002) (xy 351.381504 -274.635815) (xy 351.425578 -274.610369) (xy 351.473164 -274.592322)
			(xy 351.523028 -274.582142) (xy 351.57388 -274.580093) (xy 351.624401 -274.586227) (xy 351.673285 -274.600387)
			(xy 351.719264 -274.622204) (xy 351.761148 -274.651114) (xy 351.797852 -274.686369) (xy 351.828425 -274.727055)
			(xy 351.852076 -274.772118) (xy 351.868192 -274.820392) (xy 351.876356 -274.870626) (xy 351.876868 -274.896072)
			(xy 352.184965 -274.896072) (xy 352.18906 -274.845344) (xy 352.201239 -274.79593) (xy 352.221187 -274.74911)
			(xy 352.248388 -274.706096) (xy 352.282136 -274.668002) (xy 352.321558 -274.635815) (xy 352.365632 -274.610369)
			(xy 352.413218 -274.592322) (xy 352.463082 -274.582142) (xy 352.513934 -274.580093) (xy 352.564455 -274.586227)
			(xy 352.613339 -274.600387) (xy 352.659318 -274.622204) (xy 352.701202 -274.651114) (xy 352.737906 -274.686369)
			(xy 352.768479 -274.727055) (xy 352.79213 -274.772118) (xy 352.808246 -274.820392) (xy 352.81641 -274.870626)
			(xy 352.816922 -274.896072) (xy 352.816419 -274.921061) (xy 353.123482 -274.921061) (xy 353.123482 -274.871083)
			(xy 353.131301 -274.82172) (xy 353.146745 -274.774188) (xy 353.169435 -274.729656) (xy 353.198811 -274.689223)
			(xy 353.234151 -274.653883) (xy 353.274584 -274.624507) (xy 353.319116 -274.601817) (xy 353.366648 -274.586373)
			(xy 353.416011 -274.578554) (xy 353.465989 -274.578554) (xy 353.515352 -274.586373) (xy 353.562884 -274.601817)
			(xy 353.607416 -274.624507) (xy 353.647849 -274.653883) (xy 353.683189 -274.689223) (xy 353.712565 -274.729656)
			(xy 353.735255 -274.774188) (xy 353.750699 -274.82172) (xy 353.758518 -274.871083) (xy 353.759008 -274.896072)
			(xy 354.064819 -274.896072) (xy 354.068914 -274.845344) (xy 354.081093 -274.79593) (xy 354.101041 -274.74911)
			(xy 354.128242 -274.706096) (xy 354.16199 -274.668002) (xy 354.201412 -274.635815) (xy 354.245486 -274.610369)
			(xy 354.293072 -274.592322) (xy 354.342936 -274.582142) (xy 354.393788 -274.580093) (xy 354.444309 -274.586227)
			(xy 354.493193 -274.600387) (xy 354.539172 -274.622204) (xy 354.581056 -274.651114) (xy 354.61776 -274.686369)
			(xy 354.648333 -274.727055) (xy 354.671984 -274.772118) (xy 354.6881 -274.820392) (xy 354.696264 -274.870626)
			(xy 354.696776 -274.896072) (xy 355.004873 -274.896072) (xy 355.008968 -274.845344) (xy 355.021147 -274.79593)
			(xy 355.041095 -274.74911) (xy 355.068296 -274.706096) (xy 355.102044 -274.668002) (xy 355.141466 -274.635815)
			(xy 355.18554 -274.610369) (xy 355.233126 -274.592322) (xy 355.28299 -274.582142) (xy 355.333842 -274.580093)
			(xy 355.384363 -274.586227) (xy 355.433247 -274.600387) (xy 355.479226 -274.622204) (xy 355.52111 -274.651114)
			(xy 355.557814 -274.686369) (xy 355.588387 -274.727055) (xy 355.612038 -274.772118) (xy 355.628154 -274.820392)
			(xy 355.636318 -274.870626) (xy 355.63683 -274.896072) (xy 355.636327 -274.921061) (xy 355.943644 -274.921061)
			(xy 355.943644 -274.871083) (xy 355.951463 -274.82172) (xy 355.966907 -274.774188) (xy 355.989597 -274.729656)
			(xy 356.018973 -274.689223) (xy 356.054313 -274.653883) (xy 356.094746 -274.624507) (xy 356.139278 -274.601817)
			(xy 356.18681 -274.586373) (xy 356.236173 -274.578554) (xy 356.286151 -274.578554) (xy 356.335514 -274.586373)
			(xy 356.383046 -274.601817) (xy 356.427578 -274.624507) (xy 356.468011 -274.653883) (xy 356.503351 -274.689223)
			(xy 356.532727 -274.729656) (xy 356.555417 -274.774188) (xy 356.570861 -274.82172) (xy 356.57868 -274.871083)
			(xy 356.57917 -274.896072) (xy 356.57868 -274.921061) (xy 363.457218 -274.921061) (xy 363.457218 -274.871083)
			(xy 363.465037 -274.82172) (xy 363.480481 -274.774188) (xy 363.503171 -274.729656) (xy 363.532547 -274.689223)
			(xy 363.567887 -274.653883) (xy 363.60832 -274.624507) (xy 363.652852 -274.601817) (xy 363.700384 -274.586373)
			(xy 363.749747 -274.578554) (xy 363.799725 -274.578554) (xy 363.849088 -274.586373) (xy 363.89662 -274.601817)
			(xy 363.941152 -274.624507) (xy 363.981585 -274.653883) (xy 364.016925 -274.689223) (xy 364.046301 -274.729656)
			(xy 364.068991 -274.774188) (xy 364.084435 -274.82172) (xy 364.092254 -274.871083) (xy 364.092744 -274.896072)
			(xy 364.398555 -274.896072) (xy 364.40265 -274.845344) (xy 364.414829 -274.79593) (xy 364.434777 -274.74911)
			(xy 364.461978 -274.706096) (xy 364.495726 -274.668002) (xy 364.535148 -274.635815) (xy 364.579222 -274.610369)
			(xy 364.626808 -274.592322) (xy 364.676672 -274.582142) (xy 364.727524 -274.580093) (xy 364.778045 -274.586227)
			(xy 364.826929 -274.600387) (xy 364.872908 -274.622204) (xy 364.914792 -274.651114) (xy 364.951496 -274.686369)
			(xy 364.982069 -274.727055) (xy 365.00572 -274.772118) (xy 365.021836 -274.820392) (xy 365.03 -274.870626)
			(xy 365.030512 -274.896072) (xy 365.338609 -274.896072) (xy 365.342704 -274.845344) (xy 365.354883 -274.79593)
			(xy 365.374831 -274.74911) (xy 365.402032 -274.706096) (xy 365.43578 -274.668002) (xy 365.475202 -274.635815)
			(xy 365.519276 -274.610369) (xy 365.566862 -274.592322) (xy 365.616726 -274.582142) (xy 365.667578 -274.580093)
			(xy 365.718099 -274.586227) (xy 365.766983 -274.600387) (xy 365.812962 -274.622204) (xy 365.854846 -274.651114)
			(xy 365.89155 -274.686369) (xy 365.922123 -274.727055) (xy 365.945774 -274.772118) (xy 365.96189 -274.820392)
			(xy 365.970054 -274.870626) (xy 365.970566 -274.896072) (xy 365.970063 -274.921061) (xy 366.27738 -274.921061)
			(xy 366.27738 -274.871083) (xy 366.285199 -274.82172) (xy 366.300643 -274.774188) (xy 366.323333 -274.729656)
			(xy 366.352709 -274.689223) (xy 366.388049 -274.653883) (xy 366.428482 -274.624507) (xy 366.473014 -274.601817)
			(xy 366.520546 -274.586373) (xy 366.569909 -274.578554) (xy 366.619887 -274.578554) (xy 366.66925 -274.586373)
			(xy 366.716782 -274.601817) (xy 366.761314 -274.624507) (xy 366.801747 -274.653883) (xy 366.837087 -274.689223)
			(xy 366.866463 -274.729656) (xy 366.889153 -274.774188) (xy 366.904597 -274.82172) (xy 366.912416 -274.871083)
			(xy 366.912906 -274.896072) (xy 367.218463 -274.896072) (xy 367.222558 -274.845344) (xy 367.234737 -274.79593)
			(xy 367.254685 -274.74911) (xy 367.281886 -274.706096) (xy 367.315634 -274.668002) (xy 367.355056 -274.635815)
			(xy 367.39913 -274.610369) (xy 367.446716 -274.592322) (xy 367.49658 -274.582142) (xy 367.547432 -274.580093)
			(xy 367.597953 -274.586227) (xy 367.646837 -274.600387) (xy 367.692816 -274.622204) (xy 367.7347 -274.651114)
			(xy 367.771404 -274.686369) (xy 367.801977 -274.727055) (xy 367.825628 -274.772118) (xy 367.841744 -274.820392)
			(xy 367.849908 -274.870626) (xy 367.85042 -274.896072) (xy 368.158517 -274.896072) (xy 368.162612 -274.845344)
			(xy 368.174791 -274.79593) (xy 368.194739 -274.74911) (xy 368.22194 -274.706096) (xy 368.255688 -274.668002)
			(xy 368.29511 -274.635815) (xy 368.339184 -274.610369) (xy 368.38677 -274.592322) (xy 368.436634 -274.582142)
			(xy 368.487486 -274.580093) (xy 368.538007 -274.586227) (xy 368.586891 -274.600387) (xy 368.63287 -274.622204)
			(xy 368.674754 -274.651114) (xy 368.711458 -274.686369) (xy 368.742031 -274.727055) (xy 368.765682 -274.772118)
			(xy 368.781798 -274.820392) (xy 368.789962 -274.870626) (xy 368.790474 -274.896072) (xy 368.789971 -274.921061)
			(xy 369.097288 -274.921061) (xy 369.097288 -274.871083) (xy 369.105107 -274.82172) (xy 369.120551 -274.774188)
			(xy 369.143241 -274.729656) (xy 369.172617 -274.689223) (xy 369.207957 -274.653883) (xy 369.24839 -274.624507)
			(xy 369.292922 -274.601817) (xy 369.340454 -274.586373) (xy 369.389817 -274.578554) (xy 369.439795 -274.578554)
			(xy 369.489158 -274.586373) (xy 369.53669 -274.601817) (xy 369.581222 -274.624507) (xy 369.621655 -274.653883)
			(xy 369.656995 -274.689223) (xy 369.686371 -274.729656) (xy 369.709061 -274.774188) (xy 369.724505 -274.82172)
			(xy 369.732324 -274.871083) (xy 369.732814 -274.896072) (xy 370.038625 -274.896072) (xy 370.04272 -274.845344)
			(xy 370.054899 -274.79593) (xy 370.074847 -274.74911) (xy 370.102048 -274.706096) (xy 370.135796 -274.668002)
			(xy 370.175218 -274.635815) (xy 370.219292 -274.610369) (xy 370.266878 -274.592322) (xy 370.316742 -274.582142)
			(xy 370.367594 -274.580093) (xy 370.418115 -274.586227) (xy 370.466999 -274.600387) (xy 370.512978 -274.622204)
			(xy 370.554862 -274.651114) (xy 370.591566 -274.686369) (xy 370.622139 -274.727055) (xy 370.64579 -274.772118)
			(xy 370.661906 -274.820392) (xy 370.67007 -274.870626) (xy 370.670582 -274.896072) (xy 370.978679 -274.896072)
			(xy 370.982774 -274.845344) (xy 370.994953 -274.79593) (xy 371.014901 -274.74911) (xy 371.042102 -274.706096)
			(xy 371.07585 -274.668002) (xy 371.115272 -274.635815) (xy 371.159346 -274.610369) (xy 371.206932 -274.592322)
			(xy 371.256796 -274.582142) (xy 371.307648 -274.580093) (xy 371.358169 -274.586227) (xy 371.407053 -274.600387)
			(xy 371.453032 -274.622204) (xy 371.494916 -274.651114) (xy 371.53162 -274.686369) (xy 371.562193 -274.727055)
			(xy 371.585844 -274.772118) (xy 371.60196 -274.820392) (xy 371.610124 -274.870626) (xy 371.610636 -274.896072)
			(xy 371.610133 -274.921061) (xy 371.917196 -274.921061) (xy 371.917196 -274.871083) (xy 371.925015 -274.82172)
			(xy 371.940459 -274.774188) (xy 371.963149 -274.729656) (xy 371.992525 -274.689223) (xy 372.027865 -274.653883)
			(xy 372.068298 -274.624507) (xy 372.11283 -274.601817) (xy 372.160362 -274.586373) (xy 372.209725 -274.578554)
			(xy 372.259703 -274.578554) (xy 372.309066 -274.586373) (xy 372.356598 -274.601817) (xy 372.40113 -274.624507)
			(xy 372.441563 -274.653883) (xy 372.476903 -274.689223) (xy 372.506279 -274.729656) (xy 372.528969 -274.774188)
			(xy 372.544413 -274.82172) (xy 372.552232 -274.871083) (xy 372.552722 -274.896072) (xy 372.858533 -274.896072)
			(xy 372.862628 -274.845344) (xy 372.874807 -274.79593) (xy 372.894755 -274.74911) (xy 372.921956 -274.706096)
			(xy 372.955704 -274.668002) (xy 372.995126 -274.635815) (xy 373.0392 -274.610369) (xy 373.086786 -274.592322)
			(xy 373.13665 -274.582142) (xy 373.187502 -274.580093) (xy 373.238023 -274.586227) (xy 373.286907 -274.600387)
			(xy 373.332886 -274.622204) (xy 373.37477 -274.651114) (xy 373.411474 -274.686369) (xy 373.442047 -274.727055)
			(xy 373.465698 -274.772118) (xy 373.481814 -274.820392) (xy 373.489978 -274.870626) (xy 373.49049 -274.896072)
			(xy 373.798587 -274.896072) (xy 373.802682 -274.845344) (xy 373.814861 -274.79593) (xy 373.834809 -274.74911)
			(xy 373.86201 -274.706096) (xy 373.895758 -274.668002) (xy 373.93518 -274.635815) (xy 373.979254 -274.610369)
			(xy 374.02684 -274.592322) (xy 374.076704 -274.582142) (xy 374.127556 -274.580093) (xy 374.178077 -274.586227)
			(xy 374.226961 -274.600387) (xy 374.27294 -274.622204) (xy 374.314824 -274.651114) (xy 374.351528 -274.686369)
			(xy 374.382101 -274.727055) (xy 374.405752 -274.772118) (xy 374.421868 -274.820392) (xy 374.430032 -274.870626)
			(xy 374.430544 -274.896072) (xy 374.430032 -274.921518) (xy 374.421868 -274.971752) (xy 374.405752 -275.020026)
			(xy 374.382101 -275.065089) (xy 374.351528 -275.105775) (xy 374.314824 -275.14103) (xy 374.27294 -275.16994)
			(xy 374.226961 -275.191757) (xy 374.178077 -275.205917) (xy 374.127556 -275.212051) (xy 374.076704 -275.210002)
			(xy 374.02684 -275.199822) (xy 373.979254 -275.181775) (xy 373.93518 -275.156329) (xy 373.895758 -275.124142)
			(xy 373.86201 -275.086048) (xy 373.834809 -275.043034) (xy 373.814861 -274.996214) (xy 373.802682 -274.9468)
			(xy 373.798587 -274.896072) (xy 373.49049 -274.896072) (xy 373.489978 -274.921518) (xy 373.481814 -274.971752)
			(xy 373.465698 -275.020026) (xy 373.442047 -275.065089) (xy 373.411474 -275.105775) (xy 373.37477 -275.14103)
			(xy 373.332886 -275.16994) (xy 373.286907 -275.191757) (xy 373.238023 -275.205917) (xy 373.187502 -275.212051)
			(xy 373.13665 -275.210002) (xy 373.086786 -275.199822) (xy 373.0392 -275.181775) (xy 372.995126 -275.156329)
			(xy 372.955704 -275.124142) (xy 372.921956 -275.086048) (xy 372.894755 -275.043034) (xy 372.874807 -274.996214)
			(xy 372.862628 -274.9468) (xy 372.858533 -274.896072) (xy 372.552722 -274.896072) (xy 372.552232 -274.921061)
			(xy 372.544413 -274.970424) (xy 372.528969 -275.017956) (xy 372.506279 -275.062488) (xy 372.476903 -275.102921)
			(xy 372.441563 -275.138261) (xy 372.40113 -275.167637) (xy 372.356598 -275.190327) (xy 372.309066 -275.205771)
			(xy 372.259703 -275.21359) (xy 372.209725 -275.21359) (xy 372.160362 -275.205771) (xy 372.11283 -275.190327)
			(xy 372.068298 -275.167637) (xy 372.027865 -275.138261) (xy 371.992525 -275.102921) (xy 371.963149 -275.062488)
			(xy 371.940459 -275.017956) (xy 371.925015 -274.970424) (xy 371.917196 -274.921061) (xy 371.610133 -274.921061)
			(xy 371.610124 -274.921518) (xy 371.60196 -274.971752) (xy 371.585844 -275.020026) (xy 371.562193 -275.065089)
			(xy 371.53162 -275.105775) (xy 371.494916 -275.14103) (xy 371.453032 -275.16994) (xy 371.407053 -275.191757)
			(xy 371.358169 -275.205917) (xy 371.307648 -275.212051) (xy 371.256796 -275.210002) (xy 371.206932 -275.199822)
			(xy 371.159346 -275.181775) (xy 371.115272 -275.156329) (xy 371.07585 -275.124142) (xy 371.042102 -275.086048)
			(xy 371.014901 -275.043034) (xy 370.994953 -274.996214) (xy 370.982774 -274.9468) (xy 370.978679 -274.896072)
			(xy 370.670582 -274.896072) (xy 370.67007 -274.921518) (xy 370.661906 -274.971752) (xy 370.64579 -275.020026)
			(xy 370.622139 -275.065089) (xy 370.591566 -275.105775) (xy 370.554862 -275.14103) (xy 370.512978 -275.16994)
			(xy 370.466999 -275.191757) (xy 370.418115 -275.205917) (xy 370.367594 -275.212051) (xy 370.316742 -275.210002)
			(xy 370.266878 -275.199822) (xy 370.219292 -275.181775) (xy 370.175218 -275.156329) (xy 370.135796 -275.124142)
			(xy 370.102048 -275.086048) (xy 370.074847 -275.043034) (xy 370.054899 -274.996214) (xy 370.04272 -274.9468)
			(xy 370.038625 -274.896072) (xy 369.732814 -274.896072) (xy 369.732324 -274.921061) (xy 369.724505 -274.970424)
			(xy 369.709061 -275.017956) (xy 369.686371 -275.062488) (xy 369.656995 -275.102921) (xy 369.621655 -275.138261)
			(xy 369.581222 -275.167637) (xy 369.53669 -275.190327) (xy 369.489158 -275.205771) (xy 369.439795 -275.21359)
			(xy 369.389817 -275.21359) (xy 369.340454 -275.205771) (xy 369.292922 -275.190327) (xy 369.24839 -275.167637)
			(xy 369.207957 -275.138261) (xy 369.172617 -275.102921) (xy 369.143241 -275.062488) (xy 369.120551 -275.017956)
			(xy 369.105107 -274.970424) (xy 369.097288 -274.921061) (xy 368.789971 -274.921061) (xy 368.789962 -274.921518)
			(xy 368.781798 -274.971752) (xy 368.765682 -275.020026) (xy 368.742031 -275.065089) (xy 368.711458 -275.105775)
			(xy 368.674754 -275.14103) (xy 368.63287 -275.16994) (xy 368.586891 -275.191757) (xy 368.538007 -275.205917)
			(xy 368.487486 -275.212051) (xy 368.436634 -275.210002) (xy 368.38677 -275.199822) (xy 368.339184 -275.181775)
			(xy 368.29511 -275.156329) (xy 368.255688 -275.124142) (xy 368.22194 -275.086048) (xy 368.194739 -275.043034)
			(xy 368.174791 -274.996214) (xy 368.162612 -274.9468) (xy 368.158517 -274.896072) (xy 367.85042 -274.896072)
			(xy 367.849908 -274.921518) (xy 367.841744 -274.971752) (xy 367.825628 -275.020026) (xy 367.801977 -275.065089)
			(xy 367.771404 -275.105775) (xy 367.7347 -275.14103) (xy 367.692816 -275.16994) (xy 367.646837 -275.191757)
			(xy 367.597953 -275.205917) (xy 367.547432 -275.212051) (xy 367.49658 -275.210002) (xy 367.446716 -275.199822)
			(xy 367.39913 -275.181775) (xy 367.355056 -275.156329) (xy 367.315634 -275.124142) (xy 367.281886 -275.086048)
			(xy 367.254685 -275.043034) (xy 367.234737 -274.996214) (xy 367.222558 -274.9468) (xy 367.218463 -274.896072)
			(xy 366.912906 -274.896072) (xy 366.912416 -274.921061) (xy 366.904597 -274.970424) (xy 366.889153 -275.017956)
			(xy 366.866463 -275.062488) (xy 366.837087 -275.102921) (xy 366.801747 -275.138261) (xy 366.761314 -275.167637)
			(xy 366.716782 -275.190327) (xy 366.66925 -275.205771) (xy 366.619887 -275.21359) (xy 366.569909 -275.21359)
			(xy 366.520546 -275.205771) (xy 366.473014 -275.190327) (xy 366.428482 -275.167637) (xy 366.388049 -275.138261)
			(xy 366.352709 -275.102921) (xy 366.323333 -275.062488) (xy 366.300643 -275.017956) (xy 366.285199 -274.970424)
			(xy 366.27738 -274.921061) (xy 365.970063 -274.921061) (xy 365.970054 -274.921518) (xy 365.96189 -274.971752)
			(xy 365.945774 -275.020026) (xy 365.922123 -275.065089) (xy 365.89155 -275.105775) (xy 365.854846 -275.14103)
			(xy 365.812962 -275.16994) (xy 365.766983 -275.191757) (xy 365.718099 -275.205917) (xy 365.667578 -275.212051)
			(xy 365.616726 -275.210002) (xy 365.566862 -275.199822) (xy 365.519276 -275.181775) (xy 365.475202 -275.156329)
			(xy 365.43578 -275.124142) (xy 365.402032 -275.086048) (xy 365.374831 -275.043034) (xy 365.354883 -274.996214)
			(xy 365.342704 -274.9468) (xy 365.338609 -274.896072) (xy 365.030512 -274.896072) (xy 365.03 -274.921518)
			(xy 365.021836 -274.971752) (xy 365.00572 -275.020026) (xy 364.982069 -275.065089) (xy 364.951496 -275.105775)
			(xy 364.914792 -275.14103) (xy 364.872908 -275.16994) (xy 364.826929 -275.191757) (xy 364.778045 -275.205917)
			(xy 364.727524 -275.212051) (xy 364.676672 -275.210002) (xy 364.626808 -275.199822) (xy 364.579222 -275.181775)
			(xy 364.535148 -275.156329) (xy 364.495726 -275.124142) (xy 364.461978 -275.086048) (xy 364.434777 -275.043034)
			(xy 364.414829 -274.996214) (xy 364.40265 -274.9468) (xy 364.398555 -274.896072) (xy 364.092744 -274.896072)
			(xy 364.092254 -274.921061) (xy 364.084435 -274.970424) (xy 364.068991 -275.017956) (xy 364.046301 -275.062488)
			(xy 364.016925 -275.102921) (xy 363.981585 -275.138261) (xy 363.941152 -275.167637) (xy 363.89662 -275.190327)
			(xy 363.849088 -275.205771) (xy 363.799725 -275.21359) (xy 363.749747 -275.21359) (xy 363.700384 -275.205771)
			(xy 363.652852 -275.190327) (xy 363.60832 -275.167637) (xy 363.567887 -275.138261) (xy 363.532547 -275.102921)
			(xy 363.503171 -275.062488) (xy 363.480481 -275.017956) (xy 363.465037 -274.970424) (xy 363.457218 -274.921061)
			(xy 356.57868 -274.921061) (xy 356.570861 -274.970424) (xy 356.555417 -275.017956) (xy 356.532727 -275.062488)
			(xy 356.503351 -275.102921) (xy 356.468011 -275.138261) (xy 356.427578 -275.167637) (xy 356.383046 -275.190327)
			(xy 356.335514 -275.205771) (xy 356.286151 -275.21359) (xy 356.236173 -275.21359) (xy 356.18681 -275.205771)
			(xy 356.139278 -275.190327) (xy 356.094746 -275.167637) (xy 356.054313 -275.138261) (xy 356.018973 -275.102921)
			(xy 355.989597 -275.062488) (xy 355.966907 -275.017956) (xy 355.951463 -274.970424) (xy 355.943644 -274.921061)
			(xy 355.636327 -274.921061) (xy 355.636318 -274.921518) (xy 355.628154 -274.971752) (xy 355.612038 -275.020026)
			(xy 355.588387 -275.065089) (xy 355.557814 -275.105775) (xy 355.52111 -275.14103) (xy 355.479226 -275.16994)
			(xy 355.433247 -275.191757) (xy 355.384363 -275.205917) (xy 355.333842 -275.212051) (xy 355.28299 -275.210002)
			(xy 355.233126 -275.199822) (xy 355.18554 -275.181775) (xy 355.141466 -275.156329) (xy 355.102044 -275.124142)
			(xy 355.068296 -275.086048) (xy 355.041095 -275.043034) (xy 355.021147 -274.996214) (xy 355.008968 -274.9468)
			(xy 355.004873 -274.896072) (xy 354.696776 -274.896072) (xy 354.696264 -274.921518) (xy 354.6881 -274.971752)
			(xy 354.671984 -275.020026) (xy 354.648333 -275.065089) (xy 354.61776 -275.105775) (xy 354.581056 -275.14103)
			(xy 354.539172 -275.16994) (xy 354.493193 -275.191757) (xy 354.444309 -275.205917) (xy 354.393788 -275.212051)
			(xy 354.342936 -275.210002) (xy 354.293072 -275.199822) (xy 354.245486 -275.181775) (xy 354.201412 -275.156329)
			(xy 354.16199 -275.124142) (xy 354.128242 -275.086048) (xy 354.101041 -275.043034) (xy 354.081093 -274.996214)
			(xy 354.068914 -274.9468) (xy 354.064819 -274.896072) (xy 353.759008 -274.896072) (xy 353.758518 -274.921061)
			(xy 353.750699 -274.970424) (xy 353.735255 -275.017956) (xy 353.712565 -275.062488) (xy 353.683189 -275.102921)
			(xy 353.647849 -275.138261) (xy 353.607416 -275.167637) (xy 353.562884 -275.190327) (xy 353.515352 -275.205771)
			(xy 353.465989 -275.21359) (xy 353.416011 -275.21359) (xy 353.366648 -275.205771) (xy 353.319116 -275.190327)
			(xy 353.274584 -275.167637) (xy 353.234151 -275.138261) (xy 353.198811 -275.102921) (xy 353.169435 -275.062488)
			(xy 353.146745 -275.017956) (xy 353.131301 -274.970424) (xy 353.123482 -274.921061) (xy 352.816419 -274.921061)
			(xy 352.81641 -274.921518) (xy 352.808246 -274.971752) (xy 352.79213 -275.020026) (xy 352.768479 -275.065089)
			(xy 352.737906 -275.105775) (xy 352.701202 -275.14103) (xy 352.659318 -275.16994) (xy 352.613339 -275.191757)
			(xy 352.564455 -275.205917) (xy 352.513934 -275.212051) (xy 352.463082 -275.210002) (xy 352.413218 -275.199822)
			(xy 352.365632 -275.181775) (xy 352.321558 -275.156329) (xy 352.282136 -275.124142) (xy 352.248388 -275.086048)
			(xy 352.221187 -275.043034) (xy 352.201239 -274.996214) (xy 352.18906 -274.9468) (xy 352.184965 -274.896072)
			(xy 351.876868 -274.896072) (xy 351.876356 -274.921518) (xy 351.868192 -274.971752) (xy 351.852076 -275.020026)
			(xy 351.828425 -275.065089) (xy 351.797852 -275.105775) (xy 351.761148 -275.14103) (xy 351.719264 -275.16994)
			(xy 351.673285 -275.191757) (xy 351.624401 -275.205917) (xy 351.57388 -275.212051) (xy 351.523028 -275.210002)
			(xy 351.473164 -275.199822) (xy 351.425578 -275.181775) (xy 351.381504 -275.156329) (xy 351.342082 -275.124142)
			(xy 351.308334 -275.086048) (xy 351.281133 -275.043034) (xy 351.261185 -274.996214) (xy 351.249006 -274.9468)
			(xy 351.244911 -274.896072) (xy 350.9391 -274.896072) (xy 350.93861 -274.921061) (xy 350.930791 -274.970424)
			(xy 350.915347 -275.017956) (xy 350.892657 -275.062488) (xy 350.863281 -275.102921) (xy 350.827941 -275.138261)
			(xy 350.787508 -275.167637) (xy 350.742976 -275.190327) (xy 350.695444 -275.205771) (xy 350.646081 -275.21359)
			(xy 350.596103 -275.21359) (xy 350.54674 -275.205771) (xy 350.499208 -275.190327) (xy 350.454676 -275.167637)
			(xy 350.414243 -275.138261) (xy 350.378903 -275.102921) (xy 350.349527 -275.062488) (xy 350.326837 -275.017956)
			(xy 350.311393 -274.970424) (xy 350.303574 -274.921061) (xy 349.996257 -274.921061) (xy 349.996248 -274.921518)
			(xy 349.988084 -274.971752) (xy 349.971968 -275.020026) (xy 349.948317 -275.065089) (xy 349.917744 -275.105775)
			(xy 349.88104 -275.14103) (xy 349.839156 -275.16994) (xy 349.793177 -275.191757) (xy 349.744293 -275.205917)
			(xy 349.693772 -275.212051) (xy 349.64292 -275.210002) (xy 349.593056 -275.199822) (xy 349.54547 -275.181775)
			(xy 349.501396 -275.156329) (xy 349.461974 -275.124142) (xy 349.428226 -275.086048) (xy 349.401025 -275.043034)
			(xy 349.381077 -274.996214) (xy 349.368898 -274.9468) (xy 349.364803 -274.896072) (xy 349.05696 -274.896072)
			(xy 349.056448 -274.921518) (xy 349.048284 -274.971752) (xy 349.032168 -275.020026) (xy 349.008517 -275.065089)
			(xy 348.977944 -275.105775) (xy 348.94124 -275.14103) (xy 348.899356 -275.16994) (xy 348.853377 -275.191757)
			(xy 348.804493 -275.205917) (xy 348.753972 -275.212051) (xy 348.70312 -275.210002) (xy 348.653256 -275.199822)
			(xy 348.60567 -275.181775) (xy 348.561596 -275.156329) (xy 348.522174 -275.124142) (xy 348.488426 -275.086048)
			(xy 348.461225 -275.043034) (xy 348.441277 -274.996214) (xy 348.429098 -274.9468) (xy 348.425003 -274.896072)
			(xy 348.119192 -274.896072) (xy 348.118702 -274.921061) (xy 348.110883 -274.970424) (xy 348.095439 -275.017956)
			(xy 348.072749 -275.062488) (xy 348.043373 -275.102921) (xy 348.008033 -275.138261) (xy 347.9676 -275.167637)
			(xy 347.923068 -275.190327) (xy 347.875536 -275.205771) (xy 347.826173 -275.21359) (xy 347.776195 -275.21359)
			(xy 347.726832 -275.205771) (xy 347.6793 -275.190327) (xy 347.634768 -275.167637) (xy 347.594335 -275.138261)
			(xy 347.558995 -275.102921) (xy 347.529619 -275.062488) (xy 347.506929 -275.017956) (xy 347.491485 -274.970424)
			(xy 347.483666 -274.921061) (xy 347.176349 -274.921061) (xy 347.17634 -274.921518) (xy 347.168176 -274.971752)
			(xy 347.15206 -275.020026) (xy 347.128409 -275.065089) (xy 347.097836 -275.105775) (xy 347.061132 -275.14103)
			(xy 347.019248 -275.16994) (xy 346.973269 -275.191757) (xy 346.924385 -275.205917) (xy 346.873864 -275.212051)
			(xy 346.823012 -275.210002) (xy 346.773148 -275.199822) (xy 346.725562 -275.181775) (xy 346.681488 -275.156329)
			(xy 346.642066 -275.124142) (xy 346.608318 -275.086048) (xy 346.581117 -275.043034) (xy 346.561169 -274.996214)
			(xy 346.54899 -274.9468) (xy 346.544895 -274.896072) (xy 346.236798 -274.896072) (xy 346.236286 -274.921518)
			(xy 346.228122 -274.971752) (xy 346.212006 -275.020026) (xy 346.188355 -275.065089) (xy 346.157782 -275.105775)
			(xy 346.121078 -275.14103) (xy 346.079194 -275.16994) (xy 346.033215 -275.191757) (xy 345.984331 -275.205917)
			(xy 345.93381 -275.212051) (xy 345.882958 -275.210002) (xy 345.833094 -275.199822) (xy 345.785508 -275.181775)
			(xy 345.741434 -275.156329) (xy 345.702012 -275.124142) (xy 345.668264 -275.086048) (xy 345.641063 -275.043034)
			(xy 345.621115 -274.996214) (xy 345.608936 -274.9468) (xy 345.604841 -274.896072) (xy 345.298889 -274.896072)
			(xy 345.297293 -274.934005) (xy 345.287684 -274.982235) (xy 345.270761 -275.02841) (xy 345.246929 -275.071428)
			(xy 345.232228 -275.091144) (xy 345.214388 -275.113114) (xy 345.172314 -275.150956) (xy 345.124197 -275.180739)
			(xy 345.098116 -275.191728) (xy 345.097862 -275.191728) (xy 345.095068 -275.192744) (xy 345.086742 -275.197127)
			(xy 345.073745 -275.21071) (xy 345.066512 -275.228062) (xy 345.065858 -275.237448) (xy 345.065858 -275.731067)
			(xy 347.013512 -275.731067) (xy 347.013512 -275.681089) (xy 347.021331 -275.631726) (xy 347.036775 -275.584194)
			(xy 347.059465 -275.539662) (xy 347.088841 -275.499229) (xy 347.124181 -275.463889) (xy 347.164614 -275.434513)
			(xy 347.209146 -275.411823) (xy 347.256678 -275.396379) (xy 347.306041 -275.38856) (xy 347.356019 -275.38856)
			(xy 347.405382 -275.396379) (xy 347.452914 -275.411823) (xy 347.497446 -275.434513) (xy 347.537879 -275.463889)
			(xy 347.573219 -275.499229) (xy 347.602595 -275.539662) (xy 347.625285 -275.584194) (xy 347.640729 -275.631726)
			(xy 347.648548 -275.681089) (xy 347.649038 -275.706078) (xy 347.648548 -275.731067) (xy 349.833674 -275.731067)
			(xy 349.833674 -275.681089) (xy 349.841493 -275.631726) (xy 349.856937 -275.584194) (xy 349.879627 -275.539662)
			(xy 349.909003 -275.499229) (xy 349.944343 -275.463889) (xy 349.984776 -275.434513) (xy 350.029308 -275.411823)
			(xy 350.07684 -275.396379) (xy 350.126203 -275.38856) (xy 350.176181 -275.38856) (xy 350.225544 -275.396379)
			(xy 350.273076 -275.411823) (xy 350.317608 -275.434513) (xy 350.358041 -275.463889) (xy 350.393381 -275.499229)
			(xy 350.422757 -275.539662) (xy 350.445447 -275.584194) (xy 350.460891 -275.631726) (xy 350.46871 -275.681089)
			(xy 350.4692 -275.706078) (xy 350.46871 -275.731067) (xy 352.653582 -275.731067) (xy 352.653582 -275.681089)
			(xy 352.661401 -275.631726) (xy 352.676845 -275.584194) (xy 352.699535 -275.539662) (xy 352.728911 -275.499229)
			(xy 352.764251 -275.463889) (xy 352.804684 -275.434513) (xy 352.849216 -275.411823) (xy 352.896748 -275.396379)
			(xy 352.946111 -275.38856) (xy 352.996089 -275.38856) (xy 353.045452 -275.396379) (xy 353.092984 -275.411823)
			(xy 353.137516 -275.434513) (xy 353.177949 -275.463889) (xy 353.213289 -275.499229) (xy 353.242665 -275.539662)
			(xy 353.265355 -275.584194) (xy 353.280799 -275.631726) (xy 353.288618 -275.681089) (xy 353.289108 -275.706078)
			(xy 353.288618 -275.731067) (xy 355.47349 -275.731067) (xy 355.47349 -275.681089) (xy 355.481309 -275.631726)
			(xy 355.496753 -275.584194) (xy 355.519443 -275.539662) (xy 355.548819 -275.499229) (xy 355.584159 -275.463889)
			(xy 355.624592 -275.434513) (xy 355.669124 -275.411823) (xy 355.716656 -275.396379) (xy 355.766019 -275.38856)
			(xy 355.815997 -275.38856) (xy 355.86536 -275.396379) (xy 355.912892 -275.411823) (xy 355.957424 -275.434513)
			(xy 355.997857 -275.463889) (xy 356.033197 -275.499229) (xy 356.062573 -275.539662) (xy 356.085263 -275.584194)
			(xy 356.100707 -275.631726) (xy 356.108526 -275.681089) (xy 356.109016 -275.706078) (xy 356.414827 -275.706078)
			(xy 356.418922 -275.65535) (xy 356.431101 -275.605936) (xy 356.451049 -275.559116) (xy 356.47825 -275.516102)
			(xy 356.511998 -275.478008) (xy 356.55142 -275.445821) (xy 356.595494 -275.420375) (xy 356.64308 -275.402328)
			(xy 356.692944 -275.392148) (xy 356.743796 -275.390099) (xy 356.794317 -275.396233) (xy 356.843201 -275.410393)
			(xy 356.88918 -275.43221) (xy 356.931064 -275.46112) (xy 356.967768 -275.496375) (xy 356.998341 -275.537061)
			(xy 357.021992 -275.582124) (xy 357.038108 -275.630398) (xy 357.046272 -275.680632) (xy 357.046784 -275.706078)
			(xy 357.354881 -275.706078) (xy 357.358976 -275.65535) (xy 357.371155 -275.605936) (xy 357.391103 -275.559116)
			(xy 357.418304 -275.516102) (xy 357.452052 -275.478008) (xy 357.491474 -275.445821) (xy 357.535548 -275.420375)
			(xy 357.583134 -275.402328) (xy 357.632998 -275.392148) (xy 357.68385 -275.390099) (xy 357.734371 -275.396233)
			(xy 357.783255 -275.410393) (xy 357.829234 -275.43221) (xy 357.871118 -275.46112) (xy 357.907822 -275.496375)
			(xy 357.938395 -275.537061) (xy 357.962046 -275.582124) (xy 357.978162 -275.630398) (xy 357.986326 -275.680632)
			(xy 357.986838 -275.706078) (xy 357.986335 -275.731067) (xy 358.293652 -275.731067) (xy 358.293652 -275.681089)
			(xy 358.301471 -275.631726) (xy 358.316915 -275.584194) (xy 358.339605 -275.539662) (xy 358.368981 -275.499229)
			(xy 358.404321 -275.463889) (xy 358.444754 -275.434513) (xy 358.489286 -275.411823) (xy 358.536818 -275.396379)
			(xy 358.586181 -275.38856) (xy 358.636159 -275.38856) (xy 358.685522 -275.396379) (xy 358.733054 -275.411823)
			(xy 358.777586 -275.434513) (xy 358.818019 -275.463889) (xy 358.853359 -275.499229) (xy 358.882735 -275.539662)
			(xy 358.905425 -275.584194) (xy 358.920869 -275.631726) (xy 358.928688 -275.681089) (xy 358.929178 -275.706078)
			(xy 358.928688 -275.731067) (xy 361.10721 -275.731067) (xy 361.10721 -275.681089) (xy 361.115029 -275.631726)
			(xy 361.130473 -275.584194) (xy 361.153163 -275.539662) (xy 361.182539 -275.499229) (xy 361.217879 -275.463889)
			(xy 361.258312 -275.434513) (xy 361.302844 -275.411823) (xy 361.350376 -275.396379) (xy 361.399739 -275.38856)
			(xy 361.449717 -275.38856) (xy 361.49908 -275.396379) (xy 361.546612 -275.411823) (xy 361.591144 -275.434513)
			(xy 361.631577 -275.463889) (xy 361.666917 -275.499229) (xy 361.696293 -275.539662) (xy 361.718983 -275.584194)
			(xy 361.734427 -275.631726) (xy 361.742246 -275.681089) (xy 361.742736 -275.706078) (xy 362.048547 -275.706078)
			(xy 362.052642 -275.65535) (xy 362.064821 -275.605936) (xy 362.084769 -275.559116) (xy 362.11197 -275.516102)
			(xy 362.145718 -275.478008) (xy 362.18514 -275.445821) (xy 362.229214 -275.420375) (xy 362.2768 -275.402328)
			(xy 362.326664 -275.392148) (xy 362.377516 -275.390099) (xy 362.428037 -275.396233) (xy 362.476921 -275.410393)
			(xy 362.5229 -275.43221) (xy 362.564784 -275.46112) (xy 362.601488 -275.496375) (xy 362.632061 -275.537061)
			(xy 362.655712 -275.582124) (xy 362.671828 -275.630398) (xy 362.679992 -275.680632) (xy 362.680504 -275.706078)
			(xy 362.988601 -275.706078) (xy 362.992696 -275.65535) (xy 363.004875 -275.605936) (xy 363.024823 -275.559116)
			(xy 363.052024 -275.516102) (xy 363.085772 -275.478008) (xy 363.125194 -275.445821) (xy 363.169268 -275.420375)
			(xy 363.216854 -275.402328) (xy 363.266718 -275.392148) (xy 363.31757 -275.390099) (xy 363.368091 -275.396233)
			(xy 363.416975 -275.410393) (xy 363.462954 -275.43221) (xy 363.504838 -275.46112) (xy 363.541542 -275.496375)
			(xy 363.572115 -275.537061) (xy 363.595766 -275.582124) (xy 363.611882 -275.630398) (xy 363.620046 -275.680632)
			(xy 363.620558 -275.706078) (xy 363.620055 -275.731067) (xy 363.927372 -275.731067) (xy 363.927372 -275.681089)
			(xy 363.935191 -275.631726) (xy 363.950635 -275.584194) (xy 363.973325 -275.539662) (xy 364.002701 -275.499229)
			(xy 364.038041 -275.463889) (xy 364.078474 -275.434513) (xy 364.123006 -275.411823) (xy 364.170538 -275.396379)
			(xy 364.219901 -275.38856) (xy 364.269879 -275.38856) (xy 364.319242 -275.396379) (xy 364.366774 -275.411823)
			(xy 364.411306 -275.434513) (xy 364.451739 -275.463889) (xy 364.487079 -275.499229) (xy 364.516455 -275.539662)
			(xy 364.539145 -275.584194) (xy 364.554589 -275.631726) (xy 364.562408 -275.681089) (xy 364.562898 -275.706078)
			(xy 364.562408 -275.731067) (xy 366.74728 -275.731067) (xy 366.74728 -275.681089) (xy 366.755099 -275.631726)
			(xy 366.770543 -275.584194) (xy 366.793233 -275.539662) (xy 366.822609 -275.499229) (xy 366.857949 -275.463889)
			(xy 366.898382 -275.434513) (xy 366.942914 -275.411823) (xy 366.990446 -275.396379) (xy 367.039809 -275.38856)
			(xy 367.089787 -275.38856) (xy 367.13915 -275.396379) (xy 367.186682 -275.411823) (xy 367.231214 -275.434513)
			(xy 367.271647 -275.463889) (xy 367.306987 -275.499229) (xy 367.336363 -275.539662) (xy 367.359053 -275.584194)
			(xy 367.374497 -275.631726) (xy 367.382316 -275.681089) (xy 367.382806 -275.706078) (xy 367.382316 -275.731067)
			(xy 369.567188 -275.731067) (xy 369.567188 -275.681089) (xy 369.575007 -275.631726) (xy 369.590451 -275.584194)
			(xy 369.613141 -275.539662) (xy 369.642517 -275.499229) (xy 369.677857 -275.463889) (xy 369.71829 -275.434513)
			(xy 369.762822 -275.411823) (xy 369.810354 -275.396379) (xy 369.859717 -275.38856) (xy 369.909695 -275.38856)
			(xy 369.959058 -275.396379) (xy 370.00659 -275.411823) (xy 370.051122 -275.434513) (xy 370.091555 -275.463889)
			(xy 370.126895 -275.499229) (xy 370.156271 -275.539662) (xy 370.178961 -275.584194) (xy 370.194405 -275.631726)
			(xy 370.202224 -275.681089) (xy 370.202714 -275.706078) (xy 370.202224 -275.731067) (xy 372.38735 -275.731067)
			(xy 372.38735 -275.681089) (xy 372.395169 -275.631726) (xy 372.410613 -275.584194) (xy 372.433303 -275.539662)
			(xy 372.462679 -275.499229) (xy 372.498019 -275.463889) (xy 372.538452 -275.434513) (xy 372.582984 -275.411823)
			(xy 372.630516 -275.396379) (xy 372.679879 -275.38856) (xy 372.729857 -275.38856) (xy 372.77922 -275.396379)
			(xy 372.826752 -275.411823) (xy 372.871284 -275.434513) (xy 372.911717 -275.463889) (xy 372.947057 -275.499229)
			(xy 372.976433 -275.539662) (xy 372.999123 -275.584194) (xy 373.014567 -275.631726) (xy 373.022386 -275.681089)
			(xy 373.022876 -275.706078) (xy 373.022386 -275.731067) (xy 373.014567 -275.78043) (xy 372.999123 -275.827962)
			(xy 372.976433 -275.872494) (xy 372.947057 -275.912927) (xy 372.911717 -275.948267) (xy 372.871284 -275.977643)
			(xy 372.826752 -276.000333) (xy 372.77922 -276.015777) (xy 372.729857 -276.023596) (xy 372.679879 -276.023596)
			(xy 372.630516 -276.015777) (xy 372.582984 -276.000333) (xy 372.538452 -275.977643) (xy 372.498019 -275.948267)
			(xy 372.462679 -275.912927) (xy 372.433303 -275.872494) (xy 372.410613 -275.827962) (xy 372.395169 -275.78043)
			(xy 372.38735 -275.731067) (xy 370.202224 -275.731067) (xy 370.194405 -275.78043) (xy 370.178961 -275.827962)
			(xy 370.156271 -275.872494) (xy 370.126895 -275.912927) (xy 370.091555 -275.948267) (xy 370.051122 -275.977643)
			(xy 370.00659 -276.000333) (xy 369.959058 -276.015777) (xy 369.909695 -276.023596) (xy 369.859717 -276.023596)
			(xy 369.810354 -276.015777) (xy 369.762822 -276.000333) (xy 369.71829 -275.977643) (xy 369.677857 -275.948267)
			(xy 369.642517 -275.912927) (xy 369.613141 -275.872494) (xy 369.590451 -275.827962) (xy 369.575007 -275.78043)
			(xy 369.567188 -275.731067) (xy 367.382316 -275.731067) (xy 367.374497 -275.78043) (xy 367.359053 -275.827962)
			(xy 367.336363 -275.872494) (xy 367.306987 -275.912927) (xy 367.271647 -275.948267) (xy 367.231214 -275.977643)
			(xy 367.186682 -276.000333) (xy 367.13915 -276.015777) (xy 367.089787 -276.023596) (xy 367.039809 -276.023596)
			(xy 366.990446 -276.015777) (xy 366.942914 -276.000333) (xy 366.898382 -275.977643) (xy 366.857949 -275.948267)
			(xy 366.822609 -275.912927) (xy 366.793233 -275.872494) (xy 366.770543 -275.827962) (xy 366.755099 -275.78043)
			(xy 366.74728 -275.731067) (xy 364.562408 -275.731067) (xy 364.554589 -275.78043) (xy 364.539145 -275.827962)
			(xy 364.516455 -275.872494) (xy 364.487079 -275.912927) (xy 364.451739 -275.948267) (xy 364.411306 -275.977643)
			(xy 364.366774 -276.000333) (xy 364.319242 -276.015777) (xy 364.269879 -276.023596) (xy 364.219901 -276.023596)
			(xy 364.170538 -276.015777) (xy 364.123006 -276.000333) (xy 364.078474 -275.977643) (xy 364.038041 -275.948267)
			(xy 364.002701 -275.912927) (xy 363.973325 -275.872494) (xy 363.950635 -275.827962) (xy 363.935191 -275.78043)
			(xy 363.927372 -275.731067) (xy 363.620055 -275.731067) (xy 363.620046 -275.731524) (xy 363.611882 -275.781758)
			(xy 363.595766 -275.830032) (xy 363.572115 -275.875095) (xy 363.541542 -275.915781) (xy 363.504838 -275.951036)
			(xy 363.462954 -275.979946) (xy 363.416975 -276.001763) (xy 363.368091 -276.015923) (xy 363.31757 -276.022057)
			(xy 363.266718 -276.020008) (xy 363.216854 -276.009828) (xy 363.169268 -275.991781) (xy 363.125194 -275.966335)
			(xy 363.085772 -275.934148) (xy 363.052024 -275.896054) (xy 363.024823 -275.85304) (xy 363.004875 -275.80622)
			(xy 362.992696 -275.756806) (xy 362.988601 -275.706078) (xy 362.680504 -275.706078) (xy 362.679992 -275.731524)
			(xy 362.671828 -275.781758) (xy 362.655712 -275.830032) (xy 362.632061 -275.875095) (xy 362.601488 -275.915781)
			(xy 362.564784 -275.951036) (xy 362.5229 -275.979946) (xy 362.476921 -276.001763) (xy 362.428037 -276.015923)
			(xy 362.377516 -276.022057) (xy 362.326664 -276.020008) (xy 362.2768 -276.009828) (xy 362.229214 -275.991781)
			(xy 362.18514 -275.966335) (xy 362.145718 -275.934148) (xy 362.11197 -275.896054) (xy 362.084769 -275.85304)
			(xy 362.064821 -275.80622) (xy 362.052642 -275.756806) (xy 362.048547 -275.706078) (xy 361.742736 -275.706078)
			(xy 361.742246 -275.731067) (xy 361.734427 -275.78043) (xy 361.718983 -275.827962) (xy 361.696293 -275.872494)
			(xy 361.666917 -275.912927) (xy 361.631577 -275.948267) (xy 361.591144 -275.977643) (xy 361.546612 -276.000333)
			(xy 361.49908 -276.015777) (xy 361.449717 -276.023596) (xy 361.399739 -276.023596) (xy 361.350376 -276.015777)
			(xy 361.302844 -276.000333) (xy 361.258312 -275.977643) (xy 361.217879 -275.948267) (xy 361.182539 -275.912927)
			(xy 361.153163 -275.872494) (xy 361.130473 -275.827962) (xy 361.115029 -275.78043) (xy 361.10721 -275.731067)
			(xy 358.928688 -275.731067) (xy 358.920869 -275.78043) (xy 358.905425 -275.827962) (xy 358.882735 -275.872494)
			(xy 358.853359 -275.912927) (xy 358.818019 -275.948267) (xy 358.777586 -275.977643) (xy 358.733054 -276.000333)
			(xy 358.685522 -276.015777) (xy 358.636159 -276.023596) (xy 358.586181 -276.023596) (xy 358.536818 -276.015777)
			(xy 358.489286 -276.000333) (xy 358.444754 -275.977643) (xy 358.404321 -275.948267) (xy 358.368981 -275.912927)
			(xy 358.339605 -275.872494) (xy 358.316915 -275.827962) (xy 358.301471 -275.78043) (xy 358.293652 -275.731067)
			(xy 357.986335 -275.731067) (xy 357.986326 -275.731524) (xy 357.978162 -275.781758) (xy 357.962046 -275.830032)
			(xy 357.938395 -275.875095) (xy 357.907822 -275.915781) (xy 357.871118 -275.951036) (xy 357.829234 -275.979946)
			(xy 357.783255 -276.001763) (xy 357.734371 -276.015923) (xy 357.68385 -276.022057) (xy 357.632998 -276.020008)
			(xy 357.583134 -276.009828) (xy 357.535548 -275.991781) (xy 357.491474 -275.966335) (xy 357.452052 -275.934148)
			(xy 357.418304 -275.896054) (xy 357.391103 -275.85304) (xy 357.371155 -275.80622) (xy 357.358976 -275.756806)
			(xy 357.354881 -275.706078) (xy 357.046784 -275.706078) (xy 357.046272 -275.731524) (xy 357.038108 -275.781758)
			(xy 357.021992 -275.830032) (xy 356.998341 -275.875095) (xy 356.967768 -275.915781) (xy 356.931064 -275.951036)
			(xy 356.88918 -275.979946) (xy 356.843201 -276.001763) (xy 356.794317 -276.015923) (xy 356.743796 -276.022057)
			(xy 356.692944 -276.020008) (xy 356.64308 -276.009828) (xy 356.595494 -275.991781) (xy 356.55142 -275.966335)
			(xy 356.511998 -275.934148) (xy 356.47825 -275.896054) (xy 356.451049 -275.85304) (xy 356.431101 -275.80622)
			(xy 356.418922 -275.756806) (xy 356.414827 -275.706078) (xy 356.109016 -275.706078) (xy 356.108526 -275.731067)
			(xy 356.100707 -275.78043) (xy 356.085263 -275.827962) (xy 356.062573 -275.872494) (xy 356.033197 -275.912927)
			(xy 355.997857 -275.948267) (xy 355.957424 -275.977643) (xy 355.912892 -276.000333) (xy 355.86536 -276.015777)
			(xy 355.815997 -276.023596) (xy 355.766019 -276.023596) (xy 355.716656 -276.015777) (xy 355.669124 -276.000333)
			(xy 355.624592 -275.977643) (xy 355.584159 -275.948267) (xy 355.548819 -275.912927) (xy 355.519443 -275.872494)
			(xy 355.496753 -275.827962) (xy 355.481309 -275.78043) (xy 355.47349 -275.731067) (xy 353.288618 -275.731067)
			(xy 353.280799 -275.78043) (xy 353.265355 -275.827962) (xy 353.242665 -275.872494) (xy 353.213289 -275.912927)
			(xy 353.177949 -275.948267) (xy 353.137516 -275.977643) (xy 353.092984 -276.000333) (xy 353.045452 -276.015777)
			(xy 352.996089 -276.023596) (xy 352.946111 -276.023596) (xy 352.896748 -276.015777) (xy 352.849216 -276.000333)
			(xy 352.804684 -275.977643) (xy 352.764251 -275.948267) (xy 352.728911 -275.912927) (xy 352.699535 -275.872494)
			(xy 352.676845 -275.827962) (xy 352.661401 -275.78043) (xy 352.653582 -275.731067) (xy 350.46871 -275.731067)
			(xy 350.460891 -275.78043) (xy 350.445447 -275.827962) (xy 350.422757 -275.872494) (xy 350.393381 -275.912927)
			(xy 350.358041 -275.948267) (xy 350.317608 -275.977643) (xy 350.273076 -276.000333) (xy 350.225544 -276.015777)
			(xy 350.176181 -276.023596) (xy 350.126203 -276.023596) (xy 350.07684 -276.015777) (xy 350.029308 -276.000333)
			(xy 349.984776 -275.977643) (xy 349.944343 -275.948267) (xy 349.909003 -275.912927) (xy 349.879627 -275.872494)
			(xy 349.856937 -275.827962) (xy 349.841493 -275.78043) (xy 349.833674 -275.731067) (xy 347.648548 -275.731067)
			(xy 347.640729 -275.78043) (xy 347.625285 -275.827962) (xy 347.602595 -275.872494) (xy 347.573219 -275.912927)
			(xy 347.537879 -275.948267) (xy 347.497446 -275.977643) (xy 347.452914 -276.000333) (xy 347.405382 -276.015777)
			(xy 347.356019 -276.023596) (xy 347.306041 -276.023596) (xy 347.256678 -276.015777) (xy 347.209146 -276.000333)
			(xy 347.164614 -275.977643) (xy 347.124181 -275.948267) (xy 347.088841 -275.912927) (xy 347.059465 -275.872494)
			(xy 347.036775 -275.827962) (xy 347.021331 -275.78043) (xy 347.013512 -275.731067) (xy 345.065858 -275.731067)
			(xy 345.065858 -276.173438) (xy 345.065858 -276.174708) (xy 345.066513 -276.184099) (xy 345.073722 -276.201472)
			(xy 345.086717 -276.21507) (xy 345.095068 -276.219412) (xy 345.097862 -276.220428) (xy 345.120566 -276.22988)
			(xy 345.162985 -276.254759) (xy 345.201066 -276.285875) (xy 345.233901 -276.322485) (xy 345.260705 -276.363714)
			(xy 345.28084 -276.40858) (xy 345.293825 -276.456012) (xy 345.299349 -276.504878) (xy 345.298877 -276.516084)
			(xy 345.604841 -276.516084) (xy 345.608936 -276.465356) (xy 345.621115 -276.415942) (xy 345.641063 -276.369122)
			(xy 345.668264 -276.326108) (xy 345.702012 -276.288014) (xy 345.741434 -276.255827) (xy 345.785508 -276.230381)
			(xy 345.833094 -276.212334) (xy 345.882958 -276.202154) (xy 345.93381 -276.200105) (xy 345.984331 -276.206239)
			(xy 346.033215 -276.220399) (xy 346.079194 -276.242216) (xy 346.121078 -276.271126) (xy 346.157782 -276.306381)
			(xy 346.188355 -276.347067) (xy 346.212006 -276.39213) (xy 346.228122 -276.440404) (xy 346.236286 -276.490638)
			(xy 346.236798 -276.516084) (xy 346.544895 -276.516084) (xy 346.54899 -276.465356) (xy 346.561169 -276.415942)
			(xy 346.581117 -276.369122) (xy 346.608318 -276.326108) (xy 346.642066 -276.288014) (xy 346.681488 -276.255827)
			(xy 346.725562 -276.230381) (xy 346.773148 -276.212334) (xy 346.823012 -276.202154) (xy 346.873864 -276.200105)
			(xy 346.924385 -276.206239) (xy 346.973269 -276.220399) (xy 347.019248 -276.242216) (xy 347.061132 -276.271126)
			(xy 347.097836 -276.306381) (xy 347.128409 -276.347067) (xy 347.15206 -276.39213) (xy 347.168176 -276.440404)
			(xy 347.17634 -276.490638) (xy 347.176852 -276.516084) (xy 347.176349 -276.541073) (xy 347.483666 -276.541073)
			(xy 347.483666 -276.491095) (xy 347.491485 -276.441732) (xy 347.506929 -276.3942) (xy 347.529619 -276.349668)
			(xy 347.558995 -276.309235) (xy 347.594335 -276.273895) (xy 347.634768 -276.244519) (xy 347.6793 -276.221829)
			(xy 347.726832 -276.206385) (xy 347.776195 -276.198566) (xy 347.826173 -276.198566) (xy 347.875536 -276.206385)
			(xy 347.923068 -276.221829) (xy 347.9676 -276.244519) (xy 348.008033 -276.273895) (xy 348.043373 -276.309235)
			(xy 348.072749 -276.349668) (xy 348.095439 -276.3942) (xy 348.110883 -276.441732) (xy 348.118702 -276.491095)
			(xy 348.119192 -276.516084) (xy 348.425003 -276.516084) (xy 348.429098 -276.465356) (xy 348.441277 -276.415942)
			(xy 348.461225 -276.369122) (xy 348.488426 -276.326108) (xy 348.522174 -276.288014) (xy 348.561596 -276.255827)
			(xy 348.60567 -276.230381) (xy 348.653256 -276.212334) (xy 348.70312 -276.202154) (xy 348.753972 -276.200105)
			(xy 348.804493 -276.206239) (xy 348.853377 -276.220399) (xy 348.899356 -276.242216) (xy 348.94124 -276.271126)
			(xy 348.977944 -276.306381) (xy 349.008517 -276.347067) (xy 349.032168 -276.39213) (xy 349.048284 -276.440404)
			(xy 349.056448 -276.490638) (xy 349.05696 -276.516084) (xy 349.364803 -276.516084) (xy 349.368898 -276.465356)
			(xy 349.381077 -276.415942) (xy 349.401025 -276.369122) (xy 349.428226 -276.326108) (xy 349.461974 -276.288014)
			(xy 349.501396 -276.255827) (xy 349.54547 -276.230381) (xy 349.593056 -276.212334) (xy 349.64292 -276.202154)
			(xy 349.693772 -276.200105) (xy 349.744293 -276.206239) (xy 349.793177 -276.220399) (xy 349.839156 -276.242216)
			(xy 349.88104 -276.271126) (xy 349.917744 -276.306381) (xy 349.948317 -276.347067) (xy 349.971968 -276.39213)
			(xy 349.988084 -276.440404) (xy 349.996248 -276.490638) (xy 349.99676 -276.516084) (xy 349.996257 -276.541073)
			(xy 350.303574 -276.541073) (xy 350.303574 -276.491095) (xy 350.311393 -276.441732) (xy 350.326837 -276.3942)
			(xy 350.349527 -276.349668) (xy 350.378903 -276.309235) (xy 350.414243 -276.273895) (xy 350.454676 -276.244519)
			(xy 350.499208 -276.221829) (xy 350.54674 -276.206385) (xy 350.596103 -276.198566) (xy 350.646081 -276.198566)
			(xy 350.695444 -276.206385) (xy 350.742976 -276.221829) (xy 350.787508 -276.244519) (xy 350.827941 -276.273895)
			(xy 350.863281 -276.309235) (xy 350.892657 -276.349668) (xy 350.915347 -276.3942) (xy 350.930791 -276.441732)
			(xy 350.93861 -276.491095) (xy 350.9391 -276.516084) (xy 351.244911 -276.516084) (xy 351.249006 -276.465356)
			(xy 351.261185 -276.415942) (xy 351.281133 -276.369122) (xy 351.308334 -276.326108) (xy 351.342082 -276.288014)
			(xy 351.381504 -276.255827) (xy 351.425578 -276.230381) (xy 351.473164 -276.212334) (xy 351.523028 -276.202154)
			(xy 351.57388 -276.200105) (xy 351.624401 -276.206239) (xy 351.673285 -276.220399) (xy 351.719264 -276.242216)
			(xy 351.761148 -276.271126) (xy 351.797852 -276.306381) (xy 351.828425 -276.347067) (xy 351.852076 -276.39213)
			(xy 351.868192 -276.440404) (xy 351.876356 -276.490638) (xy 351.876868 -276.516084) (xy 352.184965 -276.516084)
			(xy 352.18906 -276.465356) (xy 352.201239 -276.415942) (xy 352.221187 -276.369122) (xy 352.248388 -276.326108)
			(xy 352.282136 -276.288014) (xy 352.321558 -276.255827) (xy 352.365632 -276.230381) (xy 352.413218 -276.212334)
			(xy 352.463082 -276.202154) (xy 352.513934 -276.200105) (xy 352.564455 -276.206239) (xy 352.613339 -276.220399)
			(xy 352.659318 -276.242216) (xy 352.701202 -276.271126) (xy 352.737906 -276.306381) (xy 352.768479 -276.347067)
			(xy 352.79213 -276.39213) (xy 352.808246 -276.440404) (xy 352.81641 -276.490638) (xy 352.816922 -276.516084)
			(xy 352.816419 -276.541073) (xy 353.123482 -276.541073) (xy 353.123482 -276.491095) (xy 353.131301 -276.441732)
			(xy 353.146745 -276.3942) (xy 353.169435 -276.349668) (xy 353.198811 -276.309235) (xy 353.234151 -276.273895)
			(xy 353.274584 -276.244519) (xy 353.319116 -276.221829) (xy 353.366648 -276.206385) (xy 353.416011 -276.198566)
			(xy 353.465989 -276.198566) (xy 353.515352 -276.206385) (xy 353.562884 -276.221829) (xy 353.607416 -276.244519)
			(xy 353.647849 -276.273895) (xy 353.683189 -276.309235) (xy 353.712565 -276.349668) (xy 353.735255 -276.3942)
			(xy 353.750699 -276.441732) (xy 353.758518 -276.491095) (xy 353.759008 -276.516084) (xy 354.064819 -276.516084)
			(xy 354.068914 -276.465356) (xy 354.081093 -276.415942) (xy 354.101041 -276.369122) (xy 354.128242 -276.326108)
			(xy 354.16199 -276.288014) (xy 354.201412 -276.255827) (xy 354.245486 -276.230381) (xy 354.293072 -276.212334)
			(xy 354.342936 -276.202154) (xy 354.393788 -276.200105) (xy 354.444309 -276.206239) (xy 354.493193 -276.220399)
			(xy 354.539172 -276.242216) (xy 354.581056 -276.271126) (xy 354.61776 -276.306381) (xy 354.648333 -276.347067)
			(xy 354.671984 -276.39213) (xy 354.6881 -276.440404) (xy 354.696264 -276.490638) (xy 354.696776 -276.516084)
			(xy 355.004873 -276.516084) (xy 355.008968 -276.465356) (xy 355.021147 -276.415942) (xy 355.041095 -276.369122)
			(xy 355.068296 -276.326108) (xy 355.102044 -276.288014) (xy 355.141466 -276.255827) (xy 355.18554 -276.230381)
			(xy 355.233126 -276.212334) (xy 355.28299 -276.202154) (xy 355.333842 -276.200105) (xy 355.384363 -276.206239)
			(xy 355.433247 -276.220399) (xy 355.479226 -276.242216) (xy 355.52111 -276.271126) (xy 355.557814 -276.306381)
			(xy 355.588387 -276.347067) (xy 355.612038 -276.39213) (xy 355.628154 -276.440404) (xy 355.636318 -276.490638)
			(xy 355.63683 -276.516084) (xy 355.636327 -276.541073) (xy 355.943644 -276.541073) (xy 355.943644 -276.491095)
			(xy 355.951463 -276.441732) (xy 355.966907 -276.3942) (xy 355.989597 -276.349668) (xy 356.018973 -276.309235)
			(xy 356.054313 -276.273895) (xy 356.094746 -276.244519) (xy 356.139278 -276.221829) (xy 356.18681 -276.206385)
			(xy 356.236173 -276.198566) (xy 356.286151 -276.198566) (xy 356.335514 -276.206385) (xy 356.383046 -276.221829)
			(xy 356.427578 -276.244519) (xy 356.468011 -276.273895) (xy 356.503351 -276.309235) (xy 356.532727 -276.349668)
			(xy 356.555417 -276.3942) (xy 356.570861 -276.441732) (xy 356.57868 -276.491095) (xy 356.57917 -276.516084)
			(xy 356.57868 -276.541073) (xy 356.883698 -276.541073) (xy 356.883698 -276.491095) (xy 356.891517 -276.441732)
			(xy 356.906961 -276.3942) (xy 356.929651 -276.349668) (xy 356.959027 -276.309235) (xy 356.994367 -276.273895)
			(xy 357.0348 -276.244519) (xy 357.079332 -276.221829) (xy 357.126864 -276.206385) (xy 357.176227 -276.198566)
			(xy 357.226205 -276.198566) (xy 357.275568 -276.206385) (xy 357.3231 -276.221829) (xy 357.367632 -276.244519)
			(xy 357.408065 -276.273895) (xy 357.443405 -276.309235) (xy 357.472781 -276.349668) (xy 357.495471 -276.3942)
			(xy 357.510915 -276.441732) (xy 357.518734 -276.491095) (xy 357.519224 -276.516084) (xy 357.518734 -276.541073)
			(xy 357.823498 -276.541073) (xy 357.823498 -276.491095) (xy 357.831317 -276.441732) (xy 357.846761 -276.3942)
			(xy 357.869451 -276.349668) (xy 357.898827 -276.309235) (xy 357.934167 -276.273895) (xy 357.9746 -276.244519)
			(xy 358.019132 -276.221829) (xy 358.066664 -276.206385) (xy 358.116027 -276.198566) (xy 358.166005 -276.198566)
			(xy 358.215368 -276.206385) (xy 358.2629 -276.221829) (xy 358.307432 -276.244519) (xy 358.347865 -276.273895)
			(xy 358.383205 -276.309235) (xy 358.412581 -276.349668) (xy 358.435271 -276.3942) (xy 358.450715 -276.441732)
			(xy 358.458534 -276.491095) (xy 358.459024 -276.516084) (xy 358.458534 -276.541073) (xy 361.577364 -276.541073)
			(xy 361.577364 -276.491095) (xy 361.585183 -276.441732) (xy 361.600627 -276.3942) (xy 361.623317 -276.349668)
			(xy 361.652693 -276.309235) (xy 361.688033 -276.273895) (xy 361.728466 -276.244519) (xy 361.772998 -276.221829)
			(xy 361.82053 -276.206385) (xy 361.869893 -276.198566) (xy 361.919871 -276.198566) (xy 361.969234 -276.206385)
			(xy 362.016766 -276.221829) (xy 362.061298 -276.244519) (xy 362.101731 -276.273895) (xy 362.137071 -276.309235)
			(xy 362.166447 -276.349668) (xy 362.189137 -276.3942) (xy 362.204581 -276.441732) (xy 362.2124 -276.491095)
			(xy 362.21289 -276.516084) (xy 362.2124 -276.541073) (xy 362.517164 -276.541073) (xy 362.517164 -276.491095)
			(xy 362.524983 -276.441732) (xy 362.540427 -276.3942) (xy 362.563117 -276.349668) (xy 362.592493 -276.309235)
			(xy 362.627833 -276.273895) (xy 362.668266 -276.244519) (xy 362.712798 -276.221829) (xy 362.76033 -276.206385)
			(xy 362.809693 -276.198566) (xy 362.859671 -276.198566) (xy 362.909034 -276.206385) (xy 362.956566 -276.221829)
			(xy 363.001098 -276.244519) (xy 363.041531 -276.273895) (xy 363.076871 -276.309235) (xy 363.106247 -276.349668)
			(xy 363.128937 -276.3942) (xy 363.144381 -276.441732) (xy 363.1522 -276.491095) (xy 363.15269 -276.516084)
			(xy 363.1522 -276.541073) (xy 363.457218 -276.541073) (xy 363.457218 -276.491095) (xy 363.465037 -276.441732)
			(xy 363.480481 -276.3942) (xy 363.503171 -276.349668) (xy 363.532547 -276.309235) (xy 363.567887 -276.273895)
			(xy 363.60832 -276.244519) (xy 363.652852 -276.221829) (xy 363.700384 -276.206385) (xy 363.749747 -276.198566)
			(xy 363.799725 -276.198566) (xy 363.849088 -276.206385) (xy 363.89662 -276.221829) (xy 363.941152 -276.244519)
			(xy 363.981585 -276.273895) (xy 364.016925 -276.309235) (xy 364.046301 -276.349668) (xy 364.068991 -276.3942)
			(xy 364.084435 -276.441732) (xy 364.092254 -276.491095) (xy 364.092744 -276.516084) (xy 364.398555 -276.516084)
			(xy 364.40265 -276.465356) (xy 364.414829 -276.415942) (xy 364.434777 -276.369122) (xy 364.461978 -276.326108)
			(xy 364.495726 -276.288014) (xy 364.535148 -276.255827) (xy 364.579222 -276.230381) (xy 364.626808 -276.212334)
			(xy 364.676672 -276.202154) (xy 364.727524 -276.200105) (xy 364.778045 -276.206239) (xy 364.826929 -276.220399)
			(xy 364.872908 -276.242216) (xy 364.914792 -276.271126) (xy 364.951496 -276.306381) (xy 364.982069 -276.347067)
			(xy 365.00572 -276.39213) (xy 365.021836 -276.440404) (xy 365.03 -276.490638) (xy 365.030512 -276.516084)
			(xy 365.338609 -276.516084) (xy 365.342704 -276.465356) (xy 365.354883 -276.415942) (xy 365.374831 -276.369122)
			(xy 365.402032 -276.326108) (xy 365.43578 -276.288014) (xy 365.475202 -276.255827) (xy 365.519276 -276.230381)
			(xy 365.566862 -276.212334) (xy 365.616726 -276.202154) (xy 365.667578 -276.200105) (xy 365.718099 -276.206239)
			(xy 365.766983 -276.220399) (xy 365.812962 -276.242216) (xy 365.854846 -276.271126) (xy 365.89155 -276.306381)
			(xy 365.922123 -276.347067) (xy 365.945774 -276.39213) (xy 365.96189 -276.440404) (xy 365.970054 -276.490638)
			(xy 365.970566 -276.516084) (xy 365.970063 -276.541073) (xy 366.27738 -276.541073) (xy 366.27738 -276.491095)
			(xy 366.285199 -276.441732) (xy 366.300643 -276.3942) (xy 366.323333 -276.349668) (xy 366.352709 -276.309235)
			(xy 366.388049 -276.273895) (xy 366.428482 -276.244519) (xy 366.473014 -276.221829) (xy 366.520546 -276.206385)
			(xy 366.569909 -276.198566) (xy 366.619887 -276.198566) (xy 366.66925 -276.206385) (xy 366.716782 -276.221829)
			(xy 366.761314 -276.244519) (xy 366.801747 -276.273895) (xy 366.837087 -276.309235) (xy 366.866463 -276.349668)
			(xy 366.889153 -276.3942) (xy 366.904597 -276.441732) (xy 366.912416 -276.491095) (xy 366.912906 -276.516084)
			(xy 367.218463 -276.516084) (xy 367.222558 -276.465356) (xy 367.234737 -276.415942) (xy 367.254685 -276.369122)
			(xy 367.281886 -276.326108) (xy 367.315634 -276.288014) (xy 367.355056 -276.255827) (xy 367.39913 -276.230381)
			(xy 367.446716 -276.212334) (xy 367.49658 -276.202154) (xy 367.547432 -276.200105) (xy 367.597953 -276.206239)
			(xy 367.646837 -276.220399) (xy 367.692816 -276.242216) (xy 367.7347 -276.271126) (xy 367.771404 -276.306381)
			(xy 367.801977 -276.347067) (xy 367.825628 -276.39213) (xy 367.841744 -276.440404) (xy 367.849908 -276.490638)
			(xy 367.85042 -276.516084) (xy 368.158517 -276.516084) (xy 368.162612 -276.465356) (xy 368.174791 -276.415942)
			(xy 368.194739 -276.369122) (xy 368.22194 -276.326108) (xy 368.255688 -276.288014) (xy 368.29511 -276.255827)
			(xy 368.339184 -276.230381) (xy 368.38677 -276.212334) (xy 368.436634 -276.202154) (xy 368.487486 -276.200105)
			(xy 368.538007 -276.206239) (xy 368.586891 -276.220399) (xy 368.63287 -276.242216) (xy 368.674754 -276.271126)
			(xy 368.711458 -276.306381) (xy 368.742031 -276.347067) (xy 368.765682 -276.39213) (xy 368.781798 -276.440404)
			(xy 368.789962 -276.490638) (xy 368.790474 -276.516084) (xy 368.789971 -276.541073) (xy 369.097288 -276.541073)
			(xy 369.097288 -276.491095) (xy 369.105107 -276.441732) (xy 369.120551 -276.3942) (xy 369.143241 -276.349668)
			(xy 369.172617 -276.309235) (xy 369.207957 -276.273895) (xy 369.24839 -276.244519) (xy 369.292922 -276.221829)
			(xy 369.340454 -276.206385) (xy 369.389817 -276.198566) (xy 369.439795 -276.198566) (xy 369.489158 -276.206385)
			(xy 369.53669 -276.221829) (xy 369.581222 -276.244519) (xy 369.621655 -276.273895) (xy 369.656995 -276.309235)
			(xy 369.686371 -276.349668) (xy 369.709061 -276.3942) (xy 369.724505 -276.441732) (xy 369.732324 -276.491095)
			(xy 369.732814 -276.516084) (xy 370.038625 -276.516084) (xy 370.04272 -276.465356) (xy 370.054899 -276.415942)
			(xy 370.074847 -276.369122) (xy 370.102048 -276.326108) (xy 370.135796 -276.288014) (xy 370.175218 -276.255827)
			(xy 370.219292 -276.230381) (xy 370.266878 -276.212334) (xy 370.316742 -276.202154) (xy 370.367594 -276.200105)
			(xy 370.418115 -276.206239) (xy 370.466999 -276.220399) (xy 370.512978 -276.242216) (xy 370.554862 -276.271126)
			(xy 370.591566 -276.306381) (xy 370.622139 -276.347067) (xy 370.64579 -276.39213) (xy 370.661906 -276.440404)
			(xy 370.67007 -276.490638) (xy 370.670582 -276.516084) (xy 370.978679 -276.516084) (xy 370.982774 -276.465356)
			(xy 370.994953 -276.415942) (xy 371.014901 -276.369122) (xy 371.042102 -276.326108) (xy 371.07585 -276.288014)
			(xy 371.115272 -276.255827) (xy 371.159346 -276.230381) (xy 371.206932 -276.212334) (xy 371.256796 -276.202154)
			(xy 371.307648 -276.200105) (xy 371.358169 -276.206239) (xy 371.407053 -276.220399) (xy 371.453032 -276.242216)
			(xy 371.494916 -276.271126) (xy 371.53162 -276.306381) (xy 371.562193 -276.347067) (xy 371.585844 -276.39213)
			(xy 371.60196 -276.440404) (xy 371.610124 -276.490638) (xy 371.610636 -276.516084) (xy 371.610133 -276.541073)
			(xy 371.917196 -276.541073) (xy 371.917196 -276.491095) (xy 371.925015 -276.441732) (xy 371.940459 -276.3942)
			(xy 371.963149 -276.349668) (xy 371.992525 -276.309235) (xy 372.027865 -276.273895) (xy 372.068298 -276.244519)
			(xy 372.11283 -276.221829) (xy 372.160362 -276.206385) (xy 372.209725 -276.198566) (xy 372.259703 -276.198566)
			(xy 372.309066 -276.206385) (xy 372.356598 -276.221829) (xy 372.40113 -276.244519) (xy 372.441563 -276.273895)
			(xy 372.476903 -276.309235) (xy 372.506279 -276.349668) (xy 372.528969 -276.3942) (xy 372.544413 -276.441732)
			(xy 372.552232 -276.491095) (xy 372.552722 -276.516084) (xy 372.858533 -276.516084) (xy 372.862628 -276.465356)
			(xy 372.874807 -276.415942) (xy 372.894755 -276.369122) (xy 372.921956 -276.326108) (xy 372.955704 -276.288014)
			(xy 372.995126 -276.255827) (xy 373.0392 -276.230381) (xy 373.086786 -276.212334) (xy 373.13665 -276.202154)
			(xy 373.187502 -276.200105) (xy 373.238023 -276.206239) (xy 373.286907 -276.220399) (xy 373.332886 -276.242216)
			(xy 373.37477 -276.271126) (xy 373.411474 -276.306381) (xy 373.442047 -276.347067) (xy 373.465698 -276.39213)
			(xy 373.481814 -276.440404) (xy 373.489978 -276.490638) (xy 373.49049 -276.516084) (xy 373.798587 -276.516084)
			(xy 373.802682 -276.465356) (xy 373.814861 -276.415942) (xy 373.834809 -276.369122) (xy 373.86201 -276.326108)
			(xy 373.895758 -276.288014) (xy 373.93518 -276.255827) (xy 373.979254 -276.230381) (xy 374.02684 -276.212334)
			(xy 374.076704 -276.202154) (xy 374.127556 -276.200105) (xy 374.178077 -276.206239) (xy 374.226961 -276.220399)
			(xy 374.27294 -276.242216) (xy 374.314824 -276.271126) (xy 374.351528 -276.306381) (xy 374.382101 -276.347067)
			(xy 374.405752 -276.39213) (xy 374.421868 -276.440404) (xy 374.430032 -276.490638) (xy 374.430544 -276.516084)
			(xy 374.430032 -276.54153) (xy 374.421868 -276.591764) (xy 374.405752 -276.640038) (xy 374.382101 -276.685101)
			(xy 374.351528 -276.725787) (xy 374.314824 -276.761042) (xy 374.27294 -276.789952) (xy 374.226961 -276.811769)
			(xy 374.178077 -276.825929) (xy 374.127556 -276.832063) (xy 374.076704 -276.830014) (xy 374.02684 -276.819834)
			(xy 373.979254 -276.801787) (xy 373.93518 -276.776341) (xy 373.895758 -276.744154) (xy 373.86201 -276.70606)
			(xy 373.834809 -276.663046) (xy 373.814861 -276.616226) (xy 373.802682 -276.566812) (xy 373.798587 -276.516084)
			(xy 373.49049 -276.516084) (xy 373.489978 -276.54153) (xy 373.481814 -276.591764) (xy 373.465698 -276.640038)
			(xy 373.442047 -276.685101) (xy 373.411474 -276.725787) (xy 373.37477 -276.761042) (xy 373.332886 -276.789952)
			(xy 373.286907 -276.811769) (xy 373.238023 -276.825929) (xy 373.187502 -276.832063) (xy 373.13665 -276.830014)
			(xy 373.086786 -276.819834) (xy 373.0392 -276.801787) (xy 372.995126 -276.776341) (xy 372.955704 -276.744154)
			(xy 372.921956 -276.70606) (xy 372.894755 -276.663046) (xy 372.874807 -276.616226) (xy 372.862628 -276.566812)
			(xy 372.858533 -276.516084) (xy 372.552722 -276.516084) (xy 372.552232 -276.541073) (xy 372.544413 -276.590436)
			(xy 372.528969 -276.637968) (xy 372.506279 -276.6825) (xy 372.476903 -276.722933) (xy 372.441563 -276.758273)
			(xy 372.40113 -276.787649) (xy 372.356598 -276.810339) (xy 372.309066 -276.825783) (xy 372.259703 -276.833602)
			(xy 372.209725 -276.833602) (xy 372.160362 -276.825783) (xy 372.11283 -276.810339) (xy 372.068298 -276.787649)
			(xy 372.027865 -276.758273) (xy 371.992525 -276.722933) (xy 371.963149 -276.6825) (xy 371.940459 -276.637968)
			(xy 371.925015 -276.590436) (xy 371.917196 -276.541073) (xy 371.610133 -276.541073) (xy 371.610124 -276.54153)
			(xy 371.60196 -276.591764) (xy 371.585844 -276.640038) (xy 371.562193 -276.685101) (xy 371.53162 -276.725787)
			(xy 371.494916 -276.761042) (xy 371.453032 -276.789952) (xy 371.407053 -276.811769) (xy 371.358169 -276.825929)
			(xy 371.307648 -276.832063) (xy 371.256796 -276.830014) (xy 371.206932 -276.819834) (xy 371.159346 -276.801787)
			(xy 371.115272 -276.776341) (xy 371.07585 -276.744154) (xy 371.042102 -276.70606) (xy 371.014901 -276.663046)
			(xy 370.994953 -276.616226) (xy 370.982774 -276.566812) (xy 370.978679 -276.516084) (xy 370.670582 -276.516084)
			(xy 370.67007 -276.54153) (xy 370.661906 -276.591764) (xy 370.64579 -276.640038) (xy 370.622139 -276.685101)
			(xy 370.591566 -276.725787) (xy 370.554862 -276.761042) (xy 370.512978 -276.789952) (xy 370.466999 -276.811769)
			(xy 370.418115 -276.825929) (xy 370.367594 -276.832063) (xy 370.316742 -276.830014) (xy 370.266878 -276.819834)
			(xy 370.219292 -276.801787) (xy 370.175218 -276.776341) (xy 370.135796 -276.744154) (xy 370.102048 -276.70606)
			(xy 370.074847 -276.663046) (xy 370.054899 -276.616226) (xy 370.04272 -276.566812) (xy 370.038625 -276.516084)
			(xy 369.732814 -276.516084) (xy 369.732324 -276.541073) (xy 369.724505 -276.590436) (xy 369.709061 -276.637968)
			(xy 369.686371 -276.6825) (xy 369.656995 -276.722933) (xy 369.621655 -276.758273) (xy 369.581222 -276.787649)
			(xy 369.53669 -276.810339) (xy 369.489158 -276.825783) (xy 369.439795 -276.833602) (xy 369.389817 -276.833602)
			(xy 369.340454 -276.825783) (xy 369.292922 -276.810339) (xy 369.24839 -276.787649) (xy 369.207957 -276.758273)
			(xy 369.172617 -276.722933) (xy 369.143241 -276.6825) (xy 369.120551 -276.637968) (xy 369.105107 -276.590436)
			(xy 369.097288 -276.541073) (xy 368.789971 -276.541073) (xy 368.789962 -276.54153) (xy 368.781798 -276.591764)
			(xy 368.765682 -276.640038) (xy 368.742031 -276.685101) (xy 368.711458 -276.725787) (xy 368.674754 -276.761042)
			(xy 368.63287 -276.789952) (xy 368.586891 -276.811769) (xy 368.538007 -276.825929) (xy 368.487486 -276.832063)
			(xy 368.436634 -276.830014) (xy 368.38677 -276.819834) (xy 368.339184 -276.801787) (xy 368.29511 -276.776341)
			(xy 368.255688 -276.744154) (xy 368.22194 -276.70606) (xy 368.194739 -276.663046) (xy 368.174791 -276.616226)
			(xy 368.162612 -276.566812) (xy 368.158517 -276.516084) (xy 367.85042 -276.516084) (xy 367.849908 -276.54153)
			(xy 367.841744 -276.591764) (xy 367.825628 -276.640038) (xy 367.801977 -276.685101) (xy 367.771404 -276.725787)
			(xy 367.7347 -276.761042) (xy 367.692816 -276.789952) (xy 367.646837 -276.811769) (xy 367.597953 -276.825929)
			(xy 367.547432 -276.832063) (xy 367.49658 -276.830014) (xy 367.446716 -276.819834) (xy 367.39913 -276.801787)
			(xy 367.355056 -276.776341) (xy 367.315634 -276.744154) (xy 367.281886 -276.70606) (xy 367.254685 -276.663046)
			(xy 367.234737 -276.616226) (xy 367.222558 -276.566812) (xy 367.218463 -276.516084) (xy 366.912906 -276.516084)
			(xy 366.912416 -276.541073) (xy 366.904597 -276.590436) (xy 366.889153 -276.637968) (xy 366.866463 -276.6825)
			(xy 366.837087 -276.722933) (xy 366.801747 -276.758273) (xy 366.761314 -276.787649) (xy 366.716782 -276.810339)
			(xy 366.66925 -276.825783) (xy 366.619887 -276.833602) (xy 366.569909 -276.833602) (xy 366.520546 -276.825783)
			(xy 366.473014 -276.810339) (xy 366.428482 -276.787649) (xy 366.388049 -276.758273) (xy 366.352709 -276.722933)
			(xy 366.323333 -276.6825) (xy 366.300643 -276.637968) (xy 366.285199 -276.590436) (xy 366.27738 -276.541073)
			(xy 365.970063 -276.541073) (xy 365.970054 -276.54153) (xy 365.96189 -276.591764) (xy 365.945774 -276.640038)
			(xy 365.922123 -276.685101) (xy 365.89155 -276.725787) (xy 365.854846 -276.761042) (xy 365.812962 -276.789952)
			(xy 365.766983 -276.811769) (xy 365.718099 -276.825929) (xy 365.667578 -276.832063) (xy 365.616726 -276.830014)
			(xy 365.566862 -276.819834) (xy 365.519276 -276.801787) (xy 365.475202 -276.776341) (xy 365.43578 -276.744154)
			(xy 365.402032 -276.70606) (xy 365.374831 -276.663046) (xy 365.354883 -276.616226) (xy 365.342704 -276.566812)
			(xy 365.338609 -276.516084) (xy 365.030512 -276.516084) (xy 365.03 -276.54153) (xy 365.021836 -276.591764)
			(xy 365.00572 -276.640038) (xy 364.982069 -276.685101) (xy 364.951496 -276.725787) (xy 364.914792 -276.761042)
			(xy 364.872908 -276.789952) (xy 364.826929 -276.811769) (xy 364.778045 -276.825929) (xy 364.727524 -276.832063)
			(xy 364.676672 -276.830014) (xy 364.626808 -276.819834) (xy 364.579222 -276.801787) (xy 364.535148 -276.776341)
			(xy 364.495726 -276.744154) (xy 364.461978 -276.70606) (xy 364.434777 -276.663046) (xy 364.414829 -276.616226)
			(xy 364.40265 -276.566812) (xy 364.398555 -276.516084) (xy 364.092744 -276.516084) (xy 364.092254 -276.541073)
			(xy 364.084435 -276.590436) (xy 364.068991 -276.637968) (xy 364.046301 -276.6825) (xy 364.016925 -276.722933)
			(xy 363.981585 -276.758273) (xy 363.941152 -276.787649) (xy 363.89662 -276.810339) (xy 363.849088 -276.825783)
			(xy 363.799725 -276.833602) (xy 363.749747 -276.833602) (xy 363.700384 -276.825783) (xy 363.652852 -276.810339)
			(xy 363.60832 -276.787649) (xy 363.567887 -276.758273) (xy 363.532547 -276.722933) (xy 363.503171 -276.6825)
			(xy 363.480481 -276.637968) (xy 363.465037 -276.590436) (xy 363.457218 -276.541073) (xy 363.1522 -276.541073)
			(xy 363.144381 -276.590436) (xy 363.128937 -276.637968) (xy 363.106247 -276.6825) (xy 363.076871 -276.722933)
			(xy 363.041531 -276.758273) (xy 363.001098 -276.787649) (xy 362.956566 -276.810339) (xy 362.909034 -276.825783)
			(xy 362.859671 -276.833602) (xy 362.809693 -276.833602) (xy 362.76033 -276.825783) (xy 362.712798 -276.810339)
			(xy 362.668266 -276.787649) (xy 362.627833 -276.758273) (xy 362.592493 -276.722933) (xy 362.563117 -276.6825)
			(xy 362.540427 -276.637968) (xy 362.524983 -276.590436) (xy 362.517164 -276.541073) (xy 362.2124 -276.541073)
			(xy 362.204581 -276.590436) (xy 362.189137 -276.637968) (xy 362.166447 -276.6825) (xy 362.137071 -276.722933)
			(xy 362.101731 -276.758273) (xy 362.061298 -276.787649) (xy 362.016766 -276.810339) (xy 361.969234 -276.825783)
			(xy 361.919871 -276.833602) (xy 361.869893 -276.833602) (xy 361.82053 -276.825783) (xy 361.772998 -276.810339)
			(xy 361.728466 -276.787649) (xy 361.688033 -276.758273) (xy 361.652693 -276.722933) (xy 361.623317 -276.6825)
			(xy 361.600627 -276.637968) (xy 361.585183 -276.590436) (xy 361.577364 -276.541073) (xy 358.458534 -276.541073)
			(xy 358.450715 -276.590436) (xy 358.435271 -276.637968) (xy 358.412581 -276.6825) (xy 358.383205 -276.722933)
			(xy 358.347865 -276.758273) (xy 358.307432 -276.787649) (xy 358.2629 -276.810339) (xy 358.215368 -276.825783)
			(xy 358.166005 -276.833602) (xy 358.116027 -276.833602) (xy 358.066664 -276.825783) (xy 358.019132 -276.810339)
			(xy 357.9746 -276.787649) (xy 357.934167 -276.758273) (xy 357.898827 -276.722933) (xy 357.869451 -276.6825)
			(xy 357.846761 -276.637968) (xy 357.831317 -276.590436) (xy 357.823498 -276.541073) (xy 357.518734 -276.541073)
			(xy 357.510915 -276.590436) (xy 357.495471 -276.637968) (xy 357.472781 -276.6825) (xy 357.443405 -276.722933)
			(xy 357.408065 -276.758273) (xy 357.367632 -276.787649) (xy 357.3231 -276.810339) (xy 357.275568 -276.825783)
			(xy 357.226205 -276.833602) (xy 357.176227 -276.833602) (xy 357.126864 -276.825783) (xy 357.079332 -276.810339)
			(xy 357.0348 -276.787649) (xy 356.994367 -276.758273) (xy 356.959027 -276.722933) (xy 356.929651 -276.6825)
			(xy 356.906961 -276.637968) (xy 356.891517 -276.590436) (xy 356.883698 -276.541073) (xy 356.57868 -276.541073)
			(xy 356.570861 -276.590436) (xy 356.555417 -276.637968) (xy 356.532727 -276.6825) (xy 356.503351 -276.722933)
			(xy 356.468011 -276.758273) (xy 356.427578 -276.787649) (xy 356.383046 -276.810339) (xy 356.335514 -276.825783)
			(xy 356.286151 -276.833602) (xy 356.236173 -276.833602) (xy 356.18681 -276.825783) (xy 356.139278 -276.810339)
			(xy 356.094746 -276.787649) (xy 356.054313 -276.758273) (xy 356.018973 -276.722933) (xy 355.989597 -276.6825)
			(xy 355.966907 -276.637968) (xy 355.951463 -276.590436) (xy 355.943644 -276.541073) (xy 355.636327 -276.541073)
			(xy 355.636318 -276.54153) (xy 355.628154 -276.591764) (xy 355.612038 -276.640038) (xy 355.588387 -276.685101)
			(xy 355.557814 -276.725787) (xy 355.52111 -276.761042) (xy 355.479226 -276.789952) (xy 355.433247 -276.811769)
			(xy 355.384363 -276.825929) (xy 355.333842 -276.832063) (xy 355.28299 -276.830014) (xy 355.233126 -276.819834)
			(xy 355.18554 -276.801787) (xy 355.141466 -276.776341) (xy 355.102044 -276.744154) (xy 355.068296 -276.70606)
			(xy 355.041095 -276.663046) (xy 355.021147 -276.616226) (xy 355.008968 -276.566812) (xy 355.004873 -276.516084)
			(xy 354.696776 -276.516084) (xy 354.696264 -276.54153) (xy 354.6881 -276.591764) (xy 354.671984 -276.640038)
			(xy 354.648333 -276.685101) (xy 354.61776 -276.725787) (xy 354.581056 -276.761042) (xy 354.539172 -276.789952)
			(xy 354.493193 -276.811769) (xy 354.444309 -276.825929) (xy 354.393788 -276.832063) (xy 354.342936 -276.830014)
			(xy 354.293072 -276.819834) (xy 354.245486 -276.801787) (xy 354.201412 -276.776341) (xy 354.16199 -276.744154)
			(xy 354.128242 -276.70606) (xy 354.101041 -276.663046) (xy 354.081093 -276.616226) (xy 354.068914 -276.566812)
			(xy 354.064819 -276.516084) (xy 353.759008 -276.516084) (xy 353.758518 -276.541073) (xy 353.750699 -276.590436)
			(xy 353.735255 -276.637968) (xy 353.712565 -276.6825) (xy 353.683189 -276.722933) (xy 353.647849 -276.758273)
			(xy 353.607416 -276.787649) (xy 353.562884 -276.810339) (xy 353.515352 -276.825783) (xy 353.465989 -276.833602)
			(xy 353.416011 -276.833602) (xy 353.366648 -276.825783) (xy 353.319116 -276.810339) (xy 353.274584 -276.787649)
			(xy 353.234151 -276.758273) (xy 353.198811 -276.722933) (xy 353.169435 -276.6825) (xy 353.146745 -276.637968)
			(xy 353.131301 -276.590436) (xy 353.123482 -276.541073) (xy 352.816419 -276.541073) (xy 352.81641 -276.54153)
			(xy 352.808246 -276.591764) (xy 352.79213 -276.640038) (xy 352.768479 -276.685101) (xy 352.737906 -276.725787)
			(xy 352.701202 -276.761042) (xy 352.659318 -276.789952) (xy 352.613339 -276.811769) (xy 352.564455 -276.825929)
			(xy 352.513934 -276.832063) (xy 352.463082 -276.830014) (xy 352.413218 -276.819834) (xy 352.365632 -276.801787)
			(xy 352.321558 -276.776341) (xy 352.282136 -276.744154) (xy 352.248388 -276.70606) (xy 352.221187 -276.663046)
			(xy 352.201239 -276.616226) (xy 352.18906 -276.566812) (xy 352.184965 -276.516084) (xy 351.876868 -276.516084)
			(xy 351.876356 -276.54153) (xy 351.868192 -276.591764) (xy 351.852076 -276.640038) (xy 351.828425 -276.685101)
			(xy 351.797852 -276.725787) (xy 351.761148 -276.761042) (xy 351.719264 -276.789952) (xy 351.673285 -276.811769)
			(xy 351.624401 -276.825929) (xy 351.57388 -276.832063) (xy 351.523028 -276.830014) (xy 351.473164 -276.819834)
			(xy 351.425578 -276.801787) (xy 351.381504 -276.776341) (xy 351.342082 -276.744154) (xy 351.308334 -276.70606)
			(xy 351.281133 -276.663046) (xy 351.261185 -276.616226) (xy 351.249006 -276.566812) (xy 351.244911 -276.516084)
			(xy 350.9391 -276.516084) (xy 350.93861 -276.541073) (xy 350.930791 -276.590436) (xy 350.915347 -276.637968)
			(xy 350.892657 -276.6825) (xy 350.863281 -276.722933) (xy 350.827941 -276.758273) (xy 350.787508 -276.787649)
			(xy 350.742976 -276.810339) (xy 350.695444 -276.825783) (xy 350.646081 -276.833602) (xy 350.596103 -276.833602)
			(xy 350.54674 -276.825783) (xy 350.499208 -276.810339) (xy 350.454676 -276.787649) (xy 350.414243 -276.758273)
			(xy 350.378903 -276.722933) (xy 350.349527 -276.6825) (xy 350.326837 -276.637968) (xy 350.311393 -276.590436)
			(xy 350.303574 -276.541073) (xy 349.996257 -276.541073) (xy 349.996248 -276.54153) (xy 349.988084 -276.591764)
			(xy 349.971968 -276.640038) (xy 349.948317 -276.685101) (xy 349.917744 -276.725787) (xy 349.88104 -276.761042)
			(xy 349.839156 -276.789952) (xy 349.793177 -276.811769) (xy 349.744293 -276.825929) (xy 349.693772 -276.832063)
			(xy 349.64292 -276.830014) (xy 349.593056 -276.819834) (xy 349.54547 -276.801787) (xy 349.501396 -276.776341)
			(xy 349.461974 -276.744154) (xy 349.428226 -276.70606) (xy 349.401025 -276.663046) (xy 349.381077 -276.616226)
			(xy 349.368898 -276.566812) (xy 349.364803 -276.516084) (xy 349.05696 -276.516084) (xy 349.056448 -276.54153)
			(xy 349.048284 -276.591764) (xy 349.032168 -276.640038) (xy 349.008517 -276.685101) (xy 348.977944 -276.725787)
			(xy 348.94124 -276.761042) (xy 348.899356 -276.789952) (xy 348.853377 -276.811769) (xy 348.804493 -276.825929)
			(xy 348.753972 -276.832063) (xy 348.70312 -276.830014) (xy 348.653256 -276.819834) (xy 348.60567 -276.801787)
			(xy 348.561596 -276.776341) (xy 348.522174 -276.744154) (xy 348.488426 -276.70606) (xy 348.461225 -276.663046)
			(xy 348.441277 -276.616226) (xy 348.429098 -276.566812) (xy 348.425003 -276.516084) (xy 348.119192 -276.516084)
			(xy 348.118702 -276.541073) (xy 348.110883 -276.590436) (xy 348.095439 -276.637968) (xy 348.072749 -276.6825)
			(xy 348.043373 -276.722933) (xy 348.008033 -276.758273) (xy 347.9676 -276.787649) (xy 347.923068 -276.810339)
			(xy 347.875536 -276.825783) (xy 347.826173 -276.833602) (xy 347.776195 -276.833602) (xy 347.726832 -276.825783)
			(xy 347.6793 -276.810339) (xy 347.634768 -276.787649) (xy 347.594335 -276.758273) (xy 347.558995 -276.722933)
			(xy 347.529619 -276.6825) (xy 347.506929 -276.637968) (xy 347.491485 -276.590436) (xy 347.483666 -276.541073)
			(xy 347.176349 -276.541073) (xy 347.17634 -276.54153) (xy 347.168176 -276.591764) (xy 347.15206 -276.640038)
			(xy 347.128409 -276.685101) (xy 347.097836 -276.725787) (xy 347.061132 -276.761042) (xy 347.019248 -276.789952)
			(xy 346.973269 -276.811769) (xy 346.924385 -276.825929) (xy 346.873864 -276.832063) (xy 346.823012 -276.830014)
			(xy 346.773148 -276.819834) (xy 346.725562 -276.801787) (xy 346.681488 -276.776341) (xy 346.642066 -276.744154)
			(xy 346.608318 -276.70606) (xy 346.581117 -276.663046) (xy 346.561169 -276.616226) (xy 346.54899 -276.566812)
			(xy 346.544895 -276.516084) (xy 346.236798 -276.516084) (xy 346.236286 -276.54153) (xy 346.228122 -276.591764)
			(xy 346.212006 -276.640038) (xy 346.188355 -276.685101) (xy 346.157782 -276.725787) (xy 346.121078 -276.761042)
			(xy 346.079194 -276.789952) (xy 346.033215 -276.811769) (xy 345.984331 -276.825929) (xy 345.93381 -276.832063)
			(xy 345.882958 -276.830014) (xy 345.833094 -276.819834) (xy 345.785508 -276.801787) (xy 345.741434 -276.776341)
			(xy 345.702012 -276.744154) (xy 345.668264 -276.70606) (xy 345.641063 -276.663046) (xy 345.621115 -276.616226)
			(xy 345.608936 -276.566812) (xy 345.604841 -276.516084) (xy 345.298877 -276.516084) (xy 345.297281 -276.554011)
			(xy 345.287671 -276.60224) (xy 345.270748 -276.648413) (xy 345.246915 -276.691429) (xy 345.232228 -276.711156)
			(xy 345.214388 -276.733126) (xy 345.172313 -276.770966) (xy 345.124196 -276.800748) (xy 345.098116 -276.81174)
			(xy 345.097862 -276.81174) (xy 345.095068 -276.812756) (xy 345.086743 -276.81714) (xy 345.07375 -276.830724)
			(xy 345.06652 -276.848075) (xy 345.065858 -276.85746) (xy 345.065858 -277.02002) (xy 345.066305 -277.029862)
			(xy 345.073725 -277.048094) (xy 345.087493 -277.062161) (xy 345.096338 -277.066502) (xy 345.14155 -277.086314)
			(xy 345.17965 -277.102824) (xy 345.186544 -277.105554) (xy 345.201255 -277.107355) (xy 345.208606 -277.10638)
			(xy 345.215464 -277.10511) (xy 345.228672 -277.09876) (xy 345.23426 -277.093426) (xy 345.252024 -277.077463)
			(xy 345.291442 -277.0505) (xy 345.334448 -277.029732) (xy 345.380074 -277.015625) (xy 345.427297 -277.008498)
			(xy 345.451176 -277.008082) (xy 345.476169 -277.008545) (xy 345.525541 -277.016361) (xy 345.573082 -277.031805)
			(xy 345.617621 -277.054496) (xy 345.658062 -277.083875) (xy 345.693409 -277.11922) (xy 345.722792 -277.159658)
			(xy 345.745486 -277.204196) (xy 345.760933 -277.251736) (xy 345.768753 -277.301107) (xy 345.768753 -277.351079)
			(xy 346.073712 -277.351079) (xy 346.073712 -277.301101) (xy 346.081531 -277.251738) (xy 346.096975 -277.204206)
			(xy 346.119665 -277.159674) (xy 346.149041 -277.119241) (xy 346.184381 -277.083901) (xy 346.224814 -277.054525)
			(xy 346.269346 -277.031835) (xy 346.316878 -277.016391) (xy 346.366241 -277.008572) (xy 346.416219 -277.008572)
			(xy 346.465582 -277.016391) (xy 346.513114 -277.031835) (xy 346.557646 -277.054525) (xy 346.598079 -277.083901)
			(xy 346.633419 -277.119241) (xy 346.662795 -277.159674) (xy 346.685485 -277.204206) (xy 346.700929 -277.251738)
			(xy 346.708748 -277.301101) (xy 346.709238 -277.32609) (xy 346.708748 -277.351079) (xy 347.013512 -277.351079)
			(xy 347.013512 -277.301101) (xy 347.021331 -277.251738) (xy 347.036775 -277.204206) (xy 347.059465 -277.159674)
			(xy 347.088841 -277.119241) (xy 347.124181 -277.083901) (xy 347.164614 -277.054525) (xy 347.209146 -277.031835)
			(xy 347.256678 -277.016391) (xy 347.306041 -277.008572) (xy 347.356019 -277.008572) (xy 347.405382 -277.016391)
			(xy 347.452914 -277.031835) (xy 347.497446 -277.054525) (xy 347.537879 -277.083901) (xy 347.573219 -277.119241)
			(xy 347.602595 -277.159674) (xy 347.625285 -277.204206) (xy 347.640729 -277.251738) (xy 347.648548 -277.301101)
			(xy 347.649038 -277.32609) (xy 347.648548 -277.351079) (xy 347.953566 -277.351079) (xy 347.953566 -277.301101)
			(xy 347.961385 -277.251738) (xy 347.976829 -277.204206) (xy 347.999519 -277.159674) (xy 348.028895 -277.119241)
			(xy 348.064235 -277.083901) (xy 348.104668 -277.054525) (xy 348.1492 -277.031835) (xy 348.196732 -277.016391)
			(xy 348.246095 -277.008572) (xy 348.296073 -277.008572) (xy 348.345436 -277.016391) (xy 348.392968 -277.031835)
			(xy 348.4375 -277.054525) (xy 348.477933 -277.083901) (xy 348.513273 -277.119241) (xy 348.542649 -277.159674)
			(xy 348.565339 -277.204206) (xy 348.580783 -277.251738) (xy 348.588602 -277.301101) (xy 348.589092 -277.32609)
			(xy 348.588602 -277.351079) (xy 348.89362 -277.351079) (xy 348.89362 -277.301101) (xy 348.901439 -277.251738)
			(xy 348.916883 -277.204206) (xy 348.939573 -277.159674) (xy 348.968949 -277.119241) (xy 349.004289 -277.083901)
			(xy 349.044722 -277.054525) (xy 349.089254 -277.031835) (xy 349.136786 -277.016391) (xy 349.186149 -277.008572)
			(xy 349.236127 -277.008572) (xy 349.28549 -277.016391) (xy 349.333022 -277.031835) (xy 349.377554 -277.054525)
			(xy 349.417987 -277.083901) (xy 349.453327 -277.119241) (xy 349.482703 -277.159674) (xy 349.505393 -277.204206)
			(xy 349.520837 -277.251738) (xy 349.528656 -277.301101) (xy 349.529146 -277.32609) (xy 349.528656 -277.351079)
			(xy 349.833674 -277.351079) (xy 349.833674 -277.301101) (xy 349.841493 -277.251738) (xy 349.856937 -277.204206)
			(xy 349.879627 -277.159674) (xy 349.909003 -277.119241) (xy 349.944343 -277.083901) (xy 349.984776 -277.054525)
			(xy 350.029308 -277.031835) (xy 350.07684 -277.016391) (xy 350.126203 -277.008572) (xy 350.176181 -277.008572)
			(xy 350.225544 -277.016391) (xy 350.273076 -277.031835) (xy 350.317608 -277.054525) (xy 350.358041 -277.083901)
			(xy 350.393381 -277.119241) (xy 350.422757 -277.159674) (xy 350.445447 -277.204206) (xy 350.460891 -277.251738)
			(xy 350.46871 -277.301101) (xy 350.4692 -277.32609) (xy 350.46871 -277.351079) (xy 350.773728 -277.351079)
			(xy 350.773728 -277.301101) (xy 350.781547 -277.251738) (xy 350.796991 -277.204206) (xy 350.819681 -277.159674)
			(xy 350.849057 -277.119241) (xy 350.884397 -277.083901) (xy 350.92483 -277.054525) (xy 350.969362 -277.031835)
			(xy 351.016894 -277.016391) (xy 351.066257 -277.008572) (xy 351.116235 -277.008572) (xy 351.165598 -277.016391)
			(xy 351.21313 -277.031835) (xy 351.257662 -277.054525) (xy 351.298095 -277.083901) (xy 351.333435 -277.119241)
			(xy 351.362811 -277.159674) (xy 351.385501 -277.204206) (xy 351.400945 -277.251738) (xy 351.408764 -277.301101)
			(xy 351.409254 -277.32609) (xy 351.408764 -277.351079) (xy 351.713528 -277.351079) (xy 351.713528 -277.301101)
			(xy 351.721347 -277.251738) (xy 351.736791 -277.204206) (xy 351.759481 -277.159674) (xy 351.788857 -277.119241)
			(xy 351.824197 -277.083901) (xy 351.86463 -277.054525) (xy 351.909162 -277.031835) (xy 351.956694 -277.016391)
			(xy 352.006057 -277.008572) (xy 352.056035 -277.008572) (xy 352.105398 -277.016391) (xy 352.15293 -277.031835)
			(xy 352.197462 -277.054525) (xy 352.237895 -277.083901) (xy 352.273235 -277.119241) (xy 352.302611 -277.159674)
			(xy 352.325301 -277.204206) (xy 352.340745 -277.251738) (xy 352.348564 -277.301101) (xy 352.349054 -277.32609)
			(xy 352.348564 -277.351079) (xy 352.653582 -277.351079) (xy 352.653582 -277.301101) (xy 352.661401 -277.251738)
			(xy 352.676845 -277.204206) (xy 352.699535 -277.159674) (xy 352.728911 -277.119241) (xy 352.764251 -277.083901)
			(xy 352.804684 -277.054525) (xy 352.849216 -277.031835) (xy 352.896748 -277.016391) (xy 352.946111 -277.008572)
			(xy 352.996089 -277.008572) (xy 353.045452 -277.016391) (xy 353.092984 -277.031835) (xy 353.137516 -277.054525)
			(xy 353.177949 -277.083901) (xy 353.213289 -277.119241) (xy 353.242665 -277.159674) (xy 353.265355 -277.204206)
			(xy 353.280799 -277.251738) (xy 353.288618 -277.301101) (xy 353.289108 -277.32609) (xy 353.288618 -277.351079)
			(xy 353.593636 -277.351079) (xy 353.593636 -277.301101) (xy 353.601455 -277.251738) (xy 353.616899 -277.204206)
			(xy 353.639589 -277.159674) (xy 353.668965 -277.119241) (xy 353.704305 -277.083901) (xy 353.744738 -277.054525)
			(xy 353.78927 -277.031835) (xy 353.836802 -277.016391) (xy 353.886165 -277.008572) (xy 353.936143 -277.008572)
			(xy 353.985506 -277.016391) (xy 354.033038 -277.031835) (xy 354.07757 -277.054525) (xy 354.118003 -277.083901)
			(xy 354.153343 -277.119241) (xy 354.182719 -277.159674) (xy 354.205409 -277.204206) (xy 354.220853 -277.251738)
			(xy 354.228672 -277.301101) (xy 354.229162 -277.32609) (xy 354.228672 -277.351079) (xy 354.53369 -277.351079)
			(xy 354.53369 -277.301101) (xy 354.541509 -277.251738) (xy 354.556953 -277.204206) (xy 354.579643 -277.159674)
			(xy 354.609019 -277.119241) (xy 354.644359 -277.083901) (xy 354.684792 -277.054525) (xy 354.729324 -277.031835)
			(xy 354.776856 -277.016391) (xy 354.826219 -277.008572) (xy 354.876197 -277.008572) (xy 354.92556 -277.016391)
			(xy 354.973092 -277.031835) (xy 355.017624 -277.054525) (xy 355.058057 -277.083901) (xy 355.093397 -277.119241)
			(xy 355.122773 -277.159674) (xy 355.145463 -277.204206) (xy 355.160907 -277.251738) (xy 355.168726 -277.301101)
			(xy 355.169216 -277.32609) (xy 355.168726 -277.351079) (xy 355.47349 -277.351079) (xy 355.47349 -277.301101)
			(xy 355.481309 -277.251738) (xy 355.496753 -277.204206) (xy 355.519443 -277.159674) (xy 355.548819 -277.119241)
			(xy 355.584159 -277.083901) (xy 355.624592 -277.054525) (xy 355.669124 -277.031835) (xy 355.716656 -277.016391)
			(xy 355.766019 -277.008572) (xy 355.815997 -277.008572) (xy 355.86536 -277.016391) (xy 355.912892 -277.031835)
			(xy 355.957424 -277.054525) (xy 355.997857 -277.083901) (xy 356.033197 -277.119241) (xy 356.062573 -277.159674)
			(xy 356.085263 -277.204206) (xy 356.100707 -277.251738) (xy 356.108526 -277.301101) (xy 356.109016 -277.32609)
			(xy 356.414827 -277.32609) (xy 356.418922 -277.275362) (xy 356.431101 -277.225948) (xy 356.451049 -277.179128)
			(xy 356.47825 -277.136114) (xy 356.511998 -277.09802) (xy 356.55142 -277.065833) (xy 356.595494 -277.040387)
			(xy 356.64308 -277.02234) (xy 356.692944 -277.01216) (xy 356.743796 -277.010111) (xy 356.794317 -277.016245)
			(xy 356.843201 -277.030405) (xy 356.88918 -277.052222) (xy 356.931064 -277.081132) (xy 356.967768 -277.116387)
			(xy 356.998341 -277.157073) (xy 357.021992 -277.202136) (xy 357.038108 -277.25041) (xy 357.046272 -277.300644)
			(xy 357.046784 -277.32609) (xy 357.354881 -277.32609) (xy 357.358976 -277.275362) (xy 357.371155 -277.225948)
			(xy 357.391103 -277.179128) (xy 357.418304 -277.136114) (xy 357.452052 -277.09802) (xy 357.491474 -277.065833)
			(xy 357.535548 -277.040387) (xy 357.583134 -277.02234) (xy 357.632998 -277.01216) (xy 357.68385 -277.010111)
			(xy 357.734371 -277.016245) (xy 357.783255 -277.030405) (xy 357.829234 -277.052222) (xy 357.871118 -277.081132)
			(xy 357.907822 -277.116387) (xy 357.938395 -277.157073) (xy 357.962046 -277.202136) (xy 357.978162 -277.25041)
			(xy 357.986326 -277.300644) (xy 357.986838 -277.32609) (xy 357.986335 -277.351079) (xy 358.293652 -277.351079)
			(xy 358.293652 -277.301101) (xy 358.301471 -277.251738) (xy 358.316915 -277.204206) (xy 358.339605 -277.159674)
			(xy 358.368981 -277.119241) (xy 358.404321 -277.083901) (xy 358.444754 -277.054525) (xy 358.489286 -277.031835)
			(xy 358.536818 -277.016391) (xy 358.586181 -277.008572) (xy 358.636159 -277.008572) (xy 358.685522 -277.016391)
			(xy 358.733054 -277.031835) (xy 358.777586 -277.054525) (xy 358.818019 -277.083901) (xy 358.853359 -277.119241)
			(xy 358.882735 -277.159674) (xy 358.905425 -277.204206) (xy 358.920869 -277.251738) (xy 358.928688 -277.301101)
			(xy 358.929178 -277.32609) (xy 358.928688 -277.351079) (xy 361.10721 -277.351079) (xy 361.10721 -277.301101)
			(xy 361.115029 -277.251738) (xy 361.130473 -277.204206) (xy 361.153163 -277.159674) (xy 361.182539 -277.119241)
			(xy 361.217879 -277.083901) (xy 361.258312 -277.054525) (xy 361.302844 -277.031835) (xy 361.350376 -277.016391)
			(xy 361.399739 -277.008572) (xy 361.449717 -277.008572) (xy 361.49908 -277.016391) (xy 361.546612 -277.031835)
			(xy 361.591144 -277.054525) (xy 361.631577 -277.083901) (xy 361.666917 -277.119241) (xy 361.696293 -277.159674)
			(xy 361.718983 -277.204206) (xy 361.734427 -277.251738) (xy 361.742246 -277.301101) (xy 361.742736 -277.32609)
			(xy 362.048547 -277.32609) (xy 362.052642 -277.275362) (xy 362.064821 -277.225948) (xy 362.084769 -277.179128)
			(xy 362.11197 -277.136114) (xy 362.145718 -277.09802) (xy 362.18514 -277.065833) (xy 362.229214 -277.040387)
			(xy 362.2768 -277.02234) (xy 362.326664 -277.01216) (xy 362.377516 -277.010111) (xy 362.428037 -277.016245)
			(xy 362.476921 -277.030405) (xy 362.5229 -277.052222) (xy 362.564784 -277.081132) (xy 362.601488 -277.116387)
			(xy 362.632061 -277.157073) (xy 362.655712 -277.202136) (xy 362.671828 -277.25041) (xy 362.679992 -277.300644)
			(xy 362.680504 -277.32609) (xy 362.988601 -277.32609) (xy 362.992696 -277.275362) (xy 363.004875 -277.225948)
			(xy 363.024823 -277.179128) (xy 363.052024 -277.136114) (xy 363.085772 -277.09802) (xy 363.125194 -277.065833)
			(xy 363.169268 -277.040387) (xy 363.216854 -277.02234) (xy 363.266718 -277.01216) (xy 363.31757 -277.010111)
			(xy 363.368091 -277.016245) (xy 363.416975 -277.030405) (xy 363.462954 -277.052222) (xy 363.504838 -277.081132)
			(xy 363.541542 -277.116387) (xy 363.572115 -277.157073) (xy 363.595766 -277.202136) (xy 363.611882 -277.25041)
			(xy 363.620046 -277.300644) (xy 363.620558 -277.32609) (xy 363.620055 -277.351079) (xy 363.927372 -277.351079)
			(xy 363.927372 -277.301101) (xy 363.935191 -277.251738) (xy 363.950635 -277.204206) (xy 363.973325 -277.159674)
			(xy 364.002701 -277.119241) (xy 364.038041 -277.083901) (xy 364.078474 -277.054525) (xy 364.123006 -277.031835)
			(xy 364.170538 -277.016391) (xy 364.219901 -277.008572) (xy 364.269879 -277.008572) (xy 364.319242 -277.016391)
			(xy 364.366774 -277.031835) (xy 364.411306 -277.054525) (xy 364.451739 -277.083901) (xy 364.487079 -277.119241)
			(xy 364.516455 -277.159674) (xy 364.539145 -277.204206) (xy 364.554589 -277.251738) (xy 364.562408 -277.301101)
			(xy 364.562898 -277.32609) (xy 364.562408 -277.351079) (xy 364.867172 -277.351079) (xy 364.867172 -277.301101)
			(xy 364.874991 -277.251738) (xy 364.890435 -277.204206) (xy 364.913125 -277.159674) (xy 364.942501 -277.119241)
			(xy 364.977841 -277.083901) (xy 365.018274 -277.054525) (xy 365.062806 -277.031835) (xy 365.110338 -277.016391)
			(xy 365.159701 -277.008572) (xy 365.209679 -277.008572) (xy 365.259042 -277.016391) (xy 365.306574 -277.031835)
			(xy 365.351106 -277.054525) (xy 365.391539 -277.083901) (xy 365.426879 -277.119241) (xy 365.456255 -277.159674)
			(xy 365.478945 -277.204206) (xy 365.494389 -277.251738) (xy 365.502208 -277.301101) (xy 365.502698 -277.32609)
			(xy 365.502208 -277.351079) (xy 365.807226 -277.351079) (xy 365.807226 -277.301101) (xy 365.815045 -277.251738)
			(xy 365.830489 -277.204206) (xy 365.853179 -277.159674) (xy 365.882555 -277.119241) (xy 365.917895 -277.083901)
			(xy 365.958328 -277.054525) (xy 366.00286 -277.031835) (xy 366.050392 -277.016391) (xy 366.099755 -277.008572)
			(xy 366.149733 -277.008572) (xy 366.199096 -277.016391) (xy 366.246628 -277.031835) (xy 366.29116 -277.054525)
			(xy 366.331593 -277.083901) (xy 366.366933 -277.119241) (xy 366.396309 -277.159674) (xy 366.418999 -277.204206)
			(xy 366.434443 -277.251738) (xy 366.442262 -277.301101) (xy 366.442752 -277.32609) (xy 366.442262 -277.351079)
			(xy 366.74728 -277.351079) (xy 366.74728 -277.301101) (xy 366.755099 -277.251738) (xy 366.770543 -277.204206)
			(xy 366.793233 -277.159674) (xy 366.822609 -277.119241) (xy 366.857949 -277.083901) (xy 366.898382 -277.054525)
			(xy 366.942914 -277.031835) (xy 366.990446 -277.016391) (xy 367.039809 -277.008572) (xy 367.089787 -277.008572)
			(xy 367.13915 -277.016391) (xy 367.186682 -277.031835) (xy 367.231214 -277.054525) (xy 367.271647 -277.083901)
			(xy 367.306987 -277.119241) (xy 367.336363 -277.159674) (xy 367.359053 -277.204206) (xy 367.374497 -277.251738)
			(xy 367.382316 -277.301101) (xy 367.382806 -277.32609) (xy 367.382316 -277.351079) (xy 367.687334 -277.351079)
			(xy 367.687334 -277.301101) (xy 367.695153 -277.251738) (xy 367.710597 -277.204206) (xy 367.733287 -277.159674)
			(xy 367.762663 -277.119241) (xy 367.798003 -277.083901) (xy 367.838436 -277.054525) (xy 367.882968 -277.031835)
			(xy 367.9305 -277.016391) (xy 367.979863 -277.008572) (xy 368.029841 -277.008572) (xy 368.079204 -277.016391)
			(xy 368.126736 -277.031835) (xy 368.171268 -277.054525) (xy 368.211701 -277.083901) (xy 368.247041 -277.119241)
			(xy 368.276417 -277.159674) (xy 368.299107 -277.204206) (xy 368.314551 -277.251738) (xy 368.32237 -277.301101)
			(xy 368.32286 -277.32609) (xy 368.32237 -277.351079) (xy 368.627388 -277.351079) (xy 368.627388 -277.301101)
			(xy 368.635207 -277.251738) (xy 368.650651 -277.204206) (xy 368.673341 -277.159674) (xy 368.702717 -277.119241)
			(xy 368.738057 -277.083901) (xy 368.77849 -277.054525) (xy 368.823022 -277.031835) (xy 368.870554 -277.016391)
			(xy 368.919917 -277.008572) (xy 368.969895 -277.008572) (xy 369.019258 -277.016391) (xy 369.06679 -277.031835)
			(xy 369.111322 -277.054525) (xy 369.151755 -277.083901) (xy 369.187095 -277.119241) (xy 369.216471 -277.159674)
			(xy 369.239161 -277.204206) (xy 369.254605 -277.251738) (xy 369.262424 -277.301101) (xy 369.262914 -277.32609)
			(xy 369.262424 -277.351079) (xy 369.567188 -277.351079) (xy 369.567188 -277.301101) (xy 369.575007 -277.251738)
			(xy 369.590451 -277.204206) (xy 369.613141 -277.159674) (xy 369.642517 -277.119241) (xy 369.677857 -277.083901)
			(xy 369.71829 -277.054525) (xy 369.762822 -277.031835) (xy 369.810354 -277.016391) (xy 369.859717 -277.008572)
			(xy 369.909695 -277.008572) (xy 369.959058 -277.016391) (xy 370.00659 -277.031835) (xy 370.051122 -277.054525)
			(xy 370.091555 -277.083901) (xy 370.126895 -277.119241) (xy 370.156271 -277.159674) (xy 370.178961 -277.204206)
			(xy 370.194405 -277.251738) (xy 370.202224 -277.301101) (xy 370.202714 -277.32609) (xy 370.202224 -277.351079)
			(xy 370.507242 -277.351079) (xy 370.507242 -277.301101) (xy 370.515061 -277.251738) (xy 370.530505 -277.204206)
			(xy 370.553195 -277.159674) (xy 370.582571 -277.119241) (xy 370.617911 -277.083901) (xy 370.658344 -277.054525)
			(xy 370.702876 -277.031835) (xy 370.750408 -277.016391) (xy 370.799771 -277.008572) (xy 370.849749 -277.008572)
			(xy 370.899112 -277.016391) (xy 370.946644 -277.031835) (xy 370.991176 -277.054525) (xy 371.031609 -277.083901)
			(xy 371.066949 -277.119241) (xy 371.096325 -277.159674) (xy 371.119015 -277.204206) (xy 371.134459 -277.251738)
			(xy 371.142278 -277.301101) (xy 371.142768 -277.32609) (xy 371.142278 -277.351079) (xy 371.447296 -277.351079)
			(xy 371.447296 -277.301101) (xy 371.455115 -277.251738) (xy 371.470559 -277.204206) (xy 371.493249 -277.159674)
			(xy 371.522625 -277.119241) (xy 371.557965 -277.083901) (xy 371.598398 -277.054525) (xy 371.64293 -277.031835)
			(xy 371.690462 -277.016391) (xy 371.739825 -277.008572) (xy 371.789803 -277.008572) (xy 371.839166 -277.016391)
			(xy 371.886698 -277.031835) (xy 371.93123 -277.054525) (xy 371.971663 -277.083901) (xy 372.007003 -277.119241)
			(xy 372.036379 -277.159674) (xy 372.059069 -277.204206) (xy 372.074513 -277.251738) (xy 372.082332 -277.301101)
			(xy 372.082822 -277.32609) (xy 372.082332 -277.351079) (xy 372.38735 -277.351079) (xy 372.38735 -277.301101)
			(xy 372.395169 -277.251738) (xy 372.410613 -277.204206) (xy 372.433303 -277.159674) (xy 372.462679 -277.119241)
			(xy 372.498019 -277.083901) (xy 372.538452 -277.054525) (xy 372.582984 -277.031835) (xy 372.630516 -277.016391)
			(xy 372.679879 -277.008572) (xy 372.729857 -277.008572) (xy 372.77922 -277.016391) (xy 372.826752 -277.031835)
			(xy 372.871284 -277.054525) (xy 372.911717 -277.083901) (xy 372.947057 -277.119241) (xy 372.976433 -277.159674)
			(xy 372.999123 -277.204206) (xy 373.014567 -277.251738) (xy 373.022386 -277.301101) (xy 373.022876 -277.32609)
			(xy 373.022386 -277.351079) (xy 373.327404 -277.351079) (xy 373.327404 -277.301101) (xy 373.335223 -277.251738)
			(xy 373.350667 -277.204206) (xy 373.373357 -277.159674) (xy 373.402733 -277.119241) (xy 373.438073 -277.083901)
			(xy 373.478506 -277.054525) (xy 373.523038 -277.031835) (xy 373.57057 -277.016391) (xy 373.619933 -277.008572)
			(xy 373.669911 -277.008572) (xy 373.719274 -277.016391) (xy 373.766806 -277.031835) (xy 373.811338 -277.054525)
			(xy 373.851771 -277.083901) (xy 373.887111 -277.119241) (xy 373.916487 -277.159674) (xy 373.939177 -277.204206)
			(xy 373.954621 -277.251738) (xy 373.96244 -277.301101) (xy 373.96293 -277.32609) (xy 373.96244 -277.351079)
			(xy 373.954621 -277.400442) (xy 373.939177 -277.447974) (xy 373.916487 -277.492506) (xy 373.887111 -277.532939)
			(xy 373.851771 -277.568279) (xy 373.811338 -277.597655) (xy 373.766806 -277.620345) (xy 373.719274 -277.635789)
			(xy 373.669911 -277.643608) (xy 373.619933 -277.643608) (xy 373.57057 -277.635789) (xy 373.523038 -277.620345)
			(xy 373.478506 -277.597655) (xy 373.438073 -277.568279) (xy 373.402733 -277.532939) (xy 373.373357 -277.492506)
			(xy 373.350667 -277.447974) (xy 373.335223 -277.400442) (xy 373.327404 -277.351079) (xy 373.022386 -277.351079)
			(xy 373.014567 -277.400442) (xy 372.999123 -277.447974) (xy 372.976433 -277.492506) (xy 372.947057 -277.532939)
			(xy 372.911717 -277.568279) (xy 372.871284 -277.597655) (xy 372.826752 -277.620345) (xy 372.77922 -277.635789)
			(xy 372.729857 -277.643608) (xy 372.679879 -277.643608) (xy 372.630516 -277.635789) (xy 372.582984 -277.620345)
			(xy 372.538452 -277.597655) (xy 372.498019 -277.568279) (xy 372.462679 -277.532939) (xy 372.433303 -277.492506)
			(xy 372.410613 -277.447974) (xy 372.395169 -277.400442) (xy 372.38735 -277.351079) (xy 372.082332 -277.351079)
			(xy 372.074513 -277.400442) (xy 372.059069 -277.447974) (xy 372.036379 -277.492506) (xy 372.007003 -277.532939)
			(xy 371.971663 -277.568279) (xy 371.93123 -277.597655) (xy 371.886698 -277.620345) (xy 371.839166 -277.635789)
			(xy 371.789803 -277.643608) (xy 371.739825 -277.643608) (xy 371.690462 -277.635789) (xy 371.64293 -277.620345)
			(xy 371.598398 -277.597655) (xy 371.557965 -277.568279) (xy 371.522625 -277.532939) (xy 371.493249 -277.492506)
			(xy 371.470559 -277.447974) (xy 371.455115 -277.400442) (xy 371.447296 -277.351079) (xy 371.142278 -277.351079)
			(xy 371.134459 -277.400442) (xy 371.119015 -277.447974) (xy 371.096325 -277.492506) (xy 371.066949 -277.532939)
			(xy 371.031609 -277.568279) (xy 370.991176 -277.597655) (xy 370.946644 -277.620345) (xy 370.899112 -277.635789)
			(xy 370.849749 -277.643608) (xy 370.799771 -277.643608) (xy 370.750408 -277.635789) (xy 370.702876 -277.620345)
			(xy 370.658344 -277.597655) (xy 370.617911 -277.568279) (xy 370.582571 -277.532939) (xy 370.553195 -277.492506)
			(xy 370.530505 -277.447974) (xy 370.515061 -277.400442) (xy 370.507242 -277.351079) (xy 370.202224 -277.351079)
			(xy 370.194405 -277.400442) (xy 370.178961 -277.447974) (xy 370.156271 -277.492506) (xy 370.126895 -277.532939)
			(xy 370.091555 -277.568279) (xy 370.051122 -277.597655) (xy 370.00659 -277.620345) (xy 369.959058 -277.635789)
			(xy 369.909695 -277.643608) (xy 369.859717 -277.643608) (xy 369.810354 -277.635789) (xy 369.762822 -277.620345)
			(xy 369.71829 -277.597655) (xy 369.677857 -277.568279) (xy 369.642517 -277.532939) (xy 369.613141 -277.492506)
			(xy 369.590451 -277.447974) (xy 369.575007 -277.400442) (xy 369.567188 -277.351079) (xy 369.262424 -277.351079)
			(xy 369.254605 -277.400442) (xy 369.239161 -277.447974) (xy 369.216471 -277.492506) (xy 369.187095 -277.532939)
			(xy 369.151755 -277.568279) (xy 369.111322 -277.597655) (xy 369.06679 -277.620345) (xy 369.019258 -277.635789)
			(xy 368.969895 -277.643608) (xy 368.919917 -277.643608) (xy 368.870554 -277.635789) (xy 368.823022 -277.620345)
			(xy 368.77849 -277.597655) (xy 368.738057 -277.568279) (xy 368.702717 -277.532939) (xy 368.673341 -277.492506)
			(xy 368.650651 -277.447974) (xy 368.635207 -277.400442) (xy 368.627388 -277.351079) (xy 368.32237 -277.351079)
			(xy 368.314551 -277.400442) (xy 368.299107 -277.447974) (xy 368.276417 -277.492506) (xy 368.247041 -277.532939)
			(xy 368.211701 -277.568279) (xy 368.171268 -277.597655) (xy 368.126736 -277.620345) (xy 368.079204 -277.635789)
			(xy 368.029841 -277.643608) (xy 367.979863 -277.643608) (xy 367.9305 -277.635789) (xy 367.882968 -277.620345)
			(xy 367.838436 -277.597655) (xy 367.798003 -277.568279) (xy 367.762663 -277.532939) (xy 367.733287 -277.492506)
			(xy 367.710597 -277.447974) (xy 367.695153 -277.400442) (xy 367.687334 -277.351079) (xy 367.382316 -277.351079)
			(xy 367.374497 -277.400442) (xy 367.359053 -277.447974) (xy 367.336363 -277.492506) (xy 367.306987 -277.532939)
			(xy 367.271647 -277.568279) (xy 367.231214 -277.597655) (xy 367.186682 -277.620345) (xy 367.13915 -277.635789)
			(xy 367.089787 -277.643608) (xy 367.039809 -277.643608) (xy 366.990446 -277.635789) (xy 366.942914 -277.620345)
			(xy 366.898382 -277.597655) (xy 366.857949 -277.568279) (xy 366.822609 -277.532939) (xy 366.793233 -277.492506)
			(xy 366.770543 -277.447974) (xy 366.755099 -277.400442) (xy 366.74728 -277.351079) (xy 366.442262 -277.351079)
			(xy 366.434443 -277.400442) (xy 366.418999 -277.447974) (xy 366.396309 -277.492506) (xy 366.366933 -277.532939)
			(xy 366.331593 -277.568279) (xy 366.29116 -277.597655) (xy 366.246628 -277.620345) (xy 366.199096 -277.635789)
			(xy 366.149733 -277.643608) (xy 366.099755 -277.643608) (xy 366.050392 -277.635789) (xy 366.00286 -277.620345)
			(xy 365.958328 -277.597655) (xy 365.917895 -277.568279) (xy 365.882555 -277.532939) (xy 365.853179 -277.492506)
			(xy 365.830489 -277.447974) (xy 365.815045 -277.400442) (xy 365.807226 -277.351079) (xy 365.502208 -277.351079)
			(xy 365.494389 -277.400442) (xy 365.478945 -277.447974) (xy 365.456255 -277.492506) (xy 365.426879 -277.532939)
			(xy 365.391539 -277.568279) (xy 365.351106 -277.597655) (xy 365.306574 -277.620345) (xy 365.259042 -277.635789)
			(xy 365.209679 -277.643608) (xy 365.159701 -277.643608) (xy 365.110338 -277.635789) (xy 365.062806 -277.620345)
			(xy 365.018274 -277.597655) (xy 364.977841 -277.568279) (xy 364.942501 -277.532939) (xy 364.913125 -277.492506)
			(xy 364.890435 -277.447974) (xy 364.874991 -277.400442) (xy 364.867172 -277.351079) (xy 364.562408 -277.351079)
			(xy 364.554589 -277.400442) (xy 364.539145 -277.447974) (xy 364.516455 -277.492506) (xy 364.487079 -277.532939)
			(xy 364.451739 -277.568279) (xy 364.411306 -277.597655) (xy 364.366774 -277.620345) (xy 364.319242 -277.635789)
			(xy 364.269879 -277.643608) (xy 364.219901 -277.643608) (xy 364.170538 -277.635789) (xy 364.123006 -277.620345)
			(xy 364.078474 -277.597655) (xy 364.038041 -277.568279) (xy 364.002701 -277.532939) (xy 363.973325 -277.492506)
			(xy 363.950635 -277.447974) (xy 363.935191 -277.400442) (xy 363.927372 -277.351079) (xy 363.620055 -277.351079)
			(xy 363.620046 -277.351536) (xy 363.611882 -277.40177) (xy 363.595766 -277.450044) (xy 363.572115 -277.495107)
			(xy 363.541542 -277.535793) (xy 363.504838 -277.571048) (xy 363.462954 -277.599958) (xy 363.416975 -277.621775)
			(xy 363.368091 -277.635935) (xy 363.31757 -277.642069) (xy 363.266718 -277.64002) (xy 363.216854 -277.62984)
			(xy 363.169268 -277.611793) (xy 363.125194 -277.586347) (xy 363.085772 -277.55416) (xy 363.052024 -277.516066)
			(xy 363.024823 -277.473052) (xy 363.004875 -277.426232) (xy 362.992696 -277.376818) (xy 362.988601 -277.32609)
			(xy 362.680504 -277.32609) (xy 362.679992 -277.351536) (xy 362.671828 -277.40177) (xy 362.655712 -277.450044)
			(xy 362.632061 -277.495107) (xy 362.601488 -277.535793) (xy 362.564784 -277.571048) (xy 362.5229 -277.599958)
			(xy 362.476921 -277.621775) (xy 362.428037 -277.635935) (xy 362.377516 -277.642069) (xy 362.326664 -277.64002)
			(xy 362.2768 -277.62984) (xy 362.229214 -277.611793) (xy 362.18514 -277.586347) (xy 362.145718 -277.55416)
			(xy 362.11197 -277.516066) (xy 362.084769 -277.473052) (xy 362.064821 -277.426232) (xy 362.052642 -277.376818)
			(xy 362.048547 -277.32609) (xy 361.742736 -277.32609) (xy 361.742246 -277.351079) (xy 361.734427 -277.400442)
			(xy 361.718983 -277.447974) (xy 361.696293 -277.492506) (xy 361.666917 -277.532939) (xy 361.631577 -277.568279)
			(xy 361.591144 -277.597655) (xy 361.546612 -277.620345) (xy 361.49908 -277.635789) (xy 361.449717 -277.643608)
			(xy 361.399739 -277.643608) (xy 361.350376 -277.635789) (xy 361.302844 -277.620345) (xy 361.258312 -277.597655)
			(xy 361.217879 -277.568279) (xy 361.182539 -277.532939) (xy 361.153163 -277.492506) (xy 361.130473 -277.447974)
			(xy 361.115029 -277.400442) (xy 361.10721 -277.351079) (xy 358.928688 -277.351079) (xy 358.920869 -277.400442)
			(xy 358.905425 -277.447974) (xy 358.882735 -277.492506) (xy 358.853359 -277.532939) (xy 358.818019 -277.568279)
			(xy 358.777586 -277.597655) (xy 358.733054 -277.620345) (xy 358.685522 -277.635789) (xy 358.636159 -277.643608)
			(xy 358.586181 -277.643608) (xy 358.536818 -277.635789) (xy 358.489286 -277.620345) (xy 358.444754 -277.597655)
			(xy 358.404321 -277.568279) (xy 358.368981 -277.532939) (xy 358.339605 -277.492506) (xy 358.316915 -277.447974)
			(xy 358.301471 -277.400442) (xy 358.293652 -277.351079) (xy 357.986335 -277.351079) (xy 357.986326 -277.351536)
			(xy 357.978162 -277.40177) (xy 357.962046 -277.450044) (xy 357.938395 -277.495107) (xy 357.907822 -277.535793)
			(xy 357.871118 -277.571048) (xy 357.829234 -277.599958) (xy 357.783255 -277.621775) (xy 357.734371 -277.635935)
			(xy 357.68385 -277.642069) (xy 357.632998 -277.64002) (xy 357.583134 -277.62984) (xy 357.535548 -277.611793)
			(xy 357.491474 -277.586347) (xy 357.452052 -277.55416) (xy 357.418304 -277.516066) (xy 357.391103 -277.473052)
			(xy 357.371155 -277.426232) (xy 357.358976 -277.376818) (xy 357.354881 -277.32609) (xy 357.046784 -277.32609)
			(xy 357.046272 -277.351536) (xy 357.038108 -277.40177) (xy 357.021992 -277.450044) (xy 356.998341 -277.495107)
			(xy 356.967768 -277.535793) (xy 356.931064 -277.571048) (xy 356.88918 -277.599958) (xy 356.843201 -277.621775)
			(xy 356.794317 -277.635935) (xy 356.743796 -277.642069) (xy 356.692944 -277.64002) (xy 356.64308 -277.62984)
			(xy 356.595494 -277.611793) (xy 356.55142 -277.586347) (xy 356.511998 -277.55416) (xy 356.47825 -277.516066)
			(xy 356.451049 -277.473052) (xy 356.431101 -277.426232) (xy 356.418922 -277.376818) (xy 356.414827 -277.32609)
			(xy 356.109016 -277.32609) (xy 356.108526 -277.351079) (xy 356.100707 -277.400442) (xy 356.085263 -277.447974)
			(xy 356.062573 -277.492506) (xy 356.033197 -277.532939) (xy 355.997857 -277.568279) (xy 355.957424 -277.597655)
			(xy 355.912892 -277.620345) (xy 355.86536 -277.635789) (xy 355.815997 -277.643608) (xy 355.766019 -277.643608)
			(xy 355.716656 -277.635789) (xy 355.669124 -277.620345) (xy 355.624592 -277.597655) (xy 355.584159 -277.568279)
			(xy 355.548819 -277.532939) (xy 355.519443 -277.492506) (xy 355.496753 -277.447974) (xy 355.481309 -277.400442)
			(xy 355.47349 -277.351079) (xy 355.168726 -277.351079) (xy 355.160907 -277.400442) (xy 355.145463 -277.447974)
			(xy 355.122773 -277.492506) (xy 355.093397 -277.532939) (xy 355.058057 -277.568279) (xy 355.017624 -277.597655)
			(xy 354.973092 -277.620345) (xy 354.92556 -277.635789) (xy 354.876197 -277.643608) (xy 354.826219 -277.643608)
			(xy 354.776856 -277.635789) (xy 354.729324 -277.620345) (xy 354.684792 -277.597655) (xy 354.644359 -277.568279)
			(xy 354.609019 -277.532939) (xy 354.579643 -277.492506) (xy 354.556953 -277.447974) (xy 354.541509 -277.400442)
			(xy 354.53369 -277.351079) (xy 354.228672 -277.351079) (xy 354.220853 -277.400442) (xy 354.205409 -277.447974)
			(xy 354.182719 -277.492506) (xy 354.153343 -277.532939) (xy 354.118003 -277.568279) (xy 354.07757 -277.597655)
			(xy 354.033038 -277.620345) (xy 353.985506 -277.635789) (xy 353.936143 -277.643608) (xy 353.886165 -277.643608)
			(xy 353.836802 -277.635789) (xy 353.78927 -277.620345) (xy 353.744738 -277.597655) (xy 353.704305 -277.568279)
			(xy 353.668965 -277.532939) (xy 353.639589 -277.492506) (xy 353.616899 -277.447974) (xy 353.601455 -277.400442)
			(xy 353.593636 -277.351079) (xy 353.288618 -277.351079) (xy 353.280799 -277.400442) (xy 353.265355 -277.447974)
			(xy 353.242665 -277.492506) (xy 353.213289 -277.532939) (xy 353.177949 -277.568279) (xy 353.137516 -277.597655)
			(xy 353.092984 -277.620345) (xy 353.045452 -277.635789) (xy 352.996089 -277.643608) (xy 352.946111 -277.643608)
			(xy 352.896748 -277.635789) (xy 352.849216 -277.620345) (xy 352.804684 -277.597655) (xy 352.764251 -277.568279)
			(xy 352.728911 -277.532939) (xy 352.699535 -277.492506) (xy 352.676845 -277.447974) (xy 352.661401 -277.400442)
			(xy 352.653582 -277.351079) (xy 352.348564 -277.351079) (xy 352.340745 -277.400442) (xy 352.325301 -277.447974)
			(xy 352.302611 -277.492506) (xy 352.273235 -277.532939) (xy 352.237895 -277.568279) (xy 352.197462 -277.597655)
			(xy 352.15293 -277.620345) (xy 352.105398 -277.635789) (xy 352.056035 -277.643608) (xy 352.006057 -277.643608)
			(xy 351.956694 -277.635789) (xy 351.909162 -277.620345) (xy 351.86463 -277.597655) (xy 351.824197 -277.568279)
			(xy 351.788857 -277.532939) (xy 351.759481 -277.492506) (xy 351.736791 -277.447974) (xy 351.721347 -277.400442)
			(xy 351.713528 -277.351079) (xy 351.408764 -277.351079) (xy 351.400945 -277.400442) (xy 351.385501 -277.447974)
			(xy 351.362811 -277.492506) (xy 351.333435 -277.532939) (xy 351.298095 -277.568279) (xy 351.257662 -277.597655)
			(xy 351.21313 -277.620345) (xy 351.165598 -277.635789) (xy 351.116235 -277.643608) (xy 351.066257 -277.643608)
			(xy 351.016894 -277.635789) (xy 350.969362 -277.620345) (xy 350.92483 -277.597655) (xy 350.884397 -277.568279)
			(xy 350.849057 -277.532939) (xy 350.819681 -277.492506) (xy 350.796991 -277.447974) (xy 350.781547 -277.400442)
			(xy 350.773728 -277.351079) (xy 350.46871 -277.351079) (xy 350.460891 -277.400442) (xy 350.445447 -277.447974)
			(xy 350.422757 -277.492506) (xy 350.393381 -277.532939) (xy 350.358041 -277.568279) (xy 350.317608 -277.597655)
			(xy 350.273076 -277.620345) (xy 350.225544 -277.635789) (xy 350.176181 -277.643608) (xy 350.126203 -277.643608)
			(xy 350.07684 -277.635789) (xy 350.029308 -277.620345) (xy 349.984776 -277.597655) (xy 349.944343 -277.568279)
			(xy 349.909003 -277.532939) (xy 349.879627 -277.492506) (xy 349.856937 -277.447974) (xy 349.841493 -277.400442)
			(xy 349.833674 -277.351079) (xy 349.528656 -277.351079) (xy 349.520837 -277.400442) (xy 349.505393 -277.447974)
			(xy 349.482703 -277.492506) (xy 349.453327 -277.532939) (xy 349.417987 -277.568279) (xy 349.377554 -277.597655)
			(xy 349.333022 -277.620345) (xy 349.28549 -277.635789) (xy 349.236127 -277.643608) (xy 349.186149 -277.643608)
			(xy 349.136786 -277.635789) (xy 349.089254 -277.620345) (xy 349.044722 -277.597655) (xy 349.004289 -277.568279)
			(xy 348.968949 -277.532939) (xy 348.939573 -277.492506) (xy 348.916883 -277.447974) (xy 348.901439 -277.400442)
			(xy 348.89362 -277.351079) (xy 348.588602 -277.351079) (xy 348.580783 -277.400442) (xy 348.565339 -277.447974)
			(xy 348.542649 -277.492506) (xy 348.513273 -277.532939) (xy 348.477933 -277.568279) (xy 348.4375 -277.597655)
			(xy 348.392968 -277.620345) (xy 348.345436 -277.635789) (xy 348.296073 -277.643608) (xy 348.246095 -277.643608)
			(xy 348.196732 -277.635789) (xy 348.1492 -277.620345) (xy 348.104668 -277.597655) (xy 348.064235 -277.568279)
			(xy 348.028895 -277.532939) (xy 347.999519 -277.492506) (xy 347.976829 -277.447974) (xy 347.961385 -277.400442)
			(xy 347.953566 -277.351079) (xy 347.648548 -277.351079) (xy 347.640729 -277.400442) (xy 347.625285 -277.447974)
			(xy 347.602595 -277.492506) (xy 347.573219 -277.532939) (xy 347.537879 -277.568279) (xy 347.497446 -277.597655)
			(xy 347.452914 -277.620345) (xy 347.405382 -277.635789) (xy 347.356019 -277.643608) (xy 347.306041 -277.643608)
			(xy 347.256678 -277.635789) (xy 347.209146 -277.620345) (xy 347.164614 -277.597655) (xy 347.124181 -277.568279)
			(xy 347.088841 -277.532939) (xy 347.059465 -277.492506) (xy 347.036775 -277.447974) (xy 347.021331 -277.400442)
			(xy 347.013512 -277.351079) (xy 346.708748 -277.351079) (xy 346.700929 -277.400442) (xy 346.685485 -277.447974)
			(xy 346.662795 -277.492506) (xy 346.633419 -277.532939) (xy 346.598079 -277.568279) (xy 346.557646 -277.597655)
			(xy 346.513114 -277.620345) (xy 346.465582 -277.635789) (xy 346.416219 -277.643608) (xy 346.366241 -277.643608)
			(xy 346.316878 -277.635789) (xy 346.269346 -277.620345) (xy 346.224814 -277.597655) (xy 346.184381 -277.568279)
			(xy 346.149041 -277.532939) (xy 346.119665 -277.492506) (xy 346.096975 -277.447974) (xy 346.081531 -277.400442)
			(xy 346.073712 -277.351079) (xy 345.768753 -277.351079) (xy 345.768753 -277.351093) (xy 345.760933 -277.400464)
			(xy 345.745486 -277.448004) (xy 345.722792 -277.492542) (xy 345.693409 -277.53298) (xy 345.658062 -277.568325)
			(xy 345.617621 -277.597704) (xy 345.573082 -277.620395) (xy 345.525541 -277.635839) (xy 345.476169 -277.643655)
			(xy 345.451176 -277.644098) (xy 345.427298 -277.643669) (xy 345.380079 -277.636534) (xy 345.334456 -277.622426)
			(xy 345.29145 -277.601663) (xy 345.252028 -277.574711) (xy 345.23426 -277.558754) (xy 345.228658 -277.553886)
			(xy 345.215367 -277.547296) (xy 345.208098 -277.5458) (xy 345.20124 -277.54453) (xy 345.186508 -277.546308)
			(xy 345.14155 -277.565866) (xy 345.096338 -277.585678) (xy 345.087516 -277.590042) (xy 345.073794 -277.604125)
			(xy 345.066363 -277.62233) (xy 345.065858 -277.63216) (xy 345.065858 -277.79345) (xy 345.065858 -277.79472)
			(xy 345.066515 -277.80411) (xy 345.073726 -277.82148) (xy 345.086722 -277.835074) (xy 345.095068 -277.839424)
			(xy 345.097862 -277.84044) (xy 345.120565 -277.849892) (xy 345.162983 -277.874772) (xy 345.201062 -277.905887)
			(xy 345.233896 -277.942496) (xy 345.260699 -277.983725) (xy 345.280832 -278.028591) (xy 345.293815 -278.076021)
			(xy 345.299338 -278.124886) (xy 345.298866 -278.136096) (xy 345.604841 -278.136096) (xy 345.608936 -278.085368)
			(xy 345.621115 -278.035954) (xy 345.641063 -277.989134) (xy 345.668264 -277.94612) (xy 345.702012 -277.908026)
			(xy 345.741434 -277.875839) (xy 345.785508 -277.850393) (xy 345.833094 -277.832346) (xy 345.882958 -277.822166)
			(xy 345.93381 -277.820117) (xy 345.984331 -277.826251) (xy 346.033215 -277.840411) (xy 346.079194 -277.862228)
			(xy 346.121078 -277.891138) (xy 346.157782 -277.926393) (xy 346.188355 -277.967079) (xy 346.212006 -278.012142)
			(xy 346.228122 -278.060416) (xy 346.236286 -278.11065) (xy 346.236798 -278.136096) (xy 346.544895 -278.136096)
			(xy 346.54899 -278.085368) (xy 346.561169 -278.035954) (xy 346.581117 -277.989134) (xy 346.608318 -277.94612)
			(xy 346.642066 -277.908026) (xy 346.681488 -277.875839) (xy 346.725562 -277.850393) (xy 346.773148 -277.832346)
			(xy 346.823012 -277.822166) (xy 346.873864 -277.820117) (xy 346.924385 -277.826251) (xy 346.973269 -277.840411)
			(xy 347.019248 -277.862228) (xy 347.061132 -277.891138) (xy 347.097836 -277.926393) (xy 347.128409 -277.967079)
			(xy 347.15206 -278.012142) (xy 347.168176 -278.060416) (xy 347.17634 -278.11065) (xy 347.176852 -278.136096)
			(xy 347.176349 -278.161085) (xy 347.483666 -278.161085) (xy 347.483666 -278.111107) (xy 347.491485 -278.061744)
			(xy 347.506929 -278.014212) (xy 347.529619 -277.96968) (xy 347.558995 -277.929247) (xy 347.594335 -277.893907)
			(xy 347.634768 -277.864531) (xy 347.6793 -277.841841) (xy 347.726832 -277.826397) (xy 347.776195 -277.818578)
			(xy 347.826173 -277.818578) (xy 347.875536 -277.826397) (xy 347.923068 -277.841841) (xy 347.9676 -277.864531)
			(xy 348.008033 -277.893907) (xy 348.043373 -277.929247) (xy 348.072749 -277.96968) (xy 348.095439 -278.014212)
			(xy 348.110883 -278.061744) (xy 348.118702 -278.111107) (xy 348.119192 -278.136096) (xy 348.425003 -278.136096)
			(xy 348.429098 -278.085368) (xy 348.441277 -278.035954) (xy 348.461225 -277.989134) (xy 348.488426 -277.94612)
			(xy 348.522174 -277.908026) (xy 348.561596 -277.875839) (xy 348.60567 -277.850393) (xy 348.653256 -277.832346)
			(xy 348.70312 -277.822166) (xy 348.753972 -277.820117) (xy 348.804493 -277.826251) (xy 348.853377 -277.840411)
			(xy 348.899356 -277.862228) (xy 348.94124 -277.891138) (xy 348.977944 -277.926393) (xy 349.008517 -277.967079)
			(xy 349.032168 -278.012142) (xy 349.048284 -278.060416) (xy 349.056448 -278.11065) (xy 349.05696 -278.136096)
			(xy 349.364803 -278.136096) (xy 349.368898 -278.085368) (xy 349.381077 -278.035954) (xy 349.401025 -277.989134)
			(xy 349.428226 -277.94612) (xy 349.461974 -277.908026) (xy 349.501396 -277.875839) (xy 349.54547 -277.850393)
			(xy 349.593056 -277.832346) (xy 349.64292 -277.822166) (xy 349.693772 -277.820117) (xy 349.744293 -277.826251)
			(xy 349.793177 -277.840411) (xy 349.839156 -277.862228) (xy 349.88104 -277.891138) (xy 349.917744 -277.926393)
			(xy 349.948317 -277.967079) (xy 349.971968 -278.012142) (xy 349.988084 -278.060416) (xy 349.996248 -278.11065)
			(xy 349.99676 -278.136096) (xy 349.996257 -278.161085) (xy 350.303574 -278.161085) (xy 350.303574 -278.111107)
			(xy 350.311393 -278.061744) (xy 350.326837 -278.014212) (xy 350.349527 -277.96968) (xy 350.378903 -277.929247)
			(xy 350.414243 -277.893907) (xy 350.454676 -277.864531) (xy 350.499208 -277.841841) (xy 350.54674 -277.826397)
			(xy 350.596103 -277.818578) (xy 350.646081 -277.818578) (xy 350.695444 -277.826397) (xy 350.742976 -277.841841)
			(xy 350.787508 -277.864531) (xy 350.827941 -277.893907) (xy 350.863281 -277.929247) (xy 350.892657 -277.96968)
			(xy 350.915347 -278.014212) (xy 350.930791 -278.061744) (xy 350.93861 -278.111107) (xy 350.9391 -278.136096)
			(xy 351.244911 -278.136096) (xy 351.249006 -278.085368) (xy 351.261185 -278.035954) (xy 351.281133 -277.989134)
			(xy 351.308334 -277.94612) (xy 351.342082 -277.908026) (xy 351.381504 -277.875839) (xy 351.425578 -277.850393)
			(xy 351.473164 -277.832346) (xy 351.523028 -277.822166) (xy 351.57388 -277.820117) (xy 351.624401 -277.826251)
			(xy 351.673285 -277.840411) (xy 351.719264 -277.862228) (xy 351.761148 -277.891138) (xy 351.797852 -277.926393)
			(xy 351.828425 -277.967079) (xy 351.852076 -278.012142) (xy 351.868192 -278.060416) (xy 351.876356 -278.11065)
			(xy 351.876868 -278.136096) (xy 352.184965 -278.136096) (xy 352.18906 -278.085368) (xy 352.201239 -278.035954)
			(xy 352.221187 -277.989134) (xy 352.248388 -277.94612) (xy 352.282136 -277.908026) (xy 352.321558 -277.875839)
			(xy 352.365632 -277.850393) (xy 352.413218 -277.832346) (xy 352.463082 -277.822166) (xy 352.513934 -277.820117)
			(xy 352.564455 -277.826251) (xy 352.613339 -277.840411) (xy 352.659318 -277.862228) (xy 352.701202 -277.891138)
			(xy 352.737906 -277.926393) (xy 352.768479 -277.967079) (xy 352.79213 -278.012142) (xy 352.808246 -278.060416)
			(xy 352.81641 -278.11065) (xy 352.816922 -278.136096) (xy 352.816419 -278.161085) (xy 353.123482 -278.161085)
			(xy 353.123482 -278.111107) (xy 353.131301 -278.061744) (xy 353.146745 -278.014212) (xy 353.169435 -277.96968)
			(xy 353.198811 -277.929247) (xy 353.234151 -277.893907) (xy 353.274584 -277.864531) (xy 353.319116 -277.841841)
			(xy 353.366648 -277.826397) (xy 353.416011 -277.818578) (xy 353.465989 -277.818578) (xy 353.515352 -277.826397)
			(xy 353.562884 -277.841841) (xy 353.607416 -277.864531) (xy 353.647849 -277.893907) (xy 353.683189 -277.929247)
			(xy 353.712565 -277.96968) (xy 353.735255 -278.014212) (xy 353.750699 -278.061744) (xy 353.758518 -278.111107)
			(xy 353.759008 -278.136096) (xy 354.064819 -278.136096) (xy 354.068914 -278.085368) (xy 354.081093 -278.035954)
			(xy 354.101041 -277.989134) (xy 354.128242 -277.94612) (xy 354.16199 -277.908026) (xy 354.201412 -277.875839)
			(xy 354.245486 -277.850393) (xy 354.293072 -277.832346) (xy 354.342936 -277.822166) (xy 354.393788 -277.820117)
			(xy 354.444309 -277.826251) (xy 354.493193 -277.840411) (xy 354.539172 -277.862228) (xy 354.581056 -277.891138)
			(xy 354.61776 -277.926393) (xy 354.648333 -277.967079) (xy 354.671984 -278.012142) (xy 354.6881 -278.060416)
			(xy 354.696264 -278.11065) (xy 354.696776 -278.136096) (xy 355.004873 -278.136096) (xy 355.008968 -278.085368)
			(xy 355.021147 -278.035954) (xy 355.041095 -277.989134) (xy 355.068296 -277.94612) (xy 355.102044 -277.908026)
			(xy 355.141466 -277.875839) (xy 355.18554 -277.850393) (xy 355.233126 -277.832346) (xy 355.28299 -277.822166)
			(xy 355.333842 -277.820117) (xy 355.384363 -277.826251) (xy 355.433247 -277.840411) (xy 355.479226 -277.862228)
			(xy 355.52111 -277.891138) (xy 355.557814 -277.926393) (xy 355.588387 -277.967079) (xy 355.612038 -278.012142)
			(xy 355.628154 -278.060416) (xy 355.636318 -278.11065) (xy 355.63683 -278.136096) (xy 355.636327 -278.161085)
			(xy 355.943644 -278.161085) (xy 355.943644 -278.111107) (xy 355.951463 -278.061744) (xy 355.966907 -278.014212)
			(xy 355.989597 -277.96968) (xy 356.018973 -277.929247) (xy 356.054313 -277.893907) (xy 356.094746 -277.864531)
			(xy 356.139278 -277.841841) (xy 356.18681 -277.826397) (xy 356.236173 -277.818578) (xy 356.286151 -277.818578)
			(xy 356.335514 -277.826397) (xy 356.383046 -277.841841) (xy 356.427578 -277.864531) (xy 356.468011 -277.893907)
			(xy 356.503351 -277.929247) (xy 356.532727 -277.96968) (xy 356.555417 -278.014212) (xy 356.570861 -278.061744)
			(xy 356.57868 -278.111107) (xy 356.57917 -278.136096) (xy 356.57868 -278.161085) (xy 363.457218 -278.161085)
			(xy 363.457218 -278.111107) (xy 363.465037 -278.061744) (xy 363.480481 -278.014212) (xy 363.503171 -277.96968)
			(xy 363.532547 -277.929247) (xy 363.567887 -277.893907) (xy 363.60832 -277.864531) (xy 363.652852 -277.841841)
			(xy 363.700384 -277.826397) (xy 363.749747 -277.818578) (xy 363.799725 -277.818578) (xy 363.849088 -277.826397)
			(xy 363.89662 -277.841841) (xy 363.941152 -277.864531) (xy 363.981585 -277.893907) (xy 364.016925 -277.929247)
			(xy 364.046301 -277.96968) (xy 364.068991 -278.014212) (xy 364.084435 -278.061744) (xy 364.092254 -278.111107)
			(xy 364.092744 -278.136096) (xy 364.398555 -278.136096) (xy 364.40265 -278.085368) (xy 364.414829 -278.035954)
			(xy 364.434777 -277.989134) (xy 364.461978 -277.94612) (xy 364.495726 -277.908026) (xy 364.535148 -277.875839)
			(xy 364.579222 -277.850393) (xy 364.626808 -277.832346) (xy 364.676672 -277.822166) (xy 364.727524 -277.820117)
			(xy 364.778045 -277.826251) (xy 364.826929 -277.840411) (xy 364.872908 -277.862228) (xy 364.914792 -277.891138)
			(xy 364.951496 -277.926393) (xy 364.982069 -277.967079) (xy 365.00572 -278.012142) (xy 365.021836 -278.060416)
			(xy 365.03 -278.11065) (xy 365.030512 -278.136096) (xy 365.338609 -278.136096) (xy 365.342704 -278.085368)
			(xy 365.354883 -278.035954) (xy 365.374831 -277.989134) (xy 365.402032 -277.94612) (xy 365.43578 -277.908026)
			(xy 365.475202 -277.875839) (xy 365.519276 -277.850393) (xy 365.566862 -277.832346) (xy 365.616726 -277.822166)
			(xy 365.667578 -277.820117) (xy 365.718099 -277.826251) (xy 365.766983 -277.840411) (xy 365.812962 -277.862228)
			(xy 365.854846 -277.891138) (xy 365.89155 -277.926393) (xy 365.922123 -277.967079) (xy 365.945774 -278.012142)
			(xy 365.96189 -278.060416) (xy 365.970054 -278.11065) (xy 365.970566 -278.136096) (xy 365.970063 -278.161085)
			(xy 366.27738 -278.161085) (xy 366.27738 -278.111107) (xy 366.285199 -278.061744) (xy 366.300643 -278.014212)
			(xy 366.323333 -277.96968) (xy 366.352709 -277.929247) (xy 366.388049 -277.893907) (xy 366.428482 -277.864531)
			(xy 366.473014 -277.841841) (xy 366.520546 -277.826397) (xy 366.569909 -277.818578) (xy 366.619887 -277.818578)
			(xy 366.66925 -277.826397) (xy 366.716782 -277.841841) (xy 366.761314 -277.864531) (xy 366.801747 -277.893907)
			(xy 366.837087 -277.929247) (xy 366.866463 -277.96968) (xy 366.889153 -278.014212) (xy 366.904597 -278.061744)
			(xy 366.912416 -278.111107) (xy 366.912906 -278.136096) (xy 367.218463 -278.136096) (xy 367.222558 -278.085368)
			(xy 367.234737 -278.035954) (xy 367.254685 -277.989134) (xy 367.281886 -277.94612) (xy 367.315634 -277.908026)
			(xy 367.355056 -277.875839) (xy 367.39913 -277.850393) (xy 367.446716 -277.832346) (xy 367.49658 -277.822166)
			(xy 367.547432 -277.820117) (xy 367.597953 -277.826251) (xy 367.646837 -277.840411) (xy 367.692816 -277.862228)
			(xy 367.7347 -277.891138) (xy 367.771404 -277.926393) (xy 367.801977 -277.967079) (xy 367.825628 -278.012142)
			(xy 367.841744 -278.060416) (xy 367.849908 -278.11065) (xy 367.85042 -278.136096) (xy 368.158517 -278.136096)
			(xy 368.162612 -278.085368) (xy 368.174791 -278.035954) (xy 368.194739 -277.989134) (xy 368.22194 -277.94612)
			(xy 368.255688 -277.908026) (xy 368.29511 -277.875839) (xy 368.339184 -277.850393) (xy 368.38677 -277.832346)
			(xy 368.436634 -277.822166) (xy 368.487486 -277.820117) (xy 368.538007 -277.826251) (xy 368.586891 -277.840411)
			(xy 368.63287 -277.862228) (xy 368.674754 -277.891138) (xy 368.711458 -277.926393) (xy 368.742031 -277.967079)
			(xy 368.765682 -278.012142) (xy 368.781798 -278.060416) (xy 368.789962 -278.11065) (xy 368.790474 -278.136096)
			(xy 368.789971 -278.161085) (xy 369.097288 -278.161085) (xy 369.097288 -278.111107) (xy 369.105107 -278.061744)
			(xy 369.120551 -278.014212) (xy 369.143241 -277.96968) (xy 369.172617 -277.929247) (xy 369.207957 -277.893907)
			(xy 369.24839 -277.864531) (xy 369.292922 -277.841841) (xy 369.340454 -277.826397) (xy 369.389817 -277.818578)
			(xy 369.439795 -277.818578) (xy 369.489158 -277.826397) (xy 369.53669 -277.841841) (xy 369.581222 -277.864531)
			(xy 369.621655 -277.893907) (xy 369.656995 -277.929247) (xy 369.686371 -277.96968) (xy 369.709061 -278.014212)
			(xy 369.724505 -278.061744) (xy 369.732324 -278.111107) (xy 369.732814 -278.136096) (xy 370.038625 -278.136096)
			(xy 370.04272 -278.085368) (xy 370.054899 -278.035954) (xy 370.074847 -277.989134) (xy 370.102048 -277.94612)
			(xy 370.135796 -277.908026) (xy 370.175218 -277.875839) (xy 370.219292 -277.850393) (xy 370.266878 -277.832346)
			(xy 370.316742 -277.822166) (xy 370.367594 -277.820117) (xy 370.418115 -277.826251) (xy 370.466999 -277.840411)
			(xy 370.512978 -277.862228) (xy 370.554862 -277.891138) (xy 370.591566 -277.926393) (xy 370.622139 -277.967079)
			(xy 370.64579 -278.012142) (xy 370.661906 -278.060416) (xy 370.67007 -278.11065) (xy 370.670582 -278.136096)
			(xy 370.978679 -278.136096) (xy 370.982774 -278.085368) (xy 370.994953 -278.035954) (xy 371.014901 -277.989134)
			(xy 371.042102 -277.94612) (xy 371.07585 -277.908026) (xy 371.115272 -277.875839) (xy 371.159346 -277.850393)
			(xy 371.206932 -277.832346) (xy 371.256796 -277.822166) (xy 371.307648 -277.820117) (xy 371.358169 -277.826251)
			(xy 371.407053 -277.840411) (xy 371.453032 -277.862228) (xy 371.494916 -277.891138) (xy 371.53162 -277.926393)
			(xy 371.562193 -277.967079) (xy 371.585844 -278.012142) (xy 371.60196 -278.060416) (xy 371.610124 -278.11065)
			(xy 371.610636 -278.136096) (xy 371.610133 -278.161085) (xy 371.917196 -278.161085) (xy 371.917196 -278.111107)
			(xy 371.925015 -278.061744) (xy 371.940459 -278.014212) (xy 371.963149 -277.96968) (xy 371.992525 -277.929247)
			(xy 372.027865 -277.893907) (xy 372.068298 -277.864531) (xy 372.11283 -277.841841) (xy 372.160362 -277.826397)
			(xy 372.209725 -277.818578) (xy 372.259703 -277.818578) (xy 372.309066 -277.826397) (xy 372.356598 -277.841841)
			(xy 372.40113 -277.864531) (xy 372.441563 -277.893907) (xy 372.476903 -277.929247) (xy 372.506279 -277.96968)
			(xy 372.528969 -278.014212) (xy 372.544413 -278.061744) (xy 372.552232 -278.111107) (xy 372.552722 -278.136096)
			(xy 372.858533 -278.136096) (xy 372.862628 -278.085368) (xy 372.874807 -278.035954) (xy 372.894755 -277.989134)
			(xy 372.921956 -277.94612) (xy 372.955704 -277.908026) (xy 372.995126 -277.875839) (xy 373.0392 -277.850393)
			(xy 373.086786 -277.832346) (xy 373.13665 -277.822166) (xy 373.187502 -277.820117) (xy 373.238023 -277.826251)
			(xy 373.286907 -277.840411) (xy 373.332886 -277.862228) (xy 373.37477 -277.891138) (xy 373.411474 -277.926393)
			(xy 373.442047 -277.967079) (xy 373.465698 -278.012142) (xy 373.481814 -278.060416) (xy 373.489978 -278.11065)
			(xy 373.49049 -278.136096) (xy 373.798587 -278.136096) (xy 373.802682 -278.085368) (xy 373.814861 -278.035954)
			(xy 373.834809 -277.989134) (xy 373.86201 -277.94612) (xy 373.895758 -277.908026) (xy 373.93518 -277.875839)
			(xy 373.979254 -277.850393) (xy 374.02684 -277.832346) (xy 374.076704 -277.822166) (xy 374.127556 -277.820117)
			(xy 374.178077 -277.826251) (xy 374.226961 -277.840411) (xy 374.27294 -277.862228) (xy 374.314824 -277.891138)
			(xy 374.351528 -277.926393) (xy 374.382101 -277.967079) (xy 374.405752 -278.012142) (xy 374.421868 -278.060416)
			(xy 374.430032 -278.11065) (xy 374.430544 -278.136096) (xy 374.430032 -278.161542) (xy 374.421868 -278.211776)
			(xy 374.405752 -278.26005) (xy 374.382101 -278.305113) (xy 374.351528 -278.345799) (xy 374.314824 -278.381054)
			(xy 374.27294 -278.409964) (xy 374.226961 -278.431781) (xy 374.178077 -278.445941) (xy 374.127556 -278.452075)
			(xy 374.076704 -278.450026) (xy 374.02684 -278.439846) (xy 373.979254 -278.421799) (xy 373.93518 -278.396353)
			(xy 373.895758 -278.364166) (xy 373.86201 -278.326072) (xy 373.834809 -278.283058) (xy 373.814861 -278.236238)
			(xy 373.802682 -278.186824) (xy 373.798587 -278.136096) (xy 373.49049 -278.136096) (xy 373.489978 -278.161542)
			(xy 373.481814 -278.211776) (xy 373.465698 -278.26005) (xy 373.442047 -278.305113) (xy 373.411474 -278.345799)
			(xy 373.37477 -278.381054) (xy 373.332886 -278.409964) (xy 373.286907 -278.431781) (xy 373.238023 -278.445941)
			(xy 373.187502 -278.452075) (xy 373.13665 -278.450026) (xy 373.086786 -278.439846) (xy 373.0392 -278.421799)
			(xy 372.995126 -278.396353) (xy 372.955704 -278.364166) (xy 372.921956 -278.326072) (xy 372.894755 -278.283058)
			(xy 372.874807 -278.236238) (xy 372.862628 -278.186824) (xy 372.858533 -278.136096) (xy 372.552722 -278.136096)
			(xy 372.552232 -278.161085) (xy 372.544413 -278.210448) (xy 372.528969 -278.25798) (xy 372.506279 -278.302512)
			(xy 372.476903 -278.342945) (xy 372.441563 -278.378285) (xy 372.40113 -278.407661) (xy 372.356598 -278.430351)
			(xy 372.309066 -278.445795) (xy 372.259703 -278.453614) (xy 372.209725 -278.453614) (xy 372.160362 -278.445795)
			(xy 372.11283 -278.430351) (xy 372.068298 -278.407661) (xy 372.027865 -278.378285) (xy 371.992525 -278.342945)
			(xy 371.963149 -278.302512) (xy 371.940459 -278.25798) (xy 371.925015 -278.210448) (xy 371.917196 -278.161085)
			(xy 371.610133 -278.161085) (xy 371.610124 -278.161542) (xy 371.60196 -278.211776) (xy 371.585844 -278.26005)
			(xy 371.562193 -278.305113) (xy 371.53162 -278.345799) (xy 371.494916 -278.381054) (xy 371.453032 -278.409964)
			(xy 371.407053 -278.431781) (xy 371.358169 -278.445941) (xy 371.307648 -278.452075) (xy 371.256796 -278.450026)
			(xy 371.206932 -278.439846) (xy 371.159346 -278.421799) (xy 371.115272 -278.396353) (xy 371.07585 -278.364166)
			(xy 371.042102 -278.326072) (xy 371.014901 -278.283058) (xy 370.994953 -278.236238) (xy 370.982774 -278.186824)
			(xy 370.978679 -278.136096) (xy 370.670582 -278.136096) (xy 370.67007 -278.161542) (xy 370.661906 -278.211776)
			(xy 370.64579 -278.26005) (xy 370.622139 -278.305113) (xy 370.591566 -278.345799) (xy 370.554862 -278.381054)
			(xy 370.512978 -278.409964) (xy 370.466999 -278.431781) (xy 370.418115 -278.445941) (xy 370.367594 -278.452075)
			(xy 370.316742 -278.450026) (xy 370.266878 -278.439846) (xy 370.219292 -278.421799) (xy 370.175218 -278.396353)
			(xy 370.135796 -278.364166) (xy 370.102048 -278.326072) (xy 370.074847 -278.283058) (xy 370.054899 -278.236238)
			(xy 370.04272 -278.186824) (xy 370.038625 -278.136096) (xy 369.732814 -278.136096) (xy 369.732324 -278.161085)
			(xy 369.724505 -278.210448) (xy 369.709061 -278.25798) (xy 369.686371 -278.302512) (xy 369.656995 -278.342945)
			(xy 369.621655 -278.378285) (xy 369.581222 -278.407661) (xy 369.53669 -278.430351) (xy 369.489158 -278.445795)
			(xy 369.439795 -278.453614) (xy 369.389817 -278.453614) (xy 369.340454 -278.445795) (xy 369.292922 -278.430351)
			(xy 369.24839 -278.407661) (xy 369.207957 -278.378285) (xy 369.172617 -278.342945) (xy 369.143241 -278.302512)
			(xy 369.120551 -278.25798) (xy 369.105107 -278.210448) (xy 369.097288 -278.161085) (xy 368.789971 -278.161085)
			(xy 368.789962 -278.161542) (xy 368.781798 -278.211776) (xy 368.765682 -278.26005) (xy 368.742031 -278.305113)
			(xy 368.711458 -278.345799) (xy 368.674754 -278.381054) (xy 368.63287 -278.409964) (xy 368.586891 -278.431781)
			(xy 368.538007 -278.445941) (xy 368.487486 -278.452075) (xy 368.436634 -278.450026) (xy 368.38677 -278.439846)
			(xy 368.339184 -278.421799) (xy 368.29511 -278.396353) (xy 368.255688 -278.364166) (xy 368.22194 -278.326072)
			(xy 368.194739 -278.283058) (xy 368.174791 -278.236238) (xy 368.162612 -278.186824) (xy 368.158517 -278.136096)
			(xy 367.85042 -278.136096) (xy 367.849908 -278.161542) (xy 367.841744 -278.211776) (xy 367.825628 -278.26005)
			(xy 367.801977 -278.305113) (xy 367.771404 -278.345799) (xy 367.7347 -278.381054) (xy 367.692816 -278.409964)
			(xy 367.646837 -278.431781) (xy 367.597953 -278.445941) (xy 367.547432 -278.452075) (xy 367.49658 -278.450026)
			(xy 367.446716 -278.439846) (xy 367.39913 -278.421799) (xy 367.355056 -278.396353) (xy 367.315634 -278.364166)
			(xy 367.281886 -278.326072) (xy 367.254685 -278.283058) (xy 367.234737 -278.236238) (xy 367.222558 -278.186824)
			(xy 367.218463 -278.136096) (xy 366.912906 -278.136096) (xy 366.912416 -278.161085) (xy 366.904597 -278.210448)
			(xy 366.889153 -278.25798) (xy 366.866463 -278.302512) (xy 366.837087 -278.342945) (xy 366.801747 -278.378285)
			(xy 366.761314 -278.407661) (xy 366.716782 -278.430351) (xy 366.66925 -278.445795) (xy 366.619887 -278.453614)
			(xy 366.569909 -278.453614) (xy 366.520546 -278.445795) (xy 366.473014 -278.430351) (xy 366.428482 -278.407661)
			(xy 366.388049 -278.378285) (xy 366.352709 -278.342945) (xy 366.323333 -278.302512) (xy 366.300643 -278.25798)
			(xy 366.285199 -278.210448) (xy 366.27738 -278.161085) (xy 365.970063 -278.161085) (xy 365.970054 -278.161542)
			(xy 365.96189 -278.211776) (xy 365.945774 -278.26005) (xy 365.922123 -278.305113) (xy 365.89155 -278.345799)
			(xy 365.854846 -278.381054) (xy 365.812962 -278.409964) (xy 365.766983 -278.431781) (xy 365.718099 -278.445941)
			(xy 365.667578 -278.452075) (xy 365.616726 -278.450026) (xy 365.566862 -278.439846) (xy 365.519276 -278.421799)
			(xy 365.475202 -278.396353) (xy 365.43578 -278.364166) (xy 365.402032 -278.326072) (xy 365.374831 -278.283058)
			(xy 365.354883 -278.236238) (xy 365.342704 -278.186824) (xy 365.338609 -278.136096) (xy 365.030512 -278.136096)
			(xy 365.03 -278.161542) (xy 365.021836 -278.211776) (xy 365.00572 -278.26005) (xy 364.982069 -278.305113)
			(xy 364.951496 -278.345799) (xy 364.914792 -278.381054) (xy 364.872908 -278.409964) (xy 364.826929 -278.431781)
			(xy 364.778045 -278.445941) (xy 364.727524 -278.452075) (xy 364.676672 -278.450026) (xy 364.626808 -278.439846)
			(xy 364.579222 -278.421799) (xy 364.535148 -278.396353) (xy 364.495726 -278.364166) (xy 364.461978 -278.326072)
			(xy 364.434777 -278.283058) (xy 364.414829 -278.236238) (xy 364.40265 -278.186824) (xy 364.398555 -278.136096)
			(xy 364.092744 -278.136096) (xy 364.092254 -278.161085) (xy 364.084435 -278.210448) (xy 364.068991 -278.25798)
			(xy 364.046301 -278.302512) (xy 364.016925 -278.342945) (xy 363.981585 -278.378285) (xy 363.941152 -278.407661)
			(xy 363.89662 -278.430351) (xy 363.849088 -278.445795) (xy 363.799725 -278.453614) (xy 363.749747 -278.453614)
			(xy 363.700384 -278.445795) (xy 363.652852 -278.430351) (xy 363.60832 -278.407661) (xy 363.567887 -278.378285)
			(xy 363.532547 -278.342945) (xy 363.503171 -278.302512) (xy 363.480481 -278.25798) (xy 363.465037 -278.210448)
			(xy 363.457218 -278.161085) (xy 356.57868 -278.161085) (xy 356.570861 -278.210448) (xy 356.555417 -278.25798)
			(xy 356.532727 -278.302512) (xy 356.503351 -278.342945) (xy 356.468011 -278.378285) (xy 356.427578 -278.407661)
			(xy 356.383046 -278.430351) (xy 356.335514 -278.445795) (xy 356.286151 -278.453614) (xy 356.236173 -278.453614)
			(xy 356.18681 -278.445795) (xy 356.139278 -278.430351) (xy 356.094746 -278.407661) (xy 356.054313 -278.378285)
			(xy 356.018973 -278.342945) (xy 355.989597 -278.302512) (xy 355.966907 -278.25798) (xy 355.951463 -278.210448)
			(xy 355.943644 -278.161085) (xy 355.636327 -278.161085) (xy 355.636318 -278.161542) (xy 355.628154 -278.211776)
			(xy 355.612038 -278.26005) (xy 355.588387 -278.305113) (xy 355.557814 -278.345799) (xy 355.52111 -278.381054)
			(xy 355.479226 -278.409964) (xy 355.433247 -278.431781) (xy 355.384363 -278.445941) (xy 355.333842 -278.452075)
			(xy 355.28299 -278.450026) (xy 355.233126 -278.439846) (xy 355.18554 -278.421799) (xy 355.141466 -278.396353)
			(xy 355.102044 -278.364166) (xy 355.068296 -278.326072) (xy 355.041095 -278.283058) (xy 355.021147 -278.236238)
			(xy 355.008968 -278.186824) (xy 355.004873 -278.136096) (xy 354.696776 -278.136096) (xy 354.696264 -278.161542)
			(xy 354.6881 -278.211776) (xy 354.671984 -278.26005) (xy 354.648333 -278.305113) (xy 354.61776 -278.345799)
			(xy 354.581056 -278.381054) (xy 354.539172 -278.409964) (xy 354.493193 -278.431781) (xy 354.444309 -278.445941)
			(xy 354.393788 -278.452075) (xy 354.342936 -278.450026) (xy 354.293072 -278.439846) (xy 354.245486 -278.421799)
			(xy 354.201412 -278.396353) (xy 354.16199 -278.364166) (xy 354.128242 -278.326072) (xy 354.101041 -278.283058)
			(xy 354.081093 -278.236238) (xy 354.068914 -278.186824) (xy 354.064819 -278.136096) (xy 353.759008 -278.136096)
			(xy 353.758518 -278.161085) (xy 353.750699 -278.210448) (xy 353.735255 -278.25798) (xy 353.712565 -278.302512)
			(xy 353.683189 -278.342945) (xy 353.647849 -278.378285) (xy 353.607416 -278.407661) (xy 353.562884 -278.430351)
			(xy 353.515352 -278.445795) (xy 353.465989 -278.453614) (xy 353.416011 -278.453614) (xy 353.366648 -278.445795)
			(xy 353.319116 -278.430351) (xy 353.274584 -278.407661) (xy 353.234151 -278.378285) (xy 353.198811 -278.342945)
			(xy 353.169435 -278.302512) (xy 353.146745 -278.25798) (xy 353.131301 -278.210448) (xy 353.123482 -278.161085)
			(xy 352.816419 -278.161085) (xy 352.81641 -278.161542) (xy 352.808246 -278.211776) (xy 352.79213 -278.26005)
			(xy 352.768479 -278.305113) (xy 352.737906 -278.345799) (xy 352.701202 -278.381054) (xy 352.659318 -278.409964)
			(xy 352.613339 -278.431781) (xy 352.564455 -278.445941) (xy 352.513934 -278.452075) (xy 352.463082 -278.450026)
			(xy 352.413218 -278.439846) (xy 352.365632 -278.421799) (xy 352.321558 -278.396353) (xy 352.282136 -278.364166)
			(xy 352.248388 -278.326072) (xy 352.221187 -278.283058) (xy 352.201239 -278.236238) (xy 352.18906 -278.186824)
			(xy 352.184965 -278.136096) (xy 351.876868 -278.136096) (xy 351.876356 -278.161542) (xy 351.868192 -278.211776)
			(xy 351.852076 -278.26005) (xy 351.828425 -278.305113) (xy 351.797852 -278.345799) (xy 351.761148 -278.381054)
			(xy 351.719264 -278.409964) (xy 351.673285 -278.431781) (xy 351.624401 -278.445941) (xy 351.57388 -278.452075)
			(xy 351.523028 -278.450026) (xy 351.473164 -278.439846) (xy 351.425578 -278.421799) (xy 351.381504 -278.396353)
			(xy 351.342082 -278.364166) (xy 351.308334 -278.326072) (xy 351.281133 -278.283058) (xy 351.261185 -278.236238)
			(xy 351.249006 -278.186824) (xy 351.244911 -278.136096) (xy 350.9391 -278.136096) (xy 350.93861 -278.161085)
			(xy 350.930791 -278.210448) (xy 350.915347 -278.25798) (xy 350.892657 -278.302512) (xy 350.863281 -278.342945)
			(xy 350.827941 -278.378285) (xy 350.787508 -278.407661) (xy 350.742976 -278.430351) (xy 350.695444 -278.445795)
			(xy 350.646081 -278.453614) (xy 350.596103 -278.453614) (xy 350.54674 -278.445795) (xy 350.499208 -278.430351)
			(xy 350.454676 -278.407661) (xy 350.414243 -278.378285) (xy 350.378903 -278.342945) (xy 350.349527 -278.302512)
			(xy 350.326837 -278.25798) (xy 350.311393 -278.210448) (xy 350.303574 -278.161085) (xy 349.996257 -278.161085)
			(xy 349.996248 -278.161542) (xy 349.988084 -278.211776) (xy 349.971968 -278.26005) (xy 349.948317 -278.305113)
			(xy 349.917744 -278.345799) (xy 349.88104 -278.381054) (xy 349.839156 -278.409964) (xy 349.793177 -278.431781)
			(xy 349.744293 -278.445941) (xy 349.693772 -278.452075) (xy 349.64292 -278.450026) (xy 349.593056 -278.439846)
			(xy 349.54547 -278.421799) (xy 349.501396 -278.396353) (xy 349.461974 -278.364166) (xy 349.428226 -278.326072)
			(xy 349.401025 -278.283058) (xy 349.381077 -278.236238) (xy 349.368898 -278.186824) (xy 349.364803 -278.136096)
			(xy 349.05696 -278.136096) (xy 349.056448 -278.161542) (xy 349.048284 -278.211776) (xy 349.032168 -278.26005)
			(xy 349.008517 -278.305113) (xy 348.977944 -278.345799) (xy 348.94124 -278.381054) (xy 348.899356 -278.409964)
			(xy 348.853377 -278.431781) (xy 348.804493 -278.445941) (xy 348.753972 -278.452075) (xy 348.70312 -278.450026)
			(xy 348.653256 -278.439846) (xy 348.60567 -278.421799) (xy 348.561596 -278.396353) (xy 348.522174 -278.364166)
			(xy 348.488426 -278.326072) (xy 348.461225 -278.283058) (xy 348.441277 -278.236238) (xy 348.429098 -278.186824)
			(xy 348.425003 -278.136096) (xy 348.119192 -278.136096) (xy 348.118702 -278.161085) (xy 348.110883 -278.210448)
			(xy 348.095439 -278.25798) (xy 348.072749 -278.302512) (xy 348.043373 -278.342945) (xy 348.008033 -278.378285)
			(xy 347.9676 -278.407661) (xy 347.923068 -278.430351) (xy 347.875536 -278.445795) (xy 347.826173 -278.453614)
			(xy 347.776195 -278.453614) (xy 347.726832 -278.445795) (xy 347.6793 -278.430351) (xy 347.634768 -278.407661)
			(xy 347.594335 -278.378285) (xy 347.558995 -278.342945) (xy 347.529619 -278.302512) (xy 347.506929 -278.25798)
			(xy 347.491485 -278.210448) (xy 347.483666 -278.161085) (xy 347.176349 -278.161085) (xy 347.17634 -278.161542)
			(xy 347.168176 -278.211776) (xy 347.15206 -278.26005) (xy 347.128409 -278.305113) (xy 347.097836 -278.345799)
			(xy 347.061132 -278.381054) (xy 347.019248 -278.409964) (xy 346.973269 -278.431781) (xy 346.924385 -278.445941)
			(xy 346.873864 -278.452075) (xy 346.823012 -278.450026) (xy 346.773148 -278.439846) (xy 346.725562 -278.421799)
			(xy 346.681488 -278.396353) (xy 346.642066 -278.364166) (xy 346.608318 -278.326072) (xy 346.581117 -278.283058)
			(xy 346.561169 -278.236238) (xy 346.54899 -278.186824) (xy 346.544895 -278.136096) (xy 346.236798 -278.136096)
			(xy 346.236286 -278.161542) (xy 346.228122 -278.211776) (xy 346.212006 -278.26005) (xy 346.188355 -278.305113)
			(xy 346.157782 -278.345799) (xy 346.121078 -278.381054) (xy 346.079194 -278.409964) (xy 346.033215 -278.431781)
			(xy 345.984331 -278.445941) (xy 345.93381 -278.452075) (xy 345.882958 -278.450026) (xy 345.833094 -278.439846)
			(xy 345.785508 -278.421799) (xy 345.741434 -278.396353) (xy 345.702012 -278.364166) (xy 345.668264 -278.326072)
			(xy 345.641063 -278.283058) (xy 345.621115 -278.236238) (xy 345.608936 -278.186824) (xy 345.604841 -278.136096)
			(xy 345.298866 -278.136096) (xy 345.297269 -278.174018) (xy 345.287658 -278.222245) (xy 345.270734 -278.268417)
			(xy 345.2469 -278.311431) (xy 345.232228 -278.331168) (xy 345.214387 -278.353137) (xy 345.172312 -278.390976)
			(xy 345.124194 -278.420757) (xy 345.098116 -278.431752) (xy 345.097862 -278.431752) (xy 345.095068 -278.432768)
			(xy 345.086744 -278.437152) (xy 345.073754 -278.450737) (xy 345.066529 -278.468088) (xy 345.065858 -278.477472)
			(xy 345.065858 -278.971091) (xy 347.013512 -278.971091) (xy 347.013512 -278.921113) (xy 347.021331 -278.87175)
			(xy 347.036775 -278.824218) (xy 347.059465 -278.779686) (xy 347.088841 -278.739253) (xy 347.124181 -278.703913)
			(xy 347.164614 -278.674537) (xy 347.209146 -278.651847) (xy 347.256678 -278.636403) (xy 347.306041 -278.628584)
			(xy 347.356019 -278.628584) (xy 347.405382 -278.636403) (xy 347.452914 -278.651847) (xy 347.497446 -278.674537)
			(xy 347.537879 -278.703913) (xy 347.573219 -278.739253) (xy 347.602595 -278.779686) (xy 347.625285 -278.824218)
			(xy 347.640729 -278.87175) (xy 347.648548 -278.921113) (xy 347.649038 -278.946102) (xy 347.648548 -278.971091)
			(xy 349.833674 -278.971091) (xy 349.833674 -278.921113) (xy 349.841493 -278.87175) (xy 349.856937 -278.824218)
			(xy 349.879627 -278.779686) (xy 349.909003 -278.739253) (xy 349.944343 -278.703913) (xy 349.984776 -278.674537)
			(xy 350.029308 -278.651847) (xy 350.07684 -278.636403) (xy 350.126203 -278.628584) (xy 350.176181 -278.628584)
			(xy 350.225544 -278.636403) (xy 350.273076 -278.651847) (xy 350.317608 -278.674537) (xy 350.358041 -278.703913)
			(xy 350.393381 -278.739253) (xy 350.422757 -278.779686) (xy 350.445447 -278.824218) (xy 350.460891 -278.87175)
			(xy 350.46871 -278.921113) (xy 350.4692 -278.946102) (xy 350.46871 -278.971091) (xy 352.653582 -278.971091)
			(xy 352.653582 -278.921113) (xy 352.661401 -278.87175) (xy 352.676845 -278.824218) (xy 352.699535 -278.779686)
			(xy 352.728911 -278.739253) (xy 352.764251 -278.703913) (xy 352.804684 -278.674537) (xy 352.849216 -278.651847)
			(xy 352.896748 -278.636403) (xy 352.946111 -278.628584) (xy 352.996089 -278.628584) (xy 353.045452 -278.636403)
			(xy 353.092984 -278.651847) (xy 353.137516 -278.674537) (xy 353.177949 -278.703913) (xy 353.213289 -278.739253)
			(xy 353.242665 -278.779686) (xy 353.265355 -278.824218) (xy 353.280799 -278.87175) (xy 353.288618 -278.921113)
			(xy 353.289108 -278.946102) (xy 353.288618 -278.971091) (xy 355.47349 -278.971091) (xy 355.47349 -278.921113)
			(xy 355.481309 -278.87175) (xy 355.496753 -278.824218) (xy 355.519443 -278.779686) (xy 355.548819 -278.739253)
			(xy 355.584159 -278.703913) (xy 355.624592 -278.674537) (xy 355.669124 -278.651847) (xy 355.716656 -278.636403)
			(xy 355.766019 -278.628584) (xy 355.815997 -278.628584) (xy 355.86536 -278.636403) (xy 355.912892 -278.651847)
			(xy 355.957424 -278.674537) (xy 355.997857 -278.703913) (xy 356.033197 -278.739253) (xy 356.062573 -278.779686)
			(xy 356.085263 -278.824218) (xy 356.100707 -278.87175) (xy 356.108526 -278.921113) (xy 356.109016 -278.946102)
			(xy 356.414827 -278.946102) (xy 356.418922 -278.895374) (xy 356.431101 -278.84596) (xy 356.451049 -278.79914)
			(xy 356.47825 -278.756126) (xy 356.511998 -278.718032) (xy 356.55142 -278.685845) (xy 356.595494 -278.660399)
			(xy 356.64308 -278.642352) (xy 356.692944 -278.632172) (xy 356.743796 -278.630123) (xy 356.794317 -278.636257)
			(xy 356.843201 -278.650417) (xy 356.88918 -278.672234) (xy 356.931064 -278.701144) (xy 356.967768 -278.736399)
			(xy 356.998341 -278.777085) (xy 357.021992 -278.822148) (xy 357.038108 -278.870422) (xy 357.046272 -278.920656)
			(xy 357.046784 -278.946102) (xy 357.354881 -278.946102) (xy 357.358976 -278.895374) (xy 357.371155 -278.84596)
			(xy 357.391103 -278.79914) (xy 357.418304 -278.756126) (xy 357.452052 -278.718032) (xy 357.491474 -278.685845)
			(xy 357.535548 -278.660399) (xy 357.583134 -278.642352) (xy 357.632998 -278.632172) (xy 357.68385 -278.630123)
			(xy 357.734371 -278.636257) (xy 357.783255 -278.650417) (xy 357.829234 -278.672234) (xy 357.871118 -278.701144)
			(xy 357.907822 -278.736399) (xy 357.938395 -278.777085) (xy 357.962046 -278.822148) (xy 357.978162 -278.870422)
			(xy 357.986326 -278.920656) (xy 357.986838 -278.946102) (xy 357.986335 -278.971091) (xy 358.293652 -278.971091)
			(xy 358.293652 -278.921113) (xy 358.301471 -278.87175) (xy 358.316915 -278.824218) (xy 358.339605 -278.779686)
			(xy 358.368981 -278.739253) (xy 358.404321 -278.703913) (xy 358.444754 -278.674537) (xy 358.489286 -278.651847)
			(xy 358.536818 -278.636403) (xy 358.586181 -278.628584) (xy 358.636159 -278.628584) (xy 358.685522 -278.636403)
			(xy 358.733054 -278.651847) (xy 358.777586 -278.674537) (xy 358.818019 -278.703913) (xy 358.853359 -278.739253)
			(xy 358.882735 -278.779686) (xy 358.905425 -278.824218) (xy 358.920869 -278.87175) (xy 358.928688 -278.921113)
			(xy 358.929178 -278.946102) (xy 358.928688 -278.971091) (xy 361.10721 -278.971091) (xy 361.10721 -278.921113)
			(xy 361.115029 -278.87175) (xy 361.130473 -278.824218) (xy 361.153163 -278.779686) (xy 361.182539 -278.739253)
			(xy 361.217879 -278.703913) (xy 361.258312 -278.674537) (xy 361.302844 -278.651847) (xy 361.350376 -278.636403)
			(xy 361.399739 -278.628584) (xy 361.449717 -278.628584) (xy 361.49908 -278.636403) (xy 361.546612 -278.651847)
			(xy 361.591144 -278.674537) (xy 361.631577 -278.703913) (xy 361.666917 -278.739253) (xy 361.696293 -278.779686)
			(xy 361.718983 -278.824218) (xy 361.734427 -278.87175) (xy 361.742246 -278.921113) (xy 361.742736 -278.946102)
			(xy 362.048547 -278.946102) (xy 362.052642 -278.895374) (xy 362.064821 -278.84596) (xy 362.084769 -278.79914)
			(xy 362.11197 -278.756126) (xy 362.145718 -278.718032) (xy 362.18514 -278.685845) (xy 362.229214 -278.660399)
			(xy 362.2768 -278.642352) (xy 362.326664 -278.632172) (xy 362.377516 -278.630123) (xy 362.428037 -278.636257)
			(xy 362.476921 -278.650417) (xy 362.5229 -278.672234) (xy 362.564784 -278.701144) (xy 362.601488 -278.736399)
			(xy 362.632061 -278.777085) (xy 362.655712 -278.822148) (xy 362.671828 -278.870422) (xy 362.679992 -278.920656)
			(xy 362.680504 -278.946102) (xy 362.988601 -278.946102) (xy 362.992696 -278.895374) (xy 363.004875 -278.84596)
			(xy 363.024823 -278.79914) (xy 363.052024 -278.756126) (xy 363.085772 -278.718032) (xy 363.125194 -278.685845)
			(xy 363.169268 -278.660399) (xy 363.216854 -278.642352) (xy 363.266718 -278.632172) (xy 363.31757 -278.630123)
			(xy 363.368091 -278.636257) (xy 363.416975 -278.650417) (xy 363.462954 -278.672234) (xy 363.504838 -278.701144)
			(xy 363.541542 -278.736399) (xy 363.572115 -278.777085) (xy 363.595766 -278.822148) (xy 363.611882 -278.870422)
			(xy 363.620046 -278.920656) (xy 363.620558 -278.946102) (xy 363.620055 -278.971091) (xy 363.927372 -278.971091)
			(xy 363.927372 -278.921113) (xy 363.935191 -278.87175) (xy 363.950635 -278.824218) (xy 363.973325 -278.779686)
			(xy 364.002701 -278.739253) (xy 364.038041 -278.703913) (xy 364.078474 -278.674537) (xy 364.123006 -278.651847)
			(xy 364.170538 -278.636403) (xy 364.219901 -278.628584) (xy 364.269879 -278.628584) (xy 364.319242 -278.636403)
			(xy 364.366774 -278.651847) (xy 364.411306 -278.674537) (xy 364.451739 -278.703913) (xy 364.487079 -278.739253)
			(xy 364.516455 -278.779686) (xy 364.539145 -278.824218) (xy 364.554589 -278.87175) (xy 364.562408 -278.921113)
			(xy 364.562898 -278.946102) (xy 364.562408 -278.971091) (xy 366.74728 -278.971091) (xy 366.74728 -278.921113)
			(xy 366.755099 -278.87175) (xy 366.770543 -278.824218) (xy 366.793233 -278.779686) (xy 366.822609 -278.739253)
			(xy 366.857949 -278.703913) (xy 366.898382 -278.674537) (xy 366.942914 -278.651847) (xy 366.990446 -278.636403)
			(xy 367.039809 -278.628584) (xy 367.089787 -278.628584) (xy 367.13915 -278.636403) (xy 367.186682 -278.651847)
			(xy 367.231214 -278.674537) (xy 367.271647 -278.703913) (xy 367.306987 -278.739253) (xy 367.336363 -278.779686)
			(xy 367.359053 -278.824218) (xy 367.374497 -278.87175) (xy 367.382316 -278.921113) (xy 367.382806 -278.946102)
			(xy 367.382316 -278.971091) (xy 369.567188 -278.971091) (xy 369.567188 -278.921113) (xy 369.575007 -278.87175)
			(xy 369.590451 -278.824218) (xy 369.613141 -278.779686) (xy 369.642517 -278.739253) (xy 369.677857 -278.703913)
			(xy 369.71829 -278.674537) (xy 369.762822 -278.651847) (xy 369.810354 -278.636403) (xy 369.859717 -278.628584)
			(xy 369.909695 -278.628584) (xy 369.959058 -278.636403) (xy 370.00659 -278.651847) (xy 370.051122 -278.674537)
			(xy 370.091555 -278.703913) (xy 370.126895 -278.739253) (xy 370.156271 -278.779686) (xy 370.178961 -278.824218)
			(xy 370.194405 -278.87175) (xy 370.202224 -278.921113) (xy 370.202714 -278.946102) (xy 370.202224 -278.971091)
			(xy 372.38735 -278.971091) (xy 372.38735 -278.921113) (xy 372.395169 -278.87175) (xy 372.410613 -278.824218)
			(xy 372.433303 -278.779686) (xy 372.462679 -278.739253) (xy 372.498019 -278.703913) (xy 372.538452 -278.674537)
			(xy 372.582984 -278.651847) (xy 372.630516 -278.636403) (xy 372.679879 -278.628584) (xy 372.729857 -278.628584)
			(xy 372.77922 -278.636403) (xy 372.826752 -278.651847) (xy 372.871284 -278.674537) (xy 372.911717 -278.703913)
			(xy 372.947057 -278.739253) (xy 372.976433 -278.779686) (xy 372.999123 -278.824218) (xy 373.014567 -278.87175)
			(xy 373.022386 -278.921113) (xy 373.022876 -278.946102) (xy 373.022386 -278.971091) (xy 373.014567 -279.020454)
			(xy 372.999123 -279.067986) (xy 372.976433 -279.112518) (xy 372.947057 -279.152951) (xy 372.911717 -279.188291)
			(xy 372.871284 -279.217667) (xy 372.826752 -279.240357) (xy 372.77922 -279.255801) (xy 372.729857 -279.26362)
			(xy 372.679879 -279.26362) (xy 372.630516 -279.255801) (xy 372.582984 -279.240357) (xy 372.538452 -279.217667)
			(xy 372.498019 -279.188291) (xy 372.462679 -279.152951) (xy 372.433303 -279.112518) (xy 372.410613 -279.067986)
			(xy 372.395169 -279.020454) (xy 372.38735 -278.971091) (xy 370.202224 -278.971091) (xy 370.194405 -279.020454)
			(xy 370.178961 -279.067986) (xy 370.156271 -279.112518) (xy 370.126895 -279.152951) (xy 370.091555 -279.188291)
			(xy 370.051122 -279.217667) (xy 370.00659 -279.240357) (xy 369.959058 -279.255801) (xy 369.909695 -279.26362)
			(xy 369.859717 -279.26362) (xy 369.810354 -279.255801) (xy 369.762822 -279.240357) (xy 369.71829 -279.217667)
			(xy 369.677857 -279.188291) (xy 369.642517 -279.152951) (xy 369.613141 -279.112518) (xy 369.590451 -279.067986)
			(xy 369.575007 -279.020454) (xy 369.567188 -278.971091) (xy 367.382316 -278.971091) (xy 367.374497 -279.020454)
			(xy 367.359053 -279.067986) (xy 367.336363 -279.112518) (xy 367.306987 -279.152951) (xy 367.271647 -279.188291)
			(xy 367.231214 -279.217667) (xy 367.186682 -279.240357) (xy 367.13915 -279.255801) (xy 367.089787 -279.26362)
			(xy 367.039809 -279.26362) (xy 366.990446 -279.255801) (xy 366.942914 -279.240357) (xy 366.898382 -279.217667)
			(xy 366.857949 -279.188291) (xy 366.822609 -279.152951) (xy 366.793233 -279.112518) (xy 366.770543 -279.067986)
			(xy 366.755099 -279.020454) (xy 366.74728 -278.971091) (xy 364.562408 -278.971091) (xy 364.554589 -279.020454)
			(xy 364.539145 -279.067986) (xy 364.516455 -279.112518) (xy 364.487079 -279.152951) (xy 364.451739 -279.188291)
			(xy 364.411306 -279.217667) (xy 364.366774 -279.240357) (xy 364.319242 -279.255801) (xy 364.269879 -279.26362)
			(xy 364.219901 -279.26362) (xy 364.170538 -279.255801) (xy 364.123006 -279.240357) (xy 364.078474 -279.217667)
			(xy 364.038041 -279.188291) (xy 364.002701 -279.152951) (xy 363.973325 -279.112518) (xy 363.950635 -279.067986)
			(xy 363.935191 -279.020454) (xy 363.927372 -278.971091) (xy 363.620055 -278.971091) (xy 363.620046 -278.971548)
			(xy 363.611882 -279.021782) (xy 363.595766 -279.070056) (xy 363.572115 -279.115119) (xy 363.541542 -279.155805)
			(xy 363.504838 -279.19106) (xy 363.462954 -279.21997) (xy 363.416975 -279.241787) (xy 363.368091 -279.255947)
			(xy 363.31757 -279.262081) (xy 363.266718 -279.260032) (xy 363.216854 -279.249852) (xy 363.169268 -279.231805)
			(xy 363.125194 -279.206359) (xy 363.085772 -279.174172) (xy 363.052024 -279.136078) (xy 363.024823 -279.093064)
			(xy 363.004875 -279.046244) (xy 362.992696 -278.99683) (xy 362.988601 -278.946102) (xy 362.680504 -278.946102)
			(xy 362.679992 -278.971548) (xy 362.671828 -279.021782) (xy 362.655712 -279.070056) (xy 362.632061 -279.115119)
			(xy 362.601488 -279.155805) (xy 362.564784 -279.19106) (xy 362.5229 -279.21997) (xy 362.476921 -279.241787)
			(xy 362.428037 -279.255947) (xy 362.377516 -279.262081) (xy 362.326664 -279.260032) (xy 362.2768 -279.249852)
			(xy 362.229214 -279.231805) (xy 362.18514 -279.206359) (xy 362.145718 -279.174172) (xy 362.11197 -279.136078)
			(xy 362.084769 -279.093064) (xy 362.064821 -279.046244) (xy 362.052642 -278.99683) (xy 362.048547 -278.946102)
			(xy 361.742736 -278.946102) (xy 361.742246 -278.971091) (xy 361.734427 -279.020454) (xy 361.718983 -279.067986)
			(xy 361.696293 -279.112518) (xy 361.666917 -279.152951) (xy 361.631577 -279.188291) (xy 361.591144 -279.217667)
			(xy 361.546612 -279.240357) (xy 361.49908 -279.255801) (xy 361.449717 -279.26362) (xy 361.399739 -279.26362)
			(xy 361.350376 -279.255801) (xy 361.302844 -279.240357) (xy 361.258312 -279.217667) (xy 361.217879 -279.188291)
			(xy 361.182539 -279.152951) (xy 361.153163 -279.112518) (xy 361.130473 -279.067986) (xy 361.115029 -279.020454)
			(xy 361.10721 -278.971091) (xy 358.928688 -278.971091) (xy 358.920869 -279.020454) (xy 358.905425 -279.067986)
			(xy 358.882735 -279.112518) (xy 358.853359 -279.152951) (xy 358.818019 -279.188291) (xy 358.777586 -279.217667)
			(xy 358.733054 -279.240357) (xy 358.685522 -279.255801) (xy 358.636159 -279.26362) (xy 358.586181 -279.26362)
			(xy 358.536818 -279.255801) (xy 358.489286 -279.240357) (xy 358.444754 -279.217667) (xy 358.404321 -279.188291)
			(xy 358.368981 -279.152951) (xy 358.339605 -279.112518) (xy 358.316915 -279.067986) (xy 358.301471 -279.020454)
			(xy 358.293652 -278.971091) (xy 357.986335 -278.971091) (xy 357.986326 -278.971548) (xy 357.978162 -279.021782)
			(xy 357.962046 -279.070056) (xy 357.938395 -279.115119) (xy 357.907822 -279.155805) (xy 357.871118 -279.19106)
			(xy 357.829234 -279.21997) (xy 357.783255 -279.241787) (xy 357.734371 -279.255947) (xy 357.68385 -279.262081)
			(xy 357.632998 -279.260032) (xy 357.583134 -279.249852) (xy 357.535548 -279.231805) (xy 357.491474 -279.206359)
			(xy 357.452052 -279.174172) (xy 357.418304 -279.136078) (xy 357.391103 -279.093064) (xy 357.371155 -279.046244)
			(xy 357.358976 -278.99683) (xy 357.354881 -278.946102) (xy 357.046784 -278.946102) (xy 357.046272 -278.971548)
			(xy 357.038108 -279.021782) (xy 357.021992 -279.070056) (xy 356.998341 -279.115119) (xy 356.967768 -279.155805)
			(xy 356.931064 -279.19106) (xy 356.88918 -279.21997) (xy 356.843201 -279.241787) (xy 356.794317 -279.255947)
			(xy 356.743796 -279.262081) (xy 356.692944 -279.260032) (xy 356.64308 -279.249852) (xy 356.595494 -279.231805)
			(xy 356.55142 -279.206359) (xy 356.511998 -279.174172) (xy 356.47825 -279.136078) (xy 356.451049 -279.093064)
			(xy 356.431101 -279.046244) (xy 356.418922 -278.99683) (xy 356.414827 -278.946102) (xy 356.109016 -278.946102)
			(xy 356.108526 -278.971091) (xy 356.100707 -279.020454) (xy 356.085263 -279.067986) (xy 356.062573 -279.112518)
			(xy 356.033197 -279.152951) (xy 355.997857 -279.188291) (xy 355.957424 -279.217667) (xy 355.912892 -279.240357)
			(xy 355.86536 -279.255801) (xy 355.815997 -279.26362) (xy 355.766019 -279.26362) (xy 355.716656 -279.255801)
			(xy 355.669124 -279.240357) (xy 355.624592 -279.217667) (xy 355.584159 -279.188291) (xy 355.548819 -279.152951)
			(xy 355.519443 -279.112518) (xy 355.496753 -279.067986) (xy 355.481309 -279.020454) (xy 355.47349 -278.971091)
			(xy 353.288618 -278.971091) (xy 353.280799 -279.020454) (xy 353.265355 -279.067986) (xy 353.242665 -279.112518)
			(xy 353.213289 -279.152951) (xy 353.177949 -279.188291) (xy 353.137516 -279.217667) (xy 353.092984 -279.240357)
			(xy 353.045452 -279.255801) (xy 352.996089 -279.26362) (xy 352.946111 -279.26362) (xy 352.896748 -279.255801)
			(xy 352.849216 -279.240357) (xy 352.804684 -279.217667) (xy 352.764251 -279.188291) (xy 352.728911 -279.152951)
			(xy 352.699535 -279.112518) (xy 352.676845 -279.067986) (xy 352.661401 -279.020454) (xy 352.653582 -278.971091)
			(xy 350.46871 -278.971091) (xy 350.460891 -279.020454) (xy 350.445447 -279.067986) (xy 350.422757 -279.112518)
			(xy 350.393381 -279.152951) (xy 350.358041 -279.188291) (xy 350.317608 -279.217667) (xy 350.273076 -279.240357)
			(xy 350.225544 -279.255801) (xy 350.176181 -279.26362) (xy 350.126203 -279.26362) (xy 350.07684 -279.255801)
			(xy 350.029308 -279.240357) (xy 349.984776 -279.217667) (xy 349.944343 -279.188291) (xy 349.909003 -279.152951)
			(xy 349.879627 -279.112518) (xy 349.856937 -279.067986) (xy 349.841493 -279.020454) (xy 349.833674 -278.971091)
			(xy 347.648548 -278.971091) (xy 347.640729 -279.020454) (xy 347.625285 -279.067986) (xy 347.602595 -279.112518)
			(xy 347.573219 -279.152951) (xy 347.537879 -279.188291) (xy 347.497446 -279.217667) (xy 347.452914 -279.240357)
			(xy 347.405382 -279.255801) (xy 347.356019 -279.26362) (xy 347.306041 -279.26362) (xy 347.256678 -279.255801)
			(xy 347.209146 -279.240357) (xy 347.164614 -279.217667) (xy 347.124181 -279.188291) (xy 347.088841 -279.152951)
			(xy 347.059465 -279.112518) (xy 347.036775 -279.067986) (xy 347.021331 -279.020454) (xy 347.013512 -278.971091)
			(xy 345.065858 -278.971091) (xy 345.065858 -279.413462) (xy 345.065858 -279.414732) (xy 345.066517 -279.424121)
			(xy 345.07373 -279.441487) (xy 345.086727 -279.455077) (xy 345.095068 -279.459436) (xy 345.097862 -279.460452)
			(xy 345.120564 -279.469904) (xy 345.16298 -279.494784) (xy 345.201059 -279.525899) (xy 345.23389 -279.562508)
			(xy 345.260692 -279.603736) (xy 345.280824 -279.648601) (xy 345.293805 -279.69603) (xy 345.299327 -279.744894)
			(xy 345.297802 -279.781097) (xy 345.603558 -279.781097) (xy 345.603558 -279.731119) (xy 345.611377 -279.681756)
			(xy 345.626821 -279.634224) (xy 345.649511 -279.589692) (xy 345.678887 -279.549259) (xy 345.714227 -279.513919)
			(xy 345.75466 -279.484543) (xy 345.799192 -279.461853) (xy 345.846724 -279.446409) (xy 345.896087 -279.43859)
			(xy 345.946065 -279.43859) (xy 345.995428 -279.446409) (xy 346.04296 -279.461853) (xy 346.087492 -279.484543)
			(xy 346.127925 -279.513919) (xy 346.163265 -279.549259) (xy 346.192641 -279.589692) (xy 346.215331 -279.634224)
			(xy 346.230775 -279.681756) (xy 346.238594 -279.731119) (xy 346.239084 -279.756108) (xy 346.238594 -279.781097)
			(xy 346.543612 -279.781097) (xy 346.543612 -279.731119) (xy 346.551431 -279.681756) (xy 346.566875 -279.634224)
			(xy 346.589565 -279.589692) (xy 346.618941 -279.549259) (xy 346.654281 -279.513919) (xy 346.694714 -279.484543)
			(xy 346.739246 -279.461853) (xy 346.786778 -279.446409) (xy 346.836141 -279.43859) (xy 346.886119 -279.43859)
			(xy 346.935482 -279.446409) (xy 346.983014 -279.461853) (xy 347.027546 -279.484543) (xy 347.067979 -279.513919)
			(xy 347.103319 -279.549259) (xy 347.132695 -279.589692) (xy 347.155385 -279.634224) (xy 347.170829 -279.681756)
			(xy 347.178648 -279.731119) (xy 347.179138 -279.756108) (xy 347.178648 -279.781097) (xy 347.483666 -279.781097)
			(xy 347.483666 -279.731119) (xy 347.491485 -279.681756) (xy 347.506929 -279.634224) (xy 347.529619 -279.589692)
			(xy 347.558995 -279.549259) (xy 347.594335 -279.513919) (xy 347.634768 -279.484543) (xy 347.6793 -279.461853)
			(xy 347.726832 -279.446409) (xy 347.776195 -279.43859) (xy 347.826173 -279.43859) (xy 347.875536 -279.446409)
			(xy 347.923068 -279.461853) (xy 347.9676 -279.484543) (xy 348.008033 -279.513919) (xy 348.043373 -279.549259)
			(xy 348.072749 -279.589692) (xy 348.095439 -279.634224) (xy 348.110883 -279.681756) (xy 348.118702 -279.731119)
			(xy 348.119192 -279.756108) (xy 348.118702 -279.781097) (xy 348.42372 -279.781097) (xy 348.42372 -279.731119)
			(xy 348.431539 -279.681756) (xy 348.446983 -279.634224) (xy 348.469673 -279.589692) (xy 348.499049 -279.549259)
			(xy 348.534389 -279.513919) (xy 348.574822 -279.484543) (xy 348.619354 -279.461853) (xy 348.666886 -279.446409)
			(xy 348.716249 -279.43859) (xy 348.766227 -279.43859) (xy 348.81559 -279.446409) (xy 348.863122 -279.461853)
			(xy 348.907654 -279.484543) (xy 348.948087 -279.513919) (xy 348.983427 -279.549259) (xy 349.012803 -279.589692)
			(xy 349.035493 -279.634224) (xy 349.050937 -279.681756) (xy 349.058756 -279.731119) (xy 349.059246 -279.756108)
			(xy 349.058756 -279.781097) (xy 349.36352 -279.781097) (xy 349.36352 -279.731119) (xy 349.371339 -279.681756)
			(xy 349.386783 -279.634224) (xy 349.409473 -279.589692) (xy 349.438849 -279.549259) (xy 349.474189 -279.513919)
			(xy 349.514622 -279.484543) (xy 349.559154 -279.461853) (xy 349.606686 -279.446409) (xy 349.656049 -279.43859)
			(xy 349.706027 -279.43859) (xy 349.75539 -279.446409) (xy 349.802922 -279.461853) (xy 349.847454 -279.484543)
			(xy 349.887887 -279.513919) (xy 349.923227 -279.549259) (xy 349.952603 -279.589692) (xy 349.975293 -279.634224)
			(xy 349.990737 -279.681756) (xy 349.998556 -279.731119) (xy 349.999046 -279.756108) (xy 349.998556 -279.781097)
			(xy 350.303574 -279.781097) (xy 350.303574 -279.731119) (xy 350.311393 -279.681756) (xy 350.326837 -279.634224)
			(xy 350.349527 -279.589692) (xy 350.378903 -279.549259) (xy 350.414243 -279.513919) (xy 350.454676 -279.484543)
			(xy 350.499208 -279.461853) (xy 350.54674 -279.446409) (xy 350.596103 -279.43859) (xy 350.646081 -279.43859)
			(xy 350.695444 -279.446409) (xy 350.742976 -279.461853) (xy 350.787508 -279.484543) (xy 350.827941 -279.513919)
			(xy 350.863281 -279.549259) (xy 350.892657 -279.589692) (xy 350.915347 -279.634224) (xy 350.930791 -279.681756)
			(xy 350.93861 -279.731119) (xy 350.9391 -279.756108) (xy 350.93861 -279.781097) (xy 351.243628 -279.781097)
			(xy 351.243628 -279.731119) (xy 351.251447 -279.681756) (xy 351.266891 -279.634224) (xy 351.289581 -279.589692)
			(xy 351.318957 -279.549259) (xy 351.354297 -279.513919) (xy 351.39473 -279.484543) (xy 351.439262 -279.461853)
			(xy 351.486794 -279.446409) (xy 351.536157 -279.43859) (xy 351.586135 -279.43859) (xy 351.635498 -279.446409)
			(xy 351.68303 -279.461853) (xy 351.727562 -279.484543) (xy 351.767995 -279.513919) (xy 351.803335 -279.549259)
			(xy 351.832711 -279.589692) (xy 351.855401 -279.634224) (xy 351.870845 -279.681756) (xy 351.878664 -279.731119)
			(xy 351.879154 -279.756108) (xy 351.878664 -279.781097) (xy 352.183682 -279.781097) (xy 352.183682 -279.731119)
			(xy 352.191501 -279.681756) (xy 352.206945 -279.634224) (xy 352.229635 -279.589692) (xy 352.259011 -279.549259)
			(xy 352.294351 -279.513919) (xy 352.334784 -279.484543) (xy 352.379316 -279.461853) (xy 352.426848 -279.446409)
			(xy 352.476211 -279.43859) (xy 352.526189 -279.43859) (xy 352.575552 -279.446409) (xy 352.623084 -279.461853)
			(xy 352.667616 -279.484543) (xy 352.708049 -279.513919) (xy 352.743389 -279.549259) (xy 352.772765 -279.589692)
			(xy 352.795455 -279.634224) (xy 352.810899 -279.681756) (xy 352.818718 -279.731119) (xy 352.819208 -279.756108)
			(xy 352.818718 -279.781097) (xy 353.123482 -279.781097) (xy 353.123482 -279.731119) (xy 353.131301 -279.681756)
			(xy 353.146745 -279.634224) (xy 353.169435 -279.589692) (xy 353.198811 -279.549259) (xy 353.234151 -279.513919)
			(xy 353.274584 -279.484543) (xy 353.319116 -279.461853) (xy 353.366648 -279.446409) (xy 353.416011 -279.43859)
			(xy 353.465989 -279.43859) (xy 353.515352 -279.446409) (xy 353.562884 -279.461853) (xy 353.607416 -279.484543)
			(xy 353.647849 -279.513919) (xy 353.683189 -279.549259) (xy 353.712565 -279.589692) (xy 353.735255 -279.634224)
			(xy 353.750699 -279.681756) (xy 353.758518 -279.731119) (xy 353.759008 -279.756108) (xy 354.064819 -279.756108)
			(xy 354.068914 -279.70538) (xy 354.081093 -279.655966) (xy 354.101041 -279.609146) (xy 354.128242 -279.566132)
			(xy 354.16199 -279.528038) (xy 354.201412 -279.495851) (xy 354.245486 -279.470405) (xy 354.293072 -279.452358)
			(xy 354.342936 -279.442178) (xy 354.393788 -279.440129) (xy 354.444309 -279.446263) (xy 354.493193 -279.460423)
			(xy 354.539172 -279.48224) (xy 354.581056 -279.51115) (xy 354.61776 -279.546405) (xy 354.648333 -279.587091)
			(xy 354.671984 -279.632154) (xy 354.6881 -279.680428) (xy 354.696264 -279.730662) (xy 354.696776 -279.756108)
			(xy 355.004873 -279.756108) (xy 355.008968 -279.70538) (xy 355.021147 -279.655966) (xy 355.041095 -279.609146)
			(xy 355.068296 -279.566132) (xy 355.102044 -279.528038) (xy 355.141466 -279.495851) (xy 355.18554 -279.470405)
			(xy 355.233126 -279.452358) (xy 355.28299 -279.442178) (xy 355.333842 -279.440129) (xy 355.384363 -279.446263)
			(xy 355.433247 -279.460423) (xy 355.479226 -279.48224) (xy 355.52111 -279.51115) (xy 355.557814 -279.546405)
			(xy 355.588387 -279.587091) (xy 355.612038 -279.632154) (xy 355.628154 -279.680428) (xy 355.636318 -279.730662)
			(xy 355.63683 -279.756108) (xy 355.636327 -279.781097) (xy 355.943644 -279.781097) (xy 355.943644 -279.731119)
			(xy 355.951463 -279.681756) (xy 355.966907 -279.634224) (xy 355.989597 -279.589692) (xy 356.018973 -279.549259)
			(xy 356.054313 -279.513919) (xy 356.094746 -279.484543) (xy 356.139278 -279.461853) (xy 356.18681 -279.446409)
			(xy 356.236173 -279.43859) (xy 356.286151 -279.43859) (xy 356.335514 -279.446409) (xy 356.383046 -279.461853)
			(xy 356.427578 -279.484543) (xy 356.468011 -279.513919) (xy 356.503351 -279.549259) (xy 356.532727 -279.589692)
			(xy 356.555417 -279.634224) (xy 356.570861 -279.681756) (xy 356.57868 -279.731119) (xy 356.57917 -279.756108)
			(xy 356.57868 -279.781097) (xy 356.883698 -279.781097) (xy 356.883698 -279.731119) (xy 356.891517 -279.681756)
			(xy 356.906961 -279.634224) (xy 356.929651 -279.589692) (xy 356.959027 -279.549259) (xy 356.994367 -279.513919)
			(xy 357.0348 -279.484543) (xy 357.079332 -279.461853) (xy 357.126864 -279.446409) (xy 357.176227 -279.43859)
			(xy 357.226205 -279.43859) (xy 357.275568 -279.446409) (xy 357.3231 -279.461853) (xy 357.367632 -279.484543)
			(xy 357.408065 -279.513919) (xy 357.443405 -279.549259) (xy 357.472781 -279.589692) (xy 357.495471 -279.634224)
			(xy 357.510915 -279.681756) (xy 357.518734 -279.731119) (xy 357.519224 -279.756108) (xy 357.518734 -279.781097)
			(xy 357.823498 -279.781097) (xy 357.823498 -279.731119) (xy 357.831317 -279.681756) (xy 357.846761 -279.634224)
			(xy 357.869451 -279.589692) (xy 357.898827 -279.549259) (xy 357.934167 -279.513919) (xy 357.9746 -279.484543)
			(xy 358.019132 -279.461853) (xy 358.066664 -279.446409) (xy 358.116027 -279.43859) (xy 358.166005 -279.43859)
			(xy 358.215368 -279.446409) (xy 358.2629 -279.461853) (xy 358.307432 -279.484543) (xy 358.347865 -279.513919)
			(xy 358.383205 -279.549259) (xy 358.412581 -279.589692) (xy 358.435271 -279.634224) (xy 358.450715 -279.681756)
			(xy 358.458534 -279.731119) (xy 358.459024 -279.756108) (xy 358.458534 -279.781097) (xy 361.577364 -279.781097)
			(xy 361.577364 -279.731119) (xy 361.585183 -279.681756) (xy 361.600627 -279.634224) (xy 361.623317 -279.589692)
			(xy 361.652693 -279.549259) (xy 361.688033 -279.513919) (xy 361.728466 -279.484543) (xy 361.772998 -279.461853)
			(xy 361.82053 -279.446409) (xy 361.869893 -279.43859) (xy 361.919871 -279.43859) (xy 361.969234 -279.446409)
			(xy 362.016766 -279.461853) (xy 362.061298 -279.484543) (xy 362.101731 -279.513919) (xy 362.137071 -279.549259)
			(xy 362.166447 -279.589692) (xy 362.189137 -279.634224) (xy 362.204581 -279.681756) (xy 362.2124 -279.731119)
			(xy 362.21289 -279.756108) (xy 362.2124 -279.781097) (xy 362.517164 -279.781097) (xy 362.517164 -279.731119)
			(xy 362.524983 -279.681756) (xy 362.540427 -279.634224) (xy 362.563117 -279.589692) (xy 362.592493 -279.549259)
			(xy 362.627833 -279.513919) (xy 362.668266 -279.484543) (xy 362.712798 -279.461853) (xy 362.76033 -279.446409)
			(xy 362.809693 -279.43859) (xy 362.859671 -279.43859) (xy 362.909034 -279.446409) (xy 362.956566 -279.461853)
			(xy 363.001098 -279.484543) (xy 363.041531 -279.513919) (xy 363.076871 -279.549259) (xy 363.106247 -279.589692)
			(xy 363.128937 -279.634224) (xy 363.144381 -279.681756) (xy 363.1522 -279.731119) (xy 363.15269 -279.756108)
			(xy 363.1522 -279.781097) (xy 363.457218 -279.781097) (xy 363.457218 -279.731119) (xy 363.465037 -279.681756)
			(xy 363.480481 -279.634224) (xy 363.503171 -279.589692) (xy 363.532547 -279.549259) (xy 363.567887 -279.513919)
			(xy 363.60832 -279.484543) (xy 363.652852 -279.461853) (xy 363.700384 -279.446409) (xy 363.749747 -279.43859)
			(xy 363.799725 -279.43859) (xy 363.849088 -279.446409) (xy 363.89662 -279.461853) (xy 363.941152 -279.484543)
			(xy 363.981585 -279.513919) (xy 364.016925 -279.549259) (xy 364.046301 -279.589692) (xy 364.068991 -279.634224)
			(xy 364.084435 -279.681756) (xy 364.092254 -279.731119) (xy 364.092744 -279.756108) (xy 364.398555 -279.756108)
			(xy 364.40265 -279.70538) (xy 364.414829 -279.655966) (xy 364.434777 -279.609146) (xy 364.461978 -279.566132)
			(xy 364.495726 -279.528038) (xy 364.535148 -279.495851) (xy 364.579222 -279.470405) (xy 364.626808 -279.452358)
			(xy 364.676672 -279.442178) (xy 364.727524 -279.440129) (xy 364.778045 -279.446263) (xy 364.826929 -279.460423)
			(xy 364.872908 -279.48224) (xy 364.914792 -279.51115) (xy 364.951496 -279.546405) (xy 364.982069 -279.587091)
			(xy 365.00572 -279.632154) (xy 365.021836 -279.680428) (xy 365.03 -279.730662) (xy 365.030512 -279.756108)
			(xy 365.338609 -279.756108) (xy 365.342704 -279.70538) (xy 365.354883 -279.655966) (xy 365.374831 -279.609146)
			(xy 365.402032 -279.566132) (xy 365.43578 -279.528038) (xy 365.475202 -279.495851) (xy 365.519276 -279.470405)
			(xy 365.566862 -279.452358) (xy 365.616726 -279.442178) (xy 365.667578 -279.440129) (xy 365.718099 -279.446263)
			(xy 365.766983 -279.460423) (xy 365.812962 -279.48224) (xy 365.854846 -279.51115) (xy 365.89155 -279.546405)
			(xy 365.922123 -279.587091) (xy 365.945774 -279.632154) (xy 365.96189 -279.680428) (xy 365.970054 -279.730662)
			(xy 365.970566 -279.756108) (xy 365.970063 -279.781097) (xy 366.27738 -279.781097) (xy 366.27738 -279.731119)
			(xy 366.285199 -279.681756) (xy 366.300643 -279.634224) (xy 366.323333 -279.589692) (xy 366.352709 -279.549259)
			(xy 366.388049 -279.513919) (xy 366.428482 -279.484543) (xy 366.473014 -279.461853) (xy 366.520546 -279.446409)
			(xy 366.569909 -279.43859) (xy 366.619887 -279.43859) (xy 366.66925 -279.446409) (xy 366.716782 -279.461853)
			(xy 366.761314 -279.484543) (xy 366.801747 -279.513919) (xy 366.837087 -279.549259) (xy 366.866463 -279.589692)
			(xy 366.889153 -279.634224) (xy 366.904597 -279.681756) (xy 366.912416 -279.731119) (xy 366.912906 -279.756108)
			(xy 366.912416 -279.781097) (xy 367.21718 -279.781097) (xy 367.21718 -279.731119) (xy 367.224999 -279.681756)
			(xy 367.240443 -279.634224) (xy 367.263133 -279.589692) (xy 367.292509 -279.549259) (xy 367.327849 -279.513919)
			(xy 367.368282 -279.484543) (xy 367.412814 -279.461853) (xy 367.460346 -279.446409) (xy 367.509709 -279.43859)
			(xy 367.559687 -279.43859) (xy 367.60905 -279.446409) (xy 367.656582 -279.461853) (xy 367.701114 -279.484543)
			(xy 367.741547 -279.513919) (xy 367.776887 -279.549259) (xy 367.806263 -279.589692) (xy 367.828953 -279.634224)
			(xy 367.844397 -279.681756) (xy 367.852216 -279.731119) (xy 367.852706 -279.756108) (xy 367.852216 -279.781097)
			(xy 368.157234 -279.781097) (xy 368.157234 -279.731119) (xy 368.165053 -279.681756) (xy 368.180497 -279.634224)
			(xy 368.203187 -279.589692) (xy 368.232563 -279.549259) (xy 368.267903 -279.513919) (xy 368.308336 -279.484543)
			(xy 368.352868 -279.461853) (xy 368.4004 -279.446409) (xy 368.449763 -279.43859) (xy 368.499741 -279.43859)
			(xy 368.549104 -279.446409) (xy 368.596636 -279.461853) (xy 368.641168 -279.484543) (xy 368.681601 -279.513919)
			(xy 368.716941 -279.549259) (xy 368.746317 -279.589692) (xy 368.769007 -279.634224) (xy 368.784451 -279.681756)
			(xy 368.79227 -279.731119) (xy 368.79276 -279.756108) (xy 368.79227 -279.781097) (xy 369.097288 -279.781097)
			(xy 369.097288 -279.731119) (xy 369.105107 -279.681756) (xy 369.120551 -279.634224) (xy 369.143241 -279.589692)
			(xy 369.172617 -279.549259) (xy 369.207957 -279.513919) (xy 369.24839 -279.484543) (xy 369.292922 -279.461853)
			(xy 369.340454 -279.446409) (xy 369.389817 -279.43859) (xy 369.439795 -279.43859) (xy 369.489158 -279.446409)
			(xy 369.53669 -279.461853) (xy 369.581222 -279.484543) (xy 369.621655 -279.513919) (xy 369.656995 -279.549259)
			(xy 369.686371 -279.589692) (xy 369.709061 -279.634224) (xy 369.724505 -279.681756) (xy 369.732324 -279.731119)
			(xy 369.732814 -279.756108) (xy 369.732324 -279.781097) (xy 370.037342 -279.781097) (xy 370.037342 -279.731119)
			(xy 370.045161 -279.681756) (xy 370.060605 -279.634224) (xy 370.083295 -279.589692) (xy 370.112671 -279.549259)
			(xy 370.148011 -279.513919) (xy 370.188444 -279.484543) (xy 370.232976 -279.461853) (xy 370.280508 -279.446409)
			(xy 370.329871 -279.43859) (xy 370.379849 -279.43859) (xy 370.429212 -279.446409) (xy 370.476744 -279.461853)
			(xy 370.521276 -279.484543) (xy 370.561709 -279.513919) (xy 370.597049 -279.549259) (xy 370.626425 -279.589692)
			(xy 370.649115 -279.634224) (xy 370.664559 -279.681756) (xy 370.672378 -279.731119) (xy 370.672868 -279.756108)
			(xy 370.672378 -279.781097) (xy 370.977396 -279.781097) (xy 370.977396 -279.731119) (xy 370.985215 -279.681756)
			(xy 371.000659 -279.634224) (xy 371.023349 -279.589692) (xy 371.052725 -279.549259) (xy 371.088065 -279.513919)
			(xy 371.128498 -279.484543) (xy 371.17303 -279.461853) (xy 371.220562 -279.446409) (xy 371.269925 -279.43859)
			(xy 371.319903 -279.43859) (xy 371.369266 -279.446409) (xy 371.416798 -279.461853) (xy 371.46133 -279.484543)
			(xy 371.501763 -279.513919) (xy 371.537103 -279.549259) (xy 371.566479 -279.589692) (xy 371.589169 -279.634224)
			(xy 371.604613 -279.681756) (xy 371.612432 -279.731119) (xy 371.612922 -279.756108) (xy 371.612432 -279.781097)
			(xy 371.917196 -279.781097) (xy 371.917196 -279.731119) (xy 371.925015 -279.681756) (xy 371.940459 -279.634224)
			(xy 371.963149 -279.589692) (xy 371.992525 -279.549259) (xy 372.027865 -279.513919) (xy 372.068298 -279.484543)
			(xy 372.11283 -279.461853) (xy 372.160362 -279.446409) (xy 372.209725 -279.43859) (xy 372.259703 -279.43859)
			(xy 372.309066 -279.446409) (xy 372.356598 -279.461853) (xy 372.40113 -279.484543) (xy 372.441563 -279.513919)
			(xy 372.476903 -279.549259) (xy 372.506279 -279.589692) (xy 372.528969 -279.634224) (xy 372.544413 -279.681756)
			(xy 372.552232 -279.731119) (xy 372.552722 -279.756108) (xy 372.552232 -279.781097) (xy 372.85725 -279.781097)
			(xy 372.85725 -279.731119) (xy 372.865069 -279.681756) (xy 372.880513 -279.634224) (xy 372.903203 -279.589692)
			(xy 372.932579 -279.549259) (xy 372.967919 -279.513919) (xy 373.008352 -279.484543) (xy 373.052884 -279.461853)
			(xy 373.100416 -279.446409) (xy 373.149779 -279.43859) (xy 373.199757 -279.43859) (xy 373.24912 -279.446409)
			(xy 373.296652 -279.461853) (xy 373.341184 -279.484543) (xy 373.381617 -279.513919) (xy 373.416957 -279.549259)
			(xy 373.446333 -279.589692) (xy 373.469023 -279.634224) (xy 373.484467 -279.681756) (xy 373.492286 -279.731119)
			(xy 373.492776 -279.756108) (xy 373.492286 -279.781097) (xy 373.484467 -279.83046) (xy 373.469023 -279.877992)
			(xy 373.446333 -279.922524) (xy 373.416957 -279.962957) (xy 373.381617 -279.998297) (xy 373.341184 -280.027673)
			(xy 373.296652 -280.050363) (xy 373.24912 -280.065807) (xy 373.199757 -280.073626) (xy 373.149779 -280.073626)
			(xy 373.100416 -280.065807) (xy 373.052884 -280.050363) (xy 373.008352 -280.027673) (xy 372.967919 -279.998297)
			(xy 372.932579 -279.962957) (xy 372.903203 -279.922524) (xy 372.880513 -279.877992) (xy 372.865069 -279.83046)
			(xy 372.85725 -279.781097) (xy 372.552232 -279.781097) (xy 372.544413 -279.83046) (xy 372.528969 -279.877992)
			(xy 372.506279 -279.922524) (xy 372.476903 -279.962957) (xy 372.441563 -279.998297) (xy 372.40113 -280.027673)
			(xy 372.356598 -280.050363) (xy 372.309066 -280.065807) (xy 372.259703 -280.073626) (xy 372.209725 -280.073626)
			(xy 372.160362 -280.065807) (xy 372.11283 -280.050363) (xy 372.068298 -280.027673) (xy 372.027865 -279.998297)
			(xy 371.992525 -279.962957) (xy 371.963149 -279.922524) (xy 371.940459 -279.877992) (xy 371.925015 -279.83046)
			(xy 371.917196 -279.781097) (xy 371.612432 -279.781097) (xy 371.604613 -279.83046) (xy 371.589169 -279.877992)
			(xy 371.566479 -279.922524) (xy 371.537103 -279.962957) (xy 371.501763 -279.998297) (xy 371.46133 -280.027673)
			(xy 371.416798 -280.050363) (xy 371.369266 -280.065807) (xy 371.319903 -280.073626) (xy 371.269925 -280.073626)
			(xy 371.220562 -280.065807) (xy 371.17303 -280.050363) (xy 371.128498 -280.027673) (xy 371.088065 -279.998297)
			(xy 371.052725 -279.962957) (xy 371.023349 -279.922524) (xy 371.000659 -279.877992) (xy 370.985215 -279.83046)
			(xy 370.977396 -279.781097) (xy 370.672378 -279.781097) (xy 370.664559 -279.83046) (xy 370.649115 -279.877992)
			(xy 370.626425 -279.922524) (xy 370.597049 -279.962957) (xy 370.561709 -279.998297) (xy 370.521276 -280.027673)
			(xy 370.476744 -280.050363) (xy 370.429212 -280.065807) (xy 370.379849 -280.073626) (xy 370.329871 -280.073626)
			(xy 370.280508 -280.065807) (xy 370.232976 -280.050363) (xy 370.188444 -280.027673) (xy 370.148011 -279.998297)
			(xy 370.112671 -279.962957) (xy 370.083295 -279.922524) (xy 370.060605 -279.877992) (xy 370.045161 -279.83046)
			(xy 370.037342 -279.781097) (xy 369.732324 -279.781097) (xy 369.724505 -279.83046) (xy 369.709061 -279.877992)
			(xy 369.686371 -279.922524) (xy 369.656995 -279.962957) (xy 369.621655 -279.998297) (xy 369.581222 -280.027673)
			(xy 369.53669 -280.050363) (xy 369.489158 -280.065807) (xy 369.439795 -280.073626) (xy 369.389817 -280.073626)
			(xy 369.340454 -280.065807) (xy 369.292922 -280.050363) (xy 369.24839 -280.027673) (xy 369.207957 -279.998297)
			(xy 369.172617 -279.962957) (xy 369.143241 -279.922524) (xy 369.120551 -279.877992) (xy 369.105107 -279.83046)
			(xy 369.097288 -279.781097) (xy 368.79227 -279.781097) (xy 368.784451 -279.83046) (xy 368.769007 -279.877992)
			(xy 368.746317 -279.922524) (xy 368.716941 -279.962957) (xy 368.681601 -279.998297) (xy 368.641168 -280.027673)
			(xy 368.596636 -280.050363) (xy 368.549104 -280.065807) (xy 368.499741 -280.073626) (xy 368.449763 -280.073626)
			(xy 368.4004 -280.065807) (xy 368.352868 -280.050363) (xy 368.308336 -280.027673) (xy 368.267903 -279.998297)
			(xy 368.232563 -279.962957) (xy 368.203187 -279.922524) (xy 368.180497 -279.877992) (xy 368.165053 -279.83046)
			(xy 368.157234 -279.781097) (xy 367.852216 -279.781097) (xy 367.844397 -279.83046) (xy 367.828953 -279.877992)
			(xy 367.806263 -279.922524) (xy 367.776887 -279.962957) (xy 367.741547 -279.998297) (xy 367.701114 -280.027673)
			(xy 367.656582 -280.050363) (xy 367.60905 -280.065807) (xy 367.559687 -280.073626) (xy 367.509709 -280.073626)
			(xy 367.460346 -280.065807) (xy 367.412814 -280.050363) (xy 367.368282 -280.027673) (xy 367.327849 -279.998297)
			(xy 367.292509 -279.962957) (xy 367.263133 -279.922524) (xy 367.240443 -279.877992) (xy 367.224999 -279.83046)
			(xy 367.21718 -279.781097) (xy 366.912416 -279.781097) (xy 366.904597 -279.83046) (xy 366.889153 -279.877992)
			(xy 366.866463 -279.922524) (xy 366.837087 -279.962957) (xy 366.801747 -279.998297) (xy 366.761314 -280.027673)
			(xy 366.716782 -280.050363) (xy 366.66925 -280.065807) (xy 366.619887 -280.073626) (xy 366.569909 -280.073626)
			(xy 366.520546 -280.065807) (xy 366.473014 -280.050363) (xy 366.428482 -280.027673) (xy 366.388049 -279.998297)
			(xy 366.352709 -279.962957) (xy 366.323333 -279.922524) (xy 366.300643 -279.877992) (xy 366.285199 -279.83046)
			(xy 366.27738 -279.781097) (xy 365.970063 -279.781097) (xy 365.970054 -279.781554) (xy 365.96189 -279.831788)
			(xy 365.945774 -279.880062) (xy 365.922123 -279.925125) (xy 365.89155 -279.965811) (xy 365.854846 -280.001066)
			(xy 365.812962 -280.029976) (xy 365.766983 -280.051793) (xy 365.718099 -280.065953) (xy 365.667578 -280.072087)
			(xy 365.616726 -280.070038) (xy 365.566862 -280.059858) (xy 365.519276 -280.041811) (xy 365.475202 -280.016365)
			(xy 365.43578 -279.984178) (xy 365.402032 -279.946084) (xy 365.374831 -279.90307) (xy 365.354883 -279.85625)
			(xy 365.342704 -279.806836) (xy 365.338609 -279.756108) (xy 365.030512 -279.756108) (xy 365.03 -279.781554)
			(xy 365.021836 -279.831788) (xy 365.00572 -279.880062) (xy 364.982069 -279.925125) (xy 364.951496 -279.965811)
			(xy 364.914792 -280.001066) (xy 364.872908 -280.029976) (xy 364.826929 -280.051793) (xy 364.778045 -280.065953)
			(xy 364.727524 -280.072087) (xy 364.676672 -280.070038) (xy 364.626808 -280.059858) (xy 364.579222 -280.041811)
			(xy 364.535148 -280.016365) (xy 364.495726 -279.984178) (xy 364.461978 -279.946084) (xy 364.434777 -279.90307)
			(xy 364.414829 -279.85625) (xy 364.40265 -279.806836) (xy 364.398555 -279.756108) (xy 364.092744 -279.756108)
			(xy 364.092254 -279.781097) (xy 364.084435 -279.83046) (xy 364.068991 -279.877992) (xy 364.046301 -279.922524)
			(xy 364.016925 -279.962957) (xy 363.981585 -279.998297) (xy 363.941152 -280.027673) (xy 363.89662 -280.050363)
			(xy 363.849088 -280.065807) (xy 363.799725 -280.073626) (xy 363.749747 -280.073626) (xy 363.700384 -280.065807)
			(xy 363.652852 -280.050363) (xy 363.60832 -280.027673) (xy 363.567887 -279.998297) (xy 363.532547 -279.962957)
			(xy 363.503171 -279.922524) (xy 363.480481 -279.877992) (xy 363.465037 -279.83046) (xy 363.457218 -279.781097)
			(xy 363.1522 -279.781097) (xy 363.144381 -279.83046) (xy 363.128937 -279.877992) (xy 363.106247 -279.922524)
			(xy 363.076871 -279.962957) (xy 363.041531 -279.998297) (xy 363.001098 -280.027673) (xy 362.956566 -280.050363)
			(xy 362.909034 -280.065807) (xy 362.859671 -280.073626) (xy 362.809693 -280.073626) (xy 362.76033 -280.065807)
			(xy 362.712798 -280.050363) (xy 362.668266 -280.027673) (xy 362.627833 -279.998297) (xy 362.592493 -279.962957)
			(xy 362.563117 -279.922524) (xy 362.540427 -279.877992) (xy 362.524983 -279.83046) (xy 362.517164 -279.781097)
			(xy 362.2124 -279.781097) (xy 362.204581 -279.83046) (xy 362.189137 -279.877992) (xy 362.166447 -279.922524)
			(xy 362.137071 -279.962957) (xy 362.101731 -279.998297) (xy 362.061298 -280.027673) (xy 362.016766 -280.050363)
			(xy 361.969234 -280.065807) (xy 361.919871 -280.073626) (xy 361.869893 -280.073626) (xy 361.82053 -280.065807)
			(xy 361.772998 -280.050363) (xy 361.728466 -280.027673) (xy 361.688033 -279.998297) (xy 361.652693 -279.962957)
			(xy 361.623317 -279.922524) (xy 361.600627 -279.877992) (xy 361.585183 -279.83046) (xy 361.577364 -279.781097)
			(xy 358.458534 -279.781097) (xy 358.450715 -279.83046) (xy 358.435271 -279.877992) (xy 358.412581 -279.922524)
			(xy 358.383205 -279.962957) (xy 358.347865 -279.998297) (xy 358.307432 -280.027673) (xy 358.2629 -280.050363)
			(xy 358.215368 -280.065807) (xy 358.166005 -280.073626) (xy 358.116027 -280.073626) (xy 358.066664 -280.065807)
			(xy 358.019132 -280.050363) (xy 357.9746 -280.027673) (xy 357.934167 -279.998297) (xy 357.898827 -279.962957)
			(xy 357.869451 -279.922524) (xy 357.846761 -279.877992) (xy 357.831317 -279.83046) (xy 357.823498 -279.781097)
			(xy 357.518734 -279.781097) (xy 357.510915 -279.83046) (xy 357.495471 -279.877992) (xy 357.472781 -279.922524)
			(xy 357.443405 -279.962957) (xy 357.408065 -279.998297) (xy 357.367632 -280.027673) (xy 357.3231 -280.050363)
			(xy 357.275568 -280.065807) (xy 357.226205 -280.073626) (xy 357.176227 -280.073626) (xy 357.126864 -280.065807)
			(xy 357.079332 -280.050363) (xy 357.0348 -280.027673) (xy 356.994367 -279.998297) (xy 356.959027 -279.962957)
			(xy 356.929651 -279.922524) (xy 356.906961 -279.877992) (xy 356.891517 -279.83046) (xy 356.883698 -279.781097)
			(xy 356.57868 -279.781097) (xy 356.570861 -279.83046) (xy 356.555417 -279.877992) (xy 356.532727 -279.922524)
			(xy 356.503351 -279.962957) (xy 356.468011 -279.998297) (xy 356.427578 -280.027673) (xy 356.383046 -280.050363)
			(xy 356.335514 -280.065807) (xy 356.286151 -280.073626) (xy 356.236173 -280.073626) (xy 356.18681 -280.065807)
			(xy 356.139278 -280.050363) (xy 356.094746 -280.027673) (xy 356.054313 -279.998297) (xy 356.018973 -279.962957)
			(xy 355.989597 -279.922524) (xy 355.966907 -279.877992) (xy 355.951463 -279.83046) (xy 355.943644 -279.781097)
			(xy 355.636327 -279.781097) (xy 355.636318 -279.781554) (xy 355.628154 -279.831788) (xy 355.612038 -279.880062)
			(xy 355.588387 -279.925125) (xy 355.557814 -279.965811) (xy 355.52111 -280.001066) (xy 355.479226 -280.029976)
			(xy 355.433247 -280.051793) (xy 355.384363 -280.065953) (xy 355.333842 -280.072087) (xy 355.28299 -280.070038)
			(xy 355.233126 -280.059858) (xy 355.18554 -280.041811) (xy 355.141466 -280.016365) (xy 355.102044 -279.984178)
			(xy 355.068296 -279.946084) (xy 355.041095 -279.90307) (xy 355.021147 -279.85625) (xy 355.008968 -279.806836)
			(xy 355.004873 -279.756108) (xy 354.696776 -279.756108) (xy 354.696264 -279.781554) (xy 354.6881 -279.831788)
			(xy 354.671984 -279.880062) (xy 354.648333 -279.925125) (xy 354.61776 -279.965811) (xy 354.581056 -280.001066)
			(xy 354.539172 -280.029976) (xy 354.493193 -280.051793) (xy 354.444309 -280.065953) (xy 354.393788 -280.072087)
			(xy 354.342936 -280.070038) (xy 354.293072 -280.059858) (xy 354.245486 -280.041811) (xy 354.201412 -280.016365)
			(xy 354.16199 -279.984178) (xy 354.128242 -279.946084) (xy 354.101041 -279.90307) (xy 354.081093 -279.85625)
			(xy 354.068914 -279.806836) (xy 354.064819 -279.756108) (xy 353.759008 -279.756108) (xy 353.758518 -279.781097)
			(xy 353.750699 -279.83046) (xy 353.735255 -279.877992) (xy 353.712565 -279.922524) (xy 353.683189 -279.962957)
			(xy 353.647849 -279.998297) (xy 353.607416 -280.027673) (xy 353.562884 -280.050363) (xy 353.515352 -280.065807)
			(xy 353.465989 -280.073626) (xy 353.416011 -280.073626) (xy 353.366648 -280.065807) (xy 353.319116 -280.050363)
			(xy 353.274584 -280.027673) (xy 353.234151 -279.998297) (xy 353.198811 -279.962957) (xy 353.169435 -279.922524)
			(xy 353.146745 -279.877992) (xy 353.131301 -279.83046) (xy 353.123482 -279.781097) (xy 352.818718 -279.781097)
			(xy 352.810899 -279.83046) (xy 352.795455 -279.877992) (xy 352.772765 -279.922524) (xy 352.743389 -279.962957)
			(xy 352.708049 -279.998297) (xy 352.667616 -280.027673) (xy 352.623084 -280.050363) (xy 352.575552 -280.065807)
			(xy 352.526189 -280.073626) (xy 352.476211 -280.073626) (xy 352.426848 -280.065807) (xy 352.379316 -280.050363)
			(xy 352.334784 -280.027673) (xy 352.294351 -279.998297) (xy 352.259011 -279.962957) (xy 352.229635 -279.922524)
			(xy 352.206945 -279.877992) (xy 352.191501 -279.83046) (xy 352.183682 -279.781097) (xy 351.878664 -279.781097)
			(xy 351.870845 -279.83046) (xy 351.855401 -279.877992) (xy 351.832711 -279.922524) (xy 351.803335 -279.962957)
			(xy 351.767995 -279.998297) (xy 351.727562 -280.027673) (xy 351.68303 -280.050363) (xy 351.635498 -280.065807)
			(xy 351.586135 -280.073626) (xy 351.536157 -280.073626) (xy 351.486794 -280.065807) (xy 351.439262 -280.050363)
			(xy 351.39473 -280.027673) (xy 351.354297 -279.998297) (xy 351.318957 -279.962957) (xy 351.289581 -279.922524)
			(xy 351.266891 -279.877992) (xy 351.251447 -279.83046) (xy 351.243628 -279.781097) (xy 350.93861 -279.781097)
			(xy 350.930791 -279.83046) (xy 350.915347 -279.877992) (xy 350.892657 -279.922524) (xy 350.863281 -279.962957)
			(xy 350.827941 -279.998297) (xy 350.787508 -280.027673) (xy 350.742976 -280.050363) (xy 350.695444 -280.065807)
			(xy 350.646081 -280.073626) (xy 350.596103 -280.073626) (xy 350.54674 -280.065807) (xy 350.499208 -280.050363)
			(xy 350.454676 -280.027673) (xy 350.414243 -279.998297) (xy 350.378903 -279.962957) (xy 350.349527 -279.922524)
			(xy 350.326837 -279.877992) (xy 350.311393 -279.83046) (xy 350.303574 -279.781097) (xy 349.998556 -279.781097)
			(xy 349.990737 -279.83046) (xy 349.975293 -279.877992) (xy 349.952603 -279.922524) (xy 349.923227 -279.962957)
			(xy 349.887887 -279.998297) (xy 349.847454 -280.027673) (xy 349.802922 -280.050363) (xy 349.75539 -280.065807)
			(xy 349.706027 -280.073626) (xy 349.656049 -280.073626) (xy 349.606686 -280.065807) (xy 349.559154 -280.050363)
			(xy 349.514622 -280.027673) (xy 349.474189 -279.998297) (xy 349.438849 -279.962957) (xy 349.409473 -279.922524)
			(xy 349.386783 -279.877992) (xy 349.371339 -279.83046) (xy 349.36352 -279.781097) (xy 349.058756 -279.781097)
			(xy 349.050937 -279.83046) (xy 349.035493 -279.877992) (xy 349.012803 -279.922524) (xy 348.983427 -279.962957)
			(xy 348.948087 -279.998297) (xy 348.907654 -280.027673) (xy 348.863122 -280.050363) (xy 348.81559 -280.065807)
			(xy 348.766227 -280.073626) (xy 348.716249 -280.073626) (xy 348.666886 -280.065807) (xy 348.619354 -280.050363)
			(xy 348.574822 -280.027673) (xy 348.534389 -279.998297) (xy 348.499049 -279.962957) (xy 348.469673 -279.922524)
			(xy 348.446983 -279.877992) (xy 348.431539 -279.83046) (xy 348.42372 -279.781097) (xy 348.118702 -279.781097)
			(xy 348.110883 -279.83046) (xy 348.095439 -279.877992) (xy 348.072749 -279.922524) (xy 348.043373 -279.962957)
			(xy 348.008033 -279.998297) (xy 347.9676 -280.027673) (xy 347.923068 -280.050363) (xy 347.875536 -280.065807)
			(xy 347.826173 -280.073626) (xy 347.776195 -280.073626) (xy 347.726832 -280.065807) (xy 347.6793 -280.050363)
			(xy 347.634768 -280.027673) (xy 347.594335 -279.998297) (xy 347.558995 -279.962957) (xy 347.529619 -279.922524)
			(xy 347.506929 -279.877992) (xy 347.491485 -279.83046) (xy 347.483666 -279.781097) (xy 347.178648 -279.781097)
			(xy 347.170829 -279.83046) (xy 347.155385 -279.877992) (xy 347.132695 -279.922524) (xy 347.103319 -279.962957)
			(xy 347.067979 -279.998297) (xy 347.027546 -280.027673) (xy 346.983014 -280.050363) (xy 346.935482 -280.065807)
			(xy 346.886119 -280.073626) (xy 346.836141 -280.073626) (xy 346.786778 -280.065807) (xy 346.739246 -280.050363)
			(xy 346.694714 -280.027673) (xy 346.654281 -279.998297) (xy 346.618941 -279.962957) (xy 346.589565 -279.922524)
			(xy 346.566875 -279.877992) (xy 346.551431 -279.83046) (xy 346.543612 -279.781097) (xy 346.238594 -279.781097)
			(xy 346.230775 -279.83046) (xy 346.215331 -279.877992) (xy 346.192641 -279.922524) (xy 346.163265 -279.962957)
			(xy 346.127925 -279.998297) (xy 346.087492 -280.027673) (xy 346.04296 -280.050363) (xy 345.995428 -280.065807)
			(xy 345.946065 -280.073626) (xy 345.896087 -280.073626) (xy 345.846724 -280.065807) (xy 345.799192 -280.050363)
			(xy 345.75466 -280.027673) (xy 345.714227 -279.998297) (xy 345.678887 -279.962957) (xy 345.649511 -279.922524)
			(xy 345.626821 -279.877992) (xy 345.611377 -279.83046) (xy 345.603558 -279.781097) (xy 345.297802 -279.781097)
			(xy 345.297257 -279.794025) (xy 345.287645 -279.84225) (xy 345.27072 -279.88842) (xy 345.246886 -279.931432)
			(xy 345.232228 -279.95118) (xy 345.214387 -279.973148) (xy 345.172311 -280.010986) (xy 345.124193 -280.040766)
			(xy 345.098116 -280.051764) (xy 345.097862 -280.051764) (xy 345.095068 -280.05278) (xy 345.086746 -280.057165)
			(xy 345.073759 -280.07075) (xy 345.066537 -280.088101) (xy 345.065858 -280.097484) (xy 345.065858 -280.260044)
			(xy 345.06631 -280.269884) (xy 345.073735 -280.288108) (xy 345.087503 -280.302168) (xy 345.096338 -280.306526)
			(xy 345.14155 -280.326338) (xy 345.17965 -280.342848) (xy 345.186544 -280.345577) (xy 345.201255 -280.347377)
			(xy 345.208606 -280.346404) (xy 345.215464 -280.345134) (xy 345.228672 -280.338784) (xy 345.23426 -280.33345)
			(xy 345.252024 -280.317486) (xy 345.291441 -280.290521) (xy 345.334446 -280.269751) (xy 345.380073 -280.255643)
			(xy 345.427297 -280.248515) (xy 345.451176 -280.248106) (xy 345.476167 -280.248569) (xy 345.525535 -280.256384)
			(xy 345.573072 -280.271827) (xy 345.617608 -280.294516) (xy 345.658047 -280.323893) (xy 345.693391 -280.359235)
			(xy 345.722771 -280.399671) (xy 345.745464 -280.444205) (xy 345.76091 -280.491741) (xy 345.76873 -280.541109)
			(xy 345.76873 -280.591091) (xy 345.768728 -280.591103) (xy 346.073712 -280.591103) (xy 346.073712 -280.541125)
			(xy 346.081531 -280.491762) (xy 346.096975 -280.44423) (xy 346.119665 -280.399698) (xy 346.149041 -280.359265)
			(xy 346.184381 -280.323925) (xy 346.224814 -280.294549) (xy 346.269346 -280.271859) (xy 346.316878 -280.256415)
			(xy 346.366241 -280.248596) (xy 346.416219 -280.248596) (xy 346.465582 -280.256415) (xy 346.513114 -280.271859)
			(xy 346.557646 -280.294549) (xy 346.598079 -280.323925) (xy 346.633419 -280.359265) (xy 346.662795 -280.399698)
			(xy 346.685485 -280.44423) (xy 346.700929 -280.491762) (xy 346.708748 -280.541125) (xy 346.709238 -280.566114)
			(xy 346.708748 -280.591103) (xy 347.013512 -280.591103) (xy 347.013512 -280.541125) (xy 347.021331 -280.491762)
			(xy 347.036775 -280.44423) (xy 347.059465 -280.399698) (xy 347.088841 -280.359265) (xy 347.124181 -280.323925)
			(xy 347.164614 -280.294549) (xy 347.209146 -280.271859) (xy 347.256678 -280.256415) (xy 347.306041 -280.248596)
			(xy 347.356019 -280.248596) (xy 347.405382 -280.256415) (xy 347.452914 -280.271859) (xy 347.497446 -280.294549)
			(xy 347.537879 -280.323925) (xy 347.573219 -280.359265) (xy 347.602595 -280.399698) (xy 347.625285 -280.44423)
			(xy 347.640729 -280.491762) (xy 347.648548 -280.541125) (xy 347.649038 -280.566114) (xy 347.648548 -280.591103)
			(xy 347.953566 -280.591103) (xy 347.953566 -280.541125) (xy 347.961385 -280.491762) (xy 347.976829 -280.44423)
			(xy 347.999519 -280.399698) (xy 348.028895 -280.359265) (xy 348.064235 -280.323925) (xy 348.104668 -280.294549)
			(xy 348.1492 -280.271859) (xy 348.196732 -280.256415) (xy 348.246095 -280.248596) (xy 348.296073 -280.248596)
			(xy 348.345436 -280.256415) (xy 348.392968 -280.271859) (xy 348.4375 -280.294549) (xy 348.477933 -280.323925)
			(xy 348.513273 -280.359265) (xy 348.542649 -280.399698) (xy 348.565339 -280.44423) (xy 348.580783 -280.491762)
			(xy 348.588602 -280.541125) (xy 348.589092 -280.566114) (xy 348.588602 -280.591103) (xy 348.89362 -280.591103)
			(xy 348.89362 -280.541125) (xy 348.901439 -280.491762) (xy 348.916883 -280.44423) (xy 348.939573 -280.399698)
			(xy 348.968949 -280.359265) (xy 349.004289 -280.323925) (xy 349.044722 -280.294549) (xy 349.089254 -280.271859)
			(xy 349.136786 -280.256415) (xy 349.186149 -280.248596) (xy 349.236127 -280.248596) (xy 349.28549 -280.256415)
			(xy 349.333022 -280.271859) (xy 349.377554 -280.294549) (xy 349.417987 -280.323925) (xy 349.453327 -280.359265)
			(xy 349.482703 -280.399698) (xy 349.505393 -280.44423) (xy 349.520837 -280.491762) (xy 349.528656 -280.541125)
			(xy 349.529146 -280.566114) (xy 349.528656 -280.591103) (xy 349.833674 -280.591103) (xy 349.833674 -280.541125)
			(xy 349.841493 -280.491762) (xy 349.856937 -280.44423) (xy 349.879627 -280.399698) (xy 349.909003 -280.359265)
			(xy 349.944343 -280.323925) (xy 349.984776 -280.294549) (xy 350.029308 -280.271859) (xy 350.07684 -280.256415)
			(xy 350.126203 -280.248596) (xy 350.176181 -280.248596) (xy 350.225544 -280.256415) (xy 350.273076 -280.271859)
			(xy 350.317608 -280.294549) (xy 350.358041 -280.323925) (xy 350.393381 -280.359265) (xy 350.422757 -280.399698)
			(xy 350.445447 -280.44423) (xy 350.460891 -280.491762) (xy 350.46871 -280.541125) (xy 350.4692 -280.566114)
			(xy 350.46871 -280.591103) (xy 350.773728 -280.591103) (xy 350.773728 -280.541125) (xy 350.781547 -280.491762)
			(xy 350.796991 -280.44423) (xy 350.819681 -280.399698) (xy 350.849057 -280.359265) (xy 350.884397 -280.323925)
			(xy 350.92483 -280.294549) (xy 350.969362 -280.271859) (xy 351.016894 -280.256415) (xy 351.066257 -280.248596)
			(xy 351.116235 -280.248596) (xy 351.165598 -280.256415) (xy 351.21313 -280.271859) (xy 351.257662 -280.294549)
			(xy 351.298095 -280.323925) (xy 351.333435 -280.359265) (xy 351.362811 -280.399698) (xy 351.385501 -280.44423)
			(xy 351.400945 -280.491762) (xy 351.408764 -280.541125) (xy 351.409254 -280.566114) (xy 351.408764 -280.591103)
			(xy 351.713528 -280.591103) (xy 351.713528 -280.541125) (xy 351.721347 -280.491762) (xy 351.736791 -280.44423)
			(xy 351.759481 -280.399698) (xy 351.788857 -280.359265) (xy 351.824197 -280.323925) (xy 351.86463 -280.294549)
			(xy 351.909162 -280.271859) (xy 351.956694 -280.256415) (xy 352.006057 -280.248596) (xy 352.056035 -280.248596)
			(xy 352.105398 -280.256415) (xy 352.15293 -280.271859) (xy 352.197462 -280.294549) (xy 352.237895 -280.323925)
			(xy 352.273235 -280.359265) (xy 352.302611 -280.399698) (xy 352.325301 -280.44423) (xy 352.340745 -280.491762)
			(xy 352.348564 -280.541125) (xy 352.349054 -280.566114) (xy 352.348564 -280.591103) (xy 352.653582 -280.591103)
			(xy 352.653582 -280.541125) (xy 352.661401 -280.491762) (xy 352.676845 -280.44423) (xy 352.699535 -280.399698)
			(xy 352.728911 -280.359265) (xy 352.764251 -280.323925) (xy 352.804684 -280.294549) (xy 352.849216 -280.271859)
			(xy 352.896748 -280.256415) (xy 352.946111 -280.248596) (xy 352.996089 -280.248596) (xy 353.045452 -280.256415)
			(xy 353.092984 -280.271859) (xy 353.137516 -280.294549) (xy 353.177949 -280.323925) (xy 353.213289 -280.359265)
			(xy 353.242665 -280.399698) (xy 353.265355 -280.44423) (xy 353.280799 -280.491762) (xy 353.288618 -280.541125)
			(xy 353.289108 -280.566114) (xy 353.288618 -280.591103) (xy 353.593636 -280.591103) (xy 353.593636 -280.541125)
			(xy 353.601455 -280.491762) (xy 353.616899 -280.44423) (xy 353.639589 -280.399698) (xy 353.668965 -280.359265)
			(xy 353.704305 -280.323925) (xy 353.744738 -280.294549) (xy 353.78927 -280.271859) (xy 353.836802 -280.256415)
			(xy 353.886165 -280.248596) (xy 353.936143 -280.248596) (xy 353.985506 -280.256415) (xy 354.033038 -280.271859)
			(xy 354.07757 -280.294549) (xy 354.118003 -280.323925) (xy 354.153343 -280.359265) (xy 354.182719 -280.399698)
			(xy 354.205409 -280.44423) (xy 354.220853 -280.491762) (xy 354.228672 -280.541125) (xy 354.229162 -280.566114)
			(xy 354.228672 -280.591103) (xy 354.53369 -280.591103) (xy 354.53369 -280.541125) (xy 354.541509 -280.491762)
			(xy 354.556953 -280.44423) (xy 354.579643 -280.399698) (xy 354.609019 -280.359265) (xy 354.644359 -280.323925)
			(xy 354.684792 -280.294549) (xy 354.729324 -280.271859) (xy 354.776856 -280.256415) (xy 354.826219 -280.248596)
			(xy 354.876197 -280.248596) (xy 354.92556 -280.256415) (xy 354.973092 -280.271859) (xy 355.017624 -280.294549)
			(xy 355.058057 -280.323925) (xy 355.093397 -280.359265) (xy 355.122773 -280.399698) (xy 355.145463 -280.44423)
			(xy 355.160907 -280.491762) (xy 355.168726 -280.541125) (xy 355.169216 -280.566114) (xy 355.168726 -280.591103)
			(xy 355.47349 -280.591103) (xy 355.47349 -280.541125) (xy 355.481309 -280.491762) (xy 355.496753 -280.44423)
			(xy 355.519443 -280.399698) (xy 355.548819 -280.359265) (xy 355.584159 -280.323925) (xy 355.624592 -280.294549)
			(xy 355.669124 -280.271859) (xy 355.716656 -280.256415) (xy 355.766019 -280.248596) (xy 355.815997 -280.248596)
			(xy 355.86536 -280.256415) (xy 355.912892 -280.271859) (xy 355.957424 -280.294549) (xy 355.997857 -280.323925)
			(xy 356.033197 -280.359265) (xy 356.062573 -280.399698) (xy 356.085263 -280.44423) (xy 356.100707 -280.491762)
			(xy 356.108526 -280.541125) (xy 356.109016 -280.566114) (xy 356.108526 -280.591103) (xy 358.293652 -280.591103)
			(xy 358.293652 -280.541125) (xy 358.301471 -280.491762) (xy 358.316915 -280.44423) (xy 358.339605 -280.399698)
			(xy 358.368981 -280.359265) (xy 358.404321 -280.323925) (xy 358.444754 -280.294549) (xy 358.489286 -280.271859)
			(xy 358.536818 -280.256415) (xy 358.586181 -280.248596) (xy 358.636159 -280.248596) (xy 358.685522 -280.256415)
			(xy 358.733054 -280.271859) (xy 358.777586 -280.294549) (xy 358.818019 -280.323925) (xy 358.853359 -280.359265)
			(xy 358.882735 -280.399698) (xy 358.905425 -280.44423) (xy 358.920869 -280.491762) (xy 358.928688 -280.541125)
			(xy 358.929178 -280.566114) (xy 358.928688 -280.591103) (xy 361.10721 -280.591103) (xy 361.10721 -280.541125)
			(xy 361.115029 -280.491762) (xy 361.130473 -280.44423) (xy 361.153163 -280.399698) (xy 361.182539 -280.359265)
			(xy 361.217879 -280.323925) (xy 361.258312 -280.294549) (xy 361.302844 -280.271859) (xy 361.350376 -280.256415)
			(xy 361.399739 -280.248596) (xy 361.449717 -280.248596) (xy 361.49908 -280.256415) (xy 361.546612 -280.271859)
			(xy 361.591144 -280.294549) (xy 361.631577 -280.323925) (xy 361.666917 -280.359265) (xy 361.696293 -280.399698)
			(xy 361.718983 -280.44423) (xy 361.734427 -280.491762) (xy 361.742246 -280.541125) (xy 361.742736 -280.566114)
			(xy 361.742246 -280.591103) (xy 363.927372 -280.591103) (xy 363.927372 -280.541125) (xy 363.935191 -280.491762)
			(xy 363.950635 -280.44423) (xy 363.973325 -280.399698) (xy 364.002701 -280.359265) (xy 364.038041 -280.323925)
			(xy 364.078474 -280.294549) (xy 364.123006 -280.271859) (xy 364.170538 -280.256415) (xy 364.219901 -280.248596)
			(xy 364.269879 -280.248596) (xy 364.319242 -280.256415) (xy 364.366774 -280.271859) (xy 364.411306 -280.294549)
			(xy 364.451739 -280.323925) (xy 364.487079 -280.359265) (xy 364.516455 -280.399698) (xy 364.539145 -280.44423)
			(xy 364.554589 -280.491762) (xy 364.562408 -280.541125) (xy 364.562898 -280.566114) (xy 364.562408 -280.591103)
			(xy 364.867172 -280.591103) (xy 364.867172 -280.541125) (xy 364.874991 -280.491762) (xy 364.890435 -280.44423)
			(xy 364.913125 -280.399698) (xy 364.942501 -280.359265) (xy 364.977841 -280.323925) (xy 365.018274 -280.294549)
			(xy 365.062806 -280.271859) (xy 365.110338 -280.256415) (xy 365.159701 -280.248596) (xy 365.209679 -280.248596)
			(xy 365.259042 -280.256415) (xy 365.306574 -280.271859) (xy 365.351106 -280.294549) (xy 365.391539 -280.323925)
			(xy 365.426879 -280.359265) (xy 365.456255 -280.399698) (xy 365.478945 -280.44423) (xy 365.494389 -280.491762)
			(xy 365.502208 -280.541125) (xy 365.502698 -280.566114) (xy 365.502208 -280.591103) (xy 365.807226 -280.591103)
			(xy 365.807226 -280.541125) (xy 365.815045 -280.491762) (xy 365.830489 -280.44423) (xy 365.853179 -280.399698)
			(xy 365.882555 -280.359265) (xy 365.917895 -280.323925) (xy 365.958328 -280.294549) (xy 366.00286 -280.271859)
			(xy 366.050392 -280.256415) (xy 366.099755 -280.248596) (xy 366.149733 -280.248596) (xy 366.199096 -280.256415)
			(xy 366.246628 -280.271859) (xy 366.29116 -280.294549) (xy 366.331593 -280.323925) (xy 366.366933 -280.359265)
			(xy 366.396309 -280.399698) (xy 366.418999 -280.44423) (xy 366.434443 -280.491762) (xy 366.442262 -280.541125)
			(xy 366.442752 -280.566114) (xy 366.442262 -280.591103) (xy 366.74728 -280.591103) (xy 366.74728 -280.541125)
			(xy 366.755099 -280.491762) (xy 366.770543 -280.44423) (xy 366.793233 -280.399698) (xy 366.822609 -280.359265)
			(xy 366.857949 -280.323925) (xy 366.898382 -280.294549) (xy 366.942914 -280.271859) (xy 366.990446 -280.256415)
			(xy 367.039809 -280.248596) (xy 367.089787 -280.248596) (xy 367.13915 -280.256415) (xy 367.186682 -280.271859)
			(xy 367.231214 -280.294549) (xy 367.271647 -280.323925) (xy 367.306987 -280.359265) (xy 367.336363 -280.399698)
			(xy 367.359053 -280.44423) (xy 367.374497 -280.491762) (xy 367.382316 -280.541125) (xy 367.382806 -280.566114)
			(xy 367.382316 -280.591103) (xy 367.687334 -280.591103) (xy 367.687334 -280.541125) (xy 367.695153 -280.491762)
			(xy 367.710597 -280.44423) (xy 367.733287 -280.399698) (xy 367.762663 -280.359265) (xy 367.798003 -280.323925)
			(xy 367.838436 -280.294549) (xy 367.882968 -280.271859) (xy 367.9305 -280.256415) (xy 367.979863 -280.248596)
			(xy 368.029841 -280.248596) (xy 368.079204 -280.256415) (xy 368.126736 -280.271859) (xy 368.171268 -280.294549)
			(xy 368.211701 -280.323925) (xy 368.247041 -280.359265) (xy 368.276417 -280.399698) (xy 368.299107 -280.44423)
			(xy 368.314551 -280.491762) (xy 368.32237 -280.541125) (xy 368.32286 -280.566114) (xy 368.32237 -280.591103)
			(xy 368.627388 -280.591103) (xy 368.627388 -280.541125) (xy 368.635207 -280.491762) (xy 368.650651 -280.44423)
			(xy 368.673341 -280.399698) (xy 368.702717 -280.359265) (xy 368.738057 -280.323925) (xy 368.77849 -280.294549)
			(xy 368.823022 -280.271859) (xy 368.870554 -280.256415) (xy 368.919917 -280.248596) (xy 368.969895 -280.248596)
			(xy 369.019258 -280.256415) (xy 369.06679 -280.271859) (xy 369.111322 -280.294549) (xy 369.151755 -280.323925)
			(xy 369.187095 -280.359265) (xy 369.216471 -280.399698) (xy 369.239161 -280.44423) (xy 369.254605 -280.491762)
			(xy 369.262424 -280.541125) (xy 369.262914 -280.566114) (xy 369.262424 -280.591103) (xy 369.567188 -280.591103)
			(xy 369.567188 -280.541125) (xy 369.575007 -280.491762) (xy 369.590451 -280.44423) (xy 369.613141 -280.399698)
			(xy 369.642517 -280.359265) (xy 369.677857 -280.323925) (xy 369.71829 -280.294549) (xy 369.762822 -280.271859)
			(xy 369.810354 -280.256415) (xy 369.859717 -280.248596) (xy 369.909695 -280.248596) (xy 369.959058 -280.256415)
			(xy 370.00659 -280.271859) (xy 370.051122 -280.294549) (xy 370.091555 -280.323925) (xy 370.126895 -280.359265)
			(xy 370.156271 -280.399698) (xy 370.178961 -280.44423) (xy 370.194405 -280.491762) (xy 370.202224 -280.541125)
			(xy 370.202714 -280.566114) (xy 370.202224 -280.591103) (xy 370.507242 -280.591103) (xy 370.507242 -280.541125)
			(xy 370.515061 -280.491762) (xy 370.530505 -280.44423) (xy 370.553195 -280.399698) (xy 370.582571 -280.359265)
			(xy 370.617911 -280.323925) (xy 370.658344 -280.294549) (xy 370.702876 -280.271859) (xy 370.750408 -280.256415)
			(xy 370.799771 -280.248596) (xy 370.849749 -280.248596) (xy 370.899112 -280.256415) (xy 370.946644 -280.271859)
			(xy 370.991176 -280.294549) (xy 371.031609 -280.323925) (xy 371.066949 -280.359265) (xy 371.096325 -280.399698)
			(xy 371.119015 -280.44423) (xy 371.134459 -280.491762) (xy 371.142278 -280.541125) (xy 371.142768 -280.566114)
			(xy 371.142278 -280.591103) (xy 371.447296 -280.591103) (xy 371.447296 -280.541125) (xy 371.455115 -280.491762)
			(xy 371.470559 -280.44423) (xy 371.493249 -280.399698) (xy 371.522625 -280.359265) (xy 371.557965 -280.323925)
			(xy 371.598398 -280.294549) (xy 371.64293 -280.271859) (xy 371.690462 -280.256415) (xy 371.739825 -280.248596)
			(xy 371.789803 -280.248596) (xy 371.839166 -280.256415) (xy 371.886698 -280.271859) (xy 371.93123 -280.294549)
			(xy 371.971663 -280.323925) (xy 372.007003 -280.359265) (xy 372.036379 -280.399698) (xy 372.059069 -280.44423)
			(xy 372.074513 -280.491762) (xy 372.082332 -280.541125) (xy 372.082822 -280.566114) (xy 372.082332 -280.591103)
			(xy 372.38735 -280.591103) (xy 372.38735 -280.541125) (xy 372.395169 -280.491762) (xy 372.410613 -280.44423)
			(xy 372.433303 -280.399698) (xy 372.462679 -280.359265) (xy 372.498019 -280.323925) (xy 372.538452 -280.294549)
			(xy 372.582984 -280.271859) (xy 372.630516 -280.256415) (xy 372.679879 -280.248596) (xy 372.729857 -280.248596)
			(xy 372.77922 -280.256415) (xy 372.826752 -280.271859) (xy 372.871284 -280.294549) (xy 372.911717 -280.323925)
			(xy 372.947057 -280.359265) (xy 372.976433 -280.399698) (xy 372.999123 -280.44423) (xy 373.014567 -280.491762)
			(xy 373.022386 -280.541125) (xy 373.022876 -280.566114) (xy 373.022386 -280.591103) (xy 373.327404 -280.591103)
			(xy 373.327404 -280.541125) (xy 373.335223 -280.491762) (xy 373.350667 -280.44423) (xy 373.373357 -280.399698)
			(xy 373.402733 -280.359265) (xy 373.438073 -280.323925) (xy 373.478506 -280.294549) (xy 373.523038 -280.271859)
			(xy 373.57057 -280.256415) (xy 373.619933 -280.248596) (xy 373.669911 -280.248596) (xy 373.719274 -280.256415)
			(xy 373.766806 -280.271859) (xy 373.811338 -280.294549) (xy 373.851771 -280.323925) (xy 373.887111 -280.359265)
			(xy 373.916487 -280.399698) (xy 373.939177 -280.44423) (xy 373.954621 -280.491762) (xy 373.96244 -280.541125)
			(xy 373.96293 -280.566114) (xy 373.96244 -280.591103) (xy 373.954621 -280.640466) (xy 373.939177 -280.687998)
			(xy 373.916487 -280.73253) (xy 373.887111 -280.772963) (xy 373.851771 -280.808303) (xy 373.811338 -280.837679)
			(xy 373.766806 -280.860369) (xy 373.719274 -280.875813) (xy 373.669911 -280.883632) (xy 373.619933 -280.883632)
			(xy 373.57057 -280.875813) (xy 373.523038 -280.860369) (xy 373.478506 -280.837679) (xy 373.438073 -280.808303)
			(xy 373.402733 -280.772963) (xy 373.373357 -280.73253) (xy 373.350667 -280.687998) (xy 373.335223 -280.640466)
			(xy 373.327404 -280.591103) (xy 373.022386 -280.591103) (xy 373.014567 -280.640466) (xy 372.999123 -280.687998)
			(xy 372.976433 -280.73253) (xy 372.947057 -280.772963) (xy 372.911717 -280.808303) (xy 372.871284 -280.837679)
			(xy 372.826752 -280.860369) (xy 372.77922 -280.875813) (xy 372.729857 -280.883632) (xy 372.679879 -280.883632)
			(xy 372.630516 -280.875813) (xy 372.582984 -280.860369) (xy 372.538452 -280.837679) (xy 372.498019 -280.808303)
			(xy 372.462679 -280.772963) (xy 372.433303 -280.73253) (xy 372.410613 -280.687998) (xy 372.395169 -280.640466)
			(xy 372.38735 -280.591103) (xy 372.082332 -280.591103) (xy 372.074513 -280.640466) (xy 372.059069 -280.687998)
			(xy 372.036379 -280.73253) (xy 372.007003 -280.772963) (xy 371.971663 -280.808303) (xy 371.93123 -280.837679)
			(xy 371.886698 -280.860369) (xy 371.839166 -280.875813) (xy 371.789803 -280.883632) (xy 371.739825 -280.883632)
			(xy 371.690462 -280.875813) (xy 371.64293 -280.860369) (xy 371.598398 -280.837679) (xy 371.557965 -280.808303)
			(xy 371.522625 -280.772963) (xy 371.493249 -280.73253) (xy 371.470559 -280.687998) (xy 371.455115 -280.640466)
			(xy 371.447296 -280.591103) (xy 371.142278 -280.591103) (xy 371.134459 -280.640466) (xy 371.119015 -280.687998)
			(xy 371.096325 -280.73253) (xy 371.066949 -280.772963) (xy 371.031609 -280.808303) (xy 370.991176 -280.837679)
			(xy 370.946644 -280.860369) (xy 370.899112 -280.875813) (xy 370.849749 -280.883632) (xy 370.799771 -280.883632)
			(xy 370.750408 -280.875813) (xy 370.702876 -280.860369) (xy 370.658344 -280.837679) (xy 370.617911 -280.808303)
			(xy 370.582571 -280.772963) (xy 370.553195 -280.73253) (xy 370.530505 -280.687998) (xy 370.515061 -280.640466)
			(xy 370.507242 -280.591103) (xy 370.202224 -280.591103) (xy 370.194405 -280.640466) (xy 370.178961 -280.687998)
			(xy 370.156271 -280.73253) (xy 370.126895 -280.772963) (xy 370.091555 -280.808303) (xy 370.051122 -280.837679)
			(xy 370.00659 -280.860369) (xy 369.959058 -280.875813) (xy 369.909695 -280.883632) (xy 369.859717 -280.883632)
			(xy 369.810354 -280.875813) (xy 369.762822 -280.860369) (xy 369.71829 -280.837679) (xy 369.677857 -280.808303)
			(xy 369.642517 -280.772963) (xy 369.613141 -280.73253) (xy 369.590451 -280.687998) (xy 369.575007 -280.640466)
			(xy 369.567188 -280.591103) (xy 369.262424 -280.591103) (xy 369.254605 -280.640466) (xy 369.239161 -280.687998)
			(xy 369.216471 -280.73253) (xy 369.187095 -280.772963) (xy 369.151755 -280.808303) (xy 369.111322 -280.837679)
			(xy 369.06679 -280.860369) (xy 369.019258 -280.875813) (xy 368.969895 -280.883632) (xy 368.919917 -280.883632)
			(xy 368.870554 -280.875813) (xy 368.823022 -280.860369) (xy 368.77849 -280.837679) (xy 368.738057 -280.808303)
			(xy 368.702717 -280.772963) (xy 368.673341 -280.73253) (xy 368.650651 -280.687998) (xy 368.635207 -280.640466)
			(xy 368.627388 -280.591103) (xy 368.32237 -280.591103) (xy 368.314551 -280.640466) (xy 368.299107 -280.687998)
			(xy 368.276417 -280.73253) (xy 368.247041 -280.772963) (xy 368.211701 -280.808303) (xy 368.171268 -280.837679)
			(xy 368.126736 -280.860369) (xy 368.079204 -280.875813) (xy 368.029841 -280.883632) (xy 367.979863 -280.883632)
			(xy 367.9305 -280.875813) (xy 367.882968 -280.860369) (xy 367.838436 -280.837679) (xy 367.798003 -280.808303)
			(xy 367.762663 -280.772963) (xy 367.733287 -280.73253) (xy 367.710597 -280.687998) (xy 367.695153 -280.640466)
			(xy 367.687334 -280.591103) (xy 367.382316 -280.591103) (xy 367.374497 -280.640466) (xy 367.359053 -280.687998)
			(xy 367.336363 -280.73253) (xy 367.306987 -280.772963) (xy 367.271647 -280.808303) (xy 367.231214 -280.837679)
			(xy 367.186682 -280.860369) (xy 367.13915 -280.875813) (xy 367.089787 -280.883632) (xy 367.039809 -280.883632)
			(xy 366.990446 -280.875813) (xy 366.942914 -280.860369) (xy 366.898382 -280.837679) (xy 366.857949 -280.808303)
			(xy 366.822609 -280.772963) (xy 366.793233 -280.73253) (xy 366.770543 -280.687998) (xy 366.755099 -280.640466)
			(xy 366.74728 -280.591103) (xy 366.442262 -280.591103) (xy 366.434443 -280.640466) (xy 366.418999 -280.687998)
			(xy 366.396309 -280.73253) (xy 366.366933 -280.772963) (xy 366.331593 -280.808303) (xy 366.29116 -280.837679)
			(xy 366.246628 -280.860369) (xy 366.199096 -280.875813) (xy 366.149733 -280.883632) (xy 366.099755 -280.883632)
			(xy 366.050392 -280.875813) (xy 366.00286 -280.860369) (xy 365.958328 -280.837679) (xy 365.917895 -280.808303)
			(xy 365.882555 -280.772963) (xy 365.853179 -280.73253) (xy 365.830489 -280.687998) (xy 365.815045 -280.640466)
			(xy 365.807226 -280.591103) (xy 365.502208 -280.591103) (xy 365.494389 -280.640466) (xy 365.478945 -280.687998)
			(xy 365.456255 -280.73253) (xy 365.426879 -280.772963) (xy 365.391539 -280.808303) (xy 365.351106 -280.837679)
			(xy 365.306574 -280.860369) (xy 365.259042 -280.875813) (xy 365.209679 -280.883632) (xy 365.159701 -280.883632)
			(xy 365.110338 -280.875813) (xy 365.062806 -280.860369) (xy 365.018274 -280.837679) (xy 364.977841 -280.808303)
			(xy 364.942501 -280.772963) (xy 364.913125 -280.73253) (xy 364.890435 -280.687998) (xy 364.874991 -280.640466)
			(xy 364.867172 -280.591103) (xy 364.562408 -280.591103) (xy 364.554589 -280.640466) (xy 364.539145 -280.687998)
			(xy 364.516455 -280.73253) (xy 364.487079 -280.772963) (xy 364.451739 -280.808303) (xy 364.411306 -280.837679)
			(xy 364.366774 -280.860369) (xy 364.319242 -280.875813) (xy 364.269879 -280.883632) (xy 364.219901 -280.883632)
			(xy 364.170538 -280.875813) (xy 364.123006 -280.860369) (xy 364.078474 -280.837679) (xy 364.038041 -280.808303)
			(xy 364.002701 -280.772963) (xy 363.973325 -280.73253) (xy 363.950635 -280.687998) (xy 363.935191 -280.640466)
			(xy 363.927372 -280.591103) (xy 361.742246 -280.591103) (xy 361.734427 -280.640466) (xy 361.718983 -280.687998)
			(xy 361.696293 -280.73253) (xy 361.666917 -280.772963) (xy 361.631577 -280.808303) (xy 361.591144 -280.837679)
			(xy 361.546612 -280.860369) (xy 361.49908 -280.875813) (xy 361.449717 -280.883632) (xy 361.399739 -280.883632)
			(xy 361.350376 -280.875813) (xy 361.302844 -280.860369) (xy 361.258312 -280.837679) (xy 361.217879 -280.808303)
			(xy 361.182539 -280.772963) (xy 361.153163 -280.73253) (xy 361.130473 -280.687998) (xy 361.115029 -280.640466)
			(xy 361.10721 -280.591103) (xy 358.928688 -280.591103) (xy 358.920869 -280.640466) (xy 358.905425 -280.687998)
			(xy 358.882735 -280.73253) (xy 358.853359 -280.772963) (xy 358.818019 -280.808303) (xy 358.777586 -280.837679)
			(xy 358.733054 -280.860369) (xy 358.685522 -280.875813) (xy 358.636159 -280.883632) (xy 358.586181 -280.883632)
			(xy 358.536818 -280.875813) (xy 358.489286 -280.860369) (xy 358.444754 -280.837679) (xy 358.404321 -280.808303)
			(xy 358.368981 -280.772963) (xy 358.339605 -280.73253) (xy 358.316915 -280.687998) (xy 358.301471 -280.640466)
			(xy 358.293652 -280.591103) (xy 356.108526 -280.591103) (xy 356.100707 -280.640466) (xy 356.085263 -280.687998)
			(xy 356.062573 -280.73253) (xy 356.033197 -280.772963) (xy 355.997857 -280.808303) (xy 355.957424 -280.837679)
			(xy 355.912892 -280.860369) (xy 355.86536 -280.875813) (xy 355.815997 -280.883632) (xy 355.766019 -280.883632)
			(xy 355.716656 -280.875813) (xy 355.669124 -280.860369) (xy 355.624592 -280.837679) (xy 355.584159 -280.808303)
			(xy 355.548819 -280.772963) (xy 355.519443 -280.73253) (xy 355.496753 -280.687998) (xy 355.481309 -280.640466)
			(xy 355.47349 -280.591103) (xy 355.168726 -280.591103) (xy 355.160907 -280.640466) (xy 355.145463 -280.687998)
			(xy 355.122773 -280.73253) (xy 355.093397 -280.772963) (xy 355.058057 -280.808303) (xy 355.017624 -280.837679)
			(xy 354.973092 -280.860369) (xy 354.92556 -280.875813) (xy 354.876197 -280.883632) (xy 354.826219 -280.883632)
			(xy 354.776856 -280.875813) (xy 354.729324 -280.860369) (xy 354.684792 -280.837679) (xy 354.644359 -280.808303)
			(xy 354.609019 -280.772963) (xy 354.579643 -280.73253) (xy 354.556953 -280.687998) (xy 354.541509 -280.640466)
			(xy 354.53369 -280.591103) (xy 354.228672 -280.591103) (xy 354.220853 -280.640466) (xy 354.205409 -280.687998)
			(xy 354.182719 -280.73253) (xy 354.153343 -280.772963) (xy 354.118003 -280.808303) (xy 354.07757 -280.837679)
			(xy 354.033038 -280.860369) (xy 353.985506 -280.875813) (xy 353.936143 -280.883632) (xy 353.886165 -280.883632)
			(xy 353.836802 -280.875813) (xy 353.78927 -280.860369) (xy 353.744738 -280.837679) (xy 353.704305 -280.808303)
			(xy 353.668965 -280.772963) (xy 353.639589 -280.73253) (xy 353.616899 -280.687998) (xy 353.601455 -280.640466)
			(xy 353.593636 -280.591103) (xy 353.288618 -280.591103) (xy 353.280799 -280.640466) (xy 353.265355 -280.687998)
			(xy 353.242665 -280.73253) (xy 353.213289 -280.772963) (xy 353.177949 -280.808303) (xy 353.137516 -280.837679)
			(xy 353.092984 -280.860369) (xy 353.045452 -280.875813) (xy 352.996089 -280.883632) (xy 352.946111 -280.883632)
			(xy 352.896748 -280.875813) (xy 352.849216 -280.860369) (xy 352.804684 -280.837679) (xy 352.764251 -280.808303)
			(xy 352.728911 -280.772963) (xy 352.699535 -280.73253) (xy 352.676845 -280.687998) (xy 352.661401 -280.640466)
			(xy 352.653582 -280.591103) (xy 352.348564 -280.591103) (xy 352.340745 -280.640466) (xy 352.325301 -280.687998)
			(xy 352.302611 -280.73253) (xy 352.273235 -280.772963) (xy 352.237895 -280.808303) (xy 352.197462 -280.837679)
			(xy 352.15293 -280.860369) (xy 352.105398 -280.875813) (xy 352.056035 -280.883632) (xy 352.006057 -280.883632)
			(xy 351.956694 -280.875813) (xy 351.909162 -280.860369) (xy 351.86463 -280.837679) (xy 351.824197 -280.808303)
			(xy 351.788857 -280.772963) (xy 351.759481 -280.73253) (xy 351.736791 -280.687998) (xy 351.721347 -280.640466)
			(xy 351.713528 -280.591103) (xy 351.408764 -280.591103) (xy 351.400945 -280.640466) (xy 351.385501 -280.687998)
			(xy 351.362811 -280.73253) (xy 351.333435 -280.772963) (xy 351.298095 -280.808303) (xy 351.257662 -280.837679)
			(xy 351.21313 -280.860369) (xy 351.165598 -280.875813) (xy 351.116235 -280.883632) (xy 351.066257 -280.883632)
			(xy 351.016894 -280.875813) (xy 350.969362 -280.860369) (xy 350.92483 -280.837679) (xy 350.884397 -280.808303)
			(xy 350.849057 -280.772963) (xy 350.819681 -280.73253) (xy 350.796991 -280.687998) (xy 350.781547 -280.640466)
			(xy 350.773728 -280.591103) (xy 350.46871 -280.591103) (xy 350.460891 -280.640466) (xy 350.445447 -280.687998)
			(xy 350.422757 -280.73253) (xy 350.393381 -280.772963) (xy 350.358041 -280.808303) (xy 350.317608 -280.837679)
			(xy 350.273076 -280.860369) (xy 350.225544 -280.875813) (xy 350.176181 -280.883632) (xy 350.126203 -280.883632)
			(xy 350.07684 -280.875813) (xy 350.029308 -280.860369) (xy 349.984776 -280.837679) (xy 349.944343 -280.808303)
			(xy 349.909003 -280.772963) (xy 349.879627 -280.73253) (xy 349.856937 -280.687998) (xy 349.841493 -280.640466)
			(xy 349.833674 -280.591103) (xy 349.528656 -280.591103) (xy 349.520837 -280.640466) (xy 349.505393 -280.687998)
			(xy 349.482703 -280.73253) (xy 349.453327 -280.772963) (xy 349.417987 -280.808303) (xy 349.377554 -280.837679)
			(xy 349.333022 -280.860369) (xy 349.28549 -280.875813) (xy 349.236127 -280.883632) (xy 349.186149 -280.883632)
			(xy 349.136786 -280.875813) (xy 349.089254 -280.860369) (xy 349.044722 -280.837679) (xy 349.004289 -280.808303)
			(xy 348.968949 -280.772963) (xy 348.939573 -280.73253) (xy 348.916883 -280.687998) (xy 348.901439 -280.640466)
			(xy 348.89362 -280.591103) (xy 348.588602 -280.591103) (xy 348.580783 -280.640466) (xy 348.565339 -280.687998)
			(xy 348.542649 -280.73253) (xy 348.513273 -280.772963) (xy 348.477933 -280.808303) (xy 348.4375 -280.837679)
			(xy 348.392968 -280.860369) (xy 348.345436 -280.875813) (xy 348.296073 -280.883632) (xy 348.246095 -280.883632)
			(xy 348.196732 -280.875813) (xy 348.1492 -280.860369) (xy 348.104668 -280.837679) (xy 348.064235 -280.808303)
			(xy 348.028895 -280.772963) (xy 347.999519 -280.73253) (xy 347.976829 -280.687998) (xy 347.961385 -280.640466)
			(xy 347.953566 -280.591103) (xy 347.648548 -280.591103) (xy 347.640729 -280.640466) (xy 347.625285 -280.687998)
			(xy 347.602595 -280.73253) (xy 347.573219 -280.772963) (xy 347.537879 -280.808303) (xy 347.497446 -280.837679)
			(xy 347.452914 -280.860369) (xy 347.405382 -280.875813) (xy 347.356019 -280.883632) (xy 347.306041 -280.883632)
			(xy 347.256678 -280.875813) (xy 347.209146 -280.860369) (xy 347.164614 -280.837679) (xy 347.124181 -280.808303)
			(xy 347.088841 -280.772963) (xy 347.059465 -280.73253) (xy 347.036775 -280.687998) (xy 347.021331 -280.640466)
			(xy 347.013512 -280.591103) (xy 346.708748 -280.591103) (xy 346.700929 -280.640466) (xy 346.685485 -280.687998)
			(xy 346.662795 -280.73253) (xy 346.633419 -280.772963) (xy 346.598079 -280.808303) (xy 346.557646 -280.837679)
			(xy 346.513114 -280.860369) (xy 346.465582 -280.875813) (xy 346.416219 -280.883632) (xy 346.366241 -280.883632)
			(xy 346.316878 -280.875813) (xy 346.269346 -280.860369) (xy 346.224814 -280.837679) (xy 346.184381 -280.808303)
			(xy 346.149041 -280.772963) (xy 346.119665 -280.73253) (xy 346.096975 -280.687998) (xy 346.081531 -280.640466)
			(xy 346.073712 -280.591103) (xy 345.768728 -280.591103) (xy 345.76091 -280.640459) (xy 345.745464 -280.687995)
			(xy 345.722771 -280.732529) (xy 345.693391 -280.772965) (xy 345.658047 -280.808307) (xy 345.617608 -280.837684)
			(xy 345.573072 -280.860373) (xy 345.525535 -280.875816) (xy 345.476167 -280.883631) (xy 345.451176 -280.884122)
			(xy 345.427298 -280.883693) (xy 345.380079 -280.876558) (xy 345.334454 -280.862452) (xy 345.291448 -280.84169)
			(xy 345.252025 -280.814739) (xy 345.23426 -280.798778) (xy 345.228659 -280.793908) (xy 345.215368 -280.787315)
			(xy 345.208098 -280.785824) (xy 345.20124 -280.784554) (xy 345.186508 -280.786332) (xy 345.14155 -280.80589)
			(xy 345.096338 -280.825702) (xy 345.087508 -280.830062) (xy 345.073765 -280.844141) (xy 345.066307 -280.862348)
			(xy 345.065858 -280.872184) (xy 345.065858 -281.033474) (xy 345.065858 -281.034744) (xy 345.066519 -281.044132)
			(xy 345.073735 -281.061494) (xy 345.086732 -281.075081) (xy 345.095068 -281.079448) (xy 345.097862 -281.080464)
			(xy 345.12057 -281.089916) (xy 345.162997 -281.114795) (xy 345.201086 -281.145912) (xy 345.233929 -281.182523)
			(xy 345.260742 -281.223756) (xy 345.280884 -281.268626) (xy 345.293876 -281.316063) (xy 345.299407 -281.364935)
			(xy 345.298938 -281.37612) (xy 345.604841 -281.37612) (xy 345.608936 -281.325392) (xy 345.621115 -281.275978)
			(xy 345.641063 -281.229158) (xy 345.668264 -281.186144) (xy 345.702012 -281.14805) (xy 345.741434 -281.115863)
			(xy 345.785508 -281.090417) (xy 345.833094 -281.07237) (xy 345.882958 -281.06219) (xy 345.93381 -281.060141)
			(xy 345.984331 -281.066275) (xy 346.033215 -281.080435) (xy 346.079194 -281.102252) (xy 346.121078 -281.131162)
			(xy 346.157782 -281.166417) (xy 346.188355 -281.207103) (xy 346.212006 -281.252166) (xy 346.228122 -281.30044)
			(xy 346.236286 -281.350674) (xy 346.236798 -281.37612) (xy 346.544895 -281.37612) (xy 346.54899 -281.325392)
			(xy 346.561169 -281.275978) (xy 346.581117 -281.229158) (xy 346.608318 -281.186144) (xy 346.642066 -281.14805)
			(xy 346.681488 -281.115863) (xy 346.725562 -281.090417) (xy 346.773148 -281.07237) (xy 346.823012 -281.06219)
			(xy 346.873864 -281.060141) (xy 346.924385 -281.066275) (xy 346.973269 -281.080435) (xy 347.019248 -281.102252)
			(xy 347.061132 -281.131162) (xy 347.097836 -281.166417) (xy 347.128409 -281.207103) (xy 347.15206 -281.252166)
			(xy 347.168176 -281.30044) (xy 347.17634 -281.350674) (xy 347.176852 -281.37612) (xy 347.176349 -281.401109)
			(xy 347.483666 -281.401109) (xy 347.483666 -281.351131) (xy 347.491485 -281.301768) (xy 347.506929 -281.254236)
			(xy 347.529619 -281.209704) (xy 347.558995 -281.169271) (xy 347.594335 -281.133931) (xy 347.634768 -281.104555)
			(xy 347.6793 -281.081865) (xy 347.726832 -281.066421) (xy 347.776195 -281.058602) (xy 347.826173 -281.058602)
			(xy 347.875536 -281.066421) (xy 347.923068 -281.081865) (xy 347.9676 -281.104555) (xy 348.008033 -281.133931)
			(xy 348.043373 -281.169271) (xy 348.072749 -281.209704) (xy 348.095439 -281.254236) (xy 348.110883 -281.301768)
			(xy 348.118702 -281.351131) (xy 348.119192 -281.37612) (xy 348.425003 -281.37612) (xy 348.429098 -281.325392)
			(xy 348.441277 -281.275978) (xy 348.461225 -281.229158) (xy 348.488426 -281.186144) (xy 348.522174 -281.14805)
			(xy 348.561596 -281.115863) (xy 348.60567 -281.090417) (xy 348.653256 -281.07237) (xy 348.70312 -281.06219)
			(xy 348.753972 -281.060141) (xy 348.804493 -281.066275) (xy 348.853377 -281.080435) (xy 348.899356 -281.102252)
			(xy 348.94124 -281.131162) (xy 348.977944 -281.166417) (xy 349.008517 -281.207103) (xy 349.032168 -281.252166)
			(xy 349.048284 -281.30044) (xy 349.056448 -281.350674) (xy 349.05696 -281.37612) (xy 349.364803 -281.37612)
			(xy 349.368898 -281.325392) (xy 349.381077 -281.275978) (xy 349.401025 -281.229158) (xy 349.428226 -281.186144)
			(xy 349.461974 -281.14805) (xy 349.501396 -281.115863) (xy 349.54547 -281.090417) (xy 349.593056 -281.07237)
			(xy 349.64292 -281.06219) (xy 349.693772 -281.060141) (xy 349.744293 -281.066275) (xy 349.793177 -281.080435)
			(xy 349.839156 -281.102252) (xy 349.88104 -281.131162) (xy 349.917744 -281.166417) (xy 349.948317 -281.207103)
			(xy 349.971968 -281.252166) (xy 349.988084 -281.30044) (xy 349.996248 -281.350674) (xy 349.99676 -281.37612)
			(xy 349.996257 -281.401109) (xy 350.303574 -281.401109) (xy 350.303574 -281.351131) (xy 350.311393 -281.301768)
			(xy 350.326837 -281.254236) (xy 350.349527 -281.209704) (xy 350.378903 -281.169271) (xy 350.414243 -281.133931)
			(xy 350.454676 -281.104555) (xy 350.499208 -281.081865) (xy 350.54674 -281.066421) (xy 350.596103 -281.058602)
			(xy 350.646081 -281.058602) (xy 350.695444 -281.066421) (xy 350.742976 -281.081865) (xy 350.787508 -281.104555)
			(xy 350.827941 -281.133931) (xy 350.863281 -281.169271) (xy 350.892657 -281.209704) (xy 350.915347 -281.254236)
			(xy 350.930791 -281.301768) (xy 350.93861 -281.351131) (xy 350.9391 -281.37612) (xy 350.93861 -281.401109)
			(xy 353.123482 -281.401109) (xy 353.123482 -281.351131) (xy 353.131301 -281.301768) (xy 353.146745 -281.254236)
			(xy 353.169435 -281.209704) (xy 353.198811 -281.169271) (xy 353.234151 -281.133931) (xy 353.274584 -281.104555)
			(xy 353.319116 -281.081865) (xy 353.366648 -281.066421) (xy 353.416011 -281.058602) (xy 353.465989 -281.058602)
			(xy 353.515352 -281.066421) (xy 353.562884 -281.081865) (xy 353.607416 -281.104555) (xy 353.647849 -281.133931)
			(xy 353.683189 -281.169271) (xy 353.712565 -281.209704) (xy 353.735255 -281.254236) (xy 353.750699 -281.301768)
			(xy 353.758518 -281.351131) (xy 353.759008 -281.37612) (xy 353.758518 -281.401109) (xy 355.943644 -281.401109)
			(xy 355.943644 -281.351131) (xy 355.951463 -281.301768) (xy 355.966907 -281.254236) (xy 355.989597 -281.209704)
			(xy 356.018973 -281.169271) (xy 356.054313 -281.133931) (xy 356.094746 -281.104555) (xy 356.139278 -281.081865)
			(xy 356.18681 -281.066421) (xy 356.236173 -281.058602) (xy 356.286151 -281.058602) (xy 356.335514 -281.066421)
			(xy 356.383046 -281.081865) (xy 356.427578 -281.104555) (xy 356.468011 -281.133931) (xy 356.503351 -281.169271)
			(xy 356.532727 -281.209704) (xy 356.555417 -281.254236) (xy 356.570861 -281.301768) (xy 356.57868 -281.351131)
			(xy 356.57917 -281.37612) (xy 356.57868 -281.401109) (xy 356.883698 -281.401109) (xy 356.883698 -281.351131)
			(xy 356.891517 -281.301768) (xy 356.906961 -281.254236) (xy 356.929651 -281.209704) (xy 356.959027 -281.169271)
			(xy 356.994367 -281.133931) (xy 357.0348 -281.104555) (xy 357.079332 -281.081865) (xy 357.126864 -281.066421)
			(xy 357.176227 -281.058602) (xy 357.226205 -281.058602) (xy 357.275568 -281.066421) (xy 357.3231 -281.081865)
			(xy 357.367632 -281.104555) (xy 357.408065 -281.133931) (xy 357.443405 -281.169271) (xy 357.472781 -281.209704)
			(xy 357.495471 -281.254236) (xy 357.510915 -281.301768) (xy 357.518734 -281.351131) (xy 357.519224 -281.37612)
			(xy 357.518734 -281.401109) (xy 357.823498 -281.401109) (xy 357.823498 -281.351131) (xy 357.831317 -281.301768)
			(xy 357.846761 -281.254236) (xy 357.869451 -281.209704) (xy 357.898827 -281.169271) (xy 357.934167 -281.133931)
			(xy 357.9746 -281.104555) (xy 358.019132 -281.081865) (xy 358.066664 -281.066421) (xy 358.116027 -281.058602)
			(xy 358.166005 -281.058602) (xy 358.215368 -281.066421) (xy 358.2629 -281.081865) (xy 358.307432 -281.104555)
			(xy 358.347865 -281.133931) (xy 358.383205 -281.169271) (xy 358.412581 -281.209704) (xy 358.435271 -281.254236)
			(xy 358.450715 -281.301768) (xy 358.458534 -281.351131) (xy 358.459024 -281.37612) (xy 358.458534 -281.401109)
			(xy 361.577364 -281.401109) (xy 361.577364 -281.351131) (xy 361.585183 -281.301768) (xy 361.600627 -281.254236)
			(xy 361.623317 -281.209704) (xy 361.652693 -281.169271) (xy 361.688033 -281.133931) (xy 361.728466 -281.104555)
			(xy 361.772998 -281.081865) (xy 361.82053 -281.066421) (xy 361.869893 -281.058602) (xy 361.919871 -281.058602)
			(xy 361.969234 -281.066421) (xy 362.016766 -281.081865) (xy 362.061298 -281.104555) (xy 362.101731 -281.133931)
			(xy 362.137071 -281.169271) (xy 362.166447 -281.209704) (xy 362.189137 -281.254236) (xy 362.204581 -281.301768)
			(xy 362.2124 -281.351131) (xy 362.21289 -281.37612) (xy 362.2124 -281.401109) (xy 362.517164 -281.401109)
			(xy 362.517164 -281.351131) (xy 362.524983 -281.301768) (xy 362.540427 -281.254236) (xy 362.563117 -281.209704)
			(xy 362.592493 -281.169271) (xy 362.627833 -281.133931) (xy 362.668266 -281.104555) (xy 362.712798 -281.081865)
			(xy 362.76033 -281.066421) (xy 362.809693 -281.058602) (xy 362.859671 -281.058602) (xy 362.909034 -281.066421)
			(xy 362.956566 -281.081865) (xy 363.001098 -281.104555) (xy 363.041531 -281.133931) (xy 363.076871 -281.169271)
			(xy 363.106247 -281.209704) (xy 363.128937 -281.254236) (xy 363.144381 -281.301768) (xy 363.1522 -281.351131)
			(xy 363.15269 -281.37612) (xy 363.1522 -281.401109) (xy 363.457218 -281.401109) (xy 363.457218 -281.351131)
			(xy 363.465037 -281.301768) (xy 363.480481 -281.254236) (xy 363.503171 -281.209704) (xy 363.532547 -281.169271)
			(xy 363.567887 -281.133931) (xy 363.60832 -281.104555) (xy 363.652852 -281.081865) (xy 363.700384 -281.066421)
			(xy 363.749747 -281.058602) (xy 363.799725 -281.058602) (xy 363.849088 -281.066421) (xy 363.89662 -281.081865)
			(xy 363.941152 -281.104555) (xy 363.981585 -281.133931) (xy 364.016925 -281.169271) (xy 364.046301 -281.209704)
			(xy 364.068991 -281.254236) (xy 364.084435 -281.301768) (xy 364.092254 -281.351131) (xy 364.092744 -281.37612)
			(xy 364.092254 -281.401109) (xy 366.27738 -281.401109) (xy 366.27738 -281.351131) (xy 366.285199 -281.301768)
			(xy 366.300643 -281.254236) (xy 366.323333 -281.209704) (xy 366.352709 -281.169271) (xy 366.388049 -281.133931)
			(xy 366.428482 -281.104555) (xy 366.473014 -281.081865) (xy 366.520546 -281.066421) (xy 366.569909 -281.058602)
			(xy 366.619887 -281.058602) (xy 366.66925 -281.066421) (xy 366.716782 -281.081865) (xy 366.761314 -281.104555)
			(xy 366.801747 -281.133931) (xy 366.837087 -281.169271) (xy 366.866463 -281.209704) (xy 366.889153 -281.254236)
			(xy 366.904597 -281.301768) (xy 366.912416 -281.351131) (xy 366.912906 -281.37612) (xy 366.912416 -281.401109)
			(xy 369.097288 -281.401109) (xy 369.097288 -281.351131) (xy 369.105107 -281.301768) (xy 369.120551 -281.254236)
			(xy 369.143241 -281.209704) (xy 369.172617 -281.169271) (xy 369.207957 -281.133931) (xy 369.24839 -281.104555)
			(xy 369.292922 -281.081865) (xy 369.340454 -281.066421) (xy 369.389817 -281.058602) (xy 369.439795 -281.058602)
			(xy 369.489158 -281.066421) (xy 369.53669 -281.081865) (xy 369.581222 -281.104555) (xy 369.621655 -281.133931)
			(xy 369.656995 -281.169271) (xy 369.686371 -281.209704) (xy 369.709061 -281.254236) (xy 369.724505 -281.301768)
			(xy 369.732324 -281.351131) (xy 369.732814 -281.37612) (xy 370.038625 -281.37612) (xy 370.04272 -281.325392)
			(xy 370.054899 -281.275978) (xy 370.074847 -281.229158) (xy 370.102048 -281.186144) (xy 370.135796 -281.14805)
			(xy 370.175218 -281.115863) (xy 370.219292 -281.090417) (xy 370.266878 -281.07237) (xy 370.316742 -281.06219)
			(xy 370.367594 -281.060141) (xy 370.418115 -281.066275) (xy 370.466999 -281.080435) (xy 370.512978 -281.102252)
			(xy 370.554862 -281.131162) (xy 370.591566 -281.166417) (xy 370.622139 -281.207103) (xy 370.64579 -281.252166)
			(xy 370.661906 -281.30044) (xy 370.67007 -281.350674) (xy 370.670582 -281.37612) (xy 370.978679 -281.37612)
			(xy 370.982774 -281.325392) (xy 370.994953 -281.275978) (xy 371.014901 -281.229158) (xy 371.042102 -281.186144)
			(xy 371.07585 -281.14805) (xy 371.115272 -281.115863) (xy 371.159346 -281.090417) (xy 371.206932 -281.07237)
			(xy 371.256796 -281.06219) (xy 371.307648 -281.060141) (xy 371.358169 -281.066275) (xy 371.407053 -281.080435)
			(xy 371.453032 -281.102252) (xy 371.494916 -281.131162) (xy 371.53162 -281.166417) (xy 371.562193 -281.207103)
			(xy 371.585844 -281.252166) (xy 371.60196 -281.30044) (xy 371.610124 -281.350674) (xy 371.610636 -281.37612)
			(xy 371.610133 -281.401109) (xy 371.917196 -281.401109) (xy 371.917196 -281.351131) (xy 371.925015 -281.301768)
			(xy 371.940459 -281.254236) (xy 371.963149 -281.209704) (xy 371.992525 -281.169271) (xy 372.027865 -281.133931)
			(xy 372.068298 -281.104555) (xy 372.11283 -281.081865) (xy 372.160362 -281.066421) (xy 372.209725 -281.058602)
			(xy 372.259703 -281.058602) (xy 372.309066 -281.066421) (xy 372.356598 -281.081865) (xy 372.40113 -281.104555)
			(xy 372.441563 -281.133931) (xy 372.476903 -281.169271) (xy 372.506279 -281.209704) (xy 372.528969 -281.254236)
			(xy 372.544413 -281.301768) (xy 372.552232 -281.351131) (xy 372.552722 -281.37612) (xy 372.858533 -281.37612)
			(xy 372.862628 -281.325392) (xy 372.874807 -281.275978) (xy 372.894755 -281.229158) (xy 372.921956 -281.186144)
			(xy 372.955704 -281.14805) (xy 372.995126 -281.115863) (xy 373.0392 -281.090417) (xy 373.086786 -281.07237)
			(xy 373.13665 -281.06219) (xy 373.187502 -281.060141) (xy 373.238023 -281.066275) (xy 373.286907 -281.080435)
			(xy 373.332886 -281.102252) (xy 373.37477 -281.131162) (xy 373.411474 -281.166417) (xy 373.442047 -281.207103)
			(xy 373.465698 -281.252166) (xy 373.481814 -281.30044) (xy 373.489978 -281.350674) (xy 373.49049 -281.37612)
			(xy 373.489978 -281.401566) (xy 373.481814 -281.4518) (xy 373.465698 -281.500074) (xy 373.442047 -281.545137)
			(xy 373.411474 -281.585823) (xy 373.37477 -281.621078) (xy 373.332886 -281.649988) (xy 373.286907 -281.671805)
			(xy 373.238023 -281.685965) (xy 373.187502 -281.692099) (xy 373.13665 -281.69005) (xy 373.086786 -281.67987)
			(xy 373.0392 -281.661823) (xy 372.995126 -281.636377) (xy 372.955704 -281.60419) (xy 372.921956 -281.566096)
			(xy 372.894755 -281.523082) (xy 372.874807 -281.476262) (xy 372.862628 -281.426848) (xy 372.858533 -281.37612)
			(xy 372.552722 -281.37612) (xy 372.552232 -281.401109) (xy 372.544413 -281.450472) (xy 372.528969 -281.498004)
			(xy 372.506279 -281.542536) (xy 372.476903 -281.582969) (xy 372.441563 -281.618309) (xy 372.40113 -281.647685)
			(xy 372.356598 -281.670375) (xy 372.309066 -281.685819) (xy 372.259703 -281.693638) (xy 372.209725 -281.693638)
			(xy 372.160362 -281.685819) (xy 372.11283 -281.670375) (xy 372.068298 -281.647685) (xy 372.027865 -281.618309)
			(xy 371.992525 -281.582969) (xy 371.963149 -281.542536) (xy 371.940459 -281.498004) (xy 371.925015 -281.450472)
			(xy 371.917196 -281.401109) (xy 371.610133 -281.401109) (xy 371.610124 -281.401566) (xy 371.60196 -281.4518)
			(xy 371.585844 -281.500074) (xy 371.562193 -281.545137) (xy 371.53162 -281.585823) (xy 371.494916 -281.621078)
			(xy 371.453032 -281.649988) (xy 371.407053 -281.671805) (xy 371.358169 -281.685965) (xy 371.307648 -281.692099)
			(xy 371.256796 -281.69005) (xy 371.206932 -281.67987) (xy 371.159346 -281.661823) (xy 371.115272 -281.636377)
			(xy 371.07585 -281.60419) (xy 371.042102 -281.566096) (xy 371.014901 -281.523082) (xy 370.994953 -281.476262)
			(xy 370.982774 -281.426848) (xy 370.978679 -281.37612) (xy 370.670582 -281.37612) (xy 370.67007 -281.401566)
			(xy 370.661906 -281.4518) (xy 370.64579 -281.500074) (xy 370.622139 -281.545137) (xy 370.591566 -281.585823)
			(xy 370.554862 -281.621078) (xy 370.512978 -281.649988) (xy 370.466999 -281.671805) (xy 370.418115 -281.685965)
			(xy 370.367594 -281.692099) (xy 370.316742 -281.69005) (xy 370.266878 -281.67987) (xy 370.219292 -281.661823)
			(xy 370.175218 -281.636377) (xy 370.135796 -281.60419) (xy 370.102048 -281.566096) (xy 370.074847 -281.523082)
			(xy 370.054899 -281.476262) (xy 370.04272 -281.426848) (xy 370.038625 -281.37612) (xy 369.732814 -281.37612)
			(xy 369.732324 -281.401109) (xy 369.724505 -281.450472) (xy 369.709061 -281.498004) (xy 369.686371 -281.542536)
			(xy 369.656995 -281.582969) (xy 369.621655 -281.618309) (xy 369.581222 -281.647685) (xy 369.53669 -281.670375)
			(xy 369.489158 -281.685819) (xy 369.439795 -281.693638) (xy 369.389817 -281.693638) (xy 369.340454 -281.685819)
			(xy 369.292922 -281.670375) (xy 369.24839 -281.647685) (xy 369.207957 -281.618309) (xy 369.172617 -281.582969)
			(xy 369.143241 -281.542536) (xy 369.120551 -281.498004) (xy 369.105107 -281.450472) (xy 369.097288 -281.401109)
			(xy 366.912416 -281.401109) (xy 366.904597 -281.450472) (xy 366.889153 -281.498004) (xy 366.866463 -281.542536)
			(xy 366.837087 -281.582969) (xy 366.801747 -281.618309) (xy 366.761314 -281.647685) (xy 366.716782 -281.670375)
			(xy 366.66925 -281.685819) (xy 366.619887 -281.693638) (xy 366.569909 -281.693638) (xy 366.520546 -281.685819)
			(xy 366.473014 -281.670375) (xy 366.428482 -281.647685) (xy 366.388049 -281.618309) (xy 366.352709 -281.582969)
			(xy 366.323333 -281.542536) (xy 366.300643 -281.498004) (xy 366.285199 -281.450472) (xy 366.27738 -281.401109)
			(xy 364.092254 -281.401109) (xy 364.084435 -281.450472) (xy 364.068991 -281.498004) (xy 364.046301 -281.542536)
			(xy 364.016925 -281.582969) (xy 363.981585 -281.618309) (xy 363.941152 -281.647685) (xy 363.89662 -281.670375)
			(xy 363.849088 -281.685819) (xy 363.799725 -281.693638) (xy 363.749747 -281.693638) (xy 363.700384 -281.685819)
			(xy 363.652852 -281.670375) (xy 363.60832 -281.647685) (xy 363.567887 -281.618309) (xy 363.532547 -281.582969)
			(xy 363.503171 -281.542536) (xy 363.480481 -281.498004) (xy 363.465037 -281.450472) (xy 363.457218 -281.401109)
			(xy 363.1522 -281.401109) (xy 363.144381 -281.450472) (xy 363.128937 -281.498004) (xy 363.106247 -281.542536)
			(xy 363.076871 -281.582969) (xy 363.041531 -281.618309) (xy 363.001098 -281.647685) (xy 362.956566 -281.670375)
			(xy 362.909034 -281.685819) (xy 362.859671 -281.693638) (xy 362.809693 -281.693638) (xy 362.76033 -281.685819)
			(xy 362.712798 -281.670375) (xy 362.668266 -281.647685) (xy 362.627833 -281.618309) (xy 362.592493 -281.582969)
			(xy 362.563117 -281.542536) (xy 362.540427 -281.498004) (xy 362.524983 -281.450472) (xy 362.517164 -281.401109)
			(xy 362.2124 -281.401109) (xy 362.204581 -281.450472) (xy 362.189137 -281.498004) (xy 362.166447 -281.542536)
			(xy 362.137071 -281.582969) (xy 362.101731 -281.618309) (xy 362.061298 -281.647685) (xy 362.016766 -281.670375)
			(xy 361.969234 -281.685819) (xy 361.919871 -281.693638) (xy 361.869893 -281.693638) (xy 361.82053 -281.685819)
			(xy 361.772998 -281.670375) (xy 361.728466 -281.647685) (xy 361.688033 -281.618309) (xy 361.652693 -281.582969)
			(xy 361.623317 -281.542536) (xy 361.600627 -281.498004) (xy 361.585183 -281.450472) (xy 361.577364 -281.401109)
			(xy 358.458534 -281.401109) (xy 358.450715 -281.450472) (xy 358.435271 -281.498004) (xy 358.412581 -281.542536)
			(xy 358.383205 -281.582969) (xy 358.347865 -281.618309) (xy 358.307432 -281.647685) (xy 358.2629 -281.670375)
			(xy 358.215368 -281.685819) (xy 358.166005 -281.693638) (xy 358.116027 -281.693638) (xy 358.066664 -281.685819)
			(xy 358.019132 -281.670375) (xy 357.9746 -281.647685) (xy 357.934167 -281.618309) (xy 357.898827 -281.582969)
			(xy 357.869451 -281.542536) (xy 357.846761 -281.498004) (xy 357.831317 -281.450472) (xy 357.823498 -281.401109)
			(xy 357.518734 -281.401109) (xy 357.510915 -281.450472) (xy 357.495471 -281.498004) (xy 357.472781 -281.542536)
			(xy 357.443405 -281.582969) (xy 357.408065 -281.618309) (xy 357.367632 -281.647685) (xy 357.3231 -281.670375)
			(xy 357.275568 -281.685819) (xy 357.226205 -281.693638) (xy 357.176227 -281.693638) (xy 357.126864 -281.685819)
			(xy 357.079332 -281.670375) (xy 357.0348 -281.647685) (xy 356.994367 -281.618309) (xy 356.959027 -281.582969)
			(xy 356.929651 -281.542536) (xy 356.906961 -281.498004) (xy 356.891517 -281.450472) (xy 356.883698 -281.401109)
			(xy 356.57868 -281.401109) (xy 356.570861 -281.450472) (xy 356.555417 -281.498004) (xy 356.532727 -281.542536)
			(xy 356.503351 -281.582969) (xy 356.468011 -281.618309) (xy 356.427578 -281.647685) (xy 356.383046 -281.670375)
			(xy 356.335514 -281.685819) (xy 356.286151 -281.693638) (xy 356.236173 -281.693638) (xy 356.18681 -281.685819)
			(xy 356.139278 -281.670375) (xy 356.094746 -281.647685) (xy 356.054313 -281.618309) (xy 356.018973 -281.582969)
			(xy 355.989597 -281.542536) (xy 355.966907 -281.498004) (xy 355.951463 -281.450472) (xy 355.943644 -281.401109)
			(xy 353.758518 -281.401109) (xy 353.750699 -281.450472) (xy 353.735255 -281.498004) (xy 353.712565 -281.542536)
			(xy 353.683189 -281.582969) (xy 353.647849 -281.618309) (xy 353.607416 -281.647685) (xy 353.562884 -281.670375)
			(xy 353.515352 -281.685819) (xy 353.465989 -281.693638) (xy 353.416011 -281.693638) (xy 353.366648 -281.685819)
			(xy 353.319116 -281.670375) (xy 353.274584 -281.647685) (xy 353.234151 -281.618309) (xy 353.198811 -281.582969)
			(xy 353.169435 -281.542536) (xy 353.146745 -281.498004) (xy 353.131301 -281.450472) (xy 353.123482 -281.401109)
			(xy 350.93861 -281.401109) (xy 350.930791 -281.450472) (xy 350.915347 -281.498004) (xy 350.892657 -281.542536)
			(xy 350.863281 -281.582969) (xy 350.827941 -281.618309) (xy 350.787508 -281.647685) (xy 350.742976 -281.670375)
			(xy 350.695444 -281.685819) (xy 350.646081 -281.693638) (xy 350.596103 -281.693638) (xy 350.54674 -281.685819)
			(xy 350.499208 -281.670375) (xy 350.454676 -281.647685) (xy 350.414243 -281.618309) (xy 350.378903 -281.582969)
			(xy 350.349527 -281.542536) (xy 350.326837 -281.498004) (xy 350.311393 -281.450472) (xy 350.303574 -281.401109)
			(xy 349.996257 -281.401109) (xy 349.996248 -281.401566) (xy 349.988084 -281.4518) (xy 349.971968 -281.500074)
			(xy 349.948317 -281.545137) (xy 349.917744 -281.585823) (xy 349.88104 -281.621078) (xy 349.839156 -281.649988)
			(xy 349.793177 -281.671805) (xy 349.744293 -281.685965) (xy 349.693772 -281.692099) (xy 349.64292 -281.69005)
			(xy 349.593056 -281.67987) (xy 349.54547 -281.661823) (xy 349.501396 -281.636377) (xy 349.461974 -281.60419)
			(xy 349.428226 -281.566096) (xy 349.401025 -281.523082) (xy 349.381077 -281.476262) (xy 349.368898 -281.426848)
			(xy 349.364803 -281.37612) (xy 349.05696 -281.37612) (xy 349.056448 -281.401566) (xy 349.048284 -281.4518)
			(xy 349.032168 -281.500074) (xy 349.008517 -281.545137) (xy 348.977944 -281.585823) (xy 348.94124 -281.621078)
			(xy 348.899356 -281.649988) (xy 348.853377 -281.671805) (xy 348.804493 -281.685965) (xy 348.753972 -281.692099)
			(xy 348.70312 -281.69005) (xy 348.653256 -281.67987) (xy 348.60567 -281.661823) (xy 348.561596 -281.636377)
			(xy 348.522174 -281.60419) (xy 348.488426 -281.566096) (xy 348.461225 -281.523082) (xy 348.441277 -281.476262)
			(xy 348.429098 -281.426848) (xy 348.425003 -281.37612) (xy 348.119192 -281.37612) (xy 348.118702 -281.401109)
			(xy 348.110883 -281.450472) (xy 348.095439 -281.498004) (xy 348.072749 -281.542536) (xy 348.043373 -281.582969)
			(xy 348.008033 -281.618309) (xy 347.9676 -281.647685) (xy 347.923068 -281.670375) (xy 347.875536 -281.685819)
			(xy 347.826173 -281.693638) (xy 347.776195 -281.693638) (xy 347.726832 -281.685819) (xy 347.6793 -281.670375)
			(xy 347.634768 -281.647685) (xy 347.594335 -281.618309) (xy 347.558995 -281.582969) (xy 347.529619 -281.542536)
			(xy 347.506929 -281.498004) (xy 347.491485 -281.450472) (xy 347.483666 -281.401109) (xy 347.176349 -281.401109)
			(xy 347.17634 -281.401566) (xy 347.168176 -281.4518) (xy 347.15206 -281.500074) (xy 347.128409 -281.545137)
			(xy 347.097836 -281.585823) (xy 347.061132 -281.621078) (xy 347.019248 -281.649988) (xy 346.973269 -281.671805)
			(xy 346.924385 -281.685965) (xy 346.873864 -281.692099) (xy 346.823012 -281.69005) (xy 346.773148 -281.67987)
			(xy 346.725562 -281.661823) (xy 346.681488 -281.636377) (xy 346.642066 -281.60419) (xy 346.608318 -281.566096)
			(xy 346.581117 -281.523082) (xy 346.561169 -281.476262) (xy 346.54899 -281.426848) (xy 346.544895 -281.37612)
			(xy 346.236798 -281.37612) (xy 346.236286 -281.401566) (xy 346.228122 -281.4518) (xy 346.212006 -281.500074)
			(xy 346.188355 -281.545137) (xy 346.157782 -281.585823) (xy 346.121078 -281.621078) (xy 346.079194 -281.649988)
			(xy 346.033215 -281.671805) (xy 345.984331 -281.685965) (xy 345.93381 -281.692099) (xy 345.882958 -281.69005)
			(xy 345.833094 -281.67987) (xy 345.785508 -281.661823) (xy 345.741434 -281.636377) (xy 345.702012 -281.60419)
			(xy 345.668264 -281.566096) (xy 345.641063 -281.523082) (xy 345.621115 -281.476262) (xy 345.608936 -281.426848)
			(xy 345.604841 -281.37612) (xy 345.298938 -281.37612) (xy 345.297345 -281.414076) (xy 345.287741 -281.462313)
			(xy 345.270821 -281.508495) (xy 345.246992 -281.551521) (xy 345.232228 -281.571192) (xy 345.214391 -281.593165)
			(xy 345.172319 -281.631013) (xy 345.124203 -281.6608) (xy 345.098116 -281.671776) (xy 345.097862 -281.671776)
			(xy 345.095068 -281.672792) (xy 345.086747 -281.677177) (xy 345.073763 -281.690763) (xy 345.066545 -281.708114)
			(xy 345.065858 -281.717496) (xy 345.065858 -281.880056) (xy 345.066312 -281.889894) (xy 345.073739 -281.908115)
			(xy 345.087508 -281.922171) (xy 345.096338 -281.926538) (xy 345.14155 -281.94635) (xy 345.17965 -281.96286)
			(xy 345.186544 -281.965589) (xy 345.201255 -281.967388) (xy 345.208606 -281.966416) (xy 345.215464 -281.965146)
			(xy 345.228672 -281.958796) (xy 345.23426 -281.953462) (xy 345.252026 -281.937502) (xy 345.291445 -281.910544)
			(xy 345.334451 -281.88978) (xy 345.380077 -281.875677) (xy 345.427298 -281.868551) (xy 345.451176 -281.868118)
			(xy 345.476166 -281.868581) (xy 345.525532 -281.876396) (xy 345.573068 -281.891838) (xy 345.617602 -281.914527)
			(xy 345.658039 -281.943903) (xy 345.693382 -281.979243) (xy 345.722761 -282.019678) (xy 345.745452 -282.06421)
			(xy 345.760898 -282.111744) (xy 345.768717 -282.16111) (xy 345.768717 -282.21109) (xy 345.768713 -282.211115)
			(xy 346.073712 -282.211115) (xy 346.073712 -282.161137) (xy 346.081531 -282.111774) (xy 346.096975 -282.064242)
			(xy 346.119665 -282.01971) (xy 346.149041 -281.979277) (xy 346.184381 -281.943937) (xy 346.224814 -281.914561)
			(xy 346.269346 -281.891871) (xy 346.316878 -281.876427) (xy 346.366241 -281.868608) (xy 346.416219 -281.868608)
			(xy 346.465582 -281.876427) (xy 346.513114 -281.891871) (xy 346.557646 -281.914561) (xy 346.598079 -281.943937)
			(xy 346.633419 -281.979277) (xy 346.662795 -282.01971) (xy 346.685485 -282.064242) (xy 346.700929 -282.111774)
			(xy 346.708748 -282.161137) (xy 346.709238 -282.186126) (xy 346.708748 -282.211115) (xy 347.013512 -282.211115)
			(xy 347.013512 -282.161137) (xy 347.021331 -282.111774) (xy 347.036775 -282.064242) (xy 347.059465 -282.01971)
			(xy 347.088841 -281.979277) (xy 347.124181 -281.943937) (xy 347.164614 -281.914561) (xy 347.209146 -281.891871)
			(xy 347.256678 -281.876427) (xy 347.306041 -281.868608) (xy 347.356019 -281.868608) (xy 347.405382 -281.876427)
			(xy 347.452914 -281.891871) (xy 347.497446 -281.914561) (xy 347.537879 -281.943937) (xy 347.573219 -281.979277)
			(xy 347.602595 -282.01971) (xy 347.625285 -282.064242) (xy 347.640729 -282.111774) (xy 347.648548 -282.161137)
			(xy 347.649038 -282.186126) (xy 347.648548 -282.211115) (xy 347.953566 -282.211115) (xy 347.953566 -282.161137)
			(xy 347.961385 -282.111774) (xy 347.976829 -282.064242) (xy 347.999519 -282.01971) (xy 348.028895 -281.979277)
			(xy 348.064235 -281.943937) (xy 348.104668 -281.914561) (xy 348.1492 -281.891871) (xy 348.196732 -281.876427)
			(xy 348.246095 -281.868608) (xy 348.296073 -281.868608) (xy 348.345436 -281.876427) (xy 348.392968 -281.891871)
			(xy 348.4375 -281.914561) (xy 348.477933 -281.943937) (xy 348.513273 -281.979277) (xy 348.542649 -282.01971)
			(xy 348.565339 -282.064242) (xy 348.580783 -282.111774) (xy 348.588602 -282.161137) (xy 348.589092 -282.186126)
			(xy 348.588602 -282.211115) (xy 348.89362 -282.211115) (xy 348.89362 -282.161137) (xy 348.901439 -282.111774)
			(xy 348.916883 -282.064242) (xy 348.939573 -282.01971) (xy 348.968949 -281.979277) (xy 349.004289 -281.943937)
			(xy 349.044722 -281.914561) (xy 349.089254 -281.891871) (xy 349.136786 -281.876427) (xy 349.186149 -281.868608)
			(xy 349.236127 -281.868608) (xy 349.28549 -281.876427) (xy 349.333022 -281.891871) (xy 349.377554 -281.914561)
			(xy 349.417987 -281.943937) (xy 349.453327 -281.979277) (xy 349.482703 -282.01971) (xy 349.505393 -282.064242)
			(xy 349.520837 -282.111774) (xy 349.528656 -282.161137) (xy 349.529146 -282.186126) (xy 349.528656 -282.211115)
			(xy 349.833674 -282.211115) (xy 349.833674 -282.161137) (xy 349.841493 -282.111774) (xy 349.856937 -282.064242)
			(xy 349.879627 -282.01971) (xy 349.909003 -281.979277) (xy 349.944343 -281.943937) (xy 349.984776 -281.914561)
			(xy 350.029308 -281.891871) (xy 350.07684 -281.876427) (xy 350.126203 -281.868608) (xy 350.176181 -281.868608)
			(xy 350.225544 -281.876427) (xy 350.273076 -281.891871) (xy 350.317608 -281.914561) (xy 350.358041 -281.943937)
			(xy 350.393381 -281.979277) (xy 350.422757 -282.01971) (xy 350.445447 -282.064242) (xy 350.460891 -282.111774)
			(xy 350.46871 -282.161137) (xy 350.4692 -282.186126) (xy 350.46871 -282.211115) (xy 350.773728 -282.211115)
			(xy 350.773728 -282.161137) (xy 350.781547 -282.111774) (xy 350.796991 -282.064242) (xy 350.819681 -282.01971)
			(xy 350.849057 -281.979277) (xy 350.884397 -281.943937) (xy 350.92483 -281.914561) (xy 350.969362 -281.891871)
			(xy 351.016894 -281.876427) (xy 351.066257 -281.868608) (xy 351.116235 -281.868608) (xy 351.165598 -281.876427)
			(xy 351.21313 -281.891871) (xy 351.257662 -281.914561) (xy 351.298095 -281.943937) (xy 351.333435 -281.979277)
			(xy 351.362811 -282.01971) (xy 351.385501 -282.064242) (xy 351.400945 -282.111774) (xy 351.408764 -282.161137)
			(xy 351.409254 -282.186126) (xy 351.408764 -282.211115) (xy 351.713528 -282.211115) (xy 351.713528 -282.161137)
			(xy 351.721347 -282.111774) (xy 351.736791 -282.064242) (xy 351.759481 -282.01971) (xy 351.788857 -281.979277)
			(xy 351.824197 -281.943937) (xy 351.86463 -281.914561) (xy 351.909162 -281.891871) (xy 351.956694 -281.876427)
			(xy 352.006057 -281.868608) (xy 352.056035 -281.868608) (xy 352.105398 -281.876427) (xy 352.15293 -281.891871)
			(xy 352.197462 -281.914561) (xy 352.237895 -281.943937) (xy 352.273235 -281.979277) (xy 352.302611 -282.01971)
			(xy 352.325301 -282.064242) (xy 352.340745 -282.111774) (xy 352.348564 -282.161137) (xy 352.349054 -282.186126)
			(xy 352.348564 -282.211115) (xy 352.653582 -282.211115) (xy 352.653582 -282.161137) (xy 352.661401 -282.111774)
			(xy 352.676845 -282.064242) (xy 352.699535 -282.01971) (xy 352.728911 -281.979277) (xy 352.764251 -281.943937)
			(xy 352.804684 -281.914561) (xy 352.849216 -281.891871) (xy 352.896748 -281.876427) (xy 352.946111 -281.868608)
			(xy 352.996089 -281.868608) (xy 353.045452 -281.876427) (xy 353.092984 -281.891871) (xy 353.137516 -281.914561)
			(xy 353.177949 -281.943937) (xy 353.213289 -281.979277) (xy 353.242665 -282.01971) (xy 353.265355 -282.064242)
			(xy 353.280799 -282.111774) (xy 353.288618 -282.161137) (xy 353.289108 -282.186126) (xy 353.288618 -282.211115)
			(xy 353.593636 -282.211115) (xy 353.593636 -282.161137) (xy 353.601455 -282.111774) (xy 353.616899 -282.064242)
			(xy 353.639589 -282.01971) (xy 353.668965 -281.979277) (xy 353.704305 -281.943937) (xy 353.744738 -281.914561)
			(xy 353.78927 -281.891871) (xy 353.836802 -281.876427) (xy 353.886165 -281.868608) (xy 353.936143 -281.868608)
			(xy 353.985506 -281.876427) (xy 354.033038 -281.891871) (xy 354.07757 -281.914561) (xy 354.118003 -281.943937)
			(xy 354.153343 -281.979277) (xy 354.182719 -282.01971) (xy 354.205409 -282.064242) (xy 354.220853 -282.111774)
			(xy 354.228672 -282.161137) (xy 354.229162 -282.186126) (xy 354.228672 -282.211115) (xy 354.53369 -282.211115)
			(xy 354.53369 -282.161137) (xy 354.541509 -282.111774) (xy 354.556953 -282.064242) (xy 354.579643 -282.01971)
			(xy 354.609019 -281.979277) (xy 354.644359 -281.943937) (xy 354.684792 -281.914561) (xy 354.729324 -281.891871)
			(xy 354.776856 -281.876427) (xy 354.826219 -281.868608) (xy 354.876197 -281.868608) (xy 354.92556 -281.876427)
			(xy 354.973092 -281.891871) (xy 355.017624 -281.914561) (xy 355.058057 -281.943937) (xy 355.093397 -281.979277)
			(xy 355.122773 -282.01971) (xy 355.145463 -282.064242) (xy 355.160907 -282.111774) (xy 355.168726 -282.161137)
			(xy 355.169216 -282.186126) (xy 355.168726 -282.211115) (xy 355.47349 -282.211115) (xy 355.47349 -282.161137)
			(xy 355.481309 -282.111774) (xy 355.496753 -282.064242) (xy 355.519443 -282.01971) (xy 355.548819 -281.979277)
			(xy 355.584159 -281.943937) (xy 355.624592 -281.914561) (xy 355.669124 -281.891871) (xy 355.716656 -281.876427)
			(xy 355.766019 -281.868608) (xy 355.815997 -281.868608) (xy 355.86536 -281.876427) (xy 355.912892 -281.891871)
			(xy 355.957424 -281.914561) (xy 355.997857 -281.943937) (xy 356.033197 -281.979277) (xy 356.062573 -282.01971)
			(xy 356.085263 -282.064242) (xy 356.100707 -282.111774) (xy 356.108526 -282.161137) (xy 356.109016 -282.186126)
			(xy 356.414827 -282.186126) (xy 356.418922 -282.135398) (xy 356.431101 -282.085984) (xy 356.451049 -282.039164)
			(xy 356.47825 -281.99615) (xy 356.511998 -281.958056) (xy 356.55142 -281.925869) (xy 356.595494 -281.900423)
			(xy 356.64308 -281.882376) (xy 356.692944 -281.872196) (xy 356.743796 -281.870147) (xy 356.794317 -281.876281)
			(xy 356.843201 -281.890441) (xy 356.88918 -281.912258) (xy 356.931064 -281.941168) (xy 356.967768 -281.976423)
			(xy 356.998341 -282.017109) (xy 357.021992 -282.062172) (xy 357.038108 -282.110446) (xy 357.046272 -282.16068)
			(xy 357.046784 -282.186126) (xy 357.354881 -282.186126) (xy 357.358976 -282.135398) (xy 357.371155 -282.085984)
			(xy 357.391103 -282.039164) (xy 357.418304 -281.99615) (xy 357.452052 -281.958056) (xy 357.491474 -281.925869)
			(xy 357.535548 -281.900423) (xy 357.583134 -281.882376) (xy 357.632998 -281.872196) (xy 357.68385 -281.870147)
			(xy 357.734371 -281.876281) (xy 357.783255 -281.890441) (xy 357.829234 -281.912258) (xy 357.871118 -281.941168)
			(xy 357.907822 -281.976423) (xy 357.938395 -282.017109) (xy 357.962046 -282.062172) (xy 357.978162 -282.110446)
			(xy 357.986326 -282.16068) (xy 357.986838 -282.186126) (xy 357.986335 -282.211115) (xy 358.293652 -282.211115)
			(xy 358.293652 -282.161137) (xy 358.301471 -282.111774) (xy 358.316915 -282.064242) (xy 358.339605 -282.01971)
			(xy 358.368981 -281.979277) (xy 358.404321 -281.943937) (xy 358.444754 -281.914561) (xy 358.489286 -281.891871)
			(xy 358.536818 -281.876427) (xy 358.586181 -281.868608) (xy 358.636159 -281.868608) (xy 358.685522 -281.876427)
			(xy 358.733054 -281.891871) (xy 358.777586 -281.914561) (xy 358.818019 -281.943937) (xy 358.853359 -281.979277)
			(xy 358.882735 -282.01971) (xy 358.905425 -282.064242) (xy 358.920869 -282.111774) (xy 358.928688 -282.161137)
			(xy 358.929178 -282.186126) (xy 358.928688 -282.211115) (xy 361.10721 -282.211115) (xy 361.10721 -282.161137)
			(xy 361.115029 -282.111774) (xy 361.130473 -282.064242) (xy 361.153163 -282.01971) (xy 361.182539 -281.979277)
			(xy 361.217879 -281.943937) (xy 361.258312 -281.914561) (xy 361.302844 -281.891871) (xy 361.350376 -281.876427)
			(xy 361.399739 -281.868608) (xy 361.449717 -281.868608) (xy 361.49908 -281.876427) (xy 361.546612 -281.891871)
			(xy 361.591144 -281.914561) (xy 361.631577 -281.943937) (xy 361.666917 -281.979277) (xy 361.696293 -282.01971)
			(xy 361.718983 -282.064242) (xy 361.734427 -282.111774) (xy 361.742246 -282.161137) (xy 361.742736 -282.186126)
			(xy 362.048547 -282.186126) (xy 362.052642 -282.135398) (xy 362.064821 -282.085984) (xy 362.084769 -282.039164)
			(xy 362.11197 -281.99615) (xy 362.145718 -281.958056) (xy 362.18514 -281.925869) (xy 362.229214 -281.900423)
			(xy 362.2768 -281.882376) (xy 362.326664 -281.872196) (xy 362.377516 -281.870147) (xy 362.428037 -281.876281)
			(xy 362.476921 -281.890441) (xy 362.5229 -281.912258) (xy 362.564784 -281.941168) (xy 362.601488 -281.976423)
			(xy 362.632061 -282.017109) (xy 362.655712 -282.062172) (xy 362.671828 -282.110446) (xy 362.679992 -282.16068)
			(xy 362.680504 -282.186126) (xy 362.988601 -282.186126) (xy 362.992696 -282.135398) (xy 363.004875 -282.085984)
			(xy 363.024823 -282.039164) (xy 363.052024 -281.99615) (xy 363.085772 -281.958056) (xy 363.125194 -281.925869)
			(xy 363.169268 -281.900423) (xy 363.216854 -281.882376) (xy 363.266718 -281.872196) (xy 363.31757 -281.870147)
			(xy 363.368091 -281.876281) (xy 363.416975 -281.890441) (xy 363.462954 -281.912258) (xy 363.504838 -281.941168)
			(xy 363.541542 -281.976423) (xy 363.572115 -282.017109) (xy 363.595766 -282.062172) (xy 363.611882 -282.110446)
			(xy 363.620046 -282.16068) (xy 363.620558 -282.186126) (xy 363.620055 -282.211115) (xy 363.927372 -282.211115)
			(xy 363.927372 -282.161137) (xy 363.935191 -282.111774) (xy 363.950635 -282.064242) (xy 363.973325 -282.01971)
			(xy 364.002701 -281.979277) (xy 364.038041 -281.943937) (xy 364.078474 -281.914561) (xy 364.123006 -281.891871)
			(xy 364.170538 -281.876427) (xy 364.219901 -281.868608) (xy 364.269879 -281.868608) (xy 364.319242 -281.876427)
			(xy 364.366774 -281.891871) (xy 364.411306 -281.914561) (xy 364.451739 -281.943937) (xy 364.487079 -281.979277)
			(xy 364.516455 -282.01971) (xy 364.539145 -282.064242) (xy 364.554589 -282.111774) (xy 364.562408 -282.161137)
			(xy 364.562898 -282.186126) (xy 364.562408 -282.211115) (xy 364.867172 -282.211115) (xy 364.867172 -282.161137)
			(xy 364.874991 -282.111774) (xy 364.890435 -282.064242) (xy 364.913125 -282.01971) (xy 364.942501 -281.979277)
			(xy 364.977841 -281.943937) (xy 365.018274 -281.914561) (xy 365.062806 -281.891871) (xy 365.110338 -281.876427)
			(xy 365.159701 -281.868608) (xy 365.209679 -281.868608) (xy 365.259042 -281.876427) (xy 365.306574 -281.891871)
			(xy 365.351106 -281.914561) (xy 365.391539 -281.943937) (xy 365.426879 -281.979277) (xy 365.456255 -282.01971)
			(xy 365.478945 -282.064242) (xy 365.494389 -282.111774) (xy 365.502208 -282.161137) (xy 365.502698 -282.186126)
			(xy 365.502208 -282.211115) (xy 365.807226 -282.211115) (xy 365.807226 -282.161137) (xy 365.815045 -282.111774)
			(xy 365.830489 -282.064242) (xy 365.853179 -282.01971) (xy 365.882555 -281.979277) (xy 365.917895 -281.943937)
			(xy 365.958328 -281.914561) (xy 366.00286 -281.891871) (xy 366.050392 -281.876427) (xy 366.099755 -281.868608)
			(xy 366.149733 -281.868608) (xy 366.199096 -281.876427) (xy 366.246628 -281.891871) (xy 366.29116 -281.914561)
			(xy 366.331593 -281.943937) (xy 366.366933 -281.979277) (xy 366.396309 -282.01971) (xy 366.418999 -282.064242)
			(xy 366.434443 -282.111774) (xy 366.442262 -282.161137) (xy 366.442752 -282.186126) (xy 366.442262 -282.211115)
			(xy 366.74728 -282.211115) (xy 366.74728 -282.161137) (xy 366.755099 -282.111774) (xy 366.770543 -282.064242)
			(xy 366.793233 -282.01971) (xy 366.822609 -281.979277) (xy 366.857949 -281.943937) (xy 366.898382 -281.914561)
			(xy 366.942914 -281.891871) (xy 366.990446 -281.876427) (xy 367.039809 -281.868608) (xy 367.089787 -281.868608)
			(xy 367.13915 -281.876427) (xy 367.186682 -281.891871) (xy 367.231214 -281.914561) (xy 367.271647 -281.943937)
			(xy 367.306987 -281.979277) (xy 367.336363 -282.01971) (xy 367.359053 -282.064242) (xy 367.374497 -282.111774)
			(xy 367.382316 -282.161137) (xy 367.382806 -282.186126) (xy 367.382316 -282.211115) (xy 367.687334 -282.211115)
			(xy 367.687334 -282.161137) (xy 367.695153 -282.111774) (xy 367.710597 -282.064242) (xy 367.733287 -282.01971)
			(xy 367.762663 -281.979277) (xy 367.798003 -281.943937) (xy 367.838436 -281.914561) (xy 367.882968 -281.891871)
			(xy 367.9305 -281.876427) (xy 367.979863 -281.868608) (xy 368.029841 -281.868608) (xy 368.079204 -281.876427)
			(xy 368.126736 -281.891871) (xy 368.171268 -281.914561) (xy 368.211701 -281.943937) (xy 368.247041 -281.979277)
			(xy 368.276417 -282.01971) (xy 368.299107 -282.064242) (xy 368.314551 -282.111774) (xy 368.32237 -282.161137)
			(xy 368.32286 -282.186126) (xy 368.32237 -282.211115) (xy 368.627388 -282.211115) (xy 368.627388 -282.161137)
			(xy 368.635207 -282.111774) (xy 368.650651 -282.064242) (xy 368.673341 -282.01971) (xy 368.702717 -281.979277)
			(xy 368.738057 -281.943937) (xy 368.77849 -281.914561) (xy 368.823022 -281.891871) (xy 368.870554 -281.876427)
			(xy 368.919917 -281.868608) (xy 368.969895 -281.868608) (xy 369.019258 -281.876427) (xy 369.06679 -281.891871)
			(xy 369.111322 -281.914561) (xy 369.151755 -281.943937) (xy 369.187095 -281.979277) (xy 369.216471 -282.01971)
			(xy 369.239161 -282.064242) (xy 369.254605 -282.111774) (xy 369.262424 -282.161137) (xy 369.262914 -282.186126)
			(xy 369.262424 -282.211115) (xy 369.567188 -282.211115) (xy 369.567188 -282.161137) (xy 369.575007 -282.111774)
			(xy 369.590451 -282.064242) (xy 369.613141 -282.01971) (xy 369.642517 -281.979277) (xy 369.677857 -281.943937)
			(xy 369.71829 -281.914561) (xy 369.762822 -281.891871) (xy 369.810354 -281.876427) (xy 369.859717 -281.868608)
			(xy 369.909695 -281.868608) (xy 369.959058 -281.876427) (xy 370.00659 -281.891871) (xy 370.051122 -281.914561)
			(xy 370.091555 -281.943937) (xy 370.126895 -281.979277) (xy 370.156271 -282.01971) (xy 370.178961 -282.064242)
			(xy 370.194405 -282.111774) (xy 370.202224 -282.161137) (xy 370.202714 -282.186126) (xy 370.202224 -282.211115)
			(xy 370.507242 -282.211115) (xy 370.507242 -282.161137) (xy 370.515061 -282.111774) (xy 370.530505 -282.064242)
			(xy 370.553195 -282.01971) (xy 370.582571 -281.979277) (xy 370.617911 -281.943937) (xy 370.658344 -281.914561)
			(xy 370.702876 -281.891871) (xy 370.750408 -281.876427) (xy 370.799771 -281.868608) (xy 370.849749 -281.868608)
			(xy 370.899112 -281.876427) (xy 370.946644 -281.891871) (xy 370.991176 -281.914561) (xy 371.031609 -281.943937)
			(xy 371.066949 -281.979277) (xy 371.096325 -282.01971) (xy 371.119015 -282.064242) (xy 371.134459 -282.111774)
			(xy 371.142278 -282.161137) (xy 371.142768 -282.186126) (xy 371.142278 -282.211115) (xy 371.447296 -282.211115)
			(xy 371.447296 -282.161137) (xy 371.455115 -282.111774) (xy 371.470559 -282.064242) (xy 371.493249 -282.01971)
			(xy 371.522625 -281.979277) (xy 371.557965 -281.943937) (xy 371.598398 -281.914561) (xy 371.64293 -281.891871)
			(xy 371.690462 -281.876427) (xy 371.739825 -281.868608) (xy 371.789803 -281.868608) (xy 371.839166 -281.876427)
			(xy 371.886698 -281.891871) (xy 371.93123 -281.914561) (xy 371.971663 -281.943937) (xy 372.007003 -281.979277)
			(xy 372.036379 -282.01971) (xy 372.059069 -282.064242) (xy 372.074513 -282.111774) (xy 372.082332 -282.161137)
			(xy 372.082822 -282.186126) (xy 372.082332 -282.211115) (xy 372.38735 -282.211115) (xy 372.38735 -282.161137)
			(xy 372.395169 -282.111774) (xy 372.410613 -282.064242) (xy 372.433303 -282.01971) (xy 372.462679 -281.979277)
			(xy 372.498019 -281.943937) (xy 372.538452 -281.914561) (xy 372.582984 -281.891871) (xy 372.630516 -281.876427)
			(xy 372.679879 -281.868608) (xy 372.729857 -281.868608) (xy 372.77922 -281.876427) (xy 372.826752 -281.891871)
			(xy 372.871284 -281.914561) (xy 372.911717 -281.943937) (xy 372.947057 -281.979277) (xy 372.976433 -282.01971)
			(xy 372.999123 -282.064242) (xy 373.014567 -282.111774) (xy 373.022386 -282.161137) (xy 373.022876 -282.186126)
			(xy 373.022386 -282.211115) (xy 373.327404 -282.211115) (xy 373.327404 -282.161137) (xy 373.335223 -282.111774)
			(xy 373.350667 -282.064242) (xy 373.373357 -282.01971) (xy 373.402733 -281.979277) (xy 373.438073 -281.943937)
			(xy 373.478506 -281.914561) (xy 373.523038 -281.891871) (xy 373.57057 -281.876427) (xy 373.619933 -281.868608)
			(xy 373.669911 -281.868608) (xy 373.719274 -281.876427) (xy 373.766806 -281.891871) (xy 373.811338 -281.914561)
			(xy 373.851771 -281.943937) (xy 373.887111 -281.979277) (xy 373.916487 -282.01971) (xy 373.939177 -282.064242)
			(xy 373.954621 -282.111774) (xy 373.96244 -282.161137) (xy 373.96293 -282.186126) (xy 373.96244 -282.211115)
			(xy 373.954621 -282.260478) (xy 373.939177 -282.30801) (xy 373.916487 -282.352542) (xy 373.887111 -282.392975)
			(xy 373.851771 -282.428315) (xy 373.811338 -282.457691) (xy 373.766806 -282.480381) (xy 373.719274 -282.495825)
			(xy 373.669911 -282.503644) (xy 373.619933 -282.503644) (xy 373.57057 -282.495825) (xy 373.523038 -282.480381)
			(xy 373.478506 -282.457691) (xy 373.438073 -282.428315) (xy 373.402733 -282.392975) (xy 373.373357 -282.352542)
			(xy 373.350667 -282.30801) (xy 373.335223 -282.260478) (xy 373.327404 -282.211115) (xy 373.022386 -282.211115)
			(xy 373.014567 -282.260478) (xy 372.999123 -282.30801) (xy 372.976433 -282.352542) (xy 372.947057 -282.392975)
			(xy 372.911717 -282.428315) (xy 372.871284 -282.457691) (xy 372.826752 -282.480381) (xy 372.77922 -282.495825)
			(xy 372.729857 -282.503644) (xy 372.679879 -282.503644) (xy 372.630516 -282.495825) (xy 372.582984 -282.480381)
			(xy 372.538452 -282.457691) (xy 372.498019 -282.428315) (xy 372.462679 -282.392975) (xy 372.433303 -282.352542)
			(xy 372.410613 -282.30801) (xy 372.395169 -282.260478) (xy 372.38735 -282.211115) (xy 372.082332 -282.211115)
			(xy 372.074513 -282.260478) (xy 372.059069 -282.30801) (xy 372.036379 -282.352542) (xy 372.007003 -282.392975)
			(xy 371.971663 -282.428315) (xy 371.93123 -282.457691) (xy 371.886698 -282.480381) (xy 371.839166 -282.495825)
			(xy 371.789803 -282.503644) (xy 371.739825 -282.503644) (xy 371.690462 -282.495825) (xy 371.64293 -282.480381)
			(xy 371.598398 -282.457691) (xy 371.557965 -282.428315) (xy 371.522625 -282.392975) (xy 371.493249 -282.352542)
			(xy 371.470559 -282.30801) (xy 371.455115 -282.260478) (xy 371.447296 -282.211115) (xy 371.142278 -282.211115)
			(xy 371.134459 -282.260478) (xy 371.119015 -282.30801) (xy 371.096325 -282.352542) (xy 371.066949 -282.392975)
			(xy 371.031609 -282.428315) (xy 370.991176 -282.457691) (xy 370.946644 -282.480381) (xy 370.899112 -282.495825)
			(xy 370.849749 -282.503644) (xy 370.799771 -282.503644) (xy 370.750408 -282.495825) (xy 370.702876 -282.480381)
			(xy 370.658344 -282.457691) (xy 370.617911 -282.428315) (xy 370.582571 -282.392975) (xy 370.553195 -282.352542)
			(xy 370.530505 -282.30801) (xy 370.515061 -282.260478) (xy 370.507242 -282.211115) (xy 370.202224 -282.211115)
			(xy 370.194405 -282.260478) (xy 370.178961 -282.30801) (xy 370.156271 -282.352542) (xy 370.126895 -282.392975)
			(xy 370.091555 -282.428315) (xy 370.051122 -282.457691) (xy 370.00659 -282.480381) (xy 369.959058 -282.495825)
			(xy 369.909695 -282.503644) (xy 369.859717 -282.503644) (xy 369.810354 -282.495825) (xy 369.762822 -282.480381)
			(xy 369.71829 -282.457691) (xy 369.677857 -282.428315) (xy 369.642517 -282.392975) (xy 369.613141 -282.352542)
			(xy 369.590451 -282.30801) (xy 369.575007 -282.260478) (xy 369.567188 -282.211115) (xy 369.262424 -282.211115)
			(xy 369.254605 -282.260478) (xy 369.239161 -282.30801) (xy 369.216471 -282.352542) (xy 369.187095 -282.392975)
			(xy 369.151755 -282.428315) (xy 369.111322 -282.457691) (xy 369.06679 -282.480381) (xy 369.019258 -282.495825)
			(xy 368.969895 -282.503644) (xy 368.919917 -282.503644) (xy 368.870554 -282.495825) (xy 368.823022 -282.480381)
			(xy 368.77849 -282.457691) (xy 368.738057 -282.428315) (xy 368.702717 -282.392975) (xy 368.673341 -282.352542)
			(xy 368.650651 -282.30801) (xy 368.635207 -282.260478) (xy 368.627388 -282.211115) (xy 368.32237 -282.211115)
			(xy 368.314551 -282.260478) (xy 368.299107 -282.30801) (xy 368.276417 -282.352542) (xy 368.247041 -282.392975)
			(xy 368.211701 -282.428315) (xy 368.171268 -282.457691) (xy 368.126736 -282.480381) (xy 368.079204 -282.495825)
			(xy 368.029841 -282.503644) (xy 367.979863 -282.503644) (xy 367.9305 -282.495825) (xy 367.882968 -282.480381)
			(xy 367.838436 -282.457691) (xy 367.798003 -282.428315) (xy 367.762663 -282.392975) (xy 367.733287 -282.352542)
			(xy 367.710597 -282.30801) (xy 367.695153 -282.260478) (xy 367.687334 -282.211115) (xy 367.382316 -282.211115)
			(xy 367.374497 -282.260478) (xy 367.359053 -282.30801) (xy 367.336363 -282.352542) (xy 367.306987 -282.392975)
			(xy 367.271647 -282.428315) (xy 367.231214 -282.457691) (xy 367.186682 -282.480381) (xy 367.13915 -282.495825)
			(xy 367.089787 -282.503644) (xy 367.039809 -282.503644) (xy 366.990446 -282.495825) (xy 366.942914 -282.480381)
			(xy 366.898382 -282.457691) (xy 366.857949 -282.428315) (xy 366.822609 -282.392975) (xy 366.793233 -282.352542)
			(xy 366.770543 -282.30801) (xy 366.755099 -282.260478) (xy 366.74728 -282.211115) (xy 366.442262 -282.211115)
			(xy 366.434443 -282.260478) (xy 366.418999 -282.30801) (xy 366.396309 -282.352542) (xy 366.366933 -282.392975)
			(xy 366.331593 -282.428315) (xy 366.29116 -282.457691) (xy 366.246628 -282.480381) (xy 366.199096 -282.495825)
			(xy 366.149733 -282.503644) (xy 366.099755 -282.503644) (xy 366.050392 -282.495825) (xy 366.00286 -282.480381)
			(xy 365.958328 -282.457691) (xy 365.917895 -282.428315) (xy 365.882555 -282.392975) (xy 365.853179 -282.352542)
			(xy 365.830489 -282.30801) (xy 365.815045 -282.260478) (xy 365.807226 -282.211115) (xy 365.502208 -282.211115)
			(xy 365.494389 -282.260478) (xy 365.478945 -282.30801) (xy 365.456255 -282.352542) (xy 365.426879 -282.392975)
			(xy 365.391539 -282.428315) (xy 365.351106 -282.457691) (xy 365.306574 -282.480381) (xy 365.259042 -282.495825)
			(xy 365.209679 -282.503644) (xy 365.159701 -282.503644) (xy 365.110338 -282.495825) (xy 365.062806 -282.480381)
			(xy 365.018274 -282.457691) (xy 364.977841 -282.428315) (xy 364.942501 -282.392975) (xy 364.913125 -282.352542)
			(xy 364.890435 -282.30801) (xy 364.874991 -282.260478) (xy 364.867172 -282.211115) (xy 364.562408 -282.211115)
			(xy 364.554589 -282.260478) (xy 364.539145 -282.30801) (xy 364.516455 -282.352542) (xy 364.487079 -282.392975)
			(xy 364.451739 -282.428315) (xy 364.411306 -282.457691) (xy 364.366774 -282.480381) (xy 364.319242 -282.495825)
			(xy 364.269879 -282.503644) (xy 364.219901 -282.503644) (xy 364.170538 -282.495825) (xy 364.123006 -282.480381)
			(xy 364.078474 -282.457691) (xy 364.038041 -282.428315) (xy 364.002701 -282.392975) (xy 363.973325 -282.352542)
			(xy 363.950635 -282.30801) (xy 363.935191 -282.260478) (xy 363.927372 -282.211115) (xy 363.620055 -282.211115)
			(xy 363.620046 -282.211572) (xy 363.611882 -282.261806) (xy 363.595766 -282.31008) (xy 363.572115 -282.355143)
			(xy 363.541542 -282.395829) (xy 363.504838 -282.431084) (xy 363.462954 -282.459994) (xy 363.416975 -282.481811)
			(xy 363.368091 -282.495971) (xy 363.31757 -282.502105) (xy 363.266718 -282.500056) (xy 363.216854 -282.489876)
			(xy 363.169268 -282.471829) (xy 363.125194 -282.446383) (xy 363.085772 -282.414196) (xy 363.052024 -282.376102)
			(xy 363.024823 -282.333088) (xy 363.004875 -282.286268) (xy 362.992696 -282.236854) (xy 362.988601 -282.186126)
			(xy 362.680504 -282.186126) (xy 362.679992 -282.211572) (xy 362.671828 -282.261806) (xy 362.655712 -282.31008)
			(xy 362.632061 -282.355143) (xy 362.601488 -282.395829) (xy 362.564784 -282.431084) (xy 362.5229 -282.459994)
			(xy 362.476921 -282.481811) (xy 362.428037 -282.495971) (xy 362.377516 -282.502105) (xy 362.326664 -282.500056)
			(xy 362.2768 -282.489876) (xy 362.229214 -282.471829) (xy 362.18514 -282.446383) (xy 362.145718 -282.414196)
			(xy 362.11197 -282.376102) (xy 362.084769 -282.333088) (xy 362.064821 -282.286268) (xy 362.052642 -282.236854)
			(xy 362.048547 -282.186126) (xy 361.742736 -282.186126) (xy 361.742246 -282.211115) (xy 361.734427 -282.260478)
			(xy 361.718983 -282.30801) (xy 361.696293 -282.352542) (xy 361.666917 -282.392975) (xy 361.631577 -282.428315)
			(xy 361.591144 -282.457691) (xy 361.546612 -282.480381) (xy 361.49908 -282.495825) (xy 361.449717 -282.503644)
			(xy 361.399739 -282.503644) (xy 361.350376 -282.495825) (xy 361.302844 -282.480381) (xy 361.258312 -282.457691)
			(xy 361.217879 -282.428315) (xy 361.182539 -282.392975) (xy 361.153163 -282.352542) (xy 361.130473 -282.30801)
			(xy 361.115029 -282.260478) (xy 361.10721 -282.211115) (xy 358.928688 -282.211115) (xy 358.920869 -282.260478)
			(xy 358.905425 -282.30801) (xy 358.882735 -282.352542) (xy 358.853359 -282.392975) (xy 358.818019 -282.428315)
			(xy 358.777586 -282.457691) (xy 358.733054 -282.480381) (xy 358.685522 -282.495825) (xy 358.636159 -282.503644)
			(xy 358.586181 -282.503644) (xy 358.536818 -282.495825) (xy 358.489286 -282.480381) (xy 358.444754 -282.457691)
			(xy 358.404321 -282.428315) (xy 358.368981 -282.392975) (xy 358.339605 -282.352542) (xy 358.316915 -282.30801)
			(xy 358.301471 -282.260478) (xy 358.293652 -282.211115) (xy 357.986335 -282.211115) (xy 357.986326 -282.211572)
			(xy 357.978162 -282.261806) (xy 357.962046 -282.31008) (xy 357.938395 -282.355143) (xy 357.907822 -282.395829)
			(xy 357.871118 -282.431084) (xy 357.829234 -282.459994) (xy 357.783255 -282.481811) (xy 357.734371 -282.495971)
			(xy 357.68385 -282.502105) (xy 357.632998 -282.500056) (xy 357.583134 -282.489876) (xy 357.535548 -282.471829)
			(xy 357.491474 -282.446383) (xy 357.452052 -282.414196) (xy 357.418304 -282.376102) (xy 357.391103 -282.333088)
			(xy 357.371155 -282.286268) (xy 357.358976 -282.236854) (xy 357.354881 -282.186126) (xy 357.046784 -282.186126)
			(xy 357.046272 -282.211572) (xy 357.038108 -282.261806) (xy 357.021992 -282.31008) (xy 356.998341 -282.355143)
			(xy 356.967768 -282.395829) (xy 356.931064 -282.431084) (xy 356.88918 -282.459994) (xy 356.843201 -282.481811)
			(xy 356.794317 -282.495971) (xy 356.743796 -282.502105) (xy 356.692944 -282.500056) (xy 356.64308 -282.489876)
			(xy 356.595494 -282.471829) (xy 356.55142 -282.446383) (xy 356.511998 -282.414196) (xy 356.47825 -282.376102)
			(xy 356.451049 -282.333088) (xy 356.431101 -282.286268) (xy 356.418922 -282.236854) (xy 356.414827 -282.186126)
			(xy 356.109016 -282.186126) (xy 356.108526 -282.211115) (xy 356.100707 -282.260478) (xy 356.085263 -282.30801)
			(xy 356.062573 -282.352542) (xy 356.033197 -282.392975) (xy 355.997857 -282.428315) (xy 355.957424 -282.457691)
			(xy 355.912892 -282.480381) (xy 355.86536 -282.495825) (xy 355.815997 -282.503644) (xy 355.766019 -282.503644)
			(xy 355.716656 -282.495825) (xy 355.669124 -282.480381) (xy 355.624592 -282.457691) (xy 355.584159 -282.428315)
			(xy 355.548819 -282.392975) (xy 355.519443 -282.352542) (xy 355.496753 -282.30801) (xy 355.481309 -282.260478)
			(xy 355.47349 -282.211115) (xy 355.168726 -282.211115) (xy 355.160907 -282.260478) (xy 355.145463 -282.30801)
			(xy 355.122773 -282.352542) (xy 355.093397 -282.392975) (xy 355.058057 -282.428315) (xy 355.017624 -282.457691)
			(xy 354.973092 -282.480381) (xy 354.92556 -282.495825) (xy 354.876197 -282.503644) (xy 354.826219 -282.503644)
			(xy 354.776856 -282.495825) (xy 354.729324 -282.480381) (xy 354.684792 -282.457691) (xy 354.644359 -282.428315)
			(xy 354.609019 -282.392975) (xy 354.579643 -282.352542) (xy 354.556953 -282.30801) (xy 354.541509 -282.260478)
			(xy 354.53369 -282.211115) (xy 354.228672 -282.211115) (xy 354.220853 -282.260478) (xy 354.205409 -282.30801)
			(xy 354.182719 -282.352542) (xy 354.153343 -282.392975) (xy 354.118003 -282.428315) (xy 354.07757 -282.457691)
			(xy 354.033038 -282.480381) (xy 353.985506 -282.495825) (xy 353.936143 -282.503644) (xy 353.886165 -282.503644)
			(xy 353.836802 -282.495825) (xy 353.78927 -282.480381) (xy 353.744738 -282.457691) (xy 353.704305 -282.428315)
			(xy 353.668965 -282.392975) (xy 353.639589 -282.352542) (xy 353.616899 -282.30801) (xy 353.601455 -282.260478)
			(xy 353.593636 -282.211115) (xy 353.288618 -282.211115) (xy 353.280799 -282.260478) (xy 353.265355 -282.30801)
			(xy 353.242665 -282.352542) (xy 353.213289 -282.392975) (xy 353.177949 -282.428315) (xy 353.137516 -282.457691)
			(xy 353.092984 -282.480381) (xy 353.045452 -282.495825) (xy 352.996089 -282.503644) (xy 352.946111 -282.503644)
			(xy 352.896748 -282.495825) (xy 352.849216 -282.480381) (xy 352.804684 -282.457691) (xy 352.764251 -282.428315)
			(xy 352.728911 -282.392975) (xy 352.699535 -282.352542) (xy 352.676845 -282.30801) (xy 352.661401 -282.260478)
			(xy 352.653582 -282.211115) (xy 352.348564 -282.211115) (xy 352.340745 -282.260478) (xy 352.325301 -282.30801)
			(xy 352.302611 -282.352542) (xy 352.273235 -282.392975) (xy 352.237895 -282.428315) (xy 352.197462 -282.457691)
			(xy 352.15293 -282.480381) (xy 352.105398 -282.495825) (xy 352.056035 -282.503644) (xy 352.006057 -282.503644)
			(xy 351.956694 -282.495825) (xy 351.909162 -282.480381) (xy 351.86463 -282.457691) (xy 351.824197 -282.428315)
			(xy 351.788857 -282.392975) (xy 351.759481 -282.352542) (xy 351.736791 -282.30801) (xy 351.721347 -282.260478)
			(xy 351.713528 -282.211115) (xy 351.408764 -282.211115) (xy 351.400945 -282.260478) (xy 351.385501 -282.30801)
			(xy 351.362811 -282.352542) (xy 351.333435 -282.392975) (xy 351.298095 -282.428315) (xy 351.257662 -282.457691)
			(xy 351.21313 -282.480381) (xy 351.165598 -282.495825) (xy 351.116235 -282.503644) (xy 351.066257 -282.503644)
			(xy 351.016894 -282.495825) (xy 350.969362 -282.480381) (xy 350.92483 -282.457691) (xy 350.884397 -282.428315)
			(xy 350.849057 -282.392975) (xy 350.819681 -282.352542) (xy 350.796991 -282.30801) (xy 350.781547 -282.260478)
			(xy 350.773728 -282.211115) (xy 350.46871 -282.211115) (xy 350.460891 -282.260478) (xy 350.445447 -282.30801)
			(xy 350.422757 -282.352542) (xy 350.393381 -282.392975) (xy 350.358041 -282.428315) (xy 350.317608 -282.457691)
			(xy 350.273076 -282.480381) (xy 350.225544 -282.495825) (xy 350.176181 -282.503644) (xy 350.126203 -282.503644)
			(xy 350.07684 -282.495825) (xy 350.029308 -282.480381) (xy 349.984776 -282.457691) (xy 349.944343 -282.428315)
			(xy 349.909003 -282.392975) (xy 349.879627 -282.352542) (xy 349.856937 -282.30801) (xy 349.841493 -282.260478)
			(xy 349.833674 -282.211115) (xy 349.528656 -282.211115) (xy 349.520837 -282.260478) (xy 349.505393 -282.30801)
			(xy 349.482703 -282.352542) (xy 349.453327 -282.392975) (xy 349.417987 -282.428315) (xy 349.377554 -282.457691)
			(xy 349.333022 -282.480381) (xy 349.28549 -282.495825) (xy 349.236127 -282.503644) (xy 349.186149 -282.503644)
			(xy 349.136786 -282.495825) (xy 349.089254 -282.480381) (xy 349.044722 -282.457691) (xy 349.004289 -282.428315)
			(xy 348.968949 -282.392975) (xy 348.939573 -282.352542) (xy 348.916883 -282.30801) (xy 348.901439 -282.260478)
			(xy 348.89362 -282.211115) (xy 348.588602 -282.211115) (xy 348.580783 -282.260478) (xy 348.565339 -282.30801)
			(xy 348.542649 -282.352542) (xy 348.513273 -282.392975) (xy 348.477933 -282.428315) (xy 348.4375 -282.457691)
			(xy 348.392968 -282.480381) (xy 348.345436 -282.495825) (xy 348.296073 -282.503644) (xy 348.246095 -282.503644)
			(xy 348.196732 -282.495825) (xy 348.1492 -282.480381) (xy 348.104668 -282.457691) (xy 348.064235 -282.428315)
			(xy 348.028895 -282.392975) (xy 347.999519 -282.352542) (xy 347.976829 -282.30801) (xy 347.961385 -282.260478)
			(xy 347.953566 -282.211115) (xy 347.648548 -282.211115) (xy 347.640729 -282.260478) (xy 347.625285 -282.30801)
			(xy 347.602595 -282.352542) (xy 347.573219 -282.392975) (xy 347.537879 -282.428315) (xy 347.497446 -282.457691)
			(xy 347.452914 -282.480381) (xy 347.405382 -282.495825) (xy 347.356019 -282.503644) (xy 347.306041 -282.503644)
			(xy 347.256678 -282.495825) (xy 347.209146 -282.480381) (xy 347.164614 -282.457691) (xy 347.124181 -282.428315)
			(xy 347.088841 -282.392975) (xy 347.059465 -282.352542) (xy 347.036775 -282.30801) (xy 347.021331 -282.260478)
			(xy 347.013512 -282.211115) (xy 346.708748 -282.211115) (xy 346.700929 -282.260478) (xy 346.685485 -282.30801)
			(xy 346.662795 -282.352542) (xy 346.633419 -282.392975) (xy 346.598079 -282.428315) (xy 346.557646 -282.457691)
			(xy 346.513114 -282.480381) (xy 346.465582 -282.495825) (xy 346.416219 -282.503644) (xy 346.366241 -282.503644)
			(xy 346.316878 -282.495825) (xy 346.269346 -282.480381) (xy 346.224814 -282.457691) (xy 346.184381 -282.428315)
			(xy 346.149041 -282.392975) (xy 346.119665 -282.352542) (xy 346.096975 -282.30801) (xy 346.081531 -282.260478)
			(xy 346.073712 -282.211115) (xy 345.768713 -282.211115) (xy 345.760898 -282.260456) (xy 345.745452 -282.30799)
			(xy 345.722761 -282.352522) (xy 345.693382 -282.392957) (xy 345.658039 -282.428297) (xy 345.617602 -282.457673)
			(xy 345.573068 -282.480362) (xy 345.525532 -282.495804) (xy 345.476166 -282.503619) (xy 345.451176 -282.504134)
			(xy 345.427298 -282.503706) (xy 345.380079 -282.496571) (xy 345.334454 -282.482464) (xy 345.291447 -282.461703)
			(xy 345.252023 -282.434753) (xy 345.23426 -282.41879) (xy 345.228659 -282.413919) (xy 345.215369 -282.407325)
			(xy 345.208098 -282.405836) (xy 345.20124 -282.404566) (xy 345.186508 -282.406344) (xy 345.14155 -282.425902)
			(xy 345.096338 -282.445714) (xy 345.087509 -282.450074) (xy 345.073769 -282.464154) (xy 345.066316 -282.482361)
			(xy 345.065858 -282.492196) (xy 345.065858 -282.653486) (xy 345.065858 -282.654756) (xy 345.066521 -282.664143)
			(xy 345.073739 -282.681502) (xy 345.086737 -282.695085) (xy 345.095068 -282.69946) (xy 345.097862 -282.700476)
			(xy 345.120569 -282.709928) (xy 345.162995 -282.734807) (xy 345.201083 -282.765924) (xy 345.233924 -282.802535)
			(xy 345.260735 -282.843767) (xy 345.280876 -282.888637) (xy 345.293866 -282.936073) (xy 345.299396 -282.984943)
			(xy 345.298926 -282.996132) (xy 345.604841 -282.996132) (xy 345.608936 -282.945404) (xy 345.621115 -282.89599)
			(xy 345.641063 -282.84917) (xy 345.668264 -282.806156) (xy 345.702012 -282.768062) (xy 345.741434 -282.735875)
			(xy 345.785508 -282.710429) (xy 345.833094 -282.692382) (xy 345.882958 -282.682202) (xy 345.93381 -282.680153)
			(xy 345.984331 -282.686287) (xy 346.033215 -282.700447) (xy 346.079194 -282.722264) (xy 346.121078 -282.751174)
			(xy 346.157782 -282.786429) (xy 346.188355 -282.827115) (xy 346.212006 -282.872178) (xy 346.228122 -282.920452)
			(xy 346.236286 -282.970686) (xy 346.236798 -282.996132) (xy 346.544895 -282.996132) (xy 346.54899 -282.945404)
			(xy 346.561169 -282.89599) (xy 346.581117 -282.84917) (xy 346.608318 -282.806156) (xy 346.642066 -282.768062)
			(xy 346.681488 -282.735875) (xy 346.725562 -282.710429) (xy 346.773148 -282.692382) (xy 346.823012 -282.682202)
			(xy 346.873864 -282.680153) (xy 346.924385 -282.686287) (xy 346.973269 -282.700447) (xy 347.019248 -282.722264)
			(xy 347.061132 -282.751174) (xy 347.097836 -282.786429) (xy 347.128409 -282.827115) (xy 347.15206 -282.872178)
			(xy 347.168176 -282.920452) (xy 347.17634 -282.970686) (xy 347.176852 -282.996132) (xy 347.176349 -283.021121)
			(xy 347.483666 -283.021121) (xy 347.483666 -282.971143) (xy 347.491485 -282.92178) (xy 347.506929 -282.874248)
			(xy 347.529619 -282.829716) (xy 347.558995 -282.789283) (xy 347.594335 -282.753943) (xy 347.634768 -282.724567)
			(xy 347.6793 -282.701877) (xy 347.726832 -282.686433) (xy 347.776195 -282.678614) (xy 347.826173 -282.678614)
			(xy 347.875536 -282.686433) (xy 347.923068 -282.701877) (xy 347.9676 -282.724567) (xy 348.008033 -282.753943)
			(xy 348.043373 -282.789283) (xy 348.072749 -282.829716) (xy 348.095439 -282.874248) (xy 348.110883 -282.92178)
			(xy 348.118702 -282.971143) (xy 348.119192 -282.996132) (xy 348.425003 -282.996132) (xy 348.429098 -282.945404)
			(xy 348.441277 -282.89599) (xy 348.461225 -282.84917) (xy 348.488426 -282.806156) (xy 348.522174 -282.768062)
			(xy 348.561596 -282.735875) (xy 348.60567 -282.710429) (xy 348.653256 -282.692382) (xy 348.70312 -282.682202)
			(xy 348.753972 -282.680153) (xy 348.804493 -282.686287) (xy 348.853377 -282.700447) (xy 348.899356 -282.722264)
			(xy 348.94124 -282.751174) (xy 348.977944 -282.786429) (xy 349.008517 -282.827115) (xy 349.032168 -282.872178)
			(xy 349.048284 -282.920452) (xy 349.056448 -282.970686) (xy 349.05696 -282.996132) (xy 349.364803 -282.996132)
			(xy 349.368898 -282.945404) (xy 349.381077 -282.89599) (xy 349.401025 -282.84917) (xy 349.428226 -282.806156)
			(xy 349.461974 -282.768062) (xy 349.501396 -282.735875) (xy 349.54547 -282.710429) (xy 349.593056 -282.692382)
			(xy 349.64292 -282.682202) (xy 349.693772 -282.680153) (xy 349.744293 -282.686287) (xy 349.793177 -282.700447)
			(xy 349.839156 -282.722264) (xy 349.88104 -282.751174) (xy 349.917744 -282.786429) (xy 349.948317 -282.827115)
			(xy 349.971968 -282.872178) (xy 349.988084 -282.920452) (xy 349.996248 -282.970686) (xy 349.99676 -282.996132)
			(xy 349.996257 -283.021121) (xy 350.303574 -283.021121) (xy 350.303574 -282.971143) (xy 350.311393 -282.92178)
			(xy 350.326837 -282.874248) (xy 350.349527 -282.829716) (xy 350.378903 -282.789283) (xy 350.414243 -282.753943)
			(xy 350.454676 -282.724567) (xy 350.499208 -282.701877) (xy 350.54674 -282.686433) (xy 350.596103 -282.678614)
			(xy 350.646081 -282.678614) (xy 350.695444 -282.686433) (xy 350.742976 -282.701877) (xy 350.787508 -282.724567)
			(xy 350.827941 -282.753943) (xy 350.863281 -282.789283) (xy 350.892657 -282.829716) (xy 350.915347 -282.874248)
			(xy 350.930791 -282.92178) (xy 350.93861 -282.971143) (xy 350.9391 -282.996132) (xy 351.244911 -282.996132)
			(xy 351.249006 -282.945404) (xy 351.261185 -282.89599) (xy 351.281133 -282.84917) (xy 351.308334 -282.806156)
			(xy 351.342082 -282.768062) (xy 351.381504 -282.735875) (xy 351.425578 -282.710429) (xy 351.473164 -282.692382)
			(xy 351.523028 -282.682202) (xy 351.57388 -282.680153) (xy 351.624401 -282.686287) (xy 351.673285 -282.700447)
			(xy 351.719264 -282.722264) (xy 351.761148 -282.751174) (xy 351.797852 -282.786429) (xy 351.828425 -282.827115)
			(xy 351.852076 -282.872178) (xy 351.868192 -282.920452) (xy 351.876356 -282.970686) (xy 351.876868 -282.996132)
			(xy 352.184965 -282.996132) (xy 352.18906 -282.945404) (xy 352.201239 -282.89599) (xy 352.221187 -282.84917)
			(xy 352.248388 -282.806156) (xy 352.282136 -282.768062) (xy 352.321558 -282.735875) (xy 352.365632 -282.710429)
			(xy 352.413218 -282.692382) (xy 352.463082 -282.682202) (xy 352.513934 -282.680153) (xy 352.564455 -282.686287)
			(xy 352.613339 -282.700447) (xy 352.659318 -282.722264) (xy 352.701202 -282.751174) (xy 352.737906 -282.786429)
			(xy 352.768479 -282.827115) (xy 352.79213 -282.872178) (xy 352.808246 -282.920452) (xy 352.81641 -282.970686)
			(xy 352.816922 -282.996132) (xy 352.816419 -283.021121) (xy 353.123482 -283.021121) (xy 353.123482 -282.971143)
			(xy 353.131301 -282.92178) (xy 353.146745 -282.874248) (xy 353.169435 -282.829716) (xy 353.198811 -282.789283)
			(xy 353.234151 -282.753943) (xy 353.274584 -282.724567) (xy 353.319116 -282.701877) (xy 353.366648 -282.686433)
			(xy 353.416011 -282.678614) (xy 353.465989 -282.678614) (xy 353.515352 -282.686433) (xy 353.562884 -282.701877)
			(xy 353.607416 -282.724567) (xy 353.647849 -282.753943) (xy 353.683189 -282.789283) (xy 353.712565 -282.829716)
			(xy 353.735255 -282.874248) (xy 353.750699 -282.92178) (xy 353.758518 -282.971143) (xy 353.759008 -282.996132)
			(xy 354.064819 -282.996132) (xy 354.068914 -282.945404) (xy 354.081093 -282.89599) (xy 354.101041 -282.84917)
			(xy 354.128242 -282.806156) (xy 354.16199 -282.768062) (xy 354.201412 -282.735875) (xy 354.245486 -282.710429)
			(xy 354.293072 -282.692382) (xy 354.342936 -282.682202) (xy 354.393788 -282.680153) (xy 354.444309 -282.686287)
			(xy 354.493193 -282.700447) (xy 354.539172 -282.722264) (xy 354.581056 -282.751174) (xy 354.61776 -282.786429)
			(xy 354.648333 -282.827115) (xy 354.671984 -282.872178) (xy 354.6881 -282.920452) (xy 354.696264 -282.970686)
			(xy 354.696776 -282.996132) (xy 355.004873 -282.996132) (xy 355.008968 -282.945404) (xy 355.021147 -282.89599)
			(xy 355.041095 -282.84917) (xy 355.068296 -282.806156) (xy 355.102044 -282.768062) (xy 355.141466 -282.735875)
			(xy 355.18554 -282.710429) (xy 355.233126 -282.692382) (xy 355.28299 -282.682202) (xy 355.333842 -282.680153)
			(xy 355.384363 -282.686287) (xy 355.433247 -282.700447) (xy 355.479226 -282.722264) (xy 355.52111 -282.751174)
			(xy 355.557814 -282.786429) (xy 355.588387 -282.827115) (xy 355.612038 -282.872178) (xy 355.628154 -282.920452)
			(xy 355.636318 -282.970686) (xy 355.63683 -282.996132) (xy 355.636327 -283.021121) (xy 355.943644 -283.021121)
			(xy 355.943644 -282.971143) (xy 355.951463 -282.92178) (xy 355.966907 -282.874248) (xy 355.989597 -282.829716)
			(xy 356.018973 -282.789283) (xy 356.054313 -282.753943) (xy 356.094746 -282.724567) (xy 356.139278 -282.701877)
			(xy 356.18681 -282.686433) (xy 356.236173 -282.678614) (xy 356.286151 -282.678614) (xy 356.335514 -282.686433)
			(xy 356.383046 -282.701877) (xy 356.427578 -282.724567) (xy 356.468011 -282.753943) (xy 356.503351 -282.789283)
			(xy 356.532727 -282.829716) (xy 356.555417 -282.874248) (xy 356.570861 -282.92178) (xy 356.57868 -282.971143)
			(xy 356.57917 -282.996132) (xy 356.57868 -283.021121) (xy 363.457218 -283.021121) (xy 363.457218 -282.971143)
			(xy 363.465037 -282.92178) (xy 363.480481 -282.874248) (xy 363.503171 -282.829716) (xy 363.532547 -282.789283)
			(xy 363.567887 -282.753943) (xy 363.60832 -282.724567) (xy 363.652852 -282.701877) (xy 363.700384 -282.686433)
			(xy 363.749747 -282.678614) (xy 363.799725 -282.678614) (xy 363.849088 -282.686433) (xy 363.89662 -282.701877)
			(xy 363.941152 -282.724567) (xy 363.981585 -282.753943) (xy 364.016925 -282.789283) (xy 364.046301 -282.829716)
			(xy 364.068991 -282.874248) (xy 364.084435 -282.92178) (xy 364.092254 -282.971143) (xy 364.092744 -282.996132)
			(xy 364.398555 -282.996132) (xy 364.40265 -282.945404) (xy 364.414829 -282.89599) (xy 364.434777 -282.84917)
			(xy 364.461978 -282.806156) (xy 364.495726 -282.768062) (xy 364.535148 -282.735875) (xy 364.579222 -282.710429)
			(xy 364.626808 -282.692382) (xy 364.676672 -282.682202) (xy 364.727524 -282.680153) (xy 364.778045 -282.686287)
			(xy 364.826929 -282.700447) (xy 364.872908 -282.722264) (xy 364.914792 -282.751174) (xy 364.951496 -282.786429)
			(xy 364.982069 -282.827115) (xy 365.00572 -282.872178) (xy 365.021836 -282.920452) (xy 365.03 -282.970686)
			(xy 365.030512 -282.996132) (xy 365.338609 -282.996132) (xy 365.342704 -282.945404) (xy 365.354883 -282.89599)
			(xy 365.374831 -282.84917) (xy 365.402032 -282.806156) (xy 365.43578 -282.768062) (xy 365.475202 -282.735875)
			(xy 365.519276 -282.710429) (xy 365.566862 -282.692382) (xy 365.616726 -282.682202) (xy 365.667578 -282.680153)
			(xy 365.718099 -282.686287) (xy 365.766983 -282.700447) (xy 365.812962 -282.722264) (xy 365.854846 -282.751174)
			(xy 365.89155 -282.786429) (xy 365.922123 -282.827115) (xy 365.945774 -282.872178) (xy 365.96189 -282.920452)
			(xy 365.970054 -282.970686) (xy 365.970566 -282.996132) (xy 365.970063 -283.021121) (xy 366.27738 -283.021121)
			(xy 366.27738 -282.971143) (xy 366.285199 -282.92178) (xy 366.300643 -282.874248) (xy 366.323333 -282.829716)
			(xy 366.352709 -282.789283) (xy 366.388049 -282.753943) (xy 366.428482 -282.724567) (xy 366.473014 -282.701877)
			(xy 366.520546 -282.686433) (xy 366.569909 -282.678614) (xy 366.619887 -282.678614) (xy 366.66925 -282.686433)
			(xy 366.716782 -282.701877) (xy 366.761314 -282.724567) (xy 366.801747 -282.753943) (xy 366.837087 -282.789283)
			(xy 366.866463 -282.829716) (xy 366.889153 -282.874248) (xy 366.904597 -282.92178) (xy 366.912416 -282.971143)
			(xy 366.912906 -282.996132) (xy 367.218463 -282.996132) (xy 367.222558 -282.945404) (xy 367.234737 -282.89599)
			(xy 367.254685 -282.84917) (xy 367.281886 -282.806156) (xy 367.315634 -282.768062) (xy 367.355056 -282.735875)
			(xy 367.39913 -282.710429) (xy 367.446716 -282.692382) (xy 367.49658 -282.682202) (xy 367.547432 -282.680153)
			(xy 367.597953 -282.686287) (xy 367.646837 -282.700447) (xy 367.692816 -282.722264) (xy 367.7347 -282.751174)
			(xy 367.771404 -282.786429) (xy 367.801977 -282.827115) (xy 367.825628 -282.872178) (xy 367.841744 -282.920452)
			(xy 367.849908 -282.970686) (xy 367.85042 -282.996132) (xy 368.158517 -282.996132) (xy 368.162612 -282.945404)
			(xy 368.174791 -282.89599) (xy 368.194739 -282.84917) (xy 368.22194 -282.806156) (xy 368.255688 -282.768062)
			(xy 368.29511 -282.735875) (xy 368.339184 -282.710429) (xy 368.38677 -282.692382) (xy 368.436634 -282.682202)
			(xy 368.487486 -282.680153) (xy 368.538007 -282.686287) (xy 368.586891 -282.700447) (xy 368.63287 -282.722264)
			(xy 368.674754 -282.751174) (xy 368.711458 -282.786429) (xy 368.742031 -282.827115) (xy 368.765682 -282.872178)
			(xy 368.781798 -282.920452) (xy 368.789962 -282.970686) (xy 368.790474 -282.996132) (xy 368.789971 -283.021121)
			(xy 369.097288 -283.021121) (xy 369.097288 -282.971143) (xy 369.105107 -282.92178) (xy 369.120551 -282.874248)
			(xy 369.143241 -282.829716) (xy 369.172617 -282.789283) (xy 369.207957 -282.753943) (xy 369.24839 -282.724567)
			(xy 369.292922 -282.701877) (xy 369.340454 -282.686433) (xy 369.389817 -282.678614) (xy 369.439795 -282.678614)
			(xy 369.489158 -282.686433) (xy 369.53669 -282.701877) (xy 369.581222 -282.724567) (xy 369.621655 -282.753943)
			(xy 369.656995 -282.789283) (xy 369.686371 -282.829716) (xy 369.709061 -282.874248) (xy 369.724505 -282.92178)
			(xy 369.732324 -282.971143) (xy 369.732814 -282.996132) (xy 370.038625 -282.996132) (xy 370.04272 -282.945404)
			(xy 370.054899 -282.89599) (xy 370.074847 -282.84917) (xy 370.102048 -282.806156) (xy 370.135796 -282.768062)
			(xy 370.175218 -282.735875) (xy 370.219292 -282.710429) (xy 370.266878 -282.692382) (xy 370.316742 -282.682202)
			(xy 370.367594 -282.680153) (xy 370.418115 -282.686287) (xy 370.466999 -282.700447) (xy 370.512978 -282.722264)
			(xy 370.554862 -282.751174) (xy 370.591566 -282.786429) (xy 370.622139 -282.827115) (xy 370.64579 -282.872178)
			(xy 370.661906 -282.920452) (xy 370.67007 -282.970686) (xy 370.670582 -282.996132) (xy 370.978679 -282.996132)
			(xy 370.982774 -282.945404) (xy 370.994953 -282.89599) (xy 371.014901 -282.84917) (xy 371.042102 -282.806156)
			(xy 371.07585 -282.768062) (xy 371.115272 -282.735875) (xy 371.159346 -282.710429) (xy 371.206932 -282.692382)
			(xy 371.256796 -282.682202) (xy 371.307648 -282.680153) (xy 371.358169 -282.686287) (xy 371.407053 -282.700447)
			(xy 371.453032 -282.722264) (xy 371.494916 -282.751174) (xy 371.53162 -282.786429) (xy 371.562193 -282.827115)
			(xy 371.585844 -282.872178) (xy 371.60196 -282.920452) (xy 371.610124 -282.970686) (xy 371.610636 -282.996132)
			(xy 371.610133 -283.021121) (xy 371.917196 -283.021121) (xy 371.917196 -282.971143) (xy 371.925015 -282.92178)
			(xy 371.940459 -282.874248) (xy 371.963149 -282.829716) (xy 371.992525 -282.789283) (xy 372.027865 -282.753943)
			(xy 372.068298 -282.724567) (xy 372.11283 -282.701877) (xy 372.160362 -282.686433) (xy 372.209725 -282.678614)
			(xy 372.259703 -282.678614) (xy 372.309066 -282.686433) (xy 372.356598 -282.701877) (xy 372.40113 -282.724567)
			(xy 372.441563 -282.753943) (xy 372.476903 -282.789283) (xy 372.506279 -282.829716) (xy 372.528969 -282.874248)
			(xy 372.544413 -282.92178) (xy 372.552232 -282.971143) (xy 372.552722 -282.996132) (xy 372.858533 -282.996132)
			(xy 372.862628 -282.945404) (xy 372.874807 -282.89599) (xy 372.894755 -282.84917) (xy 372.921956 -282.806156)
			(xy 372.955704 -282.768062) (xy 372.995126 -282.735875) (xy 373.0392 -282.710429) (xy 373.086786 -282.692382)
			(xy 373.13665 -282.682202) (xy 373.187502 -282.680153) (xy 373.238023 -282.686287) (xy 373.286907 -282.700447)
			(xy 373.332886 -282.722264) (xy 373.37477 -282.751174) (xy 373.411474 -282.786429) (xy 373.442047 -282.827115)
			(xy 373.465698 -282.872178) (xy 373.481814 -282.920452) (xy 373.489978 -282.970686) (xy 373.49049 -282.996132)
			(xy 373.798587 -282.996132) (xy 373.802682 -282.945404) (xy 373.814861 -282.89599) (xy 373.834809 -282.84917)
			(xy 373.86201 -282.806156) (xy 373.895758 -282.768062) (xy 373.93518 -282.735875) (xy 373.979254 -282.710429)
			(xy 374.02684 -282.692382) (xy 374.076704 -282.682202) (xy 374.127556 -282.680153) (xy 374.178077 -282.686287)
			(xy 374.226961 -282.700447) (xy 374.27294 -282.722264) (xy 374.314824 -282.751174) (xy 374.351528 -282.786429)
			(xy 374.382101 -282.827115) (xy 374.405752 -282.872178) (xy 374.421868 -282.920452) (xy 374.430032 -282.970686)
			(xy 374.430544 -282.996132) (xy 374.430032 -283.021578) (xy 374.421868 -283.071812) (xy 374.405752 -283.120086)
			(xy 374.382101 -283.165149) (xy 374.351528 -283.205835) (xy 374.314824 -283.24109) (xy 374.27294 -283.27)
			(xy 374.226961 -283.291817) (xy 374.178077 -283.305977) (xy 374.127556 -283.312111) (xy 374.076704 -283.310062)
			(xy 374.02684 -283.299882) (xy 373.979254 -283.281835) (xy 373.93518 -283.256389) (xy 373.895758 -283.224202)
			(xy 373.86201 -283.186108) (xy 373.834809 -283.143094) (xy 373.814861 -283.096274) (xy 373.802682 -283.04686)
			(xy 373.798587 -282.996132) (xy 373.49049 -282.996132) (xy 373.489978 -283.021578) (xy 373.481814 -283.071812)
			(xy 373.465698 -283.120086) (xy 373.442047 -283.165149) (xy 373.411474 -283.205835) (xy 373.37477 -283.24109)
			(xy 373.332886 -283.27) (xy 373.286907 -283.291817) (xy 373.238023 -283.305977) (xy 373.187502 -283.312111)
			(xy 373.13665 -283.310062) (xy 373.086786 -283.299882) (xy 373.0392 -283.281835) (xy 372.995126 -283.256389)
			(xy 372.955704 -283.224202) (xy 372.921956 -283.186108) (xy 372.894755 -283.143094) (xy 372.874807 -283.096274)
			(xy 372.862628 -283.04686) (xy 372.858533 -282.996132) (xy 372.552722 -282.996132) (xy 372.552232 -283.021121)
			(xy 372.544413 -283.070484) (xy 372.528969 -283.118016) (xy 372.506279 -283.162548) (xy 372.476903 -283.202981)
			(xy 372.441563 -283.238321) (xy 372.40113 -283.267697) (xy 372.356598 -283.290387) (xy 372.309066 -283.305831)
			(xy 372.259703 -283.31365) (xy 372.209725 -283.31365) (xy 372.160362 -283.305831) (xy 372.11283 -283.290387)
			(xy 372.068298 -283.267697) (xy 372.027865 -283.238321) (xy 371.992525 -283.202981) (xy 371.963149 -283.162548)
			(xy 371.940459 -283.118016) (xy 371.925015 -283.070484) (xy 371.917196 -283.021121) (xy 371.610133 -283.021121)
			(xy 371.610124 -283.021578) (xy 371.60196 -283.071812) (xy 371.585844 -283.120086) (xy 371.562193 -283.165149)
			(xy 371.53162 -283.205835) (xy 371.494916 -283.24109) (xy 371.453032 -283.27) (xy 371.407053 -283.291817)
			(xy 371.358169 -283.305977) (xy 371.307648 -283.312111) (xy 371.256796 -283.310062) (xy 371.206932 -283.299882)
			(xy 371.159346 -283.281835) (xy 371.115272 -283.256389) (xy 371.07585 -283.224202) (xy 371.042102 -283.186108)
			(xy 371.014901 -283.143094) (xy 370.994953 -283.096274) (xy 370.982774 -283.04686) (xy 370.978679 -282.996132)
			(xy 370.670582 -282.996132) (xy 370.67007 -283.021578) (xy 370.661906 -283.071812) (xy 370.64579 -283.120086)
			(xy 370.622139 -283.165149) (xy 370.591566 -283.205835) (xy 370.554862 -283.24109) (xy 370.512978 -283.27)
			(xy 370.466999 -283.291817) (xy 370.418115 -283.305977) (xy 370.367594 -283.312111) (xy 370.316742 -283.310062)
			(xy 370.266878 -283.299882) (xy 370.219292 -283.281835) (xy 370.175218 -283.256389) (xy 370.135796 -283.224202)
			(xy 370.102048 -283.186108) (xy 370.074847 -283.143094) (xy 370.054899 -283.096274) (xy 370.04272 -283.04686)
			(xy 370.038625 -282.996132) (xy 369.732814 -282.996132) (xy 369.732324 -283.021121) (xy 369.724505 -283.070484)
			(xy 369.709061 -283.118016) (xy 369.686371 -283.162548) (xy 369.656995 -283.202981) (xy 369.621655 -283.238321)
			(xy 369.581222 -283.267697) (xy 369.53669 -283.290387) (xy 369.489158 -283.305831) (xy 369.439795 -283.31365)
			(xy 369.389817 -283.31365) (xy 369.340454 -283.305831) (xy 369.292922 -283.290387) (xy 369.24839 -283.267697)
			(xy 369.207957 -283.238321) (xy 369.172617 -283.202981) (xy 369.143241 -283.162548) (xy 369.120551 -283.118016)
			(xy 369.105107 -283.070484) (xy 369.097288 -283.021121) (xy 368.789971 -283.021121) (xy 368.789962 -283.021578)
			(xy 368.781798 -283.071812) (xy 368.765682 -283.120086) (xy 368.742031 -283.165149) (xy 368.711458 -283.205835)
			(xy 368.674754 -283.24109) (xy 368.63287 -283.27) (xy 368.586891 -283.291817) (xy 368.538007 -283.305977)
			(xy 368.487486 -283.312111) (xy 368.436634 -283.310062) (xy 368.38677 -283.299882) (xy 368.339184 -283.281835)
			(xy 368.29511 -283.256389) (xy 368.255688 -283.224202) (xy 368.22194 -283.186108) (xy 368.194739 -283.143094)
			(xy 368.174791 -283.096274) (xy 368.162612 -283.04686) (xy 368.158517 -282.996132) (xy 367.85042 -282.996132)
			(xy 367.849908 -283.021578) (xy 367.841744 -283.071812) (xy 367.825628 -283.120086) (xy 367.801977 -283.165149)
			(xy 367.771404 -283.205835) (xy 367.7347 -283.24109) (xy 367.692816 -283.27) (xy 367.646837 -283.291817)
			(xy 367.597953 -283.305977) (xy 367.547432 -283.312111) (xy 367.49658 -283.310062) (xy 367.446716 -283.299882)
			(xy 367.39913 -283.281835) (xy 367.355056 -283.256389) (xy 367.315634 -283.224202) (xy 367.281886 -283.186108)
			(xy 367.254685 -283.143094) (xy 367.234737 -283.096274) (xy 367.222558 -283.04686) (xy 367.218463 -282.996132)
			(xy 366.912906 -282.996132) (xy 366.912416 -283.021121) (xy 366.904597 -283.070484) (xy 366.889153 -283.118016)
			(xy 366.866463 -283.162548) (xy 366.837087 -283.202981) (xy 366.801747 -283.238321) (xy 366.761314 -283.267697)
			(xy 366.716782 -283.290387) (xy 366.66925 -283.305831) (xy 366.619887 -283.31365) (xy 366.569909 -283.31365)
			(xy 366.520546 -283.305831) (xy 366.473014 -283.290387) (xy 366.428482 -283.267697) (xy 366.388049 -283.238321)
			(xy 366.352709 -283.202981) (xy 366.323333 -283.162548) (xy 366.300643 -283.118016) (xy 366.285199 -283.070484)
			(xy 366.27738 -283.021121) (xy 365.970063 -283.021121) (xy 365.970054 -283.021578) (xy 365.96189 -283.071812)
			(xy 365.945774 -283.120086) (xy 365.922123 -283.165149) (xy 365.89155 -283.205835) (xy 365.854846 -283.24109)
			(xy 365.812962 -283.27) (xy 365.766983 -283.291817) (xy 365.718099 -283.305977) (xy 365.667578 -283.312111)
			(xy 365.616726 -283.310062) (xy 365.566862 -283.299882) (xy 365.519276 -283.281835) (xy 365.475202 -283.256389)
			(xy 365.43578 -283.224202) (xy 365.402032 -283.186108) (xy 365.374831 -283.143094) (xy 365.354883 -283.096274)
			(xy 365.342704 -283.04686) (xy 365.338609 -282.996132) (xy 365.030512 -282.996132) (xy 365.03 -283.021578)
			(xy 365.021836 -283.071812) (xy 365.00572 -283.120086) (xy 364.982069 -283.165149) (xy 364.951496 -283.205835)
			(xy 364.914792 -283.24109) (xy 364.872908 -283.27) (xy 364.826929 -283.291817) (xy 364.778045 -283.305977)
			(xy 364.727524 -283.312111) (xy 364.676672 -283.310062) (xy 364.626808 -283.299882) (xy 364.579222 -283.281835)
			(xy 364.535148 -283.256389) (xy 364.495726 -283.224202) (xy 364.461978 -283.186108) (xy 364.434777 -283.143094)
			(xy 364.414829 -283.096274) (xy 364.40265 -283.04686) (xy 364.398555 -282.996132) (xy 364.092744 -282.996132)
			(xy 364.092254 -283.021121) (xy 364.084435 -283.070484) (xy 364.068991 -283.118016) (xy 364.046301 -283.162548)
			(xy 364.016925 -283.202981) (xy 363.981585 -283.238321) (xy 363.941152 -283.267697) (xy 363.89662 -283.290387)
			(xy 363.849088 -283.305831) (xy 363.799725 -283.31365) (xy 363.749747 -283.31365) (xy 363.700384 -283.305831)
			(xy 363.652852 -283.290387) (xy 363.60832 -283.267697) (xy 363.567887 -283.238321) (xy 363.532547 -283.202981)
			(xy 363.503171 -283.162548) (xy 363.480481 -283.118016) (xy 363.465037 -283.070484) (xy 363.457218 -283.021121)
			(xy 356.57868 -283.021121) (xy 356.570861 -283.070484) (xy 356.555417 -283.118016) (xy 356.532727 -283.162548)
			(xy 356.503351 -283.202981) (xy 356.468011 -283.238321) (xy 356.427578 -283.267697) (xy 356.383046 -283.290387)
			(xy 356.335514 -283.305831) (xy 356.286151 -283.31365) (xy 356.236173 -283.31365) (xy 356.18681 -283.305831)
			(xy 356.139278 -283.290387) (xy 356.094746 -283.267697) (xy 356.054313 -283.238321) (xy 356.018973 -283.202981)
			(xy 355.989597 -283.162548) (xy 355.966907 -283.118016) (xy 355.951463 -283.070484) (xy 355.943644 -283.021121)
			(xy 355.636327 -283.021121) (xy 355.636318 -283.021578) (xy 355.628154 -283.071812) (xy 355.612038 -283.120086)
			(xy 355.588387 -283.165149) (xy 355.557814 -283.205835) (xy 355.52111 -283.24109) (xy 355.479226 -283.27)
			(xy 355.433247 -283.291817) (xy 355.384363 -283.305977) (xy 355.333842 -283.312111) (xy 355.28299 -283.310062)
			(xy 355.233126 -283.299882) (xy 355.18554 -283.281835) (xy 355.141466 -283.256389) (xy 355.102044 -283.224202)
			(xy 355.068296 -283.186108) (xy 355.041095 -283.143094) (xy 355.021147 -283.096274) (xy 355.008968 -283.04686)
			(xy 355.004873 -282.996132) (xy 354.696776 -282.996132) (xy 354.696264 -283.021578) (xy 354.6881 -283.071812)
			(xy 354.671984 -283.120086) (xy 354.648333 -283.165149) (xy 354.61776 -283.205835) (xy 354.581056 -283.24109)
			(xy 354.539172 -283.27) (xy 354.493193 -283.291817) (xy 354.444309 -283.305977) (xy 354.393788 -283.312111)
			(xy 354.342936 -283.310062) (xy 354.293072 -283.299882) (xy 354.245486 -283.281835) (xy 354.201412 -283.256389)
			(xy 354.16199 -283.224202) (xy 354.128242 -283.186108) (xy 354.101041 -283.143094) (xy 354.081093 -283.096274)
			(xy 354.068914 -283.04686) (xy 354.064819 -282.996132) (xy 353.759008 -282.996132) (xy 353.758518 -283.021121)
			(xy 353.750699 -283.070484) (xy 353.735255 -283.118016) (xy 353.712565 -283.162548) (xy 353.683189 -283.202981)
			(xy 353.647849 -283.238321) (xy 353.607416 -283.267697) (xy 353.562884 -283.290387) (xy 353.515352 -283.305831)
			(xy 353.465989 -283.31365) (xy 353.416011 -283.31365) (xy 353.366648 -283.305831) (xy 353.319116 -283.290387)
			(xy 353.274584 -283.267697) (xy 353.234151 -283.238321) (xy 353.198811 -283.202981) (xy 353.169435 -283.162548)
			(xy 353.146745 -283.118016) (xy 353.131301 -283.070484) (xy 353.123482 -283.021121) (xy 352.816419 -283.021121)
			(xy 352.81641 -283.021578) (xy 352.808246 -283.071812) (xy 352.79213 -283.120086) (xy 352.768479 -283.165149)
			(xy 352.737906 -283.205835) (xy 352.701202 -283.24109) (xy 352.659318 -283.27) (xy 352.613339 -283.291817)
			(xy 352.564455 -283.305977) (xy 352.513934 -283.312111) (xy 352.463082 -283.310062) (xy 352.413218 -283.299882)
			(xy 352.365632 -283.281835) (xy 352.321558 -283.256389) (xy 352.282136 -283.224202) (xy 352.248388 -283.186108)
			(xy 352.221187 -283.143094) (xy 352.201239 -283.096274) (xy 352.18906 -283.04686) (xy 352.184965 -282.996132)
			(xy 351.876868 -282.996132) (xy 351.876356 -283.021578) (xy 351.868192 -283.071812) (xy 351.852076 -283.120086)
			(xy 351.828425 -283.165149) (xy 351.797852 -283.205835) (xy 351.761148 -283.24109) (xy 351.719264 -283.27)
			(xy 351.673285 -283.291817) (xy 351.624401 -283.305977) (xy 351.57388 -283.312111) (xy 351.523028 -283.310062)
			(xy 351.473164 -283.299882) (xy 351.425578 -283.281835) (xy 351.381504 -283.256389) (xy 351.342082 -283.224202)
			(xy 351.308334 -283.186108) (xy 351.281133 -283.143094) (xy 351.261185 -283.096274) (xy 351.249006 -283.04686)
			(xy 351.244911 -282.996132) (xy 350.9391 -282.996132) (xy 350.93861 -283.021121) (xy 350.930791 -283.070484)
			(xy 350.915347 -283.118016) (xy 350.892657 -283.162548) (xy 350.863281 -283.202981) (xy 350.827941 -283.238321)
			(xy 350.787508 -283.267697) (xy 350.742976 -283.290387) (xy 350.695444 -283.305831) (xy 350.646081 -283.31365)
			(xy 350.596103 -283.31365) (xy 350.54674 -283.305831) (xy 350.499208 -283.290387) (xy 350.454676 -283.267697)
			(xy 350.414243 -283.238321) (xy 350.378903 -283.202981) (xy 350.349527 -283.162548) (xy 350.326837 -283.118016)
			(xy 350.311393 -283.070484) (xy 350.303574 -283.021121) (xy 349.996257 -283.021121) (xy 349.996248 -283.021578)
			(xy 349.988084 -283.071812) (xy 349.971968 -283.120086) (xy 349.948317 -283.165149) (xy 349.917744 -283.205835)
			(xy 349.88104 -283.24109) (xy 349.839156 -283.27) (xy 349.793177 -283.291817) (xy 349.744293 -283.305977)
			(xy 349.693772 -283.312111) (xy 349.64292 -283.310062) (xy 349.593056 -283.299882) (xy 349.54547 -283.281835)
			(xy 349.501396 -283.256389) (xy 349.461974 -283.224202) (xy 349.428226 -283.186108) (xy 349.401025 -283.143094)
			(xy 349.381077 -283.096274) (xy 349.368898 -283.04686) (xy 349.364803 -282.996132) (xy 349.05696 -282.996132)
			(xy 349.056448 -283.021578) (xy 349.048284 -283.071812) (xy 349.032168 -283.120086) (xy 349.008517 -283.165149)
			(xy 348.977944 -283.205835) (xy 348.94124 -283.24109) (xy 348.899356 -283.27) (xy 348.853377 -283.291817)
			(xy 348.804493 -283.305977) (xy 348.753972 -283.312111) (xy 348.70312 -283.310062) (xy 348.653256 -283.299882)
			(xy 348.60567 -283.281835) (xy 348.561596 -283.256389) (xy 348.522174 -283.224202) (xy 348.488426 -283.186108)
			(xy 348.461225 -283.143094) (xy 348.441277 -283.096274) (xy 348.429098 -283.04686) (xy 348.425003 -282.996132)
			(xy 348.119192 -282.996132) (xy 348.118702 -283.021121) (xy 348.110883 -283.070484) (xy 348.095439 -283.118016)
			(xy 348.072749 -283.162548) (xy 348.043373 -283.202981) (xy 348.008033 -283.238321) (xy 347.9676 -283.267697)
			(xy 347.923068 -283.290387) (xy 347.875536 -283.305831) (xy 347.826173 -283.31365) (xy 347.776195 -283.31365)
			(xy 347.726832 -283.305831) (xy 347.6793 -283.290387) (xy 347.634768 -283.267697) (xy 347.594335 -283.238321)
			(xy 347.558995 -283.202981) (xy 347.529619 -283.162548) (xy 347.506929 -283.118016) (xy 347.491485 -283.070484)
			(xy 347.483666 -283.021121) (xy 347.176349 -283.021121) (xy 347.17634 -283.021578) (xy 347.168176 -283.071812)
			(xy 347.15206 -283.120086) (xy 347.128409 -283.165149) (xy 347.097836 -283.205835) (xy 347.061132 -283.24109)
			(xy 347.019248 -283.27) (xy 346.973269 -283.291817) (xy 346.924385 -283.305977) (xy 346.873864 -283.312111)
			(xy 346.823012 -283.310062) (xy 346.773148 -283.299882) (xy 346.725562 -283.281835) (xy 346.681488 -283.256389)
			(xy 346.642066 -283.224202) (xy 346.608318 -283.186108) (xy 346.581117 -283.143094) (xy 346.561169 -283.096274)
			(xy 346.54899 -283.04686) (xy 346.544895 -282.996132) (xy 346.236798 -282.996132) (xy 346.236286 -283.021578)
			(xy 346.228122 -283.071812) (xy 346.212006 -283.120086) (xy 346.188355 -283.165149) (xy 346.157782 -283.205835)
			(xy 346.121078 -283.24109) (xy 346.079194 -283.27) (xy 346.033215 -283.291817) (xy 345.984331 -283.305977)
			(xy 345.93381 -283.312111) (xy 345.882958 -283.310062) (xy 345.833094 -283.299882) (xy 345.785508 -283.281835)
			(xy 345.741434 -283.256389) (xy 345.702012 -283.224202) (xy 345.668264 -283.186108) (xy 345.641063 -283.143094)
			(xy 345.621115 -283.096274) (xy 345.608936 -283.04686) (xy 345.604841 -282.996132) (xy 345.298926 -282.996132)
			(xy 345.297333 -283.034083) (xy 345.287728 -283.082318) (xy 345.270808 -283.128499) (xy 345.246977 -283.171522)
			(xy 345.232228 -283.191204) (xy 345.21439 -283.213177) (xy 345.172318 -283.251023) (xy 345.124202 -283.280809)
			(xy 345.098116 -283.291788) (xy 345.097862 -283.291788) (xy 345.095068 -283.292804) (xy 345.086748 -283.29719)
			(xy 345.073768 -283.310776) (xy 345.066554 -283.328127) (xy 345.065858 -283.337508) (xy 345.065858 -283.831127)
			(xy 347.013512 -283.831127) (xy 347.013512 -283.781149) (xy 347.021331 -283.731786) (xy 347.036775 -283.684254)
			(xy 347.059465 -283.639722) (xy 347.088841 -283.599289) (xy 347.124181 -283.563949) (xy 347.164614 -283.534573)
			(xy 347.209146 -283.511883) (xy 347.256678 -283.496439) (xy 347.306041 -283.48862) (xy 347.356019 -283.48862)
			(xy 347.405382 -283.496439) (xy 347.452914 -283.511883) (xy 347.497446 -283.534573) (xy 347.537879 -283.563949)
			(xy 347.573219 -283.599289) (xy 347.602595 -283.639722) (xy 347.625285 -283.684254) (xy 347.640729 -283.731786)
			(xy 347.648548 -283.781149) (xy 347.649038 -283.806138) (xy 347.648548 -283.831127) (xy 349.833674 -283.831127)
			(xy 349.833674 -283.781149) (xy 349.841493 -283.731786) (xy 349.856937 -283.684254) (xy 349.879627 -283.639722)
			(xy 349.909003 -283.599289) (xy 349.944343 -283.563949) (xy 349.984776 -283.534573) (xy 350.029308 -283.511883)
			(xy 350.07684 -283.496439) (xy 350.126203 -283.48862) (xy 350.176181 -283.48862) (xy 350.225544 -283.496439)
			(xy 350.273076 -283.511883) (xy 350.317608 -283.534573) (xy 350.358041 -283.563949) (xy 350.393381 -283.599289)
			(xy 350.422757 -283.639722) (xy 350.445447 -283.684254) (xy 350.460891 -283.731786) (xy 350.46871 -283.781149)
			(xy 350.4692 -283.806138) (xy 350.46871 -283.831127) (xy 352.653582 -283.831127) (xy 352.653582 -283.781149)
			(xy 352.661401 -283.731786) (xy 352.676845 -283.684254) (xy 352.699535 -283.639722) (xy 352.728911 -283.599289)
			(xy 352.764251 -283.563949) (xy 352.804684 -283.534573) (xy 352.849216 -283.511883) (xy 352.896748 -283.496439)
			(xy 352.946111 -283.48862) (xy 352.996089 -283.48862) (xy 353.045452 -283.496439) (xy 353.092984 -283.511883)
			(xy 353.137516 -283.534573) (xy 353.177949 -283.563949) (xy 353.213289 -283.599289) (xy 353.242665 -283.639722)
			(xy 353.265355 -283.684254) (xy 353.280799 -283.731786) (xy 353.288618 -283.781149) (xy 353.289108 -283.806138)
			(xy 353.288618 -283.831127) (xy 355.47349 -283.831127) (xy 355.47349 -283.781149) (xy 355.481309 -283.731786)
			(xy 355.496753 -283.684254) (xy 355.519443 -283.639722) (xy 355.548819 -283.599289) (xy 355.584159 -283.563949)
			(xy 355.624592 -283.534573) (xy 355.669124 -283.511883) (xy 355.716656 -283.496439) (xy 355.766019 -283.48862)
			(xy 355.815997 -283.48862) (xy 355.86536 -283.496439) (xy 355.912892 -283.511883) (xy 355.957424 -283.534573)
			(xy 355.997857 -283.563949) (xy 356.033197 -283.599289) (xy 356.062573 -283.639722) (xy 356.085263 -283.684254)
			(xy 356.100707 -283.731786) (xy 356.108526 -283.781149) (xy 356.109016 -283.806138) (xy 356.414827 -283.806138)
			(xy 356.418922 -283.75541) (xy 356.431101 -283.705996) (xy 356.451049 -283.659176) (xy 356.47825 -283.616162)
			(xy 356.511998 -283.578068) (xy 356.55142 -283.545881) (xy 356.595494 -283.520435) (xy 356.64308 -283.502388)
			(xy 356.692944 -283.492208) (xy 356.743796 -283.490159) (xy 356.794317 -283.496293) (xy 356.843201 -283.510453)
			(xy 356.88918 -283.53227) (xy 356.931064 -283.56118) (xy 356.967768 -283.596435) (xy 356.998341 -283.637121)
			(xy 357.021992 -283.682184) (xy 357.038108 -283.730458) (xy 357.046272 -283.780692) (xy 357.046784 -283.806138)
			(xy 357.354881 -283.806138) (xy 357.358976 -283.75541) (xy 357.371155 -283.705996) (xy 357.391103 -283.659176)
			(xy 357.418304 -283.616162) (xy 357.452052 -283.578068) (xy 357.491474 -283.545881) (xy 357.535548 -283.520435)
			(xy 357.583134 -283.502388) (xy 357.632998 -283.492208) (xy 357.68385 -283.490159) (xy 357.734371 -283.496293)
			(xy 357.783255 -283.510453) (xy 357.829234 -283.53227) (xy 357.871118 -283.56118) (xy 357.907822 -283.596435)
			(xy 357.938395 -283.637121) (xy 357.962046 -283.682184) (xy 357.978162 -283.730458) (xy 357.986326 -283.780692)
			(xy 357.986838 -283.806138) (xy 357.986335 -283.831127) (xy 358.293652 -283.831127) (xy 358.293652 -283.781149)
			(xy 358.301471 -283.731786) (xy 358.316915 -283.684254) (xy 358.339605 -283.639722) (xy 358.368981 -283.599289)
			(xy 358.404321 -283.563949) (xy 358.444754 -283.534573) (xy 358.489286 -283.511883) (xy 358.536818 -283.496439)
			(xy 358.586181 -283.48862) (xy 358.636159 -283.48862) (xy 358.685522 -283.496439) (xy 358.733054 -283.511883)
			(xy 358.777586 -283.534573) (xy 358.818019 -283.563949) (xy 358.853359 -283.599289) (xy 358.882735 -283.639722)
			(xy 358.905425 -283.684254) (xy 358.920869 -283.731786) (xy 358.928688 -283.781149) (xy 358.929178 -283.806138)
			(xy 358.928688 -283.831127) (xy 361.10721 -283.831127) (xy 361.10721 -283.781149) (xy 361.115029 -283.731786)
			(xy 361.130473 -283.684254) (xy 361.153163 -283.639722) (xy 361.182539 -283.599289) (xy 361.217879 -283.563949)
			(xy 361.258312 -283.534573) (xy 361.302844 -283.511883) (xy 361.350376 -283.496439) (xy 361.399739 -283.48862)
			(xy 361.449717 -283.48862) (xy 361.49908 -283.496439) (xy 361.546612 -283.511883) (xy 361.591144 -283.534573)
			(xy 361.631577 -283.563949) (xy 361.666917 -283.599289) (xy 361.696293 -283.639722) (xy 361.718983 -283.684254)
			(xy 361.734427 -283.731786) (xy 361.742246 -283.781149) (xy 361.742736 -283.806138) (xy 362.048547 -283.806138)
			(xy 362.052642 -283.75541) (xy 362.064821 -283.705996) (xy 362.084769 -283.659176) (xy 362.11197 -283.616162)
			(xy 362.145718 -283.578068) (xy 362.18514 -283.545881) (xy 362.229214 -283.520435) (xy 362.2768 -283.502388)
			(xy 362.326664 -283.492208) (xy 362.377516 -283.490159) (xy 362.428037 -283.496293) (xy 362.476921 -283.510453)
			(xy 362.5229 -283.53227) (xy 362.564784 -283.56118) (xy 362.601488 -283.596435) (xy 362.632061 -283.637121)
			(xy 362.655712 -283.682184) (xy 362.671828 -283.730458) (xy 362.679992 -283.780692) (xy 362.680504 -283.806138)
			(xy 362.988601 -283.806138) (xy 362.992696 -283.75541) (xy 363.004875 -283.705996) (xy 363.024823 -283.659176)
			(xy 363.052024 -283.616162) (xy 363.085772 -283.578068) (xy 363.125194 -283.545881) (xy 363.169268 -283.520435)
			(xy 363.216854 -283.502388) (xy 363.266718 -283.492208) (xy 363.31757 -283.490159) (xy 363.368091 -283.496293)
			(xy 363.416975 -283.510453) (xy 363.462954 -283.53227) (xy 363.504838 -283.56118) (xy 363.541542 -283.596435)
			(xy 363.572115 -283.637121) (xy 363.595766 -283.682184) (xy 363.611882 -283.730458) (xy 363.620046 -283.780692)
			(xy 363.620558 -283.806138) (xy 363.620055 -283.831127) (xy 363.927372 -283.831127) (xy 363.927372 -283.781149)
			(xy 363.935191 -283.731786) (xy 363.950635 -283.684254) (xy 363.973325 -283.639722) (xy 364.002701 -283.599289)
			(xy 364.038041 -283.563949) (xy 364.078474 -283.534573) (xy 364.123006 -283.511883) (xy 364.170538 -283.496439)
			(xy 364.219901 -283.48862) (xy 364.269879 -283.48862) (xy 364.319242 -283.496439) (xy 364.366774 -283.511883)
			(xy 364.411306 -283.534573) (xy 364.451739 -283.563949) (xy 364.487079 -283.599289) (xy 364.516455 -283.639722)
			(xy 364.539145 -283.684254) (xy 364.554589 -283.731786) (xy 364.562408 -283.781149) (xy 364.562898 -283.806138)
			(xy 364.562408 -283.831127) (xy 366.74728 -283.831127) (xy 366.74728 -283.781149) (xy 366.755099 -283.731786)
			(xy 366.770543 -283.684254) (xy 366.793233 -283.639722) (xy 366.822609 -283.599289) (xy 366.857949 -283.563949)
			(xy 366.898382 -283.534573) (xy 366.942914 -283.511883) (xy 366.990446 -283.496439) (xy 367.039809 -283.48862)
			(xy 367.089787 -283.48862) (xy 367.13915 -283.496439) (xy 367.186682 -283.511883) (xy 367.231214 -283.534573)
			(xy 367.271647 -283.563949) (xy 367.306987 -283.599289) (xy 367.336363 -283.639722) (xy 367.359053 -283.684254)
			(xy 367.374497 -283.731786) (xy 367.382316 -283.781149) (xy 367.382806 -283.806138) (xy 367.382316 -283.831127)
			(xy 369.567188 -283.831127) (xy 369.567188 -283.781149) (xy 369.575007 -283.731786) (xy 369.590451 -283.684254)
			(xy 369.613141 -283.639722) (xy 369.642517 -283.599289) (xy 369.677857 -283.563949) (xy 369.71829 -283.534573)
			(xy 369.762822 -283.511883) (xy 369.810354 -283.496439) (xy 369.859717 -283.48862) (xy 369.909695 -283.48862)
			(xy 369.959058 -283.496439) (xy 370.00659 -283.511883) (xy 370.051122 -283.534573) (xy 370.091555 -283.563949)
			(xy 370.126895 -283.599289) (xy 370.156271 -283.639722) (xy 370.178961 -283.684254) (xy 370.194405 -283.731786)
			(xy 370.202224 -283.781149) (xy 370.202714 -283.806138) (xy 370.202224 -283.831127) (xy 372.38735 -283.831127)
			(xy 372.38735 -283.781149) (xy 372.395169 -283.731786) (xy 372.410613 -283.684254) (xy 372.433303 -283.639722)
			(xy 372.462679 -283.599289) (xy 372.498019 -283.563949) (xy 372.538452 -283.534573) (xy 372.582984 -283.511883)
			(xy 372.630516 -283.496439) (xy 372.679879 -283.48862) (xy 372.729857 -283.48862) (xy 372.77922 -283.496439)
			(xy 372.826752 -283.511883) (xy 372.871284 -283.534573) (xy 372.911717 -283.563949) (xy 372.947057 -283.599289)
			(xy 372.976433 -283.639722) (xy 372.999123 -283.684254) (xy 373.014567 -283.731786) (xy 373.022386 -283.781149)
			(xy 373.022876 -283.806138) (xy 373.022386 -283.831127) (xy 373.014567 -283.88049) (xy 372.999123 -283.928022)
			(xy 372.976433 -283.972554) (xy 372.947057 -284.012987) (xy 372.911717 -284.048327) (xy 372.871284 -284.077703)
			(xy 372.826752 -284.100393) (xy 372.77922 -284.115837) (xy 372.729857 -284.123656) (xy 372.679879 -284.123656)
			(xy 372.630516 -284.115837) (xy 372.582984 -284.100393) (xy 372.538452 -284.077703) (xy 372.498019 -284.048327)
			(xy 372.462679 -284.012987) (xy 372.433303 -283.972554) (xy 372.410613 -283.928022) (xy 372.395169 -283.88049)
			(xy 372.38735 -283.831127) (xy 370.202224 -283.831127) (xy 370.194405 -283.88049) (xy 370.178961 -283.928022)
			(xy 370.156271 -283.972554) (xy 370.126895 -284.012987) (xy 370.091555 -284.048327) (xy 370.051122 -284.077703)
			(xy 370.00659 -284.100393) (xy 369.959058 -284.115837) (xy 369.909695 -284.123656) (xy 369.859717 -284.123656)
			(xy 369.810354 -284.115837) (xy 369.762822 -284.100393) (xy 369.71829 -284.077703) (xy 369.677857 -284.048327)
			(xy 369.642517 -284.012987) (xy 369.613141 -283.972554) (xy 369.590451 -283.928022) (xy 369.575007 -283.88049)
			(xy 369.567188 -283.831127) (xy 367.382316 -283.831127) (xy 367.374497 -283.88049) (xy 367.359053 -283.928022)
			(xy 367.336363 -283.972554) (xy 367.306987 -284.012987) (xy 367.271647 -284.048327) (xy 367.231214 -284.077703)
			(xy 367.186682 -284.100393) (xy 367.13915 -284.115837) (xy 367.089787 -284.123656) (xy 367.039809 -284.123656)
			(xy 366.990446 -284.115837) (xy 366.942914 -284.100393) (xy 366.898382 -284.077703) (xy 366.857949 -284.048327)
			(xy 366.822609 -284.012987) (xy 366.793233 -283.972554) (xy 366.770543 -283.928022) (xy 366.755099 -283.88049)
			(xy 366.74728 -283.831127) (xy 364.562408 -283.831127) (xy 364.554589 -283.88049) (xy 364.539145 -283.928022)
			(xy 364.516455 -283.972554) (xy 364.487079 -284.012987) (xy 364.451739 -284.048327) (xy 364.411306 -284.077703)
			(xy 364.366774 -284.100393) (xy 364.319242 -284.115837) (xy 364.269879 -284.123656) (xy 364.219901 -284.123656)
			(xy 364.170538 -284.115837) (xy 364.123006 -284.100393) (xy 364.078474 -284.077703) (xy 364.038041 -284.048327)
			(xy 364.002701 -284.012987) (xy 363.973325 -283.972554) (xy 363.950635 -283.928022) (xy 363.935191 -283.88049)
			(xy 363.927372 -283.831127) (xy 363.620055 -283.831127) (xy 363.620046 -283.831584) (xy 363.611882 -283.881818)
			(xy 363.595766 -283.930092) (xy 363.572115 -283.975155) (xy 363.541542 -284.015841) (xy 363.504838 -284.051096)
			(xy 363.462954 -284.080006) (xy 363.416975 -284.101823) (xy 363.368091 -284.115983) (xy 363.31757 -284.122117)
			(xy 363.266718 -284.120068) (xy 363.216854 -284.109888) (xy 363.169268 -284.091841) (xy 363.125194 -284.066395)
			(xy 363.085772 -284.034208) (xy 363.052024 -283.996114) (xy 363.024823 -283.9531) (xy 363.004875 -283.90628)
			(xy 362.992696 -283.856866) (xy 362.988601 -283.806138) (xy 362.680504 -283.806138) (xy 362.679992 -283.831584)
			(xy 362.671828 -283.881818) (xy 362.655712 -283.930092) (xy 362.632061 -283.975155) (xy 362.601488 -284.015841)
			(xy 362.564784 -284.051096) (xy 362.5229 -284.080006) (xy 362.476921 -284.101823) (xy 362.428037 -284.115983)
			(xy 362.377516 -284.122117) (xy 362.326664 -284.120068) (xy 362.2768 -284.109888) (xy 362.229214 -284.091841)
			(xy 362.18514 -284.066395) (xy 362.145718 -284.034208) (xy 362.11197 -283.996114) (xy 362.084769 -283.9531)
			(xy 362.064821 -283.90628) (xy 362.052642 -283.856866) (xy 362.048547 -283.806138) (xy 361.742736 -283.806138)
			(xy 361.742246 -283.831127) (xy 361.734427 -283.88049) (xy 361.718983 -283.928022) (xy 361.696293 -283.972554)
			(xy 361.666917 -284.012987) (xy 361.631577 -284.048327) (xy 361.591144 -284.077703) (xy 361.546612 -284.100393)
			(xy 361.49908 -284.115837) (xy 361.449717 -284.123656) (xy 361.399739 -284.123656) (xy 361.350376 -284.115837)
			(xy 361.302844 -284.100393) (xy 361.258312 -284.077703) (xy 361.217879 -284.048327) (xy 361.182539 -284.012987)
			(xy 361.153163 -283.972554) (xy 361.130473 -283.928022) (xy 361.115029 -283.88049) (xy 361.10721 -283.831127)
			(xy 358.928688 -283.831127) (xy 358.920869 -283.88049) (xy 358.905425 -283.928022) (xy 358.882735 -283.972554)
			(xy 358.853359 -284.012987) (xy 358.818019 -284.048327) (xy 358.777586 -284.077703) (xy 358.733054 -284.100393)
			(xy 358.685522 -284.115837) (xy 358.636159 -284.123656) (xy 358.586181 -284.123656) (xy 358.536818 -284.115837)
			(xy 358.489286 -284.100393) (xy 358.444754 -284.077703) (xy 358.404321 -284.048327) (xy 358.368981 -284.012987)
			(xy 358.339605 -283.972554) (xy 358.316915 -283.928022) (xy 358.301471 -283.88049) (xy 358.293652 -283.831127)
			(xy 357.986335 -283.831127) (xy 357.986326 -283.831584) (xy 357.978162 -283.881818) (xy 357.962046 -283.930092)
			(xy 357.938395 -283.975155) (xy 357.907822 -284.015841) (xy 357.871118 -284.051096) (xy 357.829234 -284.080006)
			(xy 357.783255 -284.101823) (xy 357.734371 -284.115983) (xy 357.68385 -284.122117) (xy 357.632998 -284.120068)
			(xy 357.583134 -284.109888) (xy 357.535548 -284.091841) (xy 357.491474 -284.066395) (xy 357.452052 -284.034208)
			(xy 357.418304 -283.996114) (xy 357.391103 -283.9531) (xy 357.371155 -283.90628) (xy 357.358976 -283.856866)
			(xy 357.354881 -283.806138) (xy 357.046784 -283.806138) (xy 357.046272 -283.831584) (xy 357.038108 -283.881818)
			(xy 357.021992 -283.930092) (xy 356.998341 -283.975155) (xy 356.967768 -284.015841) (xy 356.931064 -284.051096)
			(xy 356.88918 -284.080006) (xy 356.843201 -284.101823) (xy 356.794317 -284.115983) (xy 356.743796 -284.122117)
			(xy 356.692944 -284.120068) (xy 356.64308 -284.109888) (xy 356.595494 -284.091841) (xy 356.55142 -284.066395)
			(xy 356.511998 -284.034208) (xy 356.47825 -283.996114) (xy 356.451049 -283.9531) (xy 356.431101 -283.90628)
			(xy 356.418922 -283.856866) (xy 356.414827 -283.806138) (xy 356.109016 -283.806138) (xy 356.108526 -283.831127)
			(xy 356.100707 -283.88049) (xy 356.085263 -283.928022) (xy 356.062573 -283.972554) (xy 356.033197 -284.012987)
			(xy 355.997857 -284.048327) (xy 355.957424 -284.077703) (xy 355.912892 -284.100393) (xy 355.86536 -284.115837)
			(xy 355.815997 -284.123656) (xy 355.766019 -284.123656) (xy 355.716656 -284.115837) (xy 355.669124 -284.100393)
			(xy 355.624592 -284.077703) (xy 355.584159 -284.048327) (xy 355.548819 -284.012987) (xy 355.519443 -283.972554)
			(xy 355.496753 -283.928022) (xy 355.481309 -283.88049) (xy 355.47349 -283.831127) (xy 353.288618 -283.831127)
			(xy 353.280799 -283.88049) (xy 353.265355 -283.928022) (xy 353.242665 -283.972554) (xy 353.213289 -284.012987)
			(xy 353.177949 -284.048327) (xy 353.137516 -284.077703) (xy 353.092984 -284.100393) (xy 353.045452 -284.115837)
			(xy 352.996089 -284.123656) (xy 352.946111 -284.123656) (xy 352.896748 -284.115837) (xy 352.849216 -284.100393)
			(xy 352.804684 -284.077703) (xy 352.764251 -284.048327) (xy 352.728911 -284.012987) (xy 352.699535 -283.972554)
			(xy 352.676845 -283.928022) (xy 352.661401 -283.88049) (xy 352.653582 -283.831127) (xy 350.46871 -283.831127)
			(xy 350.460891 -283.88049) (xy 350.445447 -283.928022) (xy 350.422757 -283.972554) (xy 350.393381 -284.012987)
			(xy 350.358041 -284.048327) (xy 350.317608 -284.077703) (xy 350.273076 -284.100393) (xy 350.225544 -284.115837)
			(xy 350.176181 -284.123656) (xy 350.126203 -284.123656) (xy 350.07684 -284.115837) (xy 350.029308 -284.100393)
			(xy 349.984776 -284.077703) (xy 349.944343 -284.048327) (xy 349.909003 -284.012987) (xy 349.879627 -283.972554)
			(xy 349.856937 -283.928022) (xy 349.841493 -283.88049) (xy 349.833674 -283.831127) (xy 347.648548 -283.831127)
			(xy 347.640729 -283.88049) (xy 347.625285 -283.928022) (xy 347.602595 -283.972554) (xy 347.573219 -284.012987)
			(xy 347.537879 -284.048327) (xy 347.497446 -284.077703) (xy 347.452914 -284.100393) (xy 347.405382 -284.115837)
			(xy 347.356019 -284.123656) (xy 347.306041 -284.123656) (xy 347.256678 -284.115837) (xy 347.209146 -284.100393)
			(xy 347.164614 -284.077703) (xy 347.124181 -284.048327) (xy 347.088841 -284.012987) (xy 347.059465 -283.972554)
			(xy 347.036775 -283.928022) (xy 347.021331 -283.88049) (xy 347.013512 -283.831127) (xy 345.065858 -283.831127)
			(xy 345.065858 -284.273498) (xy 345.065858 -284.274768) (xy 345.066523 -284.284153) (xy 345.073744 -284.301509)
			(xy 345.086742 -284.315089) (xy 345.095068 -284.319472) (xy 345.097862 -284.320488) (xy 345.120568 -284.32994)
			(xy 345.162992 -284.354819) (xy 345.201079 -284.385936) (xy 345.233918 -284.422546) (xy 345.260728 -284.463778)
			(xy 345.280868 -284.508647) (xy 345.293857 -284.556082) (xy 345.299385 -284.604951) (xy 345.298915 -284.616144)
			(xy 345.604841 -284.616144) (xy 345.608936 -284.565416) (xy 345.621115 -284.516002) (xy 345.641063 -284.469182)
			(xy 345.668264 -284.426168) (xy 345.702012 -284.388074) (xy 345.741434 -284.355887) (xy 345.785508 -284.330441)
			(xy 345.833094 -284.312394) (xy 345.882958 -284.302214) (xy 345.93381 -284.300165) (xy 345.984331 -284.306299)
			(xy 346.033215 -284.320459) (xy 346.079194 -284.342276) (xy 346.121078 -284.371186) (xy 346.157782 -284.406441)
			(xy 346.188355 -284.447127) (xy 346.212006 -284.49219) (xy 346.228122 -284.540464) (xy 346.236286 -284.590698)
			(xy 346.236798 -284.616144) (xy 346.544895 -284.616144) (xy 346.54899 -284.565416) (xy 346.561169 -284.516002)
			(xy 346.581117 -284.469182) (xy 346.608318 -284.426168) (xy 346.642066 -284.388074) (xy 346.681488 -284.355887)
			(xy 346.725562 -284.330441) (xy 346.773148 -284.312394) (xy 346.823012 -284.302214) (xy 346.873864 -284.300165)
			(xy 346.924385 -284.306299) (xy 346.973269 -284.320459) (xy 347.019248 -284.342276) (xy 347.061132 -284.371186)
			(xy 347.097836 -284.406441) (xy 347.128409 -284.447127) (xy 347.15206 -284.49219) (xy 347.168176 -284.540464)
			(xy 347.17634 -284.590698) (xy 347.176852 -284.616144) (xy 347.176349 -284.641133) (xy 347.483666 -284.641133)
			(xy 347.483666 -284.591155) (xy 347.491485 -284.541792) (xy 347.506929 -284.49426) (xy 347.529619 -284.449728)
			(xy 347.558995 -284.409295) (xy 347.594335 -284.373955) (xy 347.634768 -284.344579) (xy 347.6793 -284.321889)
			(xy 347.726832 -284.306445) (xy 347.776195 -284.298626) (xy 347.826173 -284.298626) (xy 347.875536 -284.306445)
			(xy 347.923068 -284.321889) (xy 347.9676 -284.344579) (xy 348.008033 -284.373955) (xy 348.043373 -284.409295)
			(xy 348.072749 -284.449728) (xy 348.095439 -284.49426) (xy 348.110883 -284.541792) (xy 348.118702 -284.591155)
			(xy 348.119192 -284.616144) (xy 348.425003 -284.616144) (xy 348.429098 -284.565416) (xy 348.441277 -284.516002)
			(xy 348.461225 -284.469182) (xy 348.488426 -284.426168) (xy 348.522174 -284.388074) (xy 348.561596 -284.355887)
			(xy 348.60567 -284.330441) (xy 348.653256 -284.312394) (xy 348.70312 -284.302214) (xy 348.753972 -284.300165)
			(xy 348.804493 -284.306299) (xy 348.853377 -284.320459) (xy 348.899356 -284.342276) (xy 348.94124 -284.371186)
			(xy 348.977944 -284.406441) (xy 349.008517 -284.447127) (xy 349.032168 -284.49219) (xy 349.048284 -284.540464)
			(xy 349.056448 -284.590698) (xy 349.05696 -284.616144) (xy 349.364803 -284.616144) (xy 349.368898 -284.565416)
			(xy 349.381077 -284.516002) (xy 349.401025 -284.469182) (xy 349.428226 -284.426168) (xy 349.461974 -284.388074)
			(xy 349.501396 -284.355887) (xy 349.54547 -284.330441) (xy 349.593056 -284.312394) (xy 349.64292 -284.302214)
			(xy 349.693772 -284.300165) (xy 349.744293 -284.306299) (xy 349.793177 -284.320459) (xy 349.839156 -284.342276)
			(xy 349.88104 -284.371186) (xy 349.917744 -284.406441) (xy 349.948317 -284.447127) (xy 349.971968 -284.49219)
			(xy 349.988084 -284.540464) (xy 349.996248 -284.590698) (xy 349.99676 -284.616144) (xy 349.996257 -284.641133)
			(xy 350.303574 -284.641133) (xy 350.303574 -284.591155) (xy 350.311393 -284.541792) (xy 350.326837 -284.49426)
			(xy 350.349527 -284.449728) (xy 350.378903 -284.409295) (xy 350.414243 -284.373955) (xy 350.454676 -284.344579)
			(xy 350.499208 -284.321889) (xy 350.54674 -284.306445) (xy 350.596103 -284.298626) (xy 350.646081 -284.298626)
			(xy 350.695444 -284.306445) (xy 350.742976 -284.321889) (xy 350.787508 -284.344579) (xy 350.827941 -284.373955)
			(xy 350.863281 -284.409295) (xy 350.892657 -284.449728) (xy 350.915347 -284.49426) (xy 350.930791 -284.541792)
			(xy 350.93861 -284.591155) (xy 350.9391 -284.616144) (xy 351.244911 -284.616144) (xy 351.249006 -284.565416)
			(xy 351.261185 -284.516002) (xy 351.281133 -284.469182) (xy 351.308334 -284.426168) (xy 351.342082 -284.388074)
			(xy 351.381504 -284.355887) (xy 351.425578 -284.330441) (xy 351.473164 -284.312394) (xy 351.523028 -284.302214)
			(xy 351.57388 -284.300165) (xy 351.624401 -284.306299) (xy 351.673285 -284.320459) (xy 351.719264 -284.342276)
			(xy 351.761148 -284.371186) (xy 351.797852 -284.406441) (xy 351.828425 -284.447127) (xy 351.852076 -284.49219)
			(xy 351.868192 -284.540464) (xy 351.876356 -284.590698) (xy 351.876868 -284.616144) (xy 352.184965 -284.616144)
			(xy 352.18906 -284.565416) (xy 352.201239 -284.516002) (xy 352.221187 -284.469182) (xy 352.248388 -284.426168)
			(xy 352.282136 -284.388074) (xy 352.321558 -284.355887) (xy 352.365632 -284.330441) (xy 352.413218 -284.312394)
			(xy 352.463082 -284.302214) (xy 352.513934 -284.300165) (xy 352.564455 -284.306299) (xy 352.613339 -284.320459)
			(xy 352.659318 -284.342276) (xy 352.701202 -284.371186) (xy 352.737906 -284.406441) (xy 352.768479 -284.447127)
			(xy 352.79213 -284.49219) (xy 352.808246 -284.540464) (xy 352.81641 -284.590698) (xy 352.816922 -284.616144)
			(xy 352.816419 -284.641133) (xy 353.123482 -284.641133) (xy 353.123482 -284.591155) (xy 353.131301 -284.541792)
			(xy 353.146745 -284.49426) (xy 353.169435 -284.449728) (xy 353.198811 -284.409295) (xy 353.234151 -284.373955)
			(xy 353.274584 -284.344579) (xy 353.319116 -284.321889) (xy 353.366648 -284.306445) (xy 353.416011 -284.298626)
			(xy 353.465989 -284.298626) (xy 353.515352 -284.306445) (xy 353.562884 -284.321889) (xy 353.607416 -284.344579)
			(xy 353.647849 -284.373955) (xy 353.683189 -284.409295) (xy 353.712565 -284.449728) (xy 353.735255 -284.49426)
			(xy 353.750699 -284.541792) (xy 353.758518 -284.591155) (xy 353.759008 -284.616144) (xy 354.064819 -284.616144)
			(xy 354.068914 -284.565416) (xy 354.081093 -284.516002) (xy 354.101041 -284.469182) (xy 354.128242 -284.426168)
			(xy 354.16199 -284.388074) (xy 354.201412 -284.355887) (xy 354.245486 -284.330441) (xy 354.293072 -284.312394)
			(xy 354.342936 -284.302214) (xy 354.393788 -284.300165) (xy 354.444309 -284.306299) (xy 354.493193 -284.320459)
			(xy 354.539172 -284.342276) (xy 354.581056 -284.371186) (xy 354.61776 -284.406441) (xy 354.648333 -284.447127)
			(xy 354.671984 -284.49219) (xy 354.6881 -284.540464) (xy 354.696264 -284.590698) (xy 354.696776 -284.616144)
			(xy 355.004873 -284.616144) (xy 355.008968 -284.565416) (xy 355.021147 -284.516002) (xy 355.041095 -284.469182)
			(xy 355.068296 -284.426168) (xy 355.102044 -284.388074) (xy 355.141466 -284.355887) (xy 355.18554 -284.330441)
			(xy 355.233126 -284.312394) (xy 355.28299 -284.302214) (xy 355.333842 -284.300165) (xy 355.384363 -284.306299)
			(xy 355.433247 -284.320459) (xy 355.479226 -284.342276) (xy 355.52111 -284.371186) (xy 355.557814 -284.406441)
			(xy 355.588387 -284.447127) (xy 355.612038 -284.49219) (xy 355.628154 -284.540464) (xy 355.636318 -284.590698)
			(xy 355.63683 -284.616144) (xy 355.636327 -284.641133) (xy 355.943644 -284.641133) (xy 355.943644 -284.591155)
			(xy 355.951463 -284.541792) (xy 355.966907 -284.49426) (xy 355.989597 -284.449728) (xy 356.018973 -284.409295)
			(xy 356.054313 -284.373955) (xy 356.094746 -284.344579) (xy 356.139278 -284.321889) (xy 356.18681 -284.306445)
			(xy 356.236173 -284.298626) (xy 356.286151 -284.298626) (xy 356.335514 -284.306445) (xy 356.383046 -284.321889)
			(xy 356.427578 -284.344579) (xy 356.468011 -284.373955) (xy 356.503351 -284.409295) (xy 356.532727 -284.449728)
			(xy 356.555417 -284.49426) (xy 356.570861 -284.541792) (xy 356.57868 -284.591155) (xy 356.57917 -284.616144)
			(xy 356.57868 -284.641133) (xy 356.883698 -284.641133) (xy 356.883698 -284.591155) (xy 356.891517 -284.541792)
			(xy 356.906961 -284.49426) (xy 356.929651 -284.449728) (xy 356.959027 -284.409295) (xy 356.994367 -284.373955)
			(xy 357.0348 -284.344579) (xy 357.079332 -284.321889) (xy 357.126864 -284.306445) (xy 357.176227 -284.298626)
			(xy 357.226205 -284.298626) (xy 357.275568 -284.306445) (xy 357.3231 -284.321889) (xy 357.367632 -284.344579)
			(xy 357.408065 -284.373955) (xy 357.443405 -284.409295) (xy 357.472781 -284.449728) (xy 357.495471 -284.49426)
			(xy 357.510915 -284.541792) (xy 357.518734 -284.591155) (xy 357.519224 -284.616144) (xy 357.518734 -284.641133)
			(xy 357.823498 -284.641133) (xy 357.823498 -284.591155) (xy 357.831317 -284.541792) (xy 357.846761 -284.49426)
			(xy 357.869451 -284.449728) (xy 357.898827 -284.409295) (xy 357.934167 -284.373955) (xy 357.9746 -284.344579)
			(xy 358.019132 -284.321889) (xy 358.066664 -284.306445) (xy 358.116027 -284.298626) (xy 358.166005 -284.298626)
			(xy 358.215368 -284.306445) (xy 358.2629 -284.321889) (xy 358.307432 -284.344579) (xy 358.347865 -284.373955)
			(xy 358.383205 -284.409295) (xy 358.412581 -284.449728) (xy 358.435271 -284.49426) (xy 358.450715 -284.541792)
			(xy 358.458534 -284.591155) (xy 358.459024 -284.616144) (xy 358.458534 -284.641133) (xy 361.577364 -284.641133)
			(xy 361.577364 -284.591155) (xy 361.585183 -284.541792) (xy 361.600627 -284.49426) (xy 361.623317 -284.449728)
			(xy 361.652693 -284.409295) (xy 361.688033 -284.373955) (xy 361.728466 -284.344579) (xy 361.772998 -284.321889)
			(xy 361.82053 -284.306445) (xy 361.869893 -284.298626) (xy 361.919871 -284.298626) (xy 361.969234 -284.306445)
			(xy 362.016766 -284.321889) (xy 362.061298 -284.344579) (xy 362.101731 -284.373955) (xy 362.137071 -284.409295)
			(xy 362.166447 -284.449728) (xy 362.189137 -284.49426) (xy 362.204581 -284.541792) (xy 362.2124 -284.591155)
			(xy 362.21289 -284.616144) (xy 362.2124 -284.641133) (xy 362.517164 -284.641133) (xy 362.517164 -284.591155)
			(xy 362.524983 -284.541792) (xy 362.540427 -284.49426) (xy 362.563117 -284.449728) (xy 362.592493 -284.409295)
			(xy 362.627833 -284.373955) (xy 362.668266 -284.344579) (xy 362.712798 -284.321889) (xy 362.76033 -284.306445)
			(xy 362.809693 -284.298626) (xy 362.859671 -284.298626) (xy 362.909034 -284.306445) (xy 362.956566 -284.321889)
			(xy 363.001098 -284.344579) (xy 363.041531 -284.373955) (xy 363.076871 -284.409295) (xy 363.106247 -284.449728)
			(xy 363.128937 -284.49426) (xy 363.144381 -284.541792) (xy 363.1522 -284.591155) (xy 363.15269 -284.616144)
			(xy 363.1522 -284.641133) (xy 363.457218 -284.641133) (xy 363.457218 -284.591155) (xy 363.465037 -284.541792)
			(xy 363.480481 -284.49426) (xy 363.503171 -284.449728) (xy 363.532547 -284.409295) (xy 363.567887 -284.373955)
			(xy 363.60832 -284.344579) (xy 363.652852 -284.321889) (xy 363.700384 -284.306445) (xy 363.749747 -284.298626)
			(xy 363.799725 -284.298626) (xy 363.849088 -284.306445) (xy 363.89662 -284.321889) (xy 363.941152 -284.344579)
			(xy 363.981585 -284.373955) (xy 364.016925 -284.409295) (xy 364.046301 -284.449728) (xy 364.068991 -284.49426)
			(xy 364.084435 -284.541792) (xy 364.092254 -284.591155) (xy 364.092744 -284.616144) (xy 364.398555 -284.616144)
			(xy 364.40265 -284.565416) (xy 364.414829 -284.516002) (xy 364.434777 -284.469182) (xy 364.461978 -284.426168)
			(xy 364.495726 -284.388074) (xy 364.535148 -284.355887) (xy 364.579222 -284.330441) (xy 364.626808 -284.312394)
			(xy 364.676672 -284.302214) (xy 364.727524 -284.300165) (xy 364.778045 -284.306299) (xy 364.826929 -284.320459)
			(xy 364.872908 -284.342276) (xy 364.914792 -284.371186) (xy 364.951496 -284.406441) (xy 364.982069 -284.447127)
			(xy 365.00572 -284.49219) (xy 365.021836 -284.540464) (xy 365.03 -284.590698) (xy 365.030512 -284.616144)
			(xy 365.338609 -284.616144) (xy 365.342704 -284.565416) (xy 365.354883 -284.516002) (xy 365.374831 -284.469182)
			(xy 365.402032 -284.426168) (xy 365.43578 -284.388074) (xy 365.475202 -284.355887) (xy 365.519276 -284.330441)
			(xy 365.566862 -284.312394) (xy 365.616726 -284.302214) (xy 365.667578 -284.300165) (xy 365.718099 -284.306299)
			(xy 365.766983 -284.320459) (xy 365.812962 -284.342276) (xy 365.854846 -284.371186) (xy 365.89155 -284.406441)
			(xy 365.922123 -284.447127) (xy 365.945774 -284.49219) (xy 365.96189 -284.540464) (xy 365.970054 -284.590698)
			(xy 365.970566 -284.616144) (xy 365.970063 -284.641133) (xy 366.27738 -284.641133) (xy 366.27738 -284.591155)
			(xy 366.285199 -284.541792) (xy 366.300643 -284.49426) (xy 366.323333 -284.449728) (xy 366.352709 -284.409295)
			(xy 366.388049 -284.373955) (xy 366.428482 -284.344579) (xy 366.473014 -284.321889) (xy 366.520546 -284.306445)
			(xy 366.569909 -284.298626) (xy 366.619887 -284.298626) (xy 366.66925 -284.306445) (xy 366.716782 -284.321889)
			(xy 366.761314 -284.344579) (xy 366.801747 -284.373955) (xy 366.837087 -284.409295) (xy 366.866463 -284.449728)
			(xy 366.889153 -284.49426) (xy 366.904597 -284.541792) (xy 366.912416 -284.591155) (xy 366.912906 -284.616144)
			(xy 367.218463 -284.616144) (xy 367.222558 -284.565416) (xy 367.234737 -284.516002) (xy 367.254685 -284.469182)
			(xy 367.281886 -284.426168) (xy 367.315634 -284.388074) (xy 367.355056 -284.355887) (xy 367.39913 -284.330441)
			(xy 367.446716 -284.312394) (xy 367.49658 -284.302214) (xy 367.547432 -284.300165) (xy 367.597953 -284.306299)
			(xy 367.646837 -284.320459) (xy 367.692816 -284.342276) (xy 367.7347 -284.371186) (xy 367.771404 -284.406441)
			(xy 367.801977 -284.447127) (xy 367.825628 -284.49219) (xy 367.841744 -284.540464) (xy 367.849908 -284.590698)
			(xy 367.85042 -284.616144) (xy 368.158517 -284.616144) (xy 368.162612 -284.565416) (xy 368.174791 -284.516002)
			(xy 368.194739 -284.469182) (xy 368.22194 -284.426168) (xy 368.255688 -284.388074) (xy 368.29511 -284.355887)
			(xy 368.339184 -284.330441) (xy 368.38677 -284.312394) (xy 368.436634 -284.302214) (xy 368.487486 -284.300165)
			(xy 368.538007 -284.306299) (xy 368.586891 -284.320459) (xy 368.63287 -284.342276) (xy 368.674754 -284.371186)
			(xy 368.711458 -284.406441) (xy 368.742031 -284.447127) (xy 368.765682 -284.49219) (xy 368.781798 -284.540464)
			(xy 368.789962 -284.590698) (xy 368.790474 -284.616144) (xy 368.789971 -284.641133) (xy 369.097288 -284.641133)
			(xy 369.097288 -284.591155) (xy 369.105107 -284.541792) (xy 369.120551 -284.49426) (xy 369.143241 -284.449728)
			(xy 369.172617 -284.409295) (xy 369.207957 -284.373955) (xy 369.24839 -284.344579) (xy 369.292922 -284.321889)
			(xy 369.340454 -284.306445) (xy 369.389817 -284.298626) (xy 369.439795 -284.298626) (xy 369.489158 -284.306445)
			(xy 369.53669 -284.321889) (xy 369.581222 -284.344579) (xy 369.621655 -284.373955) (xy 369.656995 -284.409295)
			(xy 369.686371 -284.449728) (xy 369.709061 -284.49426) (xy 369.724505 -284.541792) (xy 369.732324 -284.591155)
			(xy 369.732814 -284.616144) (xy 370.038625 -284.616144) (xy 370.04272 -284.565416) (xy 370.054899 -284.516002)
			(xy 370.074847 -284.469182) (xy 370.102048 -284.426168) (xy 370.135796 -284.388074) (xy 370.175218 -284.355887)
			(xy 370.219292 -284.330441) (xy 370.266878 -284.312394) (xy 370.316742 -284.302214) (xy 370.367594 -284.300165)
			(xy 370.418115 -284.306299) (xy 370.466999 -284.320459) (xy 370.512978 -284.342276) (xy 370.554862 -284.371186)
			(xy 370.591566 -284.406441) (xy 370.622139 -284.447127) (xy 370.64579 -284.49219) (xy 370.661906 -284.540464)
			(xy 370.67007 -284.590698) (xy 370.670582 -284.616144) (xy 370.978679 -284.616144) (xy 370.982774 -284.565416)
			(xy 370.994953 -284.516002) (xy 371.014901 -284.469182) (xy 371.042102 -284.426168) (xy 371.07585 -284.388074)
			(xy 371.115272 -284.355887) (xy 371.159346 -284.330441) (xy 371.206932 -284.312394) (xy 371.256796 -284.302214)
			(xy 371.307648 -284.300165) (xy 371.358169 -284.306299) (xy 371.407053 -284.320459) (xy 371.453032 -284.342276)
			(xy 371.494916 -284.371186) (xy 371.53162 -284.406441) (xy 371.562193 -284.447127) (xy 371.585844 -284.49219)
			(xy 371.60196 -284.540464) (xy 371.610124 -284.590698) (xy 371.610636 -284.616144) (xy 371.610133 -284.641133)
			(xy 371.917196 -284.641133) (xy 371.917196 -284.591155) (xy 371.925015 -284.541792) (xy 371.940459 -284.49426)
			(xy 371.963149 -284.449728) (xy 371.992525 -284.409295) (xy 372.027865 -284.373955) (xy 372.068298 -284.344579)
			(xy 372.11283 -284.321889) (xy 372.160362 -284.306445) (xy 372.209725 -284.298626) (xy 372.259703 -284.298626)
			(xy 372.309066 -284.306445) (xy 372.356598 -284.321889) (xy 372.40113 -284.344579) (xy 372.441563 -284.373955)
			(xy 372.476903 -284.409295) (xy 372.506279 -284.449728) (xy 372.528969 -284.49426) (xy 372.544413 -284.541792)
			(xy 372.552232 -284.591155) (xy 372.552722 -284.616144) (xy 372.858533 -284.616144) (xy 372.862628 -284.565416)
			(xy 372.874807 -284.516002) (xy 372.894755 -284.469182) (xy 372.921956 -284.426168) (xy 372.955704 -284.388074)
			(xy 372.995126 -284.355887) (xy 373.0392 -284.330441) (xy 373.086786 -284.312394) (xy 373.13665 -284.302214)
			(xy 373.187502 -284.300165) (xy 373.238023 -284.306299) (xy 373.286907 -284.320459) (xy 373.332886 -284.342276)
			(xy 373.37477 -284.371186) (xy 373.411474 -284.406441) (xy 373.442047 -284.447127) (xy 373.465698 -284.49219)
			(xy 373.481814 -284.540464) (xy 373.489978 -284.590698) (xy 373.49049 -284.616144) (xy 373.798587 -284.616144)
			(xy 373.802682 -284.565416) (xy 373.814861 -284.516002) (xy 373.834809 -284.469182) (xy 373.86201 -284.426168)
			(xy 373.895758 -284.388074) (xy 373.93518 -284.355887) (xy 373.979254 -284.330441) (xy 374.02684 -284.312394)
			(xy 374.076704 -284.302214) (xy 374.127556 -284.300165) (xy 374.178077 -284.306299) (xy 374.226961 -284.320459)
			(xy 374.27294 -284.342276) (xy 374.314824 -284.371186) (xy 374.351528 -284.406441) (xy 374.382101 -284.447127)
			(xy 374.405752 -284.49219) (xy 374.421868 -284.540464) (xy 374.430032 -284.590698) (xy 374.430544 -284.616144)
			(xy 374.430032 -284.64159) (xy 374.421868 -284.691824) (xy 374.405752 -284.740098) (xy 374.382101 -284.785161)
			(xy 374.351528 -284.825847) (xy 374.314824 -284.861102) (xy 374.27294 -284.890012) (xy 374.226961 -284.911829)
			(xy 374.178077 -284.925989) (xy 374.127556 -284.932123) (xy 374.076704 -284.930074) (xy 374.02684 -284.919894)
			(xy 373.979254 -284.901847) (xy 373.93518 -284.876401) (xy 373.895758 -284.844214) (xy 373.86201 -284.80612)
			(xy 373.834809 -284.763106) (xy 373.814861 -284.716286) (xy 373.802682 -284.666872) (xy 373.798587 -284.616144)
			(xy 373.49049 -284.616144) (xy 373.489978 -284.64159) (xy 373.481814 -284.691824) (xy 373.465698 -284.740098)
			(xy 373.442047 -284.785161) (xy 373.411474 -284.825847) (xy 373.37477 -284.861102) (xy 373.332886 -284.890012)
			(xy 373.286907 -284.911829) (xy 373.238023 -284.925989) (xy 373.187502 -284.932123) (xy 373.13665 -284.930074)
			(xy 373.086786 -284.919894) (xy 373.0392 -284.901847) (xy 372.995126 -284.876401) (xy 372.955704 -284.844214)
			(xy 372.921956 -284.80612) (xy 372.894755 -284.763106) (xy 372.874807 -284.716286) (xy 372.862628 -284.666872)
			(xy 372.858533 -284.616144) (xy 372.552722 -284.616144) (xy 372.552232 -284.641133) (xy 372.544413 -284.690496)
			(xy 372.528969 -284.738028) (xy 372.506279 -284.78256) (xy 372.476903 -284.822993) (xy 372.441563 -284.858333)
			(xy 372.40113 -284.887709) (xy 372.356598 -284.910399) (xy 372.309066 -284.925843) (xy 372.259703 -284.933662)
			(xy 372.209725 -284.933662) (xy 372.160362 -284.925843) (xy 372.11283 -284.910399) (xy 372.068298 -284.887709)
			(xy 372.027865 -284.858333) (xy 371.992525 -284.822993) (xy 371.963149 -284.78256) (xy 371.940459 -284.738028)
			(xy 371.925015 -284.690496) (xy 371.917196 -284.641133) (xy 371.610133 -284.641133) (xy 371.610124 -284.64159)
			(xy 371.60196 -284.691824) (xy 371.585844 -284.740098) (xy 371.562193 -284.785161) (xy 371.53162 -284.825847)
			(xy 371.494916 -284.861102) (xy 371.453032 -284.890012) (xy 371.407053 -284.911829) (xy 371.358169 -284.925989)
			(xy 371.307648 -284.932123) (xy 371.256796 -284.930074) (xy 371.206932 -284.919894) (xy 371.159346 -284.901847)
			(xy 371.115272 -284.876401) (xy 371.07585 -284.844214) (xy 371.042102 -284.80612) (xy 371.014901 -284.763106)
			(xy 370.994953 -284.716286) (xy 370.982774 -284.666872) (xy 370.978679 -284.616144) (xy 370.670582 -284.616144)
			(xy 370.67007 -284.64159) (xy 370.661906 -284.691824) (xy 370.64579 -284.740098) (xy 370.622139 -284.785161)
			(xy 370.591566 -284.825847) (xy 370.554862 -284.861102) (xy 370.512978 -284.890012) (xy 370.466999 -284.911829)
			(xy 370.418115 -284.925989) (xy 370.367594 -284.932123) (xy 370.316742 -284.930074) (xy 370.266878 -284.919894)
			(xy 370.219292 -284.901847) (xy 370.175218 -284.876401) (xy 370.135796 -284.844214) (xy 370.102048 -284.80612)
			(xy 370.074847 -284.763106) (xy 370.054899 -284.716286) (xy 370.04272 -284.666872) (xy 370.038625 -284.616144)
			(xy 369.732814 -284.616144) (xy 369.732324 -284.641133) (xy 369.724505 -284.690496) (xy 369.709061 -284.738028)
			(xy 369.686371 -284.78256) (xy 369.656995 -284.822993) (xy 369.621655 -284.858333) (xy 369.581222 -284.887709)
			(xy 369.53669 -284.910399) (xy 369.489158 -284.925843) (xy 369.439795 -284.933662) (xy 369.389817 -284.933662)
			(xy 369.340454 -284.925843) (xy 369.292922 -284.910399) (xy 369.24839 -284.887709) (xy 369.207957 -284.858333)
			(xy 369.172617 -284.822993) (xy 369.143241 -284.78256) (xy 369.120551 -284.738028) (xy 369.105107 -284.690496)
			(xy 369.097288 -284.641133) (xy 368.789971 -284.641133) (xy 368.789962 -284.64159) (xy 368.781798 -284.691824)
			(xy 368.765682 -284.740098) (xy 368.742031 -284.785161) (xy 368.711458 -284.825847) (xy 368.674754 -284.861102)
			(xy 368.63287 -284.890012) (xy 368.586891 -284.911829) (xy 368.538007 -284.925989) (xy 368.487486 -284.932123)
			(xy 368.436634 -284.930074) (xy 368.38677 -284.919894) (xy 368.339184 -284.901847) (xy 368.29511 -284.876401)
			(xy 368.255688 -284.844214) (xy 368.22194 -284.80612) (xy 368.194739 -284.763106) (xy 368.174791 -284.716286)
			(xy 368.162612 -284.666872) (xy 368.158517 -284.616144) (xy 367.85042 -284.616144) (xy 367.849908 -284.64159)
			(xy 367.841744 -284.691824) (xy 367.825628 -284.740098) (xy 367.801977 -284.785161) (xy 367.771404 -284.825847)
			(xy 367.7347 -284.861102) (xy 367.692816 -284.890012) (xy 367.646837 -284.911829) (xy 367.597953 -284.925989)
			(xy 367.547432 -284.932123) (xy 367.49658 -284.930074) (xy 367.446716 -284.919894) (xy 367.39913 -284.901847)
			(xy 367.355056 -284.876401) (xy 367.315634 -284.844214) (xy 367.281886 -284.80612) (xy 367.254685 -284.763106)
			(xy 367.234737 -284.716286) (xy 367.222558 -284.666872) (xy 367.218463 -284.616144) (xy 366.912906 -284.616144)
			(xy 366.912416 -284.641133) (xy 366.904597 -284.690496) (xy 366.889153 -284.738028) (xy 366.866463 -284.78256)
			(xy 366.837087 -284.822993) (xy 366.801747 -284.858333) (xy 366.761314 -284.887709) (xy 366.716782 -284.910399)
			(xy 366.66925 -284.925843) (xy 366.619887 -284.933662) (xy 366.569909 -284.933662) (xy 366.520546 -284.925843)
			(xy 366.473014 -284.910399) (xy 366.428482 -284.887709) (xy 366.388049 -284.858333) (xy 366.352709 -284.822993)
			(xy 366.323333 -284.78256) (xy 366.300643 -284.738028) (xy 366.285199 -284.690496) (xy 366.27738 -284.641133)
			(xy 365.970063 -284.641133) (xy 365.970054 -284.64159) (xy 365.96189 -284.691824) (xy 365.945774 -284.740098)
			(xy 365.922123 -284.785161) (xy 365.89155 -284.825847) (xy 365.854846 -284.861102) (xy 365.812962 -284.890012)
			(xy 365.766983 -284.911829) (xy 365.718099 -284.925989) (xy 365.667578 -284.932123) (xy 365.616726 -284.930074)
			(xy 365.566862 -284.919894) (xy 365.519276 -284.901847) (xy 365.475202 -284.876401) (xy 365.43578 -284.844214)
			(xy 365.402032 -284.80612) (xy 365.374831 -284.763106) (xy 365.354883 -284.716286) (xy 365.342704 -284.666872)
			(xy 365.338609 -284.616144) (xy 365.030512 -284.616144) (xy 365.03 -284.64159) (xy 365.021836 -284.691824)
			(xy 365.00572 -284.740098) (xy 364.982069 -284.785161) (xy 364.951496 -284.825847) (xy 364.914792 -284.861102)
			(xy 364.872908 -284.890012) (xy 364.826929 -284.911829) (xy 364.778045 -284.925989) (xy 364.727524 -284.932123)
			(xy 364.676672 -284.930074) (xy 364.626808 -284.919894) (xy 364.579222 -284.901847) (xy 364.535148 -284.876401)
			(xy 364.495726 -284.844214) (xy 364.461978 -284.80612) (xy 364.434777 -284.763106) (xy 364.414829 -284.716286)
			(xy 364.40265 -284.666872) (xy 364.398555 -284.616144) (xy 364.092744 -284.616144) (xy 364.092254 -284.641133)
			(xy 364.084435 -284.690496) (xy 364.068991 -284.738028) (xy 364.046301 -284.78256) (xy 364.016925 -284.822993)
			(xy 363.981585 -284.858333) (xy 363.941152 -284.887709) (xy 363.89662 -284.910399) (xy 363.849088 -284.925843)
			(xy 363.799725 -284.933662) (xy 363.749747 -284.933662) (xy 363.700384 -284.925843) (xy 363.652852 -284.910399)
			(xy 363.60832 -284.887709) (xy 363.567887 -284.858333) (xy 363.532547 -284.822993) (xy 363.503171 -284.78256)
			(xy 363.480481 -284.738028) (xy 363.465037 -284.690496) (xy 363.457218 -284.641133) (xy 363.1522 -284.641133)
			(xy 363.144381 -284.690496) (xy 363.128937 -284.738028) (xy 363.106247 -284.78256) (xy 363.076871 -284.822993)
			(xy 363.041531 -284.858333) (xy 363.001098 -284.887709) (xy 362.956566 -284.910399) (xy 362.909034 -284.925843)
			(xy 362.859671 -284.933662) (xy 362.809693 -284.933662) (xy 362.76033 -284.925843) (xy 362.712798 -284.910399)
			(xy 362.668266 -284.887709) (xy 362.627833 -284.858333) (xy 362.592493 -284.822993) (xy 362.563117 -284.78256)
			(xy 362.540427 -284.738028) (xy 362.524983 -284.690496) (xy 362.517164 -284.641133) (xy 362.2124 -284.641133)
			(xy 362.204581 -284.690496) (xy 362.189137 -284.738028) (xy 362.166447 -284.78256) (xy 362.137071 -284.822993)
			(xy 362.101731 -284.858333) (xy 362.061298 -284.887709) (xy 362.016766 -284.910399) (xy 361.969234 -284.925843)
			(xy 361.919871 -284.933662) (xy 361.869893 -284.933662) (xy 361.82053 -284.925843) (xy 361.772998 -284.910399)
			(xy 361.728466 -284.887709) (xy 361.688033 -284.858333) (xy 361.652693 -284.822993) (xy 361.623317 -284.78256)
			(xy 361.600627 -284.738028) (xy 361.585183 -284.690496) (xy 361.577364 -284.641133) (xy 358.458534 -284.641133)
			(xy 358.450715 -284.690496) (xy 358.435271 -284.738028) (xy 358.412581 -284.78256) (xy 358.383205 -284.822993)
			(xy 358.347865 -284.858333) (xy 358.307432 -284.887709) (xy 358.2629 -284.910399) (xy 358.215368 -284.925843)
			(xy 358.166005 -284.933662) (xy 358.116027 -284.933662) (xy 358.066664 -284.925843) (xy 358.019132 -284.910399)
			(xy 357.9746 -284.887709) (xy 357.934167 -284.858333) (xy 357.898827 -284.822993) (xy 357.869451 -284.78256)
			(xy 357.846761 -284.738028) (xy 357.831317 -284.690496) (xy 357.823498 -284.641133) (xy 357.518734 -284.641133)
			(xy 357.510915 -284.690496) (xy 357.495471 -284.738028) (xy 357.472781 -284.78256) (xy 357.443405 -284.822993)
			(xy 357.408065 -284.858333) (xy 357.367632 -284.887709) (xy 357.3231 -284.910399) (xy 357.275568 -284.925843)
			(xy 357.226205 -284.933662) (xy 357.176227 -284.933662) (xy 357.126864 -284.925843) (xy 357.079332 -284.910399)
			(xy 357.0348 -284.887709) (xy 356.994367 -284.858333) (xy 356.959027 -284.822993) (xy 356.929651 -284.78256)
			(xy 356.906961 -284.738028) (xy 356.891517 -284.690496) (xy 356.883698 -284.641133) (xy 356.57868 -284.641133)
			(xy 356.570861 -284.690496) (xy 356.555417 -284.738028) (xy 356.532727 -284.78256) (xy 356.503351 -284.822993)
			(xy 356.468011 -284.858333) (xy 356.427578 -284.887709) (xy 356.383046 -284.910399) (xy 356.335514 -284.925843)
			(xy 356.286151 -284.933662) (xy 356.236173 -284.933662) (xy 356.18681 -284.925843) (xy 356.139278 -284.910399)
			(xy 356.094746 -284.887709) (xy 356.054313 -284.858333) (xy 356.018973 -284.822993) (xy 355.989597 -284.78256)
			(xy 355.966907 -284.738028) (xy 355.951463 -284.690496) (xy 355.943644 -284.641133) (xy 355.636327 -284.641133)
			(xy 355.636318 -284.64159) (xy 355.628154 -284.691824) (xy 355.612038 -284.740098) (xy 355.588387 -284.785161)
			(xy 355.557814 -284.825847) (xy 355.52111 -284.861102) (xy 355.479226 -284.890012) (xy 355.433247 -284.911829)
			(xy 355.384363 -284.925989) (xy 355.333842 -284.932123) (xy 355.28299 -284.930074) (xy 355.233126 -284.919894)
			(xy 355.18554 -284.901847) (xy 355.141466 -284.876401) (xy 355.102044 -284.844214) (xy 355.068296 -284.80612)
			(xy 355.041095 -284.763106) (xy 355.021147 -284.716286) (xy 355.008968 -284.666872) (xy 355.004873 -284.616144)
			(xy 354.696776 -284.616144) (xy 354.696264 -284.64159) (xy 354.6881 -284.691824) (xy 354.671984 -284.740098)
			(xy 354.648333 -284.785161) (xy 354.61776 -284.825847) (xy 354.581056 -284.861102) (xy 354.539172 -284.890012)
			(xy 354.493193 -284.911829) (xy 354.444309 -284.925989) (xy 354.393788 -284.932123) (xy 354.342936 -284.930074)
			(xy 354.293072 -284.919894) (xy 354.245486 -284.901847) (xy 354.201412 -284.876401) (xy 354.16199 -284.844214)
			(xy 354.128242 -284.80612) (xy 354.101041 -284.763106) (xy 354.081093 -284.716286) (xy 354.068914 -284.666872)
			(xy 354.064819 -284.616144) (xy 353.759008 -284.616144) (xy 353.758518 -284.641133) (xy 353.750699 -284.690496)
			(xy 353.735255 -284.738028) (xy 353.712565 -284.78256) (xy 353.683189 -284.822993) (xy 353.647849 -284.858333)
			(xy 353.607416 -284.887709) (xy 353.562884 -284.910399) (xy 353.515352 -284.925843) (xy 353.465989 -284.933662)
			(xy 353.416011 -284.933662) (xy 353.366648 -284.925843) (xy 353.319116 -284.910399) (xy 353.274584 -284.887709)
			(xy 353.234151 -284.858333) (xy 353.198811 -284.822993) (xy 353.169435 -284.78256) (xy 353.146745 -284.738028)
			(xy 353.131301 -284.690496) (xy 353.123482 -284.641133) (xy 352.816419 -284.641133) (xy 352.81641 -284.64159)
			(xy 352.808246 -284.691824) (xy 352.79213 -284.740098) (xy 352.768479 -284.785161) (xy 352.737906 -284.825847)
			(xy 352.701202 -284.861102) (xy 352.659318 -284.890012) (xy 352.613339 -284.911829) (xy 352.564455 -284.925989)
			(xy 352.513934 -284.932123) (xy 352.463082 -284.930074) (xy 352.413218 -284.919894) (xy 352.365632 -284.901847)
			(xy 352.321558 -284.876401) (xy 352.282136 -284.844214) (xy 352.248388 -284.80612) (xy 352.221187 -284.763106)
			(xy 352.201239 -284.716286) (xy 352.18906 -284.666872) (xy 352.184965 -284.616144) (xy 351.876868 -284.616144)
			(xy 351.876356 -284.64159) (xy 351.868192 -284.691824) (xy 351.852076 -284.740098) (xy 351.828425 -284.785161)
			(xy 351.797852 -284.825847) (xy 351.761148 -284.861102) (xy 351.719264 -284.890012) (xy 351.673285 -284.911829)
			(xy 351.624401 -284.925989) (xy 351.57388 -284.932123) (xy 351.523028 -284.930074) (xy 351.473164 -284.919894)
			(xy 351.425578 -284.901847) (xy 351.381504 -284.876401) (xy 351.342082 -284.844214) (xy 351.308334 -284.80612)
			(xy 351.281133 -284.763106) (xy 351.261185 -284.716286) (xy 351.249006 -284.666872) (xy 351.244911 -284.616144)
			(xy 350.9391 -284.616144) (xy 350.93861 -284.641133) (xy 350.930791 -284.690496) (xy 350.915347 -284.738028)
			(xy 350.892657 -284.78256) (xy 350.863281 -284.822993) (xy 350.827941 -284.858333) (xy 350.787508 -284.887709)
			(xy 350.742976 -284.910399) (xy 350.695444 -284.925843) (xy 350.646081 -284.933662) (xy 350.596103 -284.933662)
			(xy 350.54674 -284.925843) (xy 350.499208 -284.910399) (xy 350.454676 -284.887709) (xy 350.414243 -284.858333)
			(xy 350.378903 -284.822993) (xy 350.349527 -284.78256) (xy 350.326837 -284.738028) (xy 350.311393 -284.690496)
			(xy 350.303574 -284.641133) (xy 349.996257 -284.641133) (xy 349.996248 -284.64159) (xy 349.988084 -284.691824)
			(xy 349.971968 -284.740098) (xy 349.948317 -284.785161) (xy 349.917744 -284.825847) (xy 349.88104 -284.861102)
			(xy 349.839156 -284.890012) (xy 349.793177 -284.911829) (xy 349.744293 -284.925989) (xy 349.693772 -284.932123)
			(xy 349.64292 -284.930074) (xy 349.593056 -284.919894) (xy 349.54547 -284.901847) (xy 349.501396 -284.876401)
			(xy 349.461974 -284.844214) (xy 349.428226 -284.80612) (xy 349.401025 -284.763106) (xy 349.381077 -284.716286)
			(xy 349.368898 -284.666872) (xy 349.364803 -284.616144) (xy 349.05696 -284.616144) (xy 349.056448 -284.64159)
			(xy 349.048284 -284.691824) (xy 349.032168 -284.740098) (xy 349.008517 -284.785161) (xy 348.977944 -284.825847)
			(xy 348.94124 -284.861102) (xy 348.899356 -284.890012) (xy 348.853377 -284.911829) (xy 348.804493 -284.925989)
			(xy 348.753972 -284.932123) (xy 348.70312 -284.930074) (xy 348.653256 -284.919894) (xy 348.60567 -284.901847)
			(xy 348.561596 -284.876401) (xy 348.522174 -284.844214) (xy 348.488426 -284.80612) (xy 348.461225 -284.763106)
			(xy 348.441277 -284.716286) (xy 348.429098 -284.666872) (xy 348.425003 -284.616144) (xy 348.119192 -284.616144)
			(xy 348.118702 -284.641133) (xy 348.110883 -284.690496) (xy 348.095439 -284.738028) (xy 348.072749 -284.78256)
			(xy 348.043373 -284.822993) (xy 348.008033 -284.858333) (xy 347.9676 -284.887709) (xy 347.923068 -284.910399)
			(xy 347.875536 -284.925843) (xy 347.826173 -284.933662) (xy 347.776195 -284.933662) (xy 347.726832 -284.925843)
			(xy 347.6793 -284.910399) (xy 347.634768 -284.887709) (xy 347.594335 -284.858333) (xy 347.558995 -284.822993)
			(xy 347.529619 -284.78256) (xy 347.506929 -284.738028) (xy 347.491485 -284.690496) (xy 347.483666 -284.641133)
			(xy 347.176349 -284.641133) (xy 347.17634 -284.64159) (xy 347.168176 -284.691824) (xy 347.15206 -284.740098)
			(xy 347.128409 -284.785161) (xy 347.097836 -284.825847) (xy 347.061132 -284.861102) (xy 347.019248 -284.890012)
			(xy 346.973269 -284.911829) (xy 346.924385 -284.925989) (xy 346.873864 -284.932123) (xy 346.823012 -284.930074)
			(xy 346.773148 -284.919894) (xy 346.725562 -284.901847) (xy 346.681488 -284.876401) (xy 346.642066 -284.844214)
			(xy 346.608318 -284.80612) (xy 346.581117 -284.763106) (xy 346.561169 -284.716286) (xy 346.54899 -284.666872)
			(xy 346.544895 -284.616144) (xy 346.236798 -284.616144) (xy 346.236286 -284.64159) (xy 346.228122 -284.691824)
			(xy 346.212006 -284.740098) (xy 346.188355 -284.785161) (xy 346.157782 -284.825847) (xy 346.121078 -284.861102)
			(xy 346.079194 -284.890012) (xy 346.033215 -284.911829) (xy 345.984331 -284.925989) (xy 345.93381 -284.932123)
			(xy 345.882958 -284.930074) (xy 345.833094 -284.919894) (xy 345.785508 -284.901847) (xy 345.741434 -284.876401)
			(xy 345.702012 -284.844214) (xy 345.668264 -284.80612) (xy 345.641063 -284.763106) (xy 345.621115 -284.716286)
			(xy 345.608936 -284.666872) (xy 345.604841 -284.616144) (xy 345.298915 -284.616144) (xy 345.297321 -284.654089)
			(xy 345.287715 -284.702323) (xy 345.270794 -284.748502) (xy 345.246963 -284.791524) (xy 345.232228 -284.811216)
			(xy 345.21439 -284.833188) (xy 345.172317 -284.871033) (xy 345.1242 -284.900818) (xy 345.098116 -284.9118)
			(xy 345.097862 -284.9118) (xy 345.095068 -284.912816) (xy 345.086739 -284.917198) (xy 345.073735 -284.930779)
			(xy 345.066492 -284.948132) (xy 345.065858 -284.95752) (xy 345.065858 -285.12008) (xy 345.066316 -285.129916)
			(xy 345.073749 -285.148129) (xy 345.087517 -285.162178) (xy 345.096338 -285.166562) (xy 345.14155 -285.186374)
			(xy 345.17965 -285.202884) (xy 345.186544 -285.205612) (xy 345.201255 -285.20741) (xy 345.208606 -285.20644)
			(xy 345.215464 -285.20517) (xy 345.228672 -285.19882) (xy 345.23426 -285.193486) (xy 345.252025 -285.177525)
			(xy 345.291444 -285.150565) (xy 345.33445 -285.129799) (xy 345.380076 -285.115695) (xy 345.427298 -285.108568)
			(xy 345.451176 -285.108142) (xy 345.476164 -285.108605) (xy 345.525527 -285.11642) (xy 345.573058 -285.131861)
			(xy 345.617589 -285.154547) (xy 345.658023 -285.183921) (xy 345.693363 -285.219259) (xy 345.72274 -285.25969)
			(xy 345.74543 -285.304219) (xy 345.760875 -285.35175) (xy 345.768693 -285.401112) (xy 345.768693 -285.451088)
			(xy 345.768685 -285.451139) (xy 346.073712 -285.451139) (xy 346.073712 -285.401161) (xy 346.081531 -285.351798)
			(xy 346.096975 -285.304266) (xy 346.119665 -285.259734) (xy 346.149041 -285.219301) (xy 346.184381 -285.183961)
			(xy 346.224814 -285.154585) (xy 346.269346 -285.131895) (xy 346.316878 -285.116451) (xy 346.366241 -285.108632)
			(xy 346.416219 -285.108632) (xy 346.465582 -285.116451) (xy 346.513114 -285.131895) (xy 346.557646 -285.154585)
			(xy 346.598079 -285.183961) (xy 346.633419 -285.219301) (xy 346.662795 -285.259734) (xy 346.685485 -285.304266)
			(xy 346.700929 -285.351798) (xy 346.708748 -285.401161) (xy 346.709238 -285.42615) (xy 346.708748 -285.451139)
			(xy 347.013512 -285.451139) (xy 347.013512 -285.401161) (xy 347.021331 -285.351798) (xy 347.036775 -285.304266)
			(xy 347.059465 -285.259734) (xy 347.088841 -285.219301) (xy 347.124181 -285.183961) (xy 347.164614 -285.154585)
			(xy 347.209146 -285.131895) (xy 347.256678 -285.116451) (xy 347.306041 -285.108632) (xy 347.356019 -285.108632)
			(xy 347.405382 -285.116451) (xy 347.452914 -285.131895) (xy 347.497446 -285.154585) (xy 347.537879 -285.183961)
			(xy 347.573219 -285.219301) (xy 347.602595 -285.259734) (xy 347.625285 -285.304266) (xy 347.640729 -285.351798)
			(xy 347.648548 -285.401161) (xy 347.649038 -285.42615) (xy 347.648548 -285.451139) (xy 347.953566 -285.451139)
			(xy 347.953566 -285.401161) (xy 347.961385 -285.351798) (xy 347.976829 -285.304266) (xy 347.999519 -285.259734)
			(xy 348.028895 -285.219301) (xy 348.064235 -285.183961) (xy 348.104668 -285.154585) (xy 348.1492 -285.131895)
			(xy 348.196732 -285.116451) (xy 348.246095 -285.108632) (xy 348.296073 -285.108632) (xy 348.345436 -285.116451)
			(xy 348.392968 -285.131895) (xy 348.4375 -285.154585) (xy 348.477933 -285.183961) (xy 348.513273 -285.219301)
			(xy 348.542649 -285.259734) (xy 348.565339 -285.304266) (xy 348.580783 -285.351798) (xy 348.588602 -285.401161)
			(xy 348.589092 -285.42615) (xy 348.588602 -285.451139) (xy 348.89362 -285.451139) (xy 348.89362 -285.401161)
			(xy 348.901439 -285.351798) (xy 348.916883 -285.304266) (xy 348.939573 -285.259734) (xy 348.968949 -285.219301)
			(xy 349.004289 -285.183961) (xy 349.044722 -285.154585) (xy 349.089254 -285.131895) (xy 349.136786 -285.116451)
			(xy 349.186149 -285.108632) (xy 349.236127 -285.108632) (xy 349.28549 -285.116451) (xy 349.333022 -285.131895)
			(xy 349.377554 -285.154585) (xy 349.417987 -285.183961) (xy 349.453327 -285.219301) (xy 349.482703 -285.259734)
			(xy 349.505393 -285.304266) (xy 349.520837 -285.351798) (xy 349.528656 -285.401161) (xy 349.529146 -285.42615)
			(xy 349.528656 -285.451139) (xy 349.833674 -285.451139) (xy 349.833674 -285.401161) (xy 349.841493 -285.351798)
			(xy 349.856937 -285.304266) (xy 349.879627 -285.259734) (xy 349.909003 -285.219301) (xy 349.944343 -285.183961)
			(xy 349.984776 -285.154585) (xy 350.029308 -285.131895) (xy 350.07684 -285.116451) (xy 350.126203 -285.108632)
			(xy 350.176181 -285.108632) (xy 350.225544 -285.116451) (xy 350.273076 -285.131895) (xy 350.317608 -285.154585)
			(xy 350.358041 -285.183961) (xy 350.393381 -285.219301) (xy 350.422757 -285.259734) (xy 350.445447 -285.304266)
			(xy 350.460891 -285.351798) (xy 350.46871 -285.401161) (xy 350.4692 -285.42615) (xy 350.46871 -285.451139)
			(xy 350.773728 -285.451139) (xy 350.773728 -285.401161) (xy 350.781547 -285.351798) (xy 350.796991 -285.304266)
			(xy 350.819681 -285.259734) (xy 350.849057 -285.219301) (xy 350.884397 -285.183961) (xy 350.92483 -285.154585)
			(xy 350.969362 -285.131895) (xy 351.016894 -285.116451) (xy 351.066257 -285.108632) (xy 351.116235 -285.108632)
			(xy 351.165598 -285.116451) (xy 351.21313 -285.131895) (xy 351.257662 -285.154585) (xy 351.298095 -285.183961)
			(xy 351.333435 -285.219301) (xy 351.362811 -285.259734) (xy 351.385501 -285.304266) (xy 351.400945 -285.351798)
			(xy 351.408764 -285.401161) (xy 351.409254 -285.42615) (xy 351.408764 -285.451139) (xy 351.713528 -285.451139)
			(xy 351.713528 -285.401161) (xy 351.721347 -285.351798) (xy 351.736791 -285.304266) (xy 351.759481 -285.259734)
			(xy 351.788857 -285.219301) (xy 351.824197 -285.183961) (xy 351.86463 -285.154585) (xy 351.909162 -285.131895)
			(xy 351.956694 -285.116451) (xy 352.006057 -285.108632) (xy 352.056035 -285.108632) (xy 352.105398 -285.116451)
			(xy 352.15293 -285.131895) (xy 352.197462 -285.154585) (xy 352.237895 -285.183961) (xy 352.273235 -285.219301)
			(xy 352.302611 -285.259734) (xy 352.325301 -285.304266) (xy 352.340745 -285.351798) (xy 352.348564 -285.401161)
			(xy 352.349054 -285.42615) (xy 352.348564 -285.451139) (xy 352.653582 -285.451139) (xy 352.653582 -285.401161)
			(xy 352.661401 -285.351798) (xy 352.676845 -285.304266) (xy 352.699535 -285.259734) (xy 352.728911 -285.219301)
			(xy 352.764251 -285.183961) (xy 352.804684 -285.154585) (xy 352.849216 -285.131895) (xy 352.896748 -285.116451)
			(xy 352.946111 -285.108632) (xy 352.996089 -285.108632) (xy 353.045452 -285.116451) (xy 353.092984 -285.131895)
			(xy 353.137516 -285.154585) (xy 353.177949 -285.183961) (xy 353.213289 -285.219301) (xy 353.242665 -285.259734)
			(xy 353.265355 -285.304266) (xy 353.280799 -285.351798) (xy 353.288618 -285.401161) (xy 353.289108 -285.42615)
			(xy 353.288618 -285.451139) (xy 353.593636 -285.451139) (xy 353.593636 -285.401161) (xy 353.601455 -285.351798)
			(xy 353.616899 -285.304266) (xy 353.639589 -285.259734) (xy 353.668965 -285.219301) (xy 353.704305 -285.183961)
			(xy 353.744738 -285.154585) (xy 353.78927 -285.131895) (xy 353.836802 -285.116451) (xy 353.886165 -285.108632)
			(xy 353.936143 -285.108632) (xy 353.985506 -285.116451) (xy 354.033038 -285.131895) (xy 354.07757 -285.154585)
			(xy 354.118003 -285.183961) (xy 354.153343 -285.219301) (xy 354.182719 -285.259734) (xy 354.205409 -285.304266)
			(xy 354.220853 -285.351798) (xy 354.228672 -285.401161) (xy 354.229162 -285.42615) (xy 354.228672 -285.451139)
			(xy 354.53369 -285.451139) (xy 354.53369 -285.401161) (xy 354.541509 -285.351798) (xy 354.556953 -285.304266)
			(xy 354.579643 -285.259734) (xy 354.609019 -285.219301) (xy 354.644359 -285.183961) (xy 354.684792 -285.154585)
			(xy 354.729324 -285.131895) (xy 354.776856 -285.116451) (xy 354.826219 -285.108632) (xy 354.876197 -285.108632)
			(xy 354.92556 -285.116451) (xy 354.973092 -285.131895) (xy 355.017624 -285.154585) (xy 355.058057 -285.183961)
			(xy 355.093397 -285.219301) (xy 355.122773 -285.259734) (xy 355.145463 -285.304266) (xy 355.160907 -285.351798)
			(xy 355.168726 -285.401161) (xy 355.169216 -285.42615) (xy 355.168726 -285.451139) (xy 355.47349 -285.451139)
			(xy 355.47349 -285.401161) (xy 355.481309 -285.351798) (xy 355.496753 -285.304266) (xy 355.519443 -285.259734)
			(xy 355.548819 -285.219301) (xy 355.584159 -285.183961) (xy 355.624592 -285.154585) (xy 355.669124 -285.131895)
			(xy 355.716656 -285.116451) (xy 355.766019 -285.108632) (xy 355.815997 -285.108632) (xy 355.86536 -285.116451)
			(xy 355.912892 -285.131895) (xy 355.957424 -285.154585) (xy 355.997857 -285.183961) (xy 356.033197 -285.219301)
			(xy 356.062573 -285.259734) (xy 356.085263 -285.304266) (xy 356.100707 -285.351798) (xy 356.108526 -285.401161)
			(xy 356.109016 -285.42615) (xy 356.414827 -285.42615) (xy 356.418922 -285.375422) (xy 356.431101 -285.326008)
			(xy 356.451049 -285.279188) (xy 356.47825 -285.236174) (xy 356.511998 -285.19808) (xy 356.55142 -285.165893)
			(xy 356.595494 -285.140447) (xy 356.64308 -285.1224) (xy 356.692944 -285.11222) (xy 356.743796 -285.110171)
			(xy 356.794317 -285.116305) (xy 356.843201 -285.130465) (xy 356.88918 -285.152282) (xy 356.931064 -285.181192)
			(xy 356.967768 -285.216447) (xy 356.998341 -285.257133) (xy 357.021992 -285.302196) (xy 357.038108 -285.35047)
			(xy 357.046272 -285.400704) (xy 357.046784 -285.42615) (xy 357.354881 -285.42615) (xy 357.358976 -285.375422)
			(xy 357.371155 -285.326008) (xy 357.391103 -285.279188) (xy 357.418304 -285.236174) (xy 357.452052 -285.19808)
			(xy 357.491474 -285.165893) (xy 357.535548 -285.140447) (xy 357.583134 -285.1224) (xy 357.632998 -285.11222)
			(xy 357.68385 -285.110171) (xy 357.734371 -285.116305) (xy 357.783255 -285.130465) (xy 357.829234 -285.152282)
			(xy 357.871118 -285.181192) (xy 357.907822 -285.216447) (xy 357.938395 -285.257133) (xy 357.962046 -285.302196)
			(xy 357.978162 -285.35047) (xy 357.986326 -285.400704) (xy 357.986838 -285.42615) (xy 357.986335 -285.451139)
			(xy 358.293652 -285.451139) (xy 358.293652 -285.401161) (xy 358.301471 -285.351798) (xy 358.316915 -285.304266)
			(xy 358.339605 -285.259734) (xy 358.368981 -285.219301) (xy 358.404321 -285.183961) (xy 358.444754 -285.154585)
			(xy 358.489286 -285.131895) (xy 358.536818 -285.116451) (xy 358.586181 -285.108632) (xy 358.636159 -285.108632)
			(xy 358.685522 -285.116451) (xy 358.733054 -285.131895) (xy 358.777586 -285.154585) (xy 358.818019 -285.183961)
			(xy 358.853359 -285.219301) (xy 358.882735 -285.259734) (xy 358.905425 -285.304266) (xy 358.920869 -285.351798)
			(xy 358.928688 -285.401161) (xy 358.929178 -285.42615) (xy 358.928688 -285.451139) (xy 361.10721 -285.451139)
			(xy 361.10721 -285.401161) (xy 361.115029 -285.351798) (xy 361.130473 -285.304266) (xy 361.153163 -285.259734)
			(xy 361.182539 -285.219301) (xy 361.217879 -285.183961) (xy 361.258312 -285.154585) (xy 361.302844 -285.131895)
			(xy 361.350376 -285.116451) (xy 361.399739 -285.108632) (xy 361.449717 -285.108632) (xy 361.49908 -285.116451)
			(xy 361.546612 -285.131895) (xy 361.591144 -285.154585) (xy 361.631577 -285.183961) (xy 361.666917 -285.219301)
			(xy 361.696293 -285.259734) (xy 361.718983 -285.304266) (xy 361.734427 -285.351798) (xy 361.742246 -285.401161)
			(xy 361.742736 -285.42615) (xy 362.048547 -285.42615) (xy 362.052642 -285.375422) (xy 362.064821 -285.326008)
			(xy 362.084769 -285.279188) (xy 362.11197 -285.236174) (xy 362.145718 -285.19808) (xy 362.18514 -285.165893)
			(xy 362.229214 -285.140447) (xy 362.2768 -285.1224) (xy 362.326664 -285.11222) (xy 362.377516 -285.110171)
			(xy 362.428037 -285.116305) (xy 362.476921 -285.130465) (xy 362.5229 -285.152282) (xy 362.564784 -285.181192)
			(xy 362.601488 -285.216447) (xy 362.632061 -285.257133) (xy 362.655712 -285.302196) (xy 362.671828 -285.35047)
			(xy 362.679992 -285.400704) (xy 362.680504 -285.42615) (xy 362.988601 -285.42615) (xy 362.992696 -285.375422)
			(xy 363.004875 -285.326008) (xy 363.024823 -285.279188) (xy 363.052024 -285.236174) (xy 363.085772 -285.19808)
			(xy 363.125194 -285.165893) (xy 363.169268 -285.140447) (xy 363.216854 -285.1224) (xy 363.266718 -285.11222)
			(xy 363.31757 -285.110171) (xy 363.368091 -285.116305) (xy 363.416975 -285.130465) (xy 363.462954 -285.152282)
			(xy 363.504838 -285.181192) (xy 363.541542 -285.216447) (xy 363.572115 -285.257133) (xy 363.595766 -285.302196)
			(xy 363.611882 -285.35047) (xy 363.620046 -285.400704) (xy 363.620558 -285.42615) (xy 363.620055 -285.451139)
			(xy 363.927372 -285.451139) (xy 363.927372 -285.401161) (xy 363.935191 -285.351798) (xy 363.950635 -285.304266)
			(xy 363.973325 -285.259734) (xy 364.002701 -285.219301) (xy 364.038041 -285.183961) (xy 364.078474 -285.154585)
			(xy 364.123006 -285.131895) (xy 364.170538 -285.116451) (xy 364.219901 -285.108632) (xy 364.269879 -285.108632)
			(xy 364.319242 -285.116451) (xy 364.366774 -285.131895) (xy 364.411306 -285.154585) (xy 364.451739 -285.183961)
			(xy 364.487079 -285.219301) (xy 364.516455 -285.259734) (xy 364.539145 -285.304266) (xy 364.554589 -285.351798)
			(xy 364.562408 -285.401161) (xy 364.562898 -285.42615) (xy 364.562408 -285.451139) (xy 364.867172 -285.451139)
			(xy 364.867172 -285.401161) (xy 364.874991 -285.351798) (xy 364.890435 -285.304266) (xy 364.913125 -285.259734)
			(xy 364.942501 -285.219301) (xy 364.977841 -285.183961) (xy 365.018274 -285.154585) (xy 365.062806 -285.131895)
			(xy 365.110338 -285.116451) (xy 365.159701 -285.108632) (xy 365.209679 -285.108632) (xy 365.259042 -285.116451)
			(xy 365.306574 -285.131895) (xy 365.351106 -285.154585) (xy 365.391539 -285.183961) (xy 365.426879 -285.219301)
			(xy 365.456255 -285.259734) (xy 365.478945 -285.304266) (xy 365.494389 -285.351798) (xy 365.502208 -285.401161)
			(xy 365.502698 -285.42615) (xy 365.502208 -285.451139) (xy 365.807226 -285.451139) (xy 365.807226 -285.401161)
			(xy 365.815045 -285.351798) (xy 365.830489 -285.304266) (xy 365.853179 -285.259734) (xy 365.882555 -285.219301)
			(xy 365.917895 -285.183961) (xy 365.958328 -285.154585) (xy 366.00286 -285.131895) (xy 366.050392 -285.116451)
			(xy 366.099755 -285.108632) (xy 366.149733 -285.108632) (xy 366.199096 -285.116451) (xy 366.246628 -285.131895)
			(xy 366.29116 -285.154585) (xy 366.331593 -285.183961) (xy 366.366933 -285.219301) (xy 366.396309 -285.259734)
			(xy 366.418999 -285.304266) (xy 366.434443 -285.351798) (xy 366.442262 -285.401161) (xy 366.442752 -285.42615)
			(xy 366.442262 -285.451139) (xy 366.74728 -285.451139) (xy 366.74728 -285.401161) (xy 366.755099 -285.351798)
			(xy 366.770543 -285.304266) (xy 366.793233 -285.259734) (xy 366.822609 -285.219301) (xy 366.857949 -285.183961)
			(xy 366.898382 -285.154585) (xy 366.942914 -285.131895) (xy 366.990446 -285.116451) (xy 367.039809 -285.108632)
			(xy 367.089787 -285.108632) (xy 367.13915 -285.116451) (xy 367.186682 -285.131895) (xy 367.231214 -285.154585)
			(xy 367.271647 -285.183961) (xy 367.306987 -285.219301) (xy 367.336363 -285.259734) (xy 367.359053 -285.304266)
			(xy 367.374497 -285.351798) (xy 367.382316 -285.401161) (xy 367.382806 -285.42615) (xy 367.382316 -285.451139)
			(xy 367.687334 -285.451139) (xy 367.687334 -285.401161) (xy 367.695153 -285.351798) (xy 367.710597 -285.304266)
			(xy 367.733287 -285.259734) (xy 367.762663 -285.219301) (xy 367.798003 -285.183961) (xy 367.838436 -285.154585)
			(xy 367.882968 -285.131895) (xy 367.9305 -285.116451) (xy 367.979863 -285.108632) (xy 368.029841 -285.108632)
			(xy 368.079204 -285.116451) (xy 368.126736 -285.131895) (xy 368.171268 -285.154585) (xy 368.211701 -285.183961)
			(xy 368.247041 -285.219301) (xy 368.276417 -285.259734) (xy 368.299107 -285.304266) (xy 368.314551 -285.351798)
			(xy 368.32237 -285.401161) (xy 368.32286 -285.42615) (xy 368.32237 -285.451139) (xy 368.627388 -285.451139)
			(xy 368.627388 -285.401161) (xy 368.635207 -285.351798) (xy 368.650651 -285.304266) (xy 368.673341 -285.259734)
			(xy 368.702717 -285.219301) (xy 368.738057 -285.183961) (xy 368.77849 -285.154585) (xy 368.823022 -285.131895)
			(xy 368.870554 -285.116451) (xy 368.919917 -285.108632) (xy 368.969895 -285.108632) (xy 369.019258 -285.116451)
			(xy 369.06679 -285.131895) (xy 369.111322 -285.154585) (xy 369.151755 -285.183961) (xy 369.187095 -285.219301)
			(xy 369.216471 -285.259734) (xy 369.239161 -285.304266) (xy 369.254605 -285.351798) (xy 369.262424 -285.401161)
			(xy 369.262914 -285.42615) (xy 369.262424 -285.451139) (xy 369.567188 -285.451139) (xy 369.567188 -285.401161)
			(xy 369.575007 -285.351798) (xy 369.590451 -285.304266) (xy 369.613141 -285.259734) (xy 369.642517 -285.219301)
			(xy 369.677857 -285.183961) (xy 369.71829 -285.154585) (xy 369.762822 -285.131895) (xy 369.810354 -285.116451)
			(xy 369.859717 -285.108632) (xy 369.909695 -285.108632) (xy 369.959058 -285.116451) (xy 370.00659 -285.131895)
			(xy 370.051122 -285.154585) (xy 370.091555 -285.183961) (xy 370.126895 -285.219301) (xy 370.156271 -285.259734)
			(xy 370.178961 -285.304266) (xy 370.194405 -285.351798) (xy 370.202224 -285.401161) (xy 370.202714 -285.42615)
			(xy 370.202224 -285.451139) (xy 370.507242 -285.451139) (xy 370.507242 -285.401161) (xy 370.515061 -285.351798)
			(xy 370.530505 -285.304266) (xy 370.553195 -285.259734) (xy 370.582571 -285.219301) (xy 370.617911 -285.183961)
			(xy 370.658344 -285.154585) (xy 370.702876 -285.131895) (xy 370.750408 -285.116451) (xy 370.799771 -285.108632)
			(xy 370.849749 -285.108632) (xy 370.899112 -285.116451) (xy 370.946644 -285.131895) (xy 370.991176 -285.154585)
			(xy 371.031609 -285.183961) (xy 371.066949 -285.219301) (xy 371.096325 -285.259734) (xy 371.119015 -285.304266)
			(xy 371.134459 -285.351798) (xy 371.142278 -285.401161) (xy 371.142768 -285.42615) (xy 371.142278 -285.451139)
			(xy 371.447296 -285.451139) (xy 371.447296 -285.401161) (xy 371.455115 -285.351798) (xy 371.470559 -285.304266)
			(xy 371.493249 -285.259734) (xy 371.522625 -285.219301) (xy 371.557965 -285.183961) (xy 371.598398 -285.154585)
			(xy 371.64293 -285.131895) (xy 371.690462 -285.116451) (xy 371.739825 -285.108632) (xy 371.789803 -285.108632)
			(xy 371.839166 -285.116451) (xy 371.886698 -285.131895) (xy 371.93123 -285.154585) (xy 371.971663 -285.183961)
			(xy 372.007003 -285.219301) (xy 372.036379 -285.259734) (xy 372.059069 -285.304266) (xy 372.074513 -285.351798)
			(xy 372.082332 -285.401161) (xy 372.082822 -285.42615) (xy 372.082332 -285.451139) (xy 372.38735 -285.451139)
			(xy 372.38735 -285.401161) (xy 372.395169 -285.351798) (xy 372.410613 -285.304266) (xy 372.433303 -285.259734)
			(xy 372.462679 -285.219301) (xy 372.498019 -285.183961) (xy 372.538452 -285.154585) (xy 372.582984 -285.131895)
			(xy 372.630516 -285.116451) (xy 372.679879 -285.108632) (xy 372.729857 -285.108632) (xy 372.77922 -285.116451)
			(xy 372.826752 -285.131895) (xy 372.871284 -285.154585) (xy 372.911717 -285.183961) (xy 372.947057 -285.219301)
			(xy 372.976433 -285.259734) (xy 372.999123 -285.304266) (xy 373.014567 -285.351798) (xy 373.022386 -285.401161)
			(xy 373.022876 -285.42615) (xy 373.022386 -285.451139) (xy 373.327404 -285.451139) (xy 373.327404 -285.401161)
			(xy 373.335223 -285.351798) (xy 373.350667 -285.304266) (xy 373.373357 -285.259734) (xy 373.402733 -285.219301)
			(xy 373.438073 -285.183961) (xy 373.478506 -285.154585) (xy 373.523038 -285.131895) (xy 373.57057 -285.116451)
			(xy 373.619933 -285.108632) (xy 373.669911 -285.108632) (xy 373.719274 -285.116451) (xy 373.766806 -285.131895)
			(xy 373.811338 -285.154585) (xy 373.851771 -285.183961) (xy 373.887111 -285.219301) (xy 373.916487 -285.259734)
			(xy 373.939177 -285.304266) (xy 373.954621 -285.351798) (xy 373.96244 -285.401161) (xy 373.96293 -285.42615)
			(xy 373.96244 -285.451139) (xy 373.954621 -285.500502) (xy 373.939177 -285.548034) (xy 373.916487 -285.592566)
			(xy 373.887111 -285.632999) (xy 373.851771 -285.668339) (xy 373.811338 -285.697715) (xy 373.766806 -285.720405)
			(xy 373.719274 -285.735849) (xy 373.669911 -285.743668) (xy 373.619933 -285.743668) (xy 373.57057 -285.735849)
			(xy 373.523038 -285.720405) (xy 373.478506 -285.697715) (xy 373.438073 -285.668339) (xy 373.402733 -285.632999)
			(xy 373.373357 -285.592566) (xy 373.350667 -285.548034) (xy 373.335223 -285.500502) (xy 373.327404 -285.451139)
			(xy 373.022386 -285.451139) (xy 373.014567 -285.500502) (xy 372.999123 -285.548034) (xy 372.976433 -285.592566)
			(xy 372.947057 -285.632999) (xy 372.911717 -285.668339) (xy 372.871284 -285.697715) (xy 372.826752 -285.720405)
			(xy 372.77922 -285.735849) (xy 372.729857 -285.743668) (xy 372.679879 -285.743668) (xy 372.630516 -285.735849)
			(xy 372.582984 -285.720405) (xy 372.538452 -285.697715) (xy 372.498019 -285.668339) (xy 372.462679 -285.632999)
			(xy 372.433303 -285.592566) (xy 372.410613 -285.548034) (xy 372.395169 -285.500502) (xy 372.38735 -285.451139)
			(xy 372.082332 -285.451139) (xy 372.074513 -285.500502) (xy 372.059069 -285.548034) (xy 372.036379 -285.592566)
			(xy 372.007003 -285.632999) (xy 371.971663 -285.668339) (xy 371.93123 -285.697715) (xy 371.886698 -285.720405)
			(xy 371.839166 -285.735849) (xy 371.789803 -285.743668) (xy 371.739825 -285.743668) (xy 371.690462 -285.735849)
			(xy 371.64293 -285.720405) (xy 371.598398 -285.697715) (xy 371.557965 -285.668339) (xy 371.522625 -285.632999)
			(xy 371.493249 -285.592566) (xy 371.470559 -285.548034) (xy 371.455115 -285.500502) (xy 371.447296 -285.451139)
			(xy 371.142278 -285.451139) (xy 371.134459 -285.500502) (xy 371.119015 -285.548034) (xy 371.096325 -285.592566)
			(xy 371.066949 -285.632999) (xy 371.031609 -285.668339) (xy 370.991176 -285.697715) (xy 370.946644 -285.720405)
			(xy 370.899112 -285.735849) (xy 370.849749 -285.743668) (xy 370.799771 -285.743668) (xy 370.750408 -285.735849)
			(xy 370.702876 -285.720405) (xy 370.658344 -285.697715) (xy 370.617911 -285.668339) (xy 370.582571 -285.632999)
			(xy 370.553195 -285.592566) (xy 370.530505 -285.548034) (xy 370.515061 -285.500502) (xy 370.507242 -285.451139)
			(xy 370.202224 -285.451139) (xy 370.194405 -285.500502) (xy 370.178961 -285.548034) (xy 370.156271 -285.592566)
			(xy 370.126895 -285.632999) (xy 370.091555 -285.668339) (xy 370.051122 -285.697715) (xy 370.00659 -285.720405)
			(xy 369.959058 -285.735849) (xy 369.909695 -285.743668) (xy 369.859717 -285.743668) (xy 369.810354 -285.735849)
			(xy 369.762822 -285.720405) (xy 369.71829 -285.697715) (xy 369.677857 -285.668339) (xy 369.642517 -285.632999)
			(xy 369.613141 -285.592566) (xy 369.590451 -285.548034) (xy 369.575007 -285.500502) (xy 369.567188 -285.451139)
			(xy 369.262424 -285.451139) (xy 369.254605 -285.500502) (xy 369.239161 -285.548034) (xy 369.216471 -285.592566)
			(xy 369.187095 -285.632999) (xy 369.151755 -285.668339) (xy 369.111322 -285.697715) (xy 369.06679 -285.720405)
			(xy 369.019258 -285.735849) (xy 368.969895 -285.743668) (xy 368.919917 -285.743668) (xy 368.870554 -285.735849)
			(xy 368.823022 -285.720405) (xy 368.77849 -285.697715) (xy 368.738057 -285.668339) (xy 368.702717 -285.632999)
			(xy 368.673341 -285.592566) (xy 368.650651 -285.548034) (xy 368.635207 -285.500502) (xy 368.627388 -285.451139)
			(xy 368.32237 -285.451139) (xy 368.314551 -285.500502) (xy 368.299107 -285.548034) (xy 368.276417 -285.592566)
			(xy 368.247041 -285.632999) (xy 368.211701 -285.668339) (xy 368.171268 -285.697715) (xy 368.126736 -285.720405)
			(xy 368.079204 -285.735849) (xy 368.029841 -285.743668) (xy 367.979863 -285.743668) (xy 367.9305 -285.735849)
			(xy 367.882968 -285.720405) (xy 367.838436 -285.697715) (xy 367.798003 -285.668339) (xy 367.762663 -285.632999)
			(xy 367.733287 -285.592566) (xy 367.710597 -285.548034) (xy 367.695153 -285.500502) (xy 367.687334 -285.451139)
			(xy 367.382316 -285.451139) (xy 367.374497 -285.500502) (xy 367.359053 -285.548034) (xy 367.336363 -285.592566)
			(xy 367.306987 -285.632999) (xy 367.271647 -285.668339) (xy 367.231214 -285.697715) (xy 367.186682 -285.720405)
			(xy 367.13915 -285.735849) (xy 367.089787 -285.743668) (xy 367.039809 -285.743668) (xy 366.990446 -285.735849)
			(xy 366.942914 -285.720405) (xy 366.898382 -285.697715) (xy 366.857949 -285.668339) (xy 366.822609 -285.632999)
			(xy 366.793233 -285.592566) (xy 366.770543 -285.548034) (xy 366.755099 -285.500502) (xy 366.74728 -285.451139)
			(xy 366.442262 -285.451139) (xy 366.434443 -285.500502) (xy 366.418999 -285.548034) (xy 366.396309 -285.592566)
			(xy 366.366933 -285.632999) (xy 366.331593 -285.668339) (xy 366.29116 -285.697715) (xy 366.246628 -285.720405)
			(xy 366.199096 -285.735849) (xy 366.149733 -285.743668) (xy 366.099755 -285.743668) (xy 366.050392 -285.735849)
			(xy 366.00286 -285.720405) (xy 365.958328 -285.697715) (xy 365.917895 -285.668339) (xy 365.882555 -285.632999)
			(xy 365.853179 -285.592566) (xy 365.830489 -285.548034) (xy 365.815045 -285.500502) (xy 365.807226 -285.451139)
			(xy 365.502208 -285.451139) (xy 365.494389 -285.500502) (xy 365.478945 -285.548034) (xy 365.456255 -285.592566)
			(xy 365.426879 -285.632999) (xy 365.391539 -285.668339) (xy 365.351106 -285.697715) (xy 365.306574 -285.720405)
			(xy 365.259042 -285.735849) (xy 365.209679 -285.743668) (xy 365.159701 -285.743668) (xy 365.110338 -285.735849)
			(xy 365.062806 -285.720405) (xy 365.018274 -285.697715) (xy 364.977841 -285.668339) (xy 364.942501 -285.632999)
			(xy 364.913125 -285.592566) (xy 364.890435 -285.548034) (xy 364.874991 -285.500502) (xy 364.867172 -285.451139)
			(xy 364.562408 -285.451139) (xy 364.554589 -285.500502) (xy 364.539145 -285.548034) (xy 364.516455 -285.592566)
			(xy 364.487079 -285.632999) (xy 364.451739 -285.668339) (xy 364.411306 -285.697715) (xy 364.366774 -285.720405)
			(xy 364.319242 -285.735849) (xy 364.269879 -285.743668) (xy 364.219901 -285.743668) (xy 364.170538 -285.735849)
			(xy 364.123006 -285.720405) (xy 364.078474 -285.697715) (xy 364.038041 -285.668339) (xy 364.002701 -285.632999)
			(xy 363.973325 -285.592566) (xy 363.950635 -285.548034) (xy 363.935191 -285.500502) (xy 363.927372 -285.451139)
			(xy 363.620055 -285.451139) (xy 363.620046 -285.451596) (xy 363.611882 -285.50183) (xy 363.595766 -285.550104)
			(xy 363.572115 -285.595167) (xy 363.541542 -285.635853) (xy 363.504838 -285.671108) (xy 363.462954 -285.700018)
			(xy 363.416975 -285.721835) (xy 363.368091 -285.735995) (xy 363.31757 -285.742129) (xy 363.266718 -285.74008)
			(xy 363.216854 -285.7299) (xy 363.169268 -285.711853) (xy 363.125194 -285.686407) (xy 363.085772 -285.65422)
			(xy 363.052024 -285.616126) (xy 363.024823 -285.573112) (xy 363.004875 -285.526292) (xy 362.992696 -285.476878)
			(xy 362.988601 -285.42615) (xy 362.680504 -285.42615) (xy 362.679992 -285.451596) (xy 362.671828 -285.50183)
			(xy 362.655712 -285.550104) (xy 362.632061 -285.595167) (xy 362.601488 -285.635853) (xy 362.564784 -285.671108)
			(xy 362.5229 -285.700018) (xy 362.476921 -285.721835) (xy 362.428037 -285.735995) (xy 362.377516 -285.742129)
			(xy 362.326664 -285.74008) (xy 362.2768 -285.7299) (xy 362.229214 -285.711853) (xy 362.18514 -285.686407)
			(xy 362.145718 -285.65422) (xy 362.11197 -285.616126) (xy 362.084769 -285.573112) (xy 362.064821 -285.526292)
			(xy 362.052642 -285.476878) (xy 362.048547 -285.42615) (xy 361.742736 -285.42615) (xy 361.742246 -285.451139)
			(xy 361.734427 -285.500502) (xy 361.718983 -285.548034) (xy 361.696293 -285.592566) (xy 361.666917 -285.632999)
			(xy 361.631577 -285.668339) (xy 361.591144 -285.697715) (xy 361.546612 -285.720405) (xy 361.49908 -285.735849)
			(xy 361.449717 -285.743668) (xy 361.399739 -285.743668) (xy 361.350376 -285.735849) (xy 361.302844 -285.720405)
			(xy 361.258312 -285.697715) (xy 361.217879 -285.668339) (xy 361.182539 -285.632999) (xy 361.153163 -285.592566)
			(xy 361.130473 -285.548034) (xy 361.115029 -285.500502) (xy 361.10721 -285.451139) (xy 358.928688 -285.451139)
			(xy 358.920869 -285.500502) (xy 358.905425 -285.548034) (xy 358.882735 -285.592566) (xy 358.853359 -285.632999)
			(xy 358.818019 -285.668339) (xy 358.777586 -285.697715) (xy 358.733054 -285.720405) (xy 358.685522 -285.735849)
			(xy 358.636159 -285.743668) (xy 358.586181 -285.743668) (xy 358.536818 -285.735849) (xy 358.489286 -285.720405)
			(xy 358.444754 -285.697715) (xy 358.404321 -285.668339) (xy 358.368981 -285.632999) (xy 358.339605 -285.592566)
			(xy 358.316915 -285.548034) (xy 358.301471 -285.500502) (xy 358.293652 -285.451139) (xy 357.986335 -285.451139)
			(xy 357.986326 -285.451596) (xy 357.978162 -285.50183) (xy 357.962046 -285.550104) (xy 357.938395 -285.595167)
			(xy 357.907822 -285.635853) (xy 357.871118 -285.671108) (xy 357.829234 -285.700018) (xy 357.783255 -285.721835)
			(xy 357.734371 -285.735995) (xy 357.68385 -285.742129) (xy 357.632998 -285.74008) (xy 357.583134 -285.7299)
			(xy 357.535548 -285.711853) (xy 357.491474 -285.686407) (xy 357.452052 -285.65422) (xy 357.418304 -285.616126)
			(xy 357.391103 -285.573112) (xy 357.371155 -285.526292) (xy 357.358976 -285.476878) (xy 357.354881 -285.42615)
			(xy 357.046784 -285.42615) (xy 357.046272 -285.451596) (xy 357.038108 -285.50183) (xy 357.021992 -285.550104)
			(xy 356.998341 -285.595167) (xy 356.967768 -285.635853) (xy 356.931064 -285.671108) (xy 356.88918 -285.700018)
			(xy 356.843201 -285.721835) (xy 356.794317 -285.735995) (xy 356.743796 -285.742129) (xy 356.692944 -285.74008)
			(xy 356.64308 -285.7299) (xy 356.595494 -285.711853) (xy 356.55142 -285.686407) (xy 356.511998 -285.65422)
			(xy 356.47825 -285.616126) (xy 356.451049 -285.573112) (xy 356.431101 -285.526292) (xy 356.418922 -285.476878)
			(xy 356.414827 -285.42615) (xy 356.109016 -285.42615) (xy 356.108526 -285.451139) (xy 356.100707 -285.500502)
			(xy 356.085263 -285.548034) (xy 356.062573 -285.592566) (xy 356.033197 -285.632999) (xy 355.997857 -285.668339)
			(xy 355.957424 -285.697715) (xy 355.912892 -285.720405) (xy 355.86536 -285.735849) (xy 355.815997 -285.743668)
			(xy 355.766019 -285.743668) (xy 355.716656 -285.735849) (xy 355.669124 -285.720405) (xy 355.624592 -285.697715)
			(xy 355.584159 -285.668339) (xy 355.548819 -285.632999) (xy 355.519443 -285.592566) (xy 355.496753 -285.548034)
			(xy 355.481309 -285.500502) (xy 355.47349 -285.451139) (xy 355.168726 -285.451139) (xy 355.160907 -285.500502)
			(xy 355.145463 -285.548034) (xy 355.122773 -285.592566) (xy 355.093397 -285.632999) (xy 355.058057 -285.668339)
			(xy 355.017624 -285.697715) (xy 354.973092 -285.720405) (xy 354.92556 -285.735849) (xy 354.876197 -285.743668)
			(xy 354.826219 -285.743668) (xy 354.776856 -285.735849) (xy 354.729324 -285.720405) (xy 354.684792 -285.697715)
			(xy 354.644359 -285.668339) (xy 354.609019 -285.632999) (xy 354.579643 -285.592566) (xy 354.556953 -285.548034)
			(xy 354.541509 -285.500502) (xy 354.53369 -285.451139) (xy 354.228672 -285.451139) (xy 354.220853 -285.500502)
			(xy 354.205409 -285.548034) (xy 354.182719 -285.592566) (xy 354.153343 -285.632999) (xy 354.118003 -285.668339)
			(xy 354.07757 -285.697715) (xy 354.033038 -285.720405) (xy 353.985506 -285.735849) (xy 353.936143 -285.743668)
			(xy 353.886165 -285.743668) (xy 353.836802 -285.735849) (xy 353.78927 -285.720405) (xy 353.744738 -285.697715)
			(xy 353.704305 -285.668339) (xy 353.668965 -285.632999) (xy 353.639589 -285.592566) (xy 353.616899 -285.548034)
			(xy 353.601455 -285.500502) (xy 353.593636 -285.451139) (xy 353.288618 -285.451139) (xy 353.280799 -285.500502)
			(xy 353.265355 -285.548034) (xy 353.242665 -285.592566) (xy 353.213289 -285.632999) (xy 353.177949 -285.668339)
			(xy 353.137516 -285.697715) (xy 353.092984 -285.720405) (xy 353.045452 -285.735849) (xy 352.996089 -285.743668)
			(xy 352.946111 -285.743668) (xy 352.896748 -285.735849) (xy 352.849216 -285.720405) (xy 352.804684 -285.697715)
			(xy 352.764251 -285.668339) (xy 352.728911 -285.632999) (xy 352.699535 -285.592566) (xy 352.676845 -285.548034)
			(xy 352.661401 -285.500502) (xy 352.653582 -285.451139) (xy 352.348564 -285.451139) (xy 352.340745 -285.500502)
			(xy 352.325301 -285.548034) (xy 352.302611 -285.592566) (xy 352.273235 -285.632999) (xy 352.237895 -285.668339)
			(xy 352.197462 -285.697715) (xy 352.15293 -285.720405) (xy 352.105398 -285.735849) (xy 352.056035 -285.743668)
			(xy 352.006057 -285.743668) (xy 351.956694 -285.735849) (xy 351.909162 -285.720405) (xy 351.86463 -285.697715)
			(xy 351.824197 -285.668339) (xy 351.788857 -285.632999) (xy 351.759481 -285.592566) (xy 351.736791 -285.548034)
			(xy 351.721347 -285.500502) (xy 351.713528 -285.451139) (xy 351.408764 -285.451139) (xy 351.400945 -285.500502)
			(xy 351.385501 -285.548034) (xy 351.362811 -285.592566) (xy 351.333435 -285.632999) (xy 351.298095 -285.668339)
			(xy 351.257662 -285.697715) (xy 351.21313 -285.720405) (xy 351.165598 -285.735849) (xy 351.116235 -285.743668)
			(xy 351.066257 -285.743668) (xy 351.016894 -285.735849) (xy 350.969362 -285.720405) (xy 350.92483 -285.697715)
			(xy 350.884397 -285.668339) (xy 350.849057 -285.632999) (xy 350.819681 -285.592566) (xy 350.796991 -285.548034)
			(xy 350.781547 -285.500502) (xy 350.773728 -285.451139) (xy 350.46871 -285.451139) (xy 350.460891 -285.500502)
			(xy 350.445447 -285.548034) (xy 350.422757 -285.592566) (xy 350.393381 -285.632999) (xy 350.358041 -285.668339)
			(xy 350.317608 -285.697715) (xy 350.273076 -285.720405) (xy 350.225544 -285.735849) (xy 350.176181 -285.743668)
			(xy 350.126203 -285.743668) (xy 350.07684 -285.735849) (xy 350.029308 -285.720405) (xy 349.984776 -285.697715)
			(xy 349.944343 -285.668339) (xy 349.909003 -285.632999) (xy 349.879627 -285.592566) (xy 349.856937 -285.548034)
			(xy 349.841493 -285.500502) (xy 349.833674 -285.451139) (xy 349.528656 -285.451139) (xy 349.520837 -285.500502)
			(xy 349.505393 -285.548034) (xy 349.482703 -285.592566) (xy 349.453327 -285.632999) (xy 349.417987 -285.668339)
			(xy 349.377554 -285.697715) (xy 349.333022 -285.720405) (xy 349.28549 -285.735849) (xy 349.236127 -285.743668)
			(xy 349.186149 -285.743668) (xy 349.136786 -285.735849) (xy 349.089254 -285.720405) (xy 349.044722 -285.697715)
			(xy 349.004289 -285.668339) (xy 348.968949 -285.632999) (xy 348.939573 -285.592566) (xy 348.916883 -285.548034)
			(xy 348.901439 -285.500502) (xy 348.89362 -285.451139) (xy 348.588602 -285.451139) (xy 348.580783 -285.500502)
			(xy 348.565339 -285.548034) (xy 348.542649 -285.592566) (xy 348.513273 -285.632999) (xy 348.477933 -285.668339)
			(xy 348.4375 -285.697715) (xy 348.392968 -285.720405) (xy 348.345436 -285.735849) (xy 348.296073 -285.743668)
			(xy 348.246095 -285.743668) (xy 348.196732 -285.735849) (xy 348.1492 -285.720405) (xy 348.104668 -285.697715)
			(xy 348.064235 -285.668339) (xy 348.028895 -285.632999) (xy 347.999519 -285.592566) (xy 347.976829 -285.548034)
			(xy 347.961385 -285.500502) (xy 347.953566 -285.451139) (xy 347.648548 -285.451139) (xy 347.640729 -285.500502)
			(xy 347.625285 -285.548034) (xy 347.602595 -285.592566) (xy 347.573219 -285.632999) (xy 347.537879 -285.668339)
			(xy 347.497446 -285.697715) (xy 347.452914 -285.720405) (xy 347.405382 -285.735849) (xy 347.356019 -285.743668)
			(xy 347.306041 -285.743668) (xy 347.256678 -285.735849) (xy 347.209146 -285.720405) (xy 347.164614 -285.697715)
			(xy 347.124181 -285.668339) (xy 347.088841 -285.632999) (xy 347.059465 -285.592566) (xy 347.036775 -285.548034)
			(xy 347.021331 -285.500502) (xy 347.013512 -285.451139) (xy 346.708748 -285.451139) (xy 346.700929 -285.500502)
			(xy 346.685485 -285.548034) (xy 346.662795 -285.592566) (xy 346.633419 -285.632999) (xy 346.598079 -285.668339)
			(xy 346.557646 -285.697715) (xy 346.513114 -285.720405) (xy 346.465582 -285.735849) (xy 346.416219 -285.743668)
			(xy 346.366241 -285.743668) (xy 346.316878 -285.735849) (xy 346.269346 -285.720405) (xy 346.224814 -285.697715)
			(xy 346.184381 -285.668339) (xy 346.149041 -285.632999) (xy 346.119665 -285.592566) (xy 346.096975 -285.548034)
			(xy 346.081531 -285.500502) (xy 346.073712 -285.451139) (xy 345.768685 -285.451139) (xy 345.760875 -285.50045)
			(xy 345.74543 -285.547981) (xy 345.72274 -285.59251) (xy 345.693363 -285.632941) (xy 345.658023 -285.668279)
			(xy 345.617589 -285.697653) (xy 345.573058 -285.720339) (xy 345.525527 -285.73578) (xy 345.476165 -285.743595)
			(xy 345.451176 -285.744158) (xy 345.427299 -285.743729) (xy 345.38008 -285.736593) (xy 345.334457 -285.722484)
			(xy 345.291454 -285.701719) (xy 345.252034 -285.674764) (xy 345.23426 -285.658814) (xy 345.22866 -285.653941)
			(xy 345.21537 -285.647344) (xy 345.208098 -285.64586) (xy 345.20124 -285.64459) (xy 345.186508 -285.646368)
			(xy 345.14155 -285.665926) (xy 345.096338 -285.685738) (xy 345.087512 -285.690099) (xy 345.073779 -285.704181)
			(xy 345.066333 -285.722387) (xy 345.065858 -285.73222) (xy 345.065858 -285.89351) (xy 345.065858 -285.89478)
			(xy 345.066525 -285.904164) (xy 345.073748 -285.921517) (xy 345.086747 -285.935093) (xy 345.095068 -285.939484)
			(xy 345.097862 -285.9405) (xy 345.120567 -285.949952) (xy 345.16299 -285.974831) (xy 345.201075 -286.005948)
			(xy 345.233913 -286.042558) (xy 345.260721 -286.083789) (xy 345.280859 -286.128657) (xy 345.293847 -286.176091)
			(xy 345.299374 -286.224959) (xy 345.298903 -286.236156) (xy 345.604841 -286.236156) (xy 345.608936 -286.185428)
			(xy 345.621115 -286.136014) (xy 345.641063 -286.089194) (xy 345.668264 -286.04618) (xy 345.702012 -286.008086)
			(xy 345.741434 -285.975899) (xy 345.785508 -285.950453) (xy 345.833094 -285.932406) (xy 345.882958 -285.922226)
			(xy 345.93381 -285.920177) (xy 345.984331 -285.926311) (xy 346.033215 -285.940471) (xy 346.079194 -285.962288)
			(xy 346.121078 -285.991198) (xy 346.157782 -286.026453) (xy 346.188355 -286.067139) (xy 346.212006 -286.112202)
			(xy 346.228122 -286.160476) (xy 346.236286 -286.21071) (xy 346.236798 -286.236156) (xy 346.544895 -286.236156)
			(xy 346.54899 -286.185428) (xy 346.561169 -286.136014) (xy 346.581117 -286.089194) (xy 346.608318 -286.04618)
			(xy 346.642066 -286.008086) (xy 346.681488 -285.975899) (xy 346.725562 -285.950453) (xy 346.773148 -285.932406)
			(xy 346.823012 -285.922226) (xy 346.873864 -285.920177) (xy 346.924385 -285.926311) (xy 346.973269 -285.940471)
			(xy 347.019248 -285.962288) (xy 347.061132 -285.991198) (xy 347.097836 -286.026453) (xy 347.128409 -286.067139)
			(xy 347.15206 -286.112202) (xy 347.168176 -286.160476) (xy 347.17634 -286.21071) (xy 347.176852 -286.236156)
			(xy 347.176349 -286.261145) (xy 347.483666 -286.261145) (xy 347.483666 -286.211167) (xy 347.491485 -286.161804)
			(xy 347.506929 -286.114272) (xy 347.529619 -286.06974) (xy 347.558995 -286.029307) (xy 347.594335 -285.993967)
			(xy 347.634768 -285.964591) (xy 347.6793 -285.941901) (xy 347.726832 -285.926457) (xy 347.776195 -285.918638)
			(xy 347.826173 -285.918638) (xy 347.875536 -285.926457) (xy 347.923068 -285.941901) (xy 347.9676 -285.964591)
			(xy 348.008033 -285.993967) (xy 348.043373 -286.029307) (xy 348.072749 -286.06974) (xy 348.095439 -286.114272)
			(xy 348.110883 -286.161804) (xy 348.118702 -286.211167) (xy 348.119192 -286.236156) (xy 348.425003 -286.236156)
			(xy 348.429098 -286.185428) (xy 348.441277 -286.136014) (xy 348.461225 -286.089194) (xy 348.488426 -286.04618)
			(xy 348.522174 -286.008086) (xy 348.561596 -285.975899) (xy 348.60567 -285.950453) (xy 348.653256 -285.932406)
			(xy 348.70312 -285.922226) (xy 348.753972 -285.920177) (xy 348.804493 -285.926311) (xy 348.853377 -285.940471)
			(xy 348.899356 -285.962288) (xy 348.94124 -285.991198) (xy 348.977944 -286.026453) (xy 349.008517 -286.067139)
			(xy 349.032168 -286.112202) (xy 349.048284 -286.160476) (xy 349.056448 -286.21071) (xy 349.05696 -286.236156)
			(xy 349.364803 -286.236156) (xy 349.368898 -286.185428) (xy 349.381077 -286.136014) (xy 349.401025 -286.089194)
			(xy 349.428226 -286.04618) (xy 349.461974 -286.008086) (xy 349.501396 -285.975899) (xy 349.54547 -285.950453)
			(xy 349.593056 -285.932406) (xy 349.64292 -285.922226) (xy 349.693772 -285.920177) (xy 349.744293 -285.926311)
			(xy 349.793177 -285.940471) (xy 349.839156 -285.962288) (xy 349.88104 -285.991198) (xy 349.917744 -286.026453)
			(xy 349.948317 -286.067139) (xy 349.971968 -286.112202) (xy 349.988084 -286.160476) (xy 349.996248 -286.21071)
			(xy 349.99676 -286.236156) (xy 349.996257 -286.261145) (xy 350.303574 -286.261145) (xy 350.303574 -286.211167)
			(xy 350.311393 -286.161804) (xy 350.326837 -286.114272) (xy 350.349527 -286.06974) (xy 350.378903 -286.029307)
			(xy 350.414243 -285.993967) (xy 350.454676 -285.964591) (xy 350.499208 -285.941901) (xy 350.54674 -285.926457)
			(xy 350.596103 -285.918638) (xy 350.646081 -285.918638) (xy 350.695444 -285.926457) (xy 350.742976 -285.941901)
			(xy 350.787508 -285.964591) (xy 350.827941 -285.993967) (xy 350.863281 -286.029307) (xy 350.892657 -286.06974)
			(xy 350.915347 -286.114272) (xy 350.930791 -286.161804) (xy 350.93861 -286.211167) (xy 350.9391 -286.236156)
			(xy 351.244911 -286.236156) (xy 351.249006 -286.185428) (xy 351.261185 -286.136014) (xy 351.281133 -286.089194)
			(xy 351.308334 -286.04618) (xy 351.342082 -286.008086) (xy 351.381504 -285.975899) (xy 351.425578 -285.950453)
			(xy 351.473164 -285.932406) (xy 351.523028 -285.922226) (xy 351.57388 -285.920177) (xy 351.624401 -285.926311)
			(xy 351.673285 -285.940471) (xy 351.719264 -285.962288) (xy 351.761148 -285.991198) (xy 351.797852 -286.026453)
			(xy 351.828425 -286.067139) (xy 351.852076 -286.112202) (xy 351.868192 -286.160476) (xy 351.876356 -286.21071)
			(xy 351.876868 -286.236156) (xy 352.184965 -286.236156) (xy 352.18906 -286.185428) (xy 352.201239 -286.136014)
			(xy 352.221187 -286.089194) (xy 352.248388 -286.04618) (xy 352.282136 -286.008086) (xy 352.321558 -285.975899)
			(xy 352.365632 -285.950453) (xy 352.413218 -285.932406) (xy 352.463082 -285.922226) (xy 352.513934 -285.920177)
			(xy 352.564455 -285.926311) (xy 352.613339 -285.940471) (xy 352.659318 -285.962288) (xy 352.701202 -285.991198)
			(xy 352.737906 -286.026453) (xy 352.768479 -286.067139) (xy 352.79213 -286.112202) (xy 352.808246 -286.160476)
			(xy 352.81641 -286.21071) (xy 352.816922 -286.236156) (xy 352.816419 -286.261145) (xy 353.123482 -286.261145)
			(xy 353.123482 -286.211167) (xy 353.131301 -286.161804) (xy 353.146745 -286.114272) (xy 353.169435 -286.06974)
			(xy 353.198811 -286.029307) (xy 353.234151 -285.993967) (xy 353.274584 -285.964591) (xy 353.319116 -285.941901)
			(xy 353.366648 -285.926457) (xy 353.416011 -285.918638) (xy 353.465989 -285.918638) (xy 353.515352 -285.926457)
			(xy 353.562884 -285.941901) (xy 353.607416 -285.964591) (xy 353.647849 -285.993967) (xy 353.683189 -286.029307)
			(xy 353.712565 -286.06974) (xy 353.735255 -286.114272) (xy 353.750699 -286.161804) (xy 353.758518 -286.211167)
			(xy 353.759008 -286.236156) (xy 354.064819 -286.236156) (xy 354.068914 -286.185428) (xy 354.081093 -286.136014)
			(xy 354.101041 -286.089194) (xy 354.128242 -286.04618) (xy 354.16199 -286.008086) (xy 354.201412 -285.975899)
			(xy 354.245486 -285.950453) (xy 354.293072 -285.932406) (xy 354.342936 -285.922226) (xy 354.393788 -285.920177)
			(xy 354.444309 -285.926311) (xy 354.493193 -285.940471) (xy 354.539172 -285.962288) (xy 354.581056 -285.991198)
			(xy 354.61776 -286.026453) (xy 354.648333 -286.067139) (xy 354.671984 -286.112202) (xy 354.6881 -286.160476)
			(xy 354.696264 -286.21071) (xy 354.696776 -286.236156) (xy 355.004873 -286.236156) (xy 355.008968 -286.185428)
			(xy 355.021147 -286.136014) (xy 355.041095 -286.089194) (xy 355.068296 -286.04618) (xy 355.102044 -286.008086)
			(xy 355.141466 -285.975899) (xy 355.18554 -285.950453) (xy 355.233126 -285.932406) (xy 355.28299 -285.922226)
			(xy 355.333842 -285.920177) (xy 355.384363 -285.926311) (xy 355.433247 -285.940471) (xy 355.479226 -285.962288)
			(xy 355.52111 -285.991198) (xy 355.557814 -286.026453) (xy 355.588387 -286.067139) (xy 355.612038 -286.112202)
			(xy 355.628154 -286.160476) (xy 355.636318 -286.21071) (xy 355.63683 -286.236156) (xy 355.636327 -286.261145)
			(xy 355.943644 -286.261145) (xy 355.943644 -286.211167) (xy 355.951463 -286.161804) (xy 355.966907 -286.114272)
			(xy 355.989597 -286.06974) (xy 356.018973 -286.029307) (xy 356.054313 -285.993967) (xy 356.094746 -285.964591)
			(xy 356.139278 -285.941901) (xy 356.18681 -285.926457) (xy 356.236173 -285.918638) (xy 356.286151 -285.918638)
			(xy 356.335514 -285.926457) (xy 356.383046 -285.941901) (xy 356.427578 -285.964591) (xy 356.468011 -285.993967)
			(xy 356.503351 -286.029307) (xy 356.532727 -286.06974) (xy 356.555417 -286.114272) (xy 356.570861 -286.161804)
			(xy 356.57868 -286.211167) (xy 356.57917 -286.236156) (xy 356.57868 -286.261145) (xy 363.457218 -286.261145)
			(xy 363.457218 -286.211167) (xy 363.465037 -286.161804) (xy 363.480481 -286.114272) (xy 363.503171 -286.06974)
			(xy 363.532547 -286.029307) (xy 363.567887 -285.993967) (xy 363.60832 -285.964591) (xy 363.652852 -285.941901)
			(xy 363.700384 -285.926457) (xy 363.749747 -285.918638) (xy 363.799725 -285.918638) (xy 363.849088 -285.926457)
			(xy 363.89662 -285.941901) (xy 363.941152 -285.964591) (xy 363.981585 -285.993967) (xy 364.016925 -286.029307)
			(xy 364.046301 -286.06974) (xy 364.068991 -286.114272) (xy 364.084435 -286.161804) (xy 364.092254 -286.211167)
			(xy 364.092744 -286.236156) (xy 364.398555 -286.236156) (xy 364.40265 -286.185428) (xy 364.414829 -286.136014)
			(xy 364.434777 -286.089194) (xy 364.461978 -286.04618) (xy 364.495726 -286.008086) (xy 364.535148 -285.975899)
			(xy 364.579222 -285.950453) (xy 364.626808 -285.932406) (xy 364.676672 -285.922226) (xy 364.727524 -285.920177)
			(xy 364.778045 -285.926311) (xy 364.826929 -285.940471) (xy 364.872908 -285.962288) (xy 364.914792 -285.991198)
			(xy 364.951496 -286.026453) (xy 364.982069 -286.067139) (xy 365.00572 -286.112202) (xy 365.021836 -286.160476)
			(xy 365.03 -286.21071) (xy 365.030512 -286.236156) (xy 365.338609 -286.236156) (xy 365.342704 -286.185428)
			(xy 365.354883 -286.136014) (xy 365.374831 -286.089194) (xy 365.402032 -286.04618) (xy 365.43578 -286.008086)
			(xy 365.475202 -285.975899) (xy 365.519276 -285.950453) (xy 365.566862 -285.932406) (xy 365.616726 -285.922226)
			(xy 365.667578 -285.920177) (xy 365.718099 -285.926311) (xy 365.766983 -285.940471) (xy 365.812962 -285.962288)
			(xy 365.854846 -285.991198) (xy 365.89155 -286.026453) (xy 365.922123 -286.067139) (xy 365.945774 -286.112202)
			(xy 365.96189 -286.160476) (xy 365.970054 -286.21071) (xy 365.970566 -286.236156) (xy 365.970063 -286.261145)
			(xy 366.27738 -286.261145) (xy 366.27738 -286.211167) (xy 366.285199 -286.161804) (xy 366.300643 -286.114272)
			(xy 366.323333 -286.06974) (xy 366.352709 -286.029307) (xy 366.388049 -285.993967) (xy 366.428482 -285.964591)
			(xy 366.473014 -285.941901) (xy 366.520546 -285.926457) (xy 366.569909 -285.918638) (xy 366.619887 -285.918638)
			(xy 366.66925 -285.926457) (xy 366.716782 -285.941901) (xy 366.761314 -285.964591) (xy 366.801747 -285.993967)
			(xy 366.837087 -286.029307) (xy 366.866463 -286.06974) (xy 366.889153 -286.114272) (xy 366.904597 -286.161804)
			(xy 366.912416 -286.211167) (xy 366.912906 -286.236156) (xy 367.218463 -286.236156) (xy 367.222558 -286.185428)
			(xy 367.234737 -286.136014) (xy 367.254685 -286.089194) (xy 367.281886 -286.04618) (xy 367.315634 -286.008086)
			(xy 367.355056 -285.975899) (xy 367.39913 -285.950453) (xy 367.446716 -285.932406) (xy 367.49658 -285.922226)
			(xy 367.547432 -285.920177) (xy 367.597953 -285.926311) (xy 367.646837 -285.940471) (xy 367.692816 -285.962288)
			(xy 367.7347 -285.991198) (xy 367.771404 -286.026453) (xy 367.801977 -286.067139) (xy 367.825628 -286.112202)
			(xy 367.841744 -286.160476) (xy 367.849908 -286.21071) (xy 367.85042 -286.236156) (xy 368.158517 -286.236156)
			(xy 368.162612 -286.185428) (xy 368.174791 -286.136014) (xy 368.194739 -286.089194) (xy 368.22194 -286.04618)
			(xy 368.255688 -286.008086) (xy 368.29511 -285.975899) (xy 368.339184 -285.950453) (xy 368.38677 -285.932406)
			(xy 368.436634 -285.922226) (xy 368.487486 -285.920177) (xy 368.538007 -285.926311) (xy 368.586891 -285.940471)
			(xy 368.63287 -285.962288) (xy 368.674754 -285.991198) (xy 368.711458 -286.026453) (xy 368.742031 -286.067139)
			(xy 368.765682 -286.112202) (xy 368.781798 -286.160476) (xy 368.789962 -286.21071) (xy 368.790474 -286.236156)
			(xy 368.789971 -286.261145) (xy 369.097288 -286.261145) (xy 369.097288 -286.211167) (xy 369.105107 -286.161804)
			(xy 369.120551 -286.114272) (xy 369.143241 -286.06974) (xy 369.172617 -286.029307) (xy 369.207957 -285.993967)
			(xy 369.24839 -285.964591) (xy 369.292922 -285.941901) (xy 369.340454 -285.926457) (xy 369.389817 -285.918638)
			(xy 369.439795 -285.918638) (xy 369.489158 -285.926457) (xy 369.53669 -285.941901) (xy 369.581222 -285.964591)
			(xy 369.621655 -285.993967) (xy 369.656995 -286.029307) (xy 369.686371 -286.06974) (xy 369.709061 -286.114272)
			(xy 369.724505 -286.161804) (xy 369.732324 -286.211167) (xy 369.732814 -286.236156) (xy 370.038625 -286.236156)
			(xy 370.04272 -286.185428) (xy 370.054899 -286.136014) (xy 370.074847 -286.089194) (xy 370.102048 -286.04618)
			(xy 370.135796 -286.008086) (xy 370.175218 -285.975899) (xy 370.219292 -285.950453) (xy 370.266878 -285.932406)
			(xy 370.316742 -285.922226) (xy 370.367594 -285.920177) (xy 370.418115 -285.926311) (xy 370.466999 -285.940471)
			(xy 370.512978 -285.962288) (xy 370.554862 -285.991198) (xy 370.591566 -286.026453) (xy 370.622139 -286.067139)
			(xy 370.64579 -286.112202) (xy 370.661906 -286.160476) (xy 370.67007 -286.21071) (xy 370.670582 -286.236156)
			(xy 370.978679 -286.236156) (xy 370.982774 -286.185428) (xy 370.994953 -286.136014) (xy 371.014901 -286.089194)
			(xy 371.042102 -286.04618) (xy 371.07585 -286.008086) (xy 371.115272 -285.975899) (xy 371.159346 -285.950453)
			(xy 371.206932 -285.932406) (xy 371.256796 -285.922226) (xy 371.307648 -285.920177) (xy 371.358169 -285.926311)
			(xy 371.407053 -285.940471) (xy 371.453032 -285.962288) (xy 371.494916 -285.991198) (xy 371.53162 -286.026453)
			(xy 371.562193 -286.067139) (xy 371.585844 -286.112202) (xy 371.60196 -286.160476) (xy 371.610124 -286.21071)
			(xy 371.610636 -286.236156) (xy 371.610133 -286.261145) (xy 371.917196 -286.261145) (xy 371.917196 -286.211167)
			(xy 371.925015 -286.161804) (xy 371.940459 -286.114272) (xy 371.963149 -286.06974) (xy 371.992525 -286.029307)
			(xy 372.027865 -285.993967) (xy 372.068298 -285.964591) (xy 372.11283 -285.941901) (xy 372.160362 -285.926457)
			(xy 372.209725 -285.918638) (xy 372.259703 -285.918638) (xy 372.309066 -285.926457) (xy 372.356598 -285.941901)
			(xy 372.40113 -285.964591) (xy 372.441563 -285.993967) (xy 372.476903 -286.029307) (xy 372.506279 -286.06974)
			(xy 372.528969 -286.114272) (xy 372.544413 -286.161804) (xy 372.552232 -286.211167) (xy 372.552722 -286.236156)
			(xy 372.858533 -286.236156) (xy 372.862628 -286.185428) (xy 372.874807 -286.136014) (xy 372.894755 -286.089194)
			(xy 372.921956 -286.04618) (xy 372.955704 -286.008086) (xy 372.995126 -285.975899) (xy 373.0392 -285.950453)
			(xy 373.086786 -285.932406) (xy 373.13665 -285.922226) (xy 373.187502 -285.920177) (xy 373.238023 -285.926311)
			(xy 373.286907 -285.940471) (xy 373.332886 -285.962288) (xy 373.37477 -285.991198) (xy 373.411474 -286.026453)
			(xy 373.442047 -286.067139) (xy 373.465698 -286.112202) (xy 373.481814 -286.160476) (xy 373.489978 -286.21071)
			(xy 373.49049 -286.236156) (xy 373.798587 -286.236156) (xy 373.802682 -286.185428) (xy 373.814861 -286.136014)
			(xy 373.834809 -286.089194) (xy 373.86201 -286.04618) (xy 373.895758 -286.008086) (xy 373.93518 -285.975899)
			(xy 373.979254 -285.950453) (xy 374.02684 -285.932406) (xy 374.076704 -285.922226) (xy 374.127556 -285.920177)
			(xy 374.178077 -285.926311) (xy 374.226961 -285.940471) (xy 374.27294 -285.962288) (xy 374.314824 -285.991198)
			(xy 374.351528 -286.026453) (xy 374.382101 -286.067139) (xy 374.405752 -286.112202) (xy 374.421868 -286.160476)
			(xy 374.430032 -286.21071) (xy 374.430544 -286.236156) (xy 374.430032 -286.261602) (xy 374.421868 -286.311836)
			(xy 374.405752 -286.36011) (xy 374.382101 -286.405173) (xy 374.351528 -286.445859) (xy 374.314824 -286.481114)
			(xy 374.27294 -286.510024) (xy 374.226961 -286.531841) (xy 374.178077 -286.546001) (xy 374.127556 -286.552135)
			(xy 374.076704 -286.550086) (xy 374.02684 -286.539906) (xy 373.979254 -286.521859) (xy 373.93518 -286.496413)
			(xy 373.895758 -286.464226) (xy 373.86201 -286.426132) (xy 373.834809 -286.383118) (xy 373.814861 -286.336298)
			(xy 373.802682 -286.286884) (xy 373.798587 -286.236156) (xy 373.49049 -286.236156) (xy 373.489978 -286.261602)
			(xy 373.481814 -286.311836) (xy 373.465698 -286.36011) (xy 373.442047 -286.405173) (xy 373.411474 -286.445859)
			(xy 373.37477 -286.481114) (xy 373.332886 -286.510024) (xy 373.286907 -286.531841) (xy 373.238023 -286.546001)
			(xy 373.187502 -286.552135) (xy 373.13665 -286.550086) (xy 373.086786 -286.539906) (xy 373.0392 -286.521859)
			(xy 372.995126 -286.496413) (xy 372.955704 -286.464226) (xy 372.921956 -286.426132) (xy 372.894755 -286.383118)
			(xy 372.874807 -286.336298) (xy 372.862628 -286.286884) (xy 372.858533 -286.236156) (xy 372.552722 -286.236156)
			(xy 372.552232 -286.261145) (xy 372.544413 -286.310508) (xy 372.528969 -286.35804) (xy 372.506279 -286.402572)
			(xy 372.476903 -286.443005) (xy 372.441563 -286.478345) (xy 372.40113 -286.507721) (xy 372.356598 -286.530411)
			(xy 372.309066 -286.545855) (xy 372.259703 -286.553674) (xy 372.209725 -286.553674) (xy 372.160362 -286.545855)
			(xy 372.11283 -286.530411) (xy 372.068298 -286.507721) (xy 372.027865 -286.478345) (xy 371.992525 -286.443005)
			(xy 371.963149 -286.402572) (xy 371.940459 -286.35804) (xy 371.925015 -286.310508) (xy 371.917196 -286.261145)
			(xy 371.610133 -286.261145) (xy 371.610124 -286.261602) (xy 371.60196 -286.311836) (xy 371.585844 -286.36011)
			(xy 371.562193 -286.405173) (xy 371.53162 -286.445859) (xy 371.494916 -286.481114) (xy 371.453032 -286.510024)
			(xy 371.407053 -286.531841) (xy 371.358169 -286.546001) (xy 371.307648 -286.552135) (xy 371.256796 -286.550086)
			(xy 371.206932 -286.539906) (xy 371.159346 -286.521859) (xy 371.115272 -286.496413) (xy 371.07585 -286.464226)
			(xy 371.042102 -286.426132) (xy 371.014901 -286.383118) (xy 370.994953 -286.336298) (xy 370.982774 -286.286884)
			(xy 370.978679 -286.236156) (xy 370.670582 -286.236156) (xy 370.67007 -286.261602) (xy 370.661906 -286.311836)
			(xy 370.64579 -286.36011) (xy 370.622139 -286.405173) (xy 370.591566 -286.445859) (xy 370.554862 -286.481114)
			(xy 370.512978 -286.510024) (xy 370.466999 -286.531841) (xy 370.418115 -286.546001) (xy 370.367594 -286.552135)
			(xy 370.316742 -286.550086) (xy 370.266878 -286.539906) (xy 370.219292 -286.521859) (xy 370.175218 -286.496413)
			(xy 370.135796 -286.464226) (xy 370.102048 -286.426132) (xy 370.074847 -286.383118) (xy 370.054899 -286.336298)
			(xy 370.04272 -286.286884) (xy 370.038625 -286.236156) (xy 369.732814 -286.236156) (xy 369.732324 -286.261145)
			(xy 369.724505 -286.310508) (xy 369.709061 -286.35804) (xy 369.686371 -286.402572) (xy 369.656995 -286.443005)
			(xy 369.621655 -286.478345) (xy 369.581222 -286.507721) (xy 369.53669 -286.530411) (xy 369.489158 -286.545855)
			(xy 369.439795 -286.553674) (xy 369.389817 -286.553674) (xy 369.340454 -286.545855) (xy 369.292922 -286.530411)
			(xy 369.24839 -286.507721) (xy 369.207957 -286.478345) (xy 369.172617 -286.443005) (xy 369.143241 -286.402572)
			(xy 369.120551 -286.35804) (xy 369.105107 -286.310508) (xy 369.097288 -286.261145) (xy 368.789971 -286.261145)
			(xy 368.789962 -286.261602) (xy 368.781798 -286.311836) (xy 368.765682 -286.36011) (xy 368.742031 -286.405173)
			(xy 368.711458 -286.445859) (xy 368.674754 -286.481114) (xy 368.63287 -286.510024) (xy 368.586891 -286.531841)
			(xy 368.538007 -286.546001) (xy 368.487486 -286.552135) (xy 368.436634 -286.550086) (xy 368.38677 -286.539906)
			(xy 368.339184 -286.521859) (xy 368.29511 -286.496413) (xy 368.255688 -286.464226) (xy 368.22194 -286.426132)
			(xy 368.194739 -286.383118) (xy 368.174791 -286.336298) (xy 368.162612 -286.286884) (xy 368.158517 -286.236156)
			(xy 367.85042 -286.236156) (xy 367.849908 -286.261602) (xy 367.841744 -286.311836) (xy 367.825628 -286.36011)
			(xy 367.801977 -286.405173) (xy 367.771404 -286.445859) (xy 367.7347 -286.481114) (xy 367.692816 -286.510024)
			(xy 367.646837 -286.531841) (xy 367.597953 -286.546001) (xy 367.547432 -286.552135) (xy 367.49658 -286.550086)
			(xy 367.446716 -286.539906) (xy 367.39913 -286.521859) (xy 367.355056 -286.496413) (xy 367.315634 -286.464226)
			(xy 367.281886 -286.426132) (xy 367.254685 -286.383118) (xy 367.234737 -286.336298) (xy 367.222558 -286.286884)
			(xy 367.218463 -286.236156) (xy 366.912906 -286.236156) (xy 366.912416 -286.261145) (xy 366.904597 -286.310508)
			(xy 366.889153 -286.35804) (xy 366.866463 -286.402572) (xy 366.837087 -286.443005) (xy 366.801747 -286.478345)
			(xy 366.761314 -286.507721) (xy 366.716782 -286.530411) (xy 366.66925 -286.545855) (xy 366.619887 -286.553674)
			(xy 366.569909 -286.553674) (xy 366.520546 -286.545855) (xy 366.473014 -286.530411) (xy 366.428482 -286.507721)
			(xy 366.388049 -286.478345) (xy 366.352709 -286.443005) (xy 366.323333 -286.402572) (xy 366.300643 -286.35804)
			(xy 366.285199 -286.310508) (xy 366.27738 -286.261145) (xy 365.970063 -286.261145) (xy 365.970054 -286.261602)
			(xy 365.96189 -286.311836) (xy 365.945774 -286.36011) (xy 365.922123 -286.405173) (xy 365.89155 -286.445859)
			(xy 365.854846 -286.481114) (xy 365.812962 -286.510024) (xy 365.766983 -286.531841) (xy 365.718099 -286.546001)
			(xy 365.667578 -286.552135) (xy 365.616726 -286.550086) (xy 365.566862 -286.539906) (xy 365.519276 -286.521859)
			(xy 365.475202 -286.496413) (xy 365.43578 -286.464226) (xy 365.402032 -286.426132) (xy 365.374831 -286.383118)
			(xy 365.354883 -286.336298) (xy 365.342704 -286.286884) (xy 365.338609 -286.236156) (xy 365.030512 -286.236156)
			(xy 365.03 -286.261602) (xy 365.021836 -286.311836) (xy 365.00572 -286.36011) (xy 364.982069 -286.405173)
			(xy 364.951496 -286.445859) (xy 364.914792 -286.481114) (xy 364.872908 -286.510024) (xy 364.826929 -286.531841)
			(xy 364.778045 -286.546001) (xy 364.727524 -286.552135) (xy 364.676672 -286.550086) (xy 364.626808 -286.539906)
			(xy 364.579222 -286.521859) (xy 364.535148 -286.496413) (xy 364.495726 -286.464226) (xy 364.461978 -286.426132)
			(xy 364.434777 -286.383118) (xy 364.414829 -286.336298) (xy 364.40265 -286.286884) (xy 364.398555 -286.236156)
			(xy 364.092744 -286.236156) (xy 364.092254 -286.261145) (xy 364.084435 -286.310508) (xy 364.068991 -286.35804)
			(xy 364.046301 -286.402572) (xy 364.016925 -286.443005) (xy 363.981585 -286.478345) (xy 363.941152 -286.507721)
			(xy 363.89662 -286.530411) (xy 363.849088 -286.545855) (xy 363.799725 -286.553674) (xy 363.749747 -286.553674)
			(xy 363.700384 -286.545855) (xy 363.652852 -286.530411) (xy 363.60832 -286.507721) (xy 363.567887 -286.478345)
			(xy 363.532547 -286.443005) (xy 363.503171 -286.402572) (xy 363.480481 -286.35804) (xy 363.465037 -286.310508)
			(xy 363.457218 -286.261145) (xy 356.57868 -286.261145) (xy 356.570861 -286.310508) (xy 356.555417 -286.35804)
			(xy 356.532727 -286.402572) (xy 356.503351 -286.443005) (xy 356.468011 -286.478345) (xy 356.427578 -286.507721)
			(xy 356.383046 -286.530411) (xy 356.335514 -286.545855) (xy 356.286151 -286.553674) (xy 356.236173 -286.553674)
			(xy 356.18681 -286.545855) (xy 356.139278 -286.530411) (xy 356.094746 -286.507721) (xy 356.054313 -286.478345)
			(xy 356.018973 -286.443005) (xy 355.989597 -286.402572) (xy 355.966907 -286.35804) (xy 355.951463 -286.310508)
			(xy 355.943644 -286.261145) (xy 355.636327 -286.261145) (xy 355.636318 -286.261602) (xy 355.628154 -286.311836)
			(xy 355.612038 -286.36011) (xy 355.588387 -286.405173) (xy 355.557814 -286.445859) (xy 355.52111 -286.481114)
			(xy 355.479226 -286.510024) (xy 355.433247 -286.531841) (xy 355.384363 -286.546001) (xy 355.333842 -286.552135)
			(xy 355.28299 -286.550086) (xy 355.233126 -286.539906) (xy 355.18554 -286.521859) (xy 355.141466 -286.496413)
			(xy 355.102044 -286.464226) (xy 355.068296 -286.426132) (xy 355.041095 -286.383118) (xy 355.021147 -286.336298)
			(xy 355.008968 -286.286884) (xy 355.004873 -286.236156) (xy 354.696776 -286.236156) (xy 354.696264 -286.261602)
			(xy 354.6881 -286.311836) (xy 354.671984 -286.36011) (xy 354.648333 -286.405173) (xy 354.61776 -286.445859)
			(xy 354.581056 -286.481114) (xy 354.539172 -286.510024) (xy 354.493193 -286.531841) (xy 354.444309 -286.546001)
			(xy 354.393788 -286.552135) (xy 354.342936 -286.550086) (xy 354.293072 -286.539906) (xy 354.245486 -286.521859)
			(xy 354.201412 -286.496413) (xy 354.16199 -286.464226) (xy 354.128242 -286.426132) (xy 354.101041 -286.383118)
			(xy 354.081093 -286.336298) (xy 354.068914 -286.286884) (xy 354.064819 -286.236156) (xy 353.759008 -286.236156)
			(xy 353.758518 -286.261145) (xy 353.750699 -286.310508) (xy 353.735255 -286.35804) (xy 353.712565 -286.402572)
			(xy 353.683189 -286.443005) (xy 353.647849 -286.478345) (xy 353.607416 -286.507721) (xy 353.562884 -286.530411)
			(xy 353.515352 -286.545855) (xy 353.465989 -286.553674) (xy 353.416011 -286.553674) (xy 353.366648 -286.545855)
			(xy 353.319116 -286.530411) (xy 353.274584 -286.507721) (xy 353.234151 -286.478345) (xy 353.198811 -286.443005)
			(xy 353.169435 -286.402572) (xy 353.146745 -286.35804) (xy 353.131301 -286.310508) (xy 353.123482 -286.261145)
			(xy 352.816419 -286.261145) (xy 352.81641 -286.261602) (xy 352.808246 -286.311836) (xy 352.79213 -286.36011)
			(xy 352.768479 -286.405173) (xy 352.737906 -286.445859) (xy 352.701202 -286.481114) (xy 352.659318 -286.510024)
			(xy 352.613339 -286.531841) (xy 352.564455 -286.546001) (xy 352.513934 -286.552135) (xy 352.463082 -286.550086)
			(xy 352.413218 -286.539906) (xy 352.365632 -286.521859) (xy 352.321558 -286.496413) (xy 352.282136 -286.464226)
			(xy 352.248388 -286.426132) (xy 352.221187 -286.383118) (xy 352.201239 -286.336298) (xy 352.18906 -286.286884)
			(xy 352.184965 -286.236156) (xy 351.876868 -286.236156) (xy 351.876356 -286.261602) (xy 351.868192 -286.311836)
			(xy 351.852076 -286.36011) (xy 351.828425 -286.405173) (xy 351.797852 -286.445859) (xy 351.761148 -286.481114)
			(xy 351.719264 -286.510024) (xy 351.673285 -286.531841) (xy 351.624401 -286.546001) (xy 351.57388 -286.552135)
			(xy 351.523028 -286.550086) (xy 351.473164 -286.539906) (xy 351.425578 -286.521859) (xy 351.381504 -286.496413)
			(xy 351.342082 -286.464226) (xy 351.308334 -286.426132) (xy 351.281133 -286.383118) (xy 351.261185 -286.336298)
			(xy 351.249006 -286.286884) (xy 351.244911 -286.236156) (xy 350.9391 -286.236156) (xy 350.93861 -286.261145)
			(xy 350.930791 -286.310508) (xy 350.915347 -286.35804) (xy 350.892657 -286.402572) (xy 350.863281 -286.443005)
			(xy 350.827941 -286.478345) (xy 350.787508 -286.507721) (xy 350.742976 -286.530411) (xy 350.695444 -286.545855)
			(xy 350.646081 -286.553674) (xy 350.596103 -286.553674) (xy 350.54674 -286.545855) (xy 350.499208 -286.530411)
			(xy 350.454676 -286.507721) (xy 350.414243 -286.478345) (xy 350.378903 -286.443005) (xy 350.349527 -286.402572)
			(xy 350.326837 -286.35804) (xy 350.311393 -286.310508) (xy 350.303574 -286.261145) (xy 349.996257 -286.261145)
			(xy 349.996248 -286.261602) (xy 349.988084 -286.311836) (xy 349.971968 -286.36011) (xy 349.948317 -286.405173)
			(xy 349.917744 -286.445859) (xy 349.88104 -286.481114) (xy 349.839156 -286.510024) (xy 349.793177 -286.531841)
			(xy 349.744293 -286.546001) (xy 349.693772 -286.552135) (xy 349.64292 -286.550086) (xy 349.593056 -286.539906)
			(xy 349.54547 -286.521859) (xy 349.501396 -286.496413) (xy 349.461974 -286.464226) (xy 349.428226 -286.426132)
			(xy 349.401025 -286.383118) (xy 349.381077 -286.336298) (xy 349.368898 -286.286884) (xy 349.364803 -286.236156)
			(xy 349.05696 -286.236156) (xy 349.056448 -286.261602) (xy 349.048284 -286.311836) (xy 349.032168 -286.36011)
			(xy 349.008517 -286.405173) (xy 348.977944 -286.445859) (xy 348.94124 -286.481114) (xy 348.899356 -286.510024)
			(xy 348.853377 -286.531841) (xy 348.804493 -286.546001) (xy 348.753972 -286.552135) (xy 348.70312 -286.550086)
			(xy 348.653256 -286.539906) (xy 348.60567 -286.521859) (xy 348.561596 -286.496413) (xy 348.522174 -286.464226)
			(xy 348.488426 -286.426132) (xy 348.461225 -286.383118) (xy 348.441277 -286.336298) (xy 348.429098 -286.286884)
			(xy 348.425003 -286.236156) (xy 348.119192 -286.236156) (xy 348.118702 -286.261145) (xy 348.110883 -286.310508)
			(xy 348.095439 -286.35804) (xy 348.072749 -286.402572) (xy 348.043373 -286.443005) (xy 348.008033 -286.478345)
			(xy 347.9676 -286.507721) (xy 347.923068 -286.530411) (xy 347.875536 -286.545855) (xy 347.826173 -286.553674)
			(xy 347.776195 -286.553674) (xy 347.726832 -286.545855) (xy 347.6793 -286.530411) (xy 347.634768 -286.507721)
			(xy 347.594335 -286.478345) (xy 347.558995 -286.443005) (xy 347.529619 -286.402572) (xy 347.506929 -286.35804)
			(xy 347.491485 -286.310508) (xy 347.483666 -286.261145) (xy 347.176349 -286.261145) (xy 347.17634 -286.261602)
			(xy 347.168176 -286.311836) (xy 347.15206 -286.36011) (xy 347.128409 -286.405173) (xy 347.097836 -286.445859)
			(xy 347.061132 -286.481114) (xy 347.019248 -286.510024) (xy 346.973269 -286.531841) (xy 346.924385 -286.546001)
			(xy 346.873864 -286.552135) (xy 346.823012 -286.550086) (xy 346.773148 -286.539906) (xy 346.725562 -286.521859)
			(xy 346.681488 -286.496413) (xy 346.642066 -286.464226) (xy 346.608318 -286.426132) (xy 346.581117 -286.383118)
			(xy 346.561169 -286.336298) (xy 346.54899 -286.286884) (xy 346.544895 -286.236156) (xy 346.236798 -286.236156)
			(xy 346.236286 -286.261602) (xy 346.228122 -286.311836) (xy 346.212006 -286.36011) (xy 346.188355 -286.405173)
			(xy 346.157782 -286.445859) (xy 346.121078 -286.481114) (xy 346.079194 -286.510024) (xy 346.033215 -286.531841)
			(xy 345.984331 -286.546001) (xy 345.93381 -286.552135) (xy 345.882958 -286.550086) (xy 345.833094 -286.539906)
			(xy 345.785508 -286.521859) (xy 345.741434 -286.496413) (xy 345.702012 -286.464226) (xy 345.668264 -286.426132)
			(xy 345.641063 -286.383118) (xy 345.621115 -286.336298) (xy 345.608936 -286.286884) (xy 345.604841 -286.236156)
			(xy 345.298903 -286.236156) (xy 345.297309 -286.274096) (xy 345.287701 -286.322328) (xy 345.27078 -286.368505)
			(xy 345.246948 -286.411525) (xy 345.232228 -286.431228) (xy 345.214389 -286.453199) (xy 345.172316 -286.491043)
			(xy 345.124199 -286.520827) (xy 345.098116 -286.531812) (xy 345.097862 -286.531812) (xy 345.095068 -286.532828)
			(xy 345.08674 -286.53721) (xy 345.073739 -286.550793) (xy 345.066501 -286.568145) (xy 345.065858 -286.577532)
			(xy 345.065858 -287.071151) (xy 347.013512 -287.071151) (xy 347.013512 -287.021173) (xy 347.021331 -286.97181)
			(xy 347.036775 -286.924278) (xy 347.059465 -286.879746) (xy 347.088841 -286.839313) (xy 347.124181 -286.803973)
			(xy 347.164614 -286.774597) (xy 347.209146 -286.751907) (xy 347.256678 -286.736463) (xy 347.306041 -286.728644)
			(xy 347.356019 -286.728644) (xy 347.405382 -286.736463) (xy 347.452914 -286.751907) (xy 347.497446 -286.774597)
			(xy 347.537879 -286.803973) (xy 347.573219 -286.839313) (xy 347.602595 -286.879746) (xy 347.625285 -286.924278)
			(xy 347.640729 -286.97181) (xy 347.648548 -287.021173) (xy 347.649038 -287.046162) (xy 347.648553 -287.070897)
			(xy 349.833674 -287.070897) (xy 349.833674 -287.020919) (xy 349.841493 -286.971556) (xy 349.856937 -286.924024)
			(xy 349.879627 -286.879492) (xy 349.909003 -286.839059) (xy 349.944343 -286.803719) (xy 349.984776 -286.774343)
			(xy 350.029308 -286.751653) (xy 350.07684 -286.736209) (xy 350.126203 -286.72839) (xy 350.176181 -286.72839)
			(xy 350.225544 -286.736209) (xy 350.273076 -286.751653) (xy 350.317608 -286.774343) (xy 350.358041 -286.803719)
			(xy 350.393381 -286.839059) (xy 350.422757 -286.879492) (xy 350.445447 -286.924024) (xy 350.460891 -286.971556)
			(xy 350.46871 -287.020919) (xy 350.4692 -287.045908) (xy 350.46871 -287.070897) (xy 352.653582 -287.070897)
			(xy 352.653582 -287.020919) (xy 352.661401 -286.971556) (xy 352.676845 -286.924024) (xy 352.699535 -286.879492)
			(xy 352.728911 -286.839059) (xy 352.764251 -286.803719) (xy 352.804684 -286.774343) (xy 352.849216 -286.751653)
			(xy 352.896748 -286.736209) (xy 352.946111 -286.72839) (xy 352.996089 -286.72839) (xy 353.045452 -286.736209)
			(xy 353.092984 -286.751653) (xy 353.137516 -286.774343) (xy 353.177949 -286.803719) (xy 353.213289 -286.839059)
			(xy 353.242665 -286.879492) (xy 353.265355 -286.924024) (xy 353.280799 -286.971556) (xy 353.288618 -287.020919)
			(xy 353.289108 -287.045908) (xy 353.288618 -287.070897) (xy 353.288578 -287.071151) (xy 355.47349 -287.071151)
			(xy 355.47349 -287.021173) (xy 355.481309 -286.97181) (xy 355.496753 -286.924278) (xy 355.519443 -286.879746)
			(xy 355.548819 -286.839313) (xy 355.584159 -286.803973) (xy 355.624592 -286.774597) (xy 355.669124 -286.751907)
			(xy 355.716656 -286.736463) (xy 355.766019 -286.728644) (xy 355.815997 -286.728644) (xy 355.86536 -286.736463)
			(xy 355.912892 -286.751907) (xy 355.957424 -286.774597) (xy 355.997857 -286.803973) (xy 356.033197 -286.839313)
			(xy 356.062573 -286.879746) (xy 356.085263 -286.924278) (xy 356.100707 -286.97181) (xy 356.108526 -287.021173)
			(xy 356.109011 -287.045908) (xy 356.414827 -287.045908) (xy 356.418922 -286.99518) (xy 356.431101 -286.945766)
			(xy 356.451049 -286.898946) (xy 356.47825 -286.855932) (xy 356.511998 -286.817838) (xy 356.55142 -286.785651)
			(xy 356.595494 -286.760205) (xy 356.64308 -286.742158) (xy 356.692944 -286.731978) (xy 356.743796 -286.729929)
			(xy 356.794317 -286.736063) (xy 356.843201 -286.750223) (xy 356.88918 -286.77204) (xy 356.931064 -286.80095)
			(xy 356.967768 -286.836205) (xy 356.998341 -286.876891) (xy 357.021992 -286.921954) (xy 357.038108 -286.970228)
			(xy 357.046272 -287.020462) (xy 357.046784 -287.045908) (xy 357.354881 -287.045908) (xy 357.358976 -286.99518)
			(xy 357.371155 -286.945766) (xy 357.391103 -286.898946) (xy 357.418304 -286.855932) (xy 357.452052 -286.817838)
			(xy 357.491474 -286.785651) (xy 357.535548 -286.760205) (xy 357.583134 -286.742158) (xy 357.632998 -286.731978)
			(xy 357.68385 -286.729929) (xy 357.734371 -286.736063) (xy 357.783255 -286.750223) (xy 357.829234 -286.77204)
			(xy 357.871118 -286.80095) (xy 357.907822 -286.836205) (xy 357.938395 -286.876891) (xy 357.962046 -286.921954)
			(xy 357.978162 -286.970228) (xy 357.986326 -287.020462) (xy 357.986838 -287.045908) (xy 357.986335 -287.070897)
			(xy 358.293652 -287.070897) (xy 358.293652 -287.020919) (xy 358.301471 -286.971556) (xy 358.316915 -286.924024)
			(xy 358.339605 -286.879492) (xy 358.368981 -286.839059) (xy 358.404321 -286.803719) (xy 358.444754 -286.774343)
			(xy 358.489286 -286.751653) (xy 358.536818 -286.736209) (xy 358.586181 -286.72839) (xy 358.636159 -286.72839)
			(xy 358.685522 -286.736209) (xy 358.733054 -286.751653) (xy 358.777586 -286.774343) (xy 358.818019 -286.803719)
			(xy 358.853359 -286.839059) (xy 358.882735 -286.879492) (xy 358.905425 -286.924024) (xy 358.920869 -286.971556)
			(xy 358.928688 -287.020919) (xy 358.929178 -287.045908) (xy 358.928688 -287.070897) (xy 361.10721 -287.070897)
			(xy 361.10721 -287.020919) (xy 361.115029 -286.971556) (xy 361.130473 -286.924024) (xy 361.153163 -286.879492)
			(xy 361.182539 -286.839059) (xy 361.217879 -286.803719) (xy 361.258312 -286.774343) (xy 361.302844 -286.751653)
			(xy 361.350376 -286.736209) (xy 361.399739 -286.72839) (xy 361.449717 -286.72839) (xy 361.49908 -286.736209)
			(xy 361.546612 -286.751653) (xy 361.591144 -286.774343) (xy 361.631577 -286.803719) (xy 361.666917 -286.839059)
			(xy 361.696293 -286.879492) (xy 361.718983 -286.924024) (xy 361.734427 -286.971556) (xy 361.742246 -287.020919)
			(xy 361.742736 -287.045908) (xy 362.048547 -287.045908) (xy 362.052642 -286.99518) (xy 362.064821 -286.945766)
			(xy 362.084769 -286.898946) (xy 362.11197 -286.855932) (xy 362.145718 -286.817838) (xy 362.18514 -286.785651)
			(xy 362.229214 -286.760205) (xy 362.2768 -286.742158) (xy 362.326664 -286.731978) (xy 362.377516 -286.729929)
			(xy 362.428037 -286.736063) (xy 362.476921 -286.750223) (xy 362.5229 -286.77204) (xy 362.564784 -286.80095)
			(xy 362.601488 -286.836205) (xy 362.632061 -286.876891) (xy 362.655712 -286.921954) (xy 362.671828 -286.970228)
			(xy 362.679992 -287.020462) (xy 362.680504 -287.045908) (xy 362.988601 -287.045908) (xy 362.992696 -286.99518)
			(xy 363.004875 -286.945766) (xy 363.024823 -286.898946) (xy 363.052024 -286.855932) (xy 363.085772 -286.817838)
			(xy 363.125194 -286.785651) (xy 363.169268 -286.760205) (xy 363.216854 -286.742158) (xy 363.266718 -286.731978)
			(xy 363.31757 -286.729929) (xy 363.368091 -286.736063) (xy 363.416975 -286.750223) (xy 363.462954 -286.77204)
			(xy 363.504838 -286.80095) (xy 363.541542 -286.836205) (xy 363.572115 -286.876891) (xy 363.595766 -286.921954)
			(xy 363.611882 -286.970228) (xy 363.620046 -287.020462) (xy 363.620558 -287.045908) (xy 363.62005 -287.071151)
			(xy 363.927372 -287.071151) (xy 363.927372 -287.021173) (xy 363.935191 -286.97181) (xy 363.950635 -286.924278)
			(xy 363.973325 -286.879746) (xy 364.002701 -286.839313) (xy 364.038041 -286.803973) (xy 364.078474 -286.774597)
			(xy 364.123006 -286.751907) (xy 364.170538 -286.736463) (xy 364.219901 -286.728644) (xy 364.269879 -286.728644)
			(xy 364.319242 -286.736463) (xy 364.366774 -286.751907) (xy 364.411306 -286.774597) (xy 364.451739 -286.803973)
			(xy 364.487079 -286.839313) (xy 364.516455 -286.879746) (xy 364.539145 -286.924278) (xy 364.554589 -286.97181)
			(xy 364.562408 -287.021173) (xy 364.562898 -287.046162) (xy 364.562413 -287.070897) (xy 366.74728 -287.070897)
			(xy 366.74728 -287.020919) (xy 366.755099 -286.971556) (xy 366.770543 -286.924024) (xy 366.793233 -286.879492)
			(xy 366.822609 -286.839059) (xy 366.857949 -286.803719) (xy 366.898382 -286.774343) (xy 366.942914 -286.751653)
			(xy 366.990446 -286.736209) (xy 367.039809 -286.72839) (xy 367.089787 -286.72839) (xy 367.13915 -286.736209)
			(xy 367.186682 -286.751653) (xy 367.231214 -286.774343) (xy 367.271647 -286.803719) (xy 367.306987 -286.839059)
			(xy 367.336363 -286.879492) (xy 367.359053 -286.924024) (xy 367.374497 -286.971556) (xy 367.382316 -287.020919)
			(xy 367.382806 -287.045908) (xy 367.382316 -287.070897) (xy 369.567188 -287.070897) (xy 369.567188 -287.020919)
			(xy 369.575007 -286.971556) (xy 369.590451 -286.924024) (xy 369.613141 -286.879492) (xy 369.642517 -286.839059)
			(xy 369.677857 -286.803719) (xy 369.71829 -286.774343) (xy 369.762822 -286.751653) (xy 369.810354 -286.736209)
			(xy 369.859717 -286.72839) (xy 369.909695 -286.72839) (xy 369.959058 -286.736209) (xy 370.00659 -286.751653)
			(xy 370.051122 -286.774343) (xy 370.091555 -286.803719) (xy 370.126895 -286.839059) (xy 370.156271 -286.879492)
			(xy 370.178961 -286.924024) (xy 370.194405 -286.971556) (xy 370.202224 -287.020919) (xy 370.202714 -287.045908)
			(xy 370.202224 -287.070897) (xy 372.38735 -287.070897) (xy 372.38735 -287.020919) (xy 372.395169 -286.971556)
			(xy 372.410613 -286.924024) (xy 372.433303 -286.879492) (xy 372.462679 -286.839059) (xy 372.498019 -286.803719)
			(xy 372.538452 -286.774343) (xy 372.582984 -286.751653) (xy 372.630516 -286.736209) (xy 372.679879 -286.72839)
			(xy 372.729857 -286.72839) (xy 372.77922 -286.736209) (xy 372.826752 -286.751653) (xy 372.871284 -286.774343)
			(xy 372.911717 -286.803719) (xy 372.947057 -286.839059) (xy 372.976433 -286.879492) (xy 372.999123 -286.924024)
			(xy 373.014567 -286.971556) (xy 373.022386 -287.020919) (xy 373.022876 -287.045908) (xy 373.022386 -287.070897)
			(xy 373.014567 -287.12026) (xy 372.999123 -287.167792) (xy 372.976433 -287.212324) (xy 372.947057 -287.252757)
			(xy 372.911717 -287.288097) (xy 372.871284 -287.317473) (xy 372.826752 -287.340163) (xy 372.77922 -287.355607)
			(xy 372.729857 -287.363426) (xy 372.679879 -287.363426) (xy 372.630516 -287.355607) (xy 372.582984 -287.340163)
			(xy 372.538452 -287.317473) (xy 372.498019 -287.288097) (xy 372.462679 -287.252757) (xy 372.433303 -287.212324)
			(xy 372.410613 -287.167792) (xy 372.395169 -287.12026) (xy 372.38735 -287.070897) (xy 370.202224 -287.070897)
			(xy 370.194405 -287.12026) (xy 370.178961 -287.167792) (xy 370.156271 -287.212324) (xy 370.126895 -287.252757)
			(xy 370.091555 -287.288097) (xy 370.051122 -287.317473) (xy 370.00659 -287.340163) (xy 369.959058 -287.355607)
			(xy 369.909695 -287.363426) (xy 369.859717 -287.363426) (xy 369.810354 -287.355607) (xy 369.762822 -287.340163)
			(xy 369.71829 -287.317473) (xy 369.677857 -287.288097) (xy 369.642517 -287.252757) (xy 369.613141 -287.212324)
			(xy 369.590451 -287.167792) (xy 369.575007 -287.12026) (xy 369.567188 -287.070897) (xy 367.382316 -287.070897)
			(xy 367.374497 -287.12026) (xy 367.359053 -287.167792) (xy 367.336363 -287.212324) (xy 367.306987 -287.252757)
			(xy 367.271647 -287.288097) (xy 367.231214 -287.317473) (xy 367.186682 -287.340163) (xy 367.13915 -287.355607)
			(xy 367.089787 -287.363426) (xy 367.039809 -287.363426) (xy 366.990446 -287.355607) (xy 366.942914 -287.340163)
			(xy 366.898382 -287.317473) (xy 366.857949 -287.288097) (xy 366.822609 -287.252757) (xy 366.793233 -287.212324)
			(xy 366.770543 -287.167792) (xy 366.755099 -287.12026) (xy 366.74728 -287.070897) (xy 364.562413 -287.070897)
			(xy 364.562408 -287.071151) (xy 364.554589 -287.120514) (xy 364.539145 -287.168046) (xy 364.516455 -287.212578)
			(xy 364.487079 -287.253011) (xy 364.451739 -287.288351) (xy 364.411306 -287.317727) (xy 364.366774 -287.340417)
			(xy 364.319242 -287.355861) (xy 364.269879 -287.36368) (xy 364.219901 -287.36368) (xy 364.170538 -287.355861)
			(xy 364.123006 -287.340417) (xy 364.078474 -287.317727) (xy 364.038041 -287.288351) (xy 364.002701 -287.253011)
			(xy 363.973325 -287.212578) (xy 363.950635 -287.168046) (xy 363.935191 -287.120514) (xy 363.927372 -287.071151)
			(xy 363.62005 -287.071151) (xy 363.620046 -287.071354) (xy 363.611882 -287.121588) (xy 363.595766 -287.169862)
			(xy 363.572115 -287.214925) (xy 363.541542 -287.255611) (xy 363.504838 -287.290866) (xy 363.462954 -287.319776)
			(xy 363.416975 -287.341593) (xy 363.368091 -287.355753) (xy 363.31757 -287.361887) (xy 363.266718 -287.359838)
			(xy 363.216854 -287.349658) (xy 363.169268 -287.331611) (xy 363.125194 -287.306165) (xy 363.085772 -287.273978)
			(xy 363.052024 -287.235884) (xy 363.024823 -287.19287) (xy 363.004875 -287.14605) (xy 362.992696 -287.096636)
			(xy 362.988601 -287.045908) (xy 362.680504 -287.045908) (xy 362.679992 -287.071354) (xy 362.671828 -287.121588)
			(xy 362.655712 -287.169862) (xy 362.632061 -287.214925) (xy 362.601488 -287.255611) (xy 362.564784 -287.290866)
			(xy 362.5229 -287.319776) (xy 362.476921 -287.341593) (xy 362.428037 -287.355753) (xy 362.377516 -287.361887)
			(xy 362.326664 -287.359838) (xy 362.2768 -287.349658) (xy 362.229214 -287.331611) (xy 362.18514 -287.306165)
			(xy 362.145718 -287.273978) (xy 362.11197 -287.235884) (xy 362.084769 -287.19287) (xy 362.064821 -287.14605)
			(xy 362.052642 -287.096636) (xy 362.048547 -287.045908) (xy 361.742736 -287.045908) (xy 361.742246 -287.070897)
			(xy 361.734427 -287.12026) (xy 361.718983 -287.167792) (xy 361.696293 -287.212324) (xy 361.666917 -287.252757)
			(xy 361.631577 -287.288097) (xy 361.591144 -287.317473) (xy 361.546612 -287.340163) (xy 361.49908 -287.355607)
			(xy 361.449717 -287.363426) (xy 361.399739 -287.363426) (xy 361.350376 -287.355607) (xy 361.302844 -287.340163)
			(xy 361.258312 -287.317473) (xy 361.217879 -287.288097) (xy 361.182539 -287.252757) (xy 361.153163 -287.212324)
			(xy 361.130473 -287.167792) (xy 361.115029 -287.12026) (xy 361.10721 -287.070897) (xy 358.928688 -287.070897)
			(xy 358.920869 -287.12026) (xy 358.905425 -287.167792) (xy 358.882735 -287.212324) (xy 358.853359 -287.252757)
			(xy 358.818019 -287.288097) (xy 358.777586 -287.317473) (xy 358.733054 -287.340163) (xy 358.685522 -287.355607)
			(xy 358.636159 -287.363426) (xy 358.586181 -287.363426) (xy 358.536818 -287.355607) (xy 358.489286 -287.340163)
			(xy 358.444754 -287.317473) (xy 358.404321 -287.288097) (xy 358.368981 -287.252757) (xy 358.339605 -287.212324)
			(xy 358.316915 -287.167792) (xy 358.301471 -287.12026) (xy 358.293652 -287.070897) (xy 357.986335 -287.070897)
			(xy 357.986326 -287.071354) (xy 357.978162 -287.121588) (xy 357.962046 -287.169862) (xy 357.938395 -287.214925)
			(xy 357.907822 -287.255611) (xy 357.871118 -287.290866) (xy 357.829234 -287.319776) (xy 357.783255 -287.341593)
			(xy 357.734371 -287.355753) (xy 357.68385 -287.361887) (xy 357.632998 -287.359838) (xy 357.583134 -287.349658)
			(xy 357.535548 -287.331611) (xy 357.491474 -287.306165) (xy 357.452052 -287.273978) (xy 357.418304 -287.235884)
			(xy 357.391103 -287.19287) (xy 357.371155 -287.14605) (xy 357.358976 -287.096636) (xy 357.354881 -287.045908)
			(xy 357.046784 -287.045908) (xy 357.046272 -287.071354) (xy 357.038108 -287.121588) (xy 357.021992 -287.169862)
			(xy 356.998341 -287.214925) (xy 356.967768 -287.255611) (xy 356.931064 -287.290866) (xy 356.88918 -287.319776)
			(xy 356.843201 -287.341593) (xy 356.794317 -287.355753) (xy 356.743796 -287.361887) (xy 356.692944 -287.359838)
			(xy 356.64308 -287.349658) (xy 356.595494 -287.331611) (xy 356.55142 -287.306165) (xy 356.511998 -287.273978)
			(xy 356.47825 -287.235884) (xy 356.451049 -287.19287) (xy 356.431101 -287.14605) (xy 356.418922 -287.096636)
			(xy 356.414827 -287.045908) (xy 356.109011 -287.045908) (xy 356.109016 -287.046162) (xy 356.108526 -287.071151)
			(xy 356.100707 -287.120514) (xy 356.085263 -287.168046) (xy 356.062573 -287.212578) (xy 356.033197 -287.253011)
			(xy 355.997857 -287.288351) (xy 355.957424 -287.317727) (xy 355.912892 -287.340417) (xy 355.86536 -287.355861)
			(xy 355.815997 -287.36368) (xy 355.766019 -287.36368) (xy 355.716656 -287.355861) (xy 355.669124 -287.340417)
			(xy 355.624592 -287.317727) (xy 355.584159 -287.288351) (xy 355.548819 -287.253011) (xy 355.519443 -287.212578)
			(xy 355.496753 -287.168046) (xy 355.481309 -287.120514) (xy 355.47349 -287.071151) (xy 353.288578 -287.071151)
			(xy 353.280799 -287.12026) (xy 353.265355 -287.167792) (xy 353.242665 -287.212324) (xy 353.213289 -287.252757)
			(xy 353.177949 -287.288097) (xy 353.137516 -287.317473) (xy 353.092984 -287.340163) (xy 353.045452 -287.355607)
			(xy 352.996089 -287.363426) (xy 352.946111 -287.363426) (xy 352.896748 -287.355607) (xy 352.849216 -287.340163)
			(xy 352.804684 -287.317473) (xy 352.764251 -287.288097) (xy 352.728911 -287.252757) (xy 352.699535 -287.212324)
			(xy 352.676845 -287.167792) (xy 352.661401 -287.12026) (xy 352.653582 -287.070897) (xy 350.46871 -287.070897)
			(xy 350.460891 -287.12026) (xy 350.445447 -287.167792) (xy 350.422757 -287.212324) (xy 350.393381 -287.252757)
			(xy 350.358041 -287.288097) (xy 350.317608 -287.317473) (xy 350.273076 -287.340163) (xy 350.225544 -287.355607)
			(xy 350.176181 -287.363426) (xy 350.126203 -287.363426) (xy 350.07684 -287.355607) (xy 350.029308 -287.340163)
			(xy 349.984776 -287.317473) (xy 349.944343 -287.288097) (xy 349.909003 -287.252757) (xy 349.879627 -287.212324)
			(xy 349.856937 -287.167792) (xy 349.841493 -287.12026) (xy 349.833674 -287.070897) (xy 347.648553 -287.070897)
			(xy 347.648548 -287.071151) (xy 347.640729 -287.120514) (xy 347.625285 -287.168046) (xy 347.602595 -287.212578)
			(xy 347.573219 -287.253011) (xy 347.537879 -287.288351) (xy 347.497446 -287.317727) (xy 347.452914 -287.340417)
			(xy 347.405382 -287.355861) (xy 347.356019 -287.36368) (xy 347.306041 -287.36368) (xy 347.256678 -287.355861)
			(xy 347.209146 -287.340417) (xy 347.164614 -287.317727) (xy 347.124181 -287.288351) (xy 347.088841 -287.253011)
			(xy 347.059465 -287.212578) (xy 347.036775 -287.168046) (xy 347.021331 -287.120514) (xy 347.013512 -287.071151)
			(xy 345.065858 -287.071151) (xy 345.065858 -287.513522) (xy 345.065858 -287.514792) (xy 345.066527 -287.524175)
			(xy 345.073753 -287.541524) (xy 345.086752 -287.555097) (xy 345.095068 -287.559496) (xy 345.097862 -287.560512)
			(xy 345.120567 -287.569964) (xy 345.162988 -287.594843) (xy 345.201071 -287.625959) (xy 345.233908 -287.662569)
			(xy 345.260714 -287.7038) (xy 345.280851 -287.748667) (xy 345.293837 -287.7961) (xy 345.299363 -287.844967)
			(xy 345.298892 -287.856168) (xy 345.604841 -287.856168) (xy 345.608936 -287.80544) (xy 345.621115 -287.756026)
			(xy 345.641063 -287.709206) (xy 345.668264 -287.666192) (xy 345.702012 -287.628098) (xy 345.741434 -287.595911)
			(xy 345.785508 -287.570465) (xy 345.833094 -287.552418) (xy 345.882958 -287.542238) (xy 345.93381 -287.540189)
			(xy 345.984331 -287.546323) (xy 346.033215 -287.560483) (xy 346.079194 -287.5823) (xy 346.121078 -287.61121)
			(xy 346.157782 -287.646465) (xy 346.188355 -287.687151) (xy 346.212006 -287.732214) (xy 346.228122 -287.780488)
			(xy 346.236286 -287.830722) (xy 346.236798 -287.856168) (xy 346.544895 -287.856168) (xy 346.54899 -287.80544)
			(xy 346.561169 -287.756026) (xy 346.581117 -287.709206) (xy 346.608318 -287.666192) (xy 346.642066 -287.628098)
			(xy 346.681488 -287.595911) (xy 346.725562 -287.570465) (xy 346.773148 -287.552418) (xy 346.823012 -287.542238)
			(xy 346.873864 -287.540189) (xy 346.924385 -287.546323) (xy 346.973269 -287.560483) (xy 347.019248 -287.5823)
			(xy 347.061132 -287.61121) (xy 347.097836 -287.646465) (xy 347.128409 -287.687151) (xy 347.15206 -287.732214)
			(xy 347.168176 -287.780488) (xy 347.17634 -287.830722) (xy 347.176852 -287.856168) (xy 347.176349 -287.881157)
			(xy 347.483666 -287.881157) (xy 347.483666 -287.831179) (xy 347.491485 -287.781816) (xy 347.506929 -287.734284)
			(xy 347.529619 -287.689752) (xy 347.558995 -287.649319) (xy 347.594335 -287.613979) (xy 347.634768 -287.584603)
			(xy 347.6793 -287.561913) (xy 347.726832 -287.546469) (xy 347.776195 -287.53865) (xy 347.826173 -287.53865)
			(xy 347.875536 -287.546469) (xy 347.923068 -287.561913) (xy 347.9676 -287.584603) (xy 348.008033 -287.613979)
			(xy 348.043373 -287.649319) (xy 348.072749 -287.689752) (xy 348.095439 -287.734284) (xy 348.110883 -287.781816)
			(xy 348.118702 -287.831179) (xy 348.119192 -287.856168) (xy 348.425003 -287.856168) (xy 348.429098 -287.80544)
			(xy 348.441277 -287.756026) (xy 348.461225 -287.709206) (xy 348.488426 -287.666192) (xy 348.522174 -287.628098)
			(xy 348.561596 -287.595911) (xy 348.60567 -287.570465) (xy 348.653256 -287.552418) (xy 348.70312 -287.542238)
			(xy 348.753972 -287.540189) (xy 348.804493 -287.546323) (xy 348.853377 -287.560483) (xy 348.899356 -287.5823)
			(xy 348.94124 -287.61121) (xy 348.977944 -287.646465) (xy 349.008517 -287.687151) (xy 349.032168 -287.732214)
			(xy 349.048284 -287.780488) (xy 349.056448 -287.830722) (xy 349.05696 -287.856168) (xy 349.364803 -287.856168)
			(xy 349.368898 -287.80544) (xy 349.381077 -287.756026) (xy 349.401025 -287.709206) (xy 349.428226 -287.666192)
			(xy 349.461974 -287.628098) (xy 349.501396 -287.595911) (xy 349.54547 -287.570465) (xy 349.593056 -287.552418)
			(xy 349.64292 -287.542238) (xy 349.693772 -287.540189) (xy 349.744293 -287.546323) (xy 349.793177 -287.560483)
			(xy 349.839156 -287.5823) (xy 349.88104 -287.61121) (xy 349.917744 -287.646465) (xy 349.948317 -287.687151)
			(xy 349.971968 -287.732214) (xy 349.988084 -287.780488) (xy 349.996248 -287.830722) (xy 349.99676 -287.856168)
			(xy 349.996257 -287.881157) (xy 350.303574 -287.881157) (xy 350.303574 -287.831179) (xy 350.311393 -287.781816)
			(xy 350.326837 -287.734284) (xy 350.349527 -287.689752) (xy 350.378903 -287.649319) (xy 350.414243 -287.613979)
			(xy 350.454676 -287.584603) (xy 350.499208 -287.561913) (xy 350.54674 -287.546469) (xy 350.596103 -287.53865)
			(xy 350.646081 -287.53865) (xy 350.695444 -287.546469) (xy 350.742976 -287.561913) (xy 350.787508 -287.584603)
			(xy 350.827941 -287.613979) (xy 350.863281 -287.649319) (xy 350.892657 -287.689752) (xy 350.915347 -287.734284)
			(xy 350.930791 -287.781816) (xy 350.93861 -287.831179) (xy 350.9391 -287.856168) (xy 351.244911 -287.856168)
			(xy 351.249006 -287.80544) (xy 351.261185 -287.756026) (xy 351.281133 -287.709206) (xy 351.308334 -287.666192)
			(xy 351.342082 -287.628098) (xy 351.381504 -287.595911) (xy 351.425578 -287.570465) (xy 351.473164 -287.552418)
			(xy 351.523028 -287.542238) (xy 351.57388 -287.540189) (xy 351.624401 -287.546323) (xy 351.673285 -287.560483)
			(xy 351.719264 -287.5823) (xy 351.761148 -287.61121) (xy 351.797852 -287.646465) (xy 351.828425 -287.687151)
			(xy 351.852076 -287.732214) (xy 351.868192 -287.780488) (xy 351.876356 -287.830722) (xy 351.876868 -287.856168)
			(xy 352.184965 -287.856168) (xy 352.18906 -287.80544) (xy 352.201239 -287.756026) (xy 352.221187 -287.709206)
			(xy 352.248388 -287.666192) (xy 352.282136 -287.628098) (xy 352.321558 -287.595911) (xy 352.365632 -287.570465)
			(xy 352.413218 -287.552418) (xy 352.463082 -287.542238) (xy 352.513934 -287.540189) (xy 352.564455 -287.546323)
			(xy 352.613339 -287.560483) (xy 352.659318 -287.5823) (xy 352.701202 -287.61121) (xy 352.737906 -287.646465)
			(xy 352.768479 -287.687151) (xy 352.79213 -287.732214) (xy 352.808246 -287.780488) (xy 352.81641 -287.830722)
			(xy 352.816922 -287.856168) (xy 352.816419 -287.881157) (xy 353.123482 -287.881157) (xy 353.123482 -287.831179)
			(xy 353.131301 -287.781816) (xy 353.146745 -287.734284) (xy 353.169435 -287.689752) (xy 353.198811 -287.649319)
			(xy 353.234151 -287.613979) (xy 353.274584 -287.584603) (xy 353.319116 -287.561913) (xy 353.366648 -287.546469)
			(xy 353.416011 -287.53865) (xy 353.465989 -287.53865) (xy 353.515352 -287.546469) (xy 353.562884 -287.561913)
			(xy 353.607416 -287.584603) (xy 353.647849 -287.613979) (xy 353.683189 -287.649319) (xy 353.712565 -287.689752)
			(xy 353.735255 -287.734284) (xy 353.750699 -287.781816) (xy 353.758518 -287.831179) (xy 353.759008 -287.856168)
			(xy 354.064819 -287.856168) (xy 354.068914 -287.80544) (xy 354.081093 -287.756026) (xy 354.101041 -287.709206)
			(xy 354.128242 -287.666192) (xy 354.16199 -287.628098) (xy 354.201412 -287.595911) (xy 354.245486 -287.570465)
			(xy 354.293072 -287.552418) (xy 354.342936 -287.542238) (xy 354.393788 -287.540189) (xy 354.444309 -287.546323)
			(xy 354.493193 -287.560483) (xy 354.539172 -287.5823) (xy 354.581056 -287.61121) (xy 354.61776 -287.646465)
			(xy 354.648333 -287.687151) (xy 354.671984 -287.732214) (xy 354.6881 -287.780488) (xy 354.696264 -287.830722)
			(xy 354.696776 -287.856168) (xy 355.004873 -287.856168) (xy 355.008968 -287.80544) (xy 355.021147 -287.756026)
			(xy 355.041095 -287.709206) (xy 355.068296 -287.666192) (xy 355.102044 -287.628098) (xy 355.141466 -287.595911)
			(xy 355.18554 -287.570465) (xy 355.233126 -287.552418) (xy 355.28299 -287.542238) (xy 355.333842 -287.540189)
			(xy 355.384363 -287.546323) (xy 355.433247 -287.560483) (xy 355.479226 -287.5823) (xy 355.52111 -287.61121)
			(xy 355.557814 -287.646465) (xy 355.588387 -287.687151) (xy 355.612038 -287.732214) (xy 355.628154 -287.780488)
			(xy 355.636318 -287.830722) (xy 355.63683 -287.856168) (xy 355.636327 -287.881157) (xy 355.943644 -287.881157)
			(xy 355.943644 -287.831179) (xy 355.951463 -287.781816) (xy 355.966907 -287.734284) (xy 355.989597 -287.689752)
			(xy 356.018973 -287.649319) (xy 356.054313 -287.613979) (xy 356.094746 -287.584603) (xy 356.139278 -287.561913)
			(xy 356.18681 -287.546469) (xy 356.236173 -287.53865) (xy 356.286151 -287.53865) (xy 356.335514 -287.546469)
			(xy 356.383046 -287.561913) (xy 356.427578 -287.584603) (xy 356.468011 -287.613979) (xy 356.503351 -287.649319)
			(xy 356.532727 -287.689752) (xy 356.555417 -287.734284) (xy 356.570861 -287.781816) (xy 356.57868 -287.831179)
			(xy 356.57917 -287.856168) (xy 356.57868 -287.881157) (xy 356.883698 -287.881157) (xy 356.883698 -287.831179)
			(xy 356.891517 -287.781816) (xy 356.906961 -287.734284) (xy 356.929651 -287.689752) (xy 356.959027 -287.649319)
			(xy 356.994367 -287.613979) (xy 357.0348 -287.584603) (xy 357.079332 -287.561913) (xy 357.126864 -287.546469)
			(xy 357.176227 -287.53865) (xy 357.226205 -287.53865) (xy 357.275568 -287.546469) (xy 357.3231 -287.561913)
			(xy 357.367632 -287.584603) (xy 357.408065 -287.613979) (xy 357.443405 -287.649319) (xy 357.472781 -287.689752)
			(xy 357.495471 -287.734284) (xy 357.510915 -287.781816) (xy 357.518734 -287.831179) (xy 357.519224 -287.856168)
			(xy 357.518734 -287.881157) (xy 357.823498 -287.881157) (xy 357.823498 -287.831179) (xy 357.831317 -287.781816)
			(xy 357.846761 -287.734284) (xy 357.869451 -287.689752) (xy 357.898827 -287.649319) (xy 357.934167 -287.613979)
			(xy 357.9746 -287.584603) (xy 358.019132 -287.561913) (xy 358.066664 -287.546469) (xy 358.116027 -287.53865)
			(xy 358.166005 -287.53865) (xy 358.215368 -287.546469) (xy 358.2629 -287.561913) (xy 358.307432 -287.584603)
			(xy 358.347865 -287.613979) (xy 358.383205 -287.649319) (xy 358.412581 -287.689752) (xy 358.435271 -287.734284)
			(xy 358.450715 -287.781816) (xy 358.458534 -287.831179) (xy 358.459024 -287.856168) (xy 358.458534 -287.881157)
			(xy 361.577364 -287.881157) (xy 361.577364 -287.831179) (xy 361.585183 -287.781816) (xy 361.600627 -287.734284)
			(xy 361.623317 -287.689752) (xy 361.652693 -287.649319) (xy 361.688033 -287.613979) (xy 361.728466 -287.584603)
			(xy 361.772998 -287.561913) (xy 361.82053 -287.546469) (xy 361.869893 -287.53865) (xy 361.919871 -287.53865)
			(xy 361.969234 -287.546469) (xy 362.016766 -287.561913) (xy 362.061298 -287.584603) (xy 362.101731 -287.613979)
			(xy 362.137071 -287.649319) (xy 362.166447 -287.689752) (xy 362.189137 -287.734284) (xy 362.204581 -287.781816)
			(xy 362.2124 -287.831179) (xy 362.21289 -287.856168) (xy 362.2124 -287.881157) (xy 362.517164 -287.881157)
			(xy 362.517164 -287.831179) (xy 362.524983 -287.781816) (xy 362.540427 -287.734284) (xy 362.563117 -287.689752)
			(xy 362.592493 -287.649319) (xy 362.627833 -287.613979) (xy 362.668266 -287.584603) (xy 362.712798 -287.561913)
			(xy 362.76033 -287.546469) (xy 362.809693 -287.53865) (xy 362.859671 -287.53865) (xy 362.909034 -287.546469)
			(xy 362.956566 -287.561913) (xy 363.001098 -287.584603) (xy 363.041531 -287.613979) (xy 363.076871 -287.649319)
			(xy 363.106247 -287.689752) (xy 363.128937 -287.734284) (xy 363.144381 -287.781816) (xy 363.1522 -287.831179)
			(xy 363.15269 -287.856168) (xy 363.1522 -287.881157) (xy 363.457218 -287.881157) (xy 363.457218 -287.831179)
			(xy 363.465037 -287.781816) (xy 363.480481 -287.734284) (xy 363.503171 -287.689752) (xy 363.532547 -287.649319)
			(xy 363.567887 -287.613979) (xy 363.60832 -287.584603) (xy 363.652852 -287.561913) (xy 363.700384 -287.546469)
			(xy 363.749747 -287.53865) (xy 363.799725 -287.53865) (xy 363.849088 -287.546469) (xy 363.89662 -287.561913)
			(xy 363.941152 -287.584603) (xy 363.981585 -287.613979) (xy 364.016925 -287.649319) (xy 364.046301 -287.689752)
			(xy 364.068991 -287.734284) (xy 364.084435 -287.781816) (xy 364.092254 -287.831179) (xy 364.092744 -287.856168)
			(xy 364.398555 -287.856168) (xy 364.40265 -287.80544) (xy 364.414829 -287.756026) (xy 364.434777 -287.709206)
			(xy 364.461978 -287.666192) (xy 364.495726 -287.628098) (xy 364.535148 -287.595911) (xy 364.579222 -287.570465)
			(xy 364.626808 -287.552418) (xy 364.676672 -287.542238) (xy 364.727524 -287.540189) (xy 364.778045 -287.546323)
			(xy 364.826929 -287.560483) (xy 364.872908 -287.5823) (xy 364.914792 -287.61121) (xy 364.951496 -287.646465)
			(xy 364.982069 -287.687151) (xy 365.00572 -287.732214) (xy 365.021836 -287.780488) (xy 365.03 -287.830722)
			(xy 365.030512 -287.856168) (xy 365.338609 -287.856168) (xy 365.342704 -287.80544) (xy 365.354883 -287.756026)
			(xy 365.374831 -287.709206) (xy 365.402032 -287.666192) (xy 365.43578 -287.628098) (xy 365.475202 -287.595911)
			(xy 365.519276 -287.570465) (xy 365.566862 -287.552418) (xy 365.616726 -287.542238) (xy 365.667578 -287.540189)
			(xy 365.718099 -287.546323) (xy 365.766983 -287.560483) (xy 365.812962 -287.5823) (xy 365.854846 -287.61121)
			(xy 365.89155 -287.646465) (xy 365.922123 -287.687151) (xy 365.945774 -287.732214) (xy 365.96189 -287.780488)
			(xy 365.970054 -287.830722) (xy 365.970566 -287.856168) (xy 365.970063 -287.881157) (xy 366.27738 -287.881157)
			(xy 366.27738 -287.831179) (xy 366.285199 -287.781816) (xy 366.300643 -287.734284) (xy 366.323333 -287.689752)
			(xy 366.352709 -287.649319) (xy 366.388049 -287.613979) (xy 366.428482 -287.584603) (xy 366.473014 -287.561913)
			(xy 366.520546 -287.546469) (xy 366.569909 -287.53865) (xy 366.619887 -287.53865) (xy 366.66925 -287.546469)
			(xy 366.716782 -287.561913) (xy 366.761314 -287.584603) (xy 366.801747 -287.613979) (xy 366.837087 -287.649319)
			(xy 366.866463 -287.689752) (xy 366.889153 -287.734284) (xy 366.904597 -287.781816) (xy 366.912416 -287.831179)
			(xy 366.912906 -287.856168) (xy 367.218463 -287.856168) (xy 367.222558 -287.80544) (xy 367.234737 -287.756026)
			(xy 367.254685 -287.709206) (xy 367.281886 -287.666192) (xy 367.315634 -287.628098) (xy 367.355056 -287.595911)
			(xy 367.39913 -287.570465) (xy 367.446716 -287.552418) (xy 367.49658 -287.542238) (xy 367.547432 -287.540189)
			(xy 367.597953 -287.546323) (xy 367.646837 -287.560483) (xy 367.692816 -287.5823) (xy 367.7347 -287.61121)
			(xy 367.771404 -287.646465) (xy 367.801977 -287.687151) (xy 367.825628 -287.732214) (xy 367.841744 -287.780488)
			(xy 367.849908 -287.830722) (xy 367.85042 -287.856168) (xy 368.158517 -287.856168) (xy 368.162612 -287.80544)
			(xy 368.174791 -287.756026) (xy 368.194739 -287.709206) (xy 368.22194 -287.666192) (xy 368.255688 -287.628098)
			(xy 368.29511 -287.595911) (xy 368.339184 -287.570465) (xy 368.38677 -287.552418) (xy 368.436634 -287.542238)
			(xy 368.487486 -287.540189) (xy 368.538007 -287.546323) (xy 368.586891 -287.560483) (xy 368.63287 -287.5823)
			(xy 368.674754 -287.61121) (xy 368.711458 -287.646465) (xy 368.742031 -287.687151) (xy 368.765682 -287.732214)
			(xy 368.781798 -287.780488) (xy 368.789962 -287.830722) (xy 368.790474 -287.856168) (xy 368.789971 -287.881157)
			(xy 369.097288 -287.881157) (xy 369.097288 -287.831179) (xy 369.105107 -287.781816) (xy 369.120551 -287.734284)
			(xy 369.143241 -287.689752) (xy 369.172617 -287.649319) (xy 369.207957 -287.613979) (xy 369.24839 -287.584603)
			(xy 369.292922 -287.561913) (xy 369.340454 -287.546469) (xy 369.389817 -287.53865) (xy 369.439795 -287.53865)
			(xy 369.489158 -287.546469) (xy 369.53669 -287.561913) (xy 369.581222 -287.584603) (xy 369.621655 -287.613979)
			(xy 369.656995 -287.649319) (xy 369.686371 -287.689752) (xy 369.709061 -287.734284) (xy 369.724505 -287.781816)
			(xy 369.732324 -287.831179) (xy 369.732814 -287.856168) (xy 370.038625 -287.856168) (xy 370.04272 -287.80544)
			(xy 370.054899 -287.756026) (xy 370.074847 -287.709206) (xy 370.102048 -287.666192) (xy 370.135796 -287.628098)
			(xy 370.175218 -287.595911) (xy 370.219292 -287.570465) (xy 370.266878 -287.552418) (xy 370.316742 -287.542238)
			(xy 370.367594 -287.540189) (xy 370.418115 -287.546323) (xy 370.466999 -287.560483) (xy 370.512978 -287.5823)
			(xy 370.554862 -287.61121) (xy 370.591566 -287.646465) (xy 370.622139 -287.687151) (xy 370.64579 -287.732214)
			(xy 370.661906 -287.780488) (xy 370.67007 -287.830722) (xy 370.670582 -287.856168) (xy 370.978679 -287.856168)
			(xy 370.982774 -287.80544) (xy 370.994953 -287.756026) (xy 371.014901 -287.709206) (xy 371.042102 -287.666192)
			(xy 371.07585 -287.628098) (xy 371.115272 -287.595911) (xy 371.159346 -287.570465) (xy 371.206932 -287.552418)
			(xy 371.256796 -287.542238) (xy 371.307648 -287.540189) (xy 371.358169 -287.546323) (xy 371.407053 -287.560483)
			(xy 371.453032 -287.5823) (xy 371.494916 -287.61121) (xy 371.53162 -287.646465) (xy 371.562193 -287.687151)
			(xy 371.585844 -287.732214) (xy 371.60196 -287.780488) (xy 371.610124 -287.830722) (xy 371.610636 -287.856168)
			(xy 371.610133 -287.881157) (xy 371.917196 -287.881157) (xy 371.917196 -287.831179) (xy 371.925015 -287.781816)
			(xy 371.940459 -287.734284) (xy 371.963149 -287.689752) (xy 371.992525 -287.649319) (xy 372.027865 -287.613979)
			(xy 372.068298 -287.584603) (xy 372.11283 -287.561913) (xy 372.160362 -287.546469) (xy 372.209725 -287.53865)
			(xy 372.259703 -287.53865) (xy 372.309066 -287.546469) (xy 372.356598 -287.561913) (xy 372.40113 -287.584603)
			(xy 372.441563 -287.613979) (xy 372.476903 -287.649319) (xy 372.506279 -287.689752) (xy 372.528969 -287.734284)
			(xy 372.544413 -287.781816) (xy 372.552232 -287.831179) (xy 372.552722 -287.856168) (xy 372.858533 -287.856168)
			(xy 372.862628 -287.80544) (xy 372.874807 -287.756026) (xy 372.894755 -287.709206) (xy 372.921956 -287.666192)
			(xy 372.955704 -287.628098) (xy 372.995126 -287.595911) (xy 373.0392 -287.570465) (xy 373.086786 -287.552418)
			(xy 373.13665 -287.542238) (xy 373.187502 -287.540189) (xy 373.238023 -287.546323) (xy 373.286907 -287.560483)
			(xy 373.332886 -287.5823) (xy 373.37477 -287.61121) (xy 373.411474 -287.646465) (xy 373.442047 -287.687151)
			(xy 373.465698 -287.732214) (xy 373.481814 -287.780488) (xy 373.489978 -287.830722) (xy 373.49049 -287.856168)
			(xy 373.798587 -287.856168) (xy 373.802682 -287.80544) (xy 373.814861 -287.756026) (xy 373.834809 -287.709206)
			(xy 373.86201 -287.666192) (xy 373.895758 -287.628098) (xy 373.93518 -287.595911) (xy 373.979254 -287.570465)
			(xy 374.02684 -287.552418) (xy 374.076704 -287.542238) (xy 374.127556 -287.540189) (xy 374.178077 -287.546323)
			(xy 374.226961 -287.560483) (xy 374.27294 -287.5823) (xy 374.314824 -287.61121) (xy 374.351528 -287.646465)
			(xy 374.382101 -287.687151) (xy 374.405752 -287.732214) (xy 374.421868 -287.780488) (xy 374.430032 -287.830722)
			(xy 374.430544 -287.856168) (xy 374.430032 -287.881614) (xy 374.421868 -287.931848) (xy 374.405752 -287.980122)
			(xy 374.382101 -288.025185) (xy 374.351528 -288.065871) (xy 374.314824 -288.101126) (xy 374.27294 -288.130036)
			(xy 374.226961 -288.151853) (xy 374.178077 -288.166013) (xy 374.127556 -288.172147) (xy 374.076704 -288.170098)
			(xy 374.02684 -288.159918) (xy 373.979254 -288.141871) (xy 373.93518 -288.116425) (xy 373.895758 -288.084238)
			(xy 373.86201 -288.046144) (xy 373.834809 -288.00313) (xy 373.814861 -287.95631) (xy 373.802682 -287.906896)
			(xy 373.798587 -287.856168) (xy 373.49049 -287.856168) (xy 373.489978 -287.881614) (xy 373.481814 -287.931848)
			(xy 373.465698 -287.980122) (xy 373.442047 -288.025185) (xy 373.411474 -288.065871) (xy 373.37477 -288.101126)
			(xy 373.332886 -288.130036) (xy 373.286907 -288.151853) (xy 373.238023 -288.166013) (xy 373.187502 -288.172147)
			(xy 373.13665 -288.170098) (xy 373.086786 -288.159918) (xy 373.0392 -288.141871) (xy 372.995126 -288.116425)
			(xy 372.955704 -288.084238) (xy 372.921956 -288.046144) (xy 372.894755 -288.00313) (xy 372.874807 -287.95631)
			(xy 372.862628 -287.906896) (xy 372.858533 -287.856168) (xy 372.552722 -287.856168) (xy 372.552232 -287.881157)
			(xy 372.544413 -287.93052) (xy 372.528969 -287.978052) (xy 372.506279 -288.022584) (xy 372.476903 -288.063017)
			(xy 372.441563 -288.098357) (xy 372.40113 -288.127733) (xy 372.356598 -288.150423) (xy 372.309066 -288.165867)
			(xy 372.259703 -288.173686) (xy 372.209725 -288.173686) (xy 372.160362 -288.165867) (xy 372.11283 -288.150423)
			(xy 372.068298 -288.127733) (xy 372.027865 -288.098357) (xy 371.992525 -288.063017) (xy 371.963149 -288.022584)
			(xy 371.940459 -287.978052) (xy 371.925015 -287.93052) (xy 371.917196 -287.881157) (xy 371.610133 -287.881157)
			(xy 371.610124 -287.881614) (xy 371.60196 -287.931848) (xy 371.585844 -287.980122) (xy 371.562193 -288.025185)
			(xy 371.53162 -288.065871) (xy 371.494916 -288.101126) (xy 371.453032 -288.130036) (xy 371.407053 -288.151853)
			(xy 371.358169 -288.166013) (xy 371.307648 -288.172147) (xy 371.256796 -288.170098) (xy 371.206932 -288.159918)
			(xy 371.159346 -288.141871) (xy 371.115272 -288.116425) (xy 371.07585 -288.084238) (xy 371.042102 -288.046144)
			(xy 371.014901 -288.00313) (xy 370.994953 -287.95631) (xy 370.982774 -287.906896) (xy 370.978679 -287.856168)
			(xy 370.670582 -287.856168) (xy 370.67007 -287.881614) (xy 370.661906 -287.931848) (xy 370.64579 -287.980122)
			(xy 370.622139 -288.025185) (xy 370.591566 -288.065871) (xy 370.554862 -288.101126) (xy 370.512978 -288.130036)
			(xy 370.466999 -288.151853) (xy 370.418115 -288.166013) (xy 370.367594 -288.172147) (xy 370.316742 -288.170098)
			(xy 370.266878 -288.159918) (xy 370.219292 -288.141871) (xy 370.175218 -288.116425) (xy 370.135796 -288.084238)
			(xy 370.102048 -288.046144) (xy 370.074847 -288.00313) (xy 370.054899 -287.95631) (xy 370.04272 -287.906896)
			(xy 370.038625 -287.856168) (xy 369.732814 -287.856168) (xy 369.732324 -287.881157) (xy 369.724505 -287.93052)
			(xy 369.709061 -287.978052) (xy 369.686371 -288.022584) (xy 369.656995 -288.063017) (xy 369.621655 -288.098357)
			(xy 369.581222 -288.127733) (xy 369.53669 -288.150423) (xy 369.489158 -288.165867) (xy 369.439795 -288.173686)
			(xy 369.389817 -288.173686) (xy 369.340454 -288.165867) (xy 369.292922 -288.150423) (xy 369.24839 -288.127733)
			(xy 369.207957 -288.098357) (xy 369.172617 -288.063017) (xy 369.143241 -288.022584) (xy 369.120551 -287.978052)
			(xy 369.105107 -287.93052) (xy 369.097288 -287.881157) (xy 368.789971 -287.881157) (xy 368.789962 -287.881614)
			(xy 368.781798 -287.931848) (xy 368.765682 -287.980122) (xy 368.742031 -288.025185) (xy 368.711458 -288.065871)
			(xy 368.674754 -288.101126) (xy 368.63287 -288.130036) (xy 368.586891 -288.151853) (xy 368.538007 -288.166013)
			(xy 368.487486 -288.172147) (xy 368.436634 -288.170098) (xy 368.38677 -288.159918) (xy 368.339184 -288.141871)
			(xy 368.29511 -288.116425) (xy 368.255688 -288.084238) (xy 368.22194 -288.046144) (xy 368.194739 -288.00313)
			(xy 368.174791 -287.95631) (xy 368.162612 -287.906896) (xy 368.158517 -287.856168) (xy 367.85042 -287.856168)
			(xy 367.849908 -287.881614) (xy 367.841744 -287.931848) (xy 367.825628 -287.980122) (xy 367.801977 -288.025185)
			(xy 367.771404 -288.065871) (xy 367.7347 -288.101126) (xy 367.692816 -288.130036) (xy 367.646837 -288.151853)
			(xy 367.597953 -288.166013) (xy 367.547432 -288.172147) (xy 367.49658 -288.170098) (xy 367.446716 -288.159918)
			(xy 367.39913 -288.141871) (xy 367.355056 -288.116425) (xy 367.315634 -288.084238) (xy 367.281886 -288.046144)
			(xy 367.254685 -288.00313) (xy 367.234737 -287.95631) (xy 367.222558 -287.906896) (xy 367.218463 -287.856168)
			(xy 366.912906 -287.856168) (xy 366.912416 -287.881157) (xy 366.904597 -287.93052) (xy 366.889153 -287.978052)
			(xy 366.866463 -288.022584) (xy 366.837087 -288.063017) (xy 366.801747 -288.098357) (xy 366.761314 -288.127733)
			(xy 366.716782 -288.150423) (xy 366.66925 -288.165867) (xy 366.619887 -288.173686) (xy 366.569909 -288.173686)
			(xy 366.520546 -288.165867) (xy 366.473014 -288.150423) (xy 366.428482 -288.127733) (xy 366.388049 -288.098357)
			(xy 366.352709 -288.063017) (xy 366.323333 -288.022584) (xy 366.300643 -287.978052) (xy 366.285199 -287.93052)
			(xy 366.27738 -287.881157) (xy 365.970063 -287.881157) (xy 365.970054 -287.881614) (xy 365.96189 -287.931848)
			(xy 365.945774 -287.980122) (xy 365.922123 -288.025185) (xy 365.89155 -288.065871) (xy 365.854846 -288.101126)
			(xy 365.812962 -288.130036) (xy 365.766983 -288.151853) (xy 365.718099 -288.166013) (xy 365.667578 -288.172147)
			(xy 365.616726 -288.170098) (xy 365.566862 -288.159918) (xy 365.519276 -288.141871) (xy 365.475202 -288.116425)
			(xy 365.43578 -288.084238) (xy 365.402032 -288.046144) (xy 365.374831 -288.00313) (xy 365.354883 -287.95631)
			(xy 365.342704 -287.906896) (xy 365.338609 -287.856168) (xy 365.030512 -287.856168) (xy 365.03 -287.881614)
			(xy 365.021836 -287.931848) (xy 365.00572 -287.980122) (xy 364.982069 -288.025185) (xy 364.951496 -288.065871)
			(xy 364.914792 -288.101126) (xy 364.872908 -288.130036) (xy 364.826929 -288.151853) (xy 364.778045 -288.166013)
			(xy 364.727524 -288.172147) (xy 364.676672 -288.170098) (xy 364.626808 -288.159918) (xy 364.579222 -288.141871)
			(xy 364.535148 -288.116425) (xy 364.495726 -288.084238) (xy 364.461978 -288.046144) (xy 364.434777 -288.00313)
			(xy 364.414829 -287.95631) (xy 364.40265 -287.906896) (xy 364.398555 -287.856168) (xy 364.092744 -287.856168)
			(xy 364.092254 -287.881157) (xy 364.084435 -287.93052) (xy 364.068991 -287.978052) (xy 364.046301 -288.022584)
			(xy 364.016925 -288.063017) (xy 363.981585 -288.098357) (xy 363.941152 -288.127733) (xy 363.89662 -288.150423)
			(xy 363.849088 -288.165867) (xy 363.799725 -288.173686) (xy 363.749747 -288.173686) (xy 363.700384 -288.165867)
			(xy 363.652852 -288.150423) (xy 363.60832 -288.127733) (xy 363.567887 -288.098357) (xy 363.532547 -288.063017)
			(xy 363.503171 -288.022584) (xy 363.480481 -287.978052) (xy 363.465037 -287.93052) (xy 363.457218 -287.881157)
			(xy 363.1522 -287.881157) (xy 363.144381 -287.93052) (xy 363.128937 -287.978052) (xy 363.106247 -288.022584)
			(xy 363.076871 -288.063017) (xy 363.041531 -288.098357) (xy 363.001098 -288.127733) (xy 362.956566 -288.150423)
			(xy 362.909034 -288.165867) (xy 362.859671 -288.173686) (xy 362.809693 -288.173686) (xy 362.76033 -288.165867)
			(xy 362.712798 -288.150423) (xy 362.668266 -288.127733) (xy 362.627833 -288.098357) (xy 362.592493 -288.063017)
			(xy 362.563117 -288.022584) (xy 362.540427 -287.978052) (xy 362.524983 -287.93052) (xy 362.517164 -287.881157)
			(xy 362.2124 -287.881157) (xy 362.204581 -287.93052) (xy 362.189137 -287.978052) (xy 362.166447 -288.022584)
			(xy 362.137071 -288.063017) (xy 362.101731 -288.098357) (xy 362.061298 -288.127733) (xy 362.016766 -288.150423)
			(xy 361.969234 -288.165867) (xy 361.919871 -288.173686) (xy 361.869893 -288.173686) (xy 361.82053 -288.165867)
			(xy 361.772998 -288.150423) (xy 361.728466 -288.127733) (xy 361.688033 -288.098357) (xy 361.652693 -288.063017)
			(xy 361.623317 -288.022584) (xy 361.600627 -287.978052) (xy 361.585183 -287.93052) (xy 361.577364 -287.881157)
			(xy 358.458534 -287.881157) (xy 358.450715 -287.93052) (xy 358.435271 -287.978052) (xy 358.412581 -288.022584)
			(xy 358.383205 -288.063017) (xy 358.347865 -288.098357) (xy 358.307432 -288.127733) (xy 358.2629 -288.150423)
			(xy 358.215368 -288.165867) (xy 358.166005 -288.173686) (xy 358.116027 -288.173686) (xy 358.066664 -288.165867)
			(xy 358.019132 -288.150423) (xy 357.9746 -288.127733) (xy 357.934167 -288.098357) (xy 357.898827 -288.063017)
			(xy 357.869451 -288.022584) (xy 357.846761 -287.978052) (xy 357.831317 -287.93052) (xy 357.823498 -287.881157)
			(xy 357.518734 -287.881157) (xy 357.510915 -287.93052) (xy 357.495471 -287.978052) (xy 357.472781 -288.022584)
			(xy 357.443405 -288.063017) (xy 357.408065 -288.098357) (xy 357.367632 -288.127733) (xy 357.3231 -288.150423)
			(xy 357.275568 -288.165867) (xy 357.226205 -288.173686) (xy 357.176227 -288.173686) (xy 357.126864 -288.165867)
			(xy 357.079332 -288.150423) (xy 357.0348 -288.127733) (xy 356.994367 -288.098357) (xy 356.959027 -288.063017)
			(xy 356.929651 -288.022584) (xy 356.906961 -287.978052) (xy 356.891517 -287.93052) (xy 356.883698 -287.881157)
			(xy 356.57868 -287.881157) (xy 356.570861 -287.93052) (xy 356.555417 -287.978052) (xy 356.532727 -288.022584)
			(xy 356.503351 -288.063017) (xy 356.468011 -288.098357) (xy 356.427578 -288.127733) (xy 356.383046 -288.150423)
			(xy 356.335514 -288.165867) (xy 356.286151 -288.173686) (xy 356.236173 -288.173686) (xy 356.18681 -288.165867)
			(xy 356.139278 -288.150423) (xy 356.094746 -288.127733) (xy 356.054313 -288.098357) (xy 356.018973 -288.063017)
			(xy 355.989597 -288.022584) (xy 355.966907 -287.978052) (xy 355.951463 -287.93052) (xy 355.943644 -287.881157)
			(xy 355.636327 -287.881157) (xy 355.636318 -287.881614) (xy 355.628154 -287.931848) (xy 355.612038 -287.980122)
			(xy 355.588387 -288.025185) (xy 355.557814 -288.065871) (xy 355.52111 -288.101126) (xy 355.479226 -288.130036)
			(xy 355.433247 -288.151853) (xy 355.384363 -288.166013) (xy 355.333842 -288.172147) (xy 355.28299 -288.170098)
			(xy 355.233126 -288.159918) (xy 355.18554 -288.141871) (xy 355.141466 -288.116425) (xy 355.102044 -288.084238)
			(xy 355.068296 -288.046144) (xy 355.041095 -288.00313) (xy 355.021147 -287.95631) (xy 355.008968 -287.906896)
			(xy 355.004873 -287.856168) (xy 354.696776 -287.856168) (xy 354.696264 -287.881614) (xy 354.6881 -287.931848)
			(xy 354.671984 -287.980122) (xy 354.648333 -288.025185) (xy 354.61776 -288.065871) (xy 354.581056 -288.101126)
			(xy 354.539172 -288.130036) (xy 354.493193 -288.151853) (xy 354.444309 -288.166013) (xy 354.393788 -288.172147)
			(xy 354.342936 -288.170098) (xy 354.293072 -288.159918) (xy 354.245486 -288.141871) (xy 354.201412 -288.116425)
			(xy 354.16199 -288.084238) (xy 354.128242 -288.046144) (xy 354.101041 -288.00313) (xy 354.081093 -287.95631)
			(xy 354.068914 -287.906896) (xy 354.064819 -287.856168) (xy 353.759008 -287.856168) (xy 353.758518 -287.881157)
			(xy 353.750699 -287.93052) (xy 353.735255 -287.978052) (xy 353.712565 -288.022584) (xy 353.683189 -288.063017)
			(xy 353.647849 -288.098357) (xy 353.607416 -288.127733) (xy 353.562884 -288.150423) (xy 353.515352 -288.165867)
			(xy 353.465989 -288.173686) (xy 353.416011 -288.173686) (xy 353.366648 -288.165867) (xy 353.319116 -288.150423)
			(xy 353.274584 -288.127733) (xy 353.234151 -288.098357) (xy 353.198811 -288.063017) (xy 353.169435 -288.022584)
			(xy 353.146745 -287.978052) (xy 353.131301 -287.93052) (xy 353.123482 -287.881157) (xy 352.816419 -287.881157)
			(xy 352.81641 -287.881614) (xy 352.808246 -287.931848) (xy 352.79213 -287.980122) (xy 352.768479 -288.025185)
			(xy 352.737906 -288.065871) (xy 352.701202 -288.101126) (xy 352.659318 -288.130036) (xy 352.613339 -288.151853)
			(xy 352.564455 -288.166013) (xy 352.513934 -288.172147) (xy 352.463082 -288.170098) (xy 352.413218 -288.159918)
			(xy 352.365632 -288.141871) (xy 352.321558 -288.116425) (xy 352.282136 -288.084238) (xy 352.248388 -288.046144)
			(xy 352.221187 -288.00313) (xy 352.201239 -287.95631) (xy 352.18906 -287.906896) (xy 352.184965 -287.856168)
			(xy 351.876868 -287.856168) (xy 351.876356 -287.881614) (xy 351.868192 -287.931848) (xy 351.852076 -287.980122)
			(xy 351.828425 -288.025185) (xy 351.797852 -288.065871) (xy 351.761148 -288.101126) (xy 351.719264 -288.130036)
			(xy 351.673285 -288.151853) (xy 351.624401 -288.166013) (xy 351.57388 -288.172147) (xy 351.523028 -288.170098)
			(xy 351.473164 -288.159918) (xy 351.425578 -288.141871) (xy 351.381504 -288.116425) (xy 351.342082 -288.084238)
			(xy 351.308334 -288.046144) (xy 351.281133 -288.00313) (xy 351.261185 -287.95631) (xy 351.249006 -287.906896)
			(xy 351.244911 -287.856168) (xy 350.9391 -287.856168) (xy 350.93861 -287.881157) (xy 350.930791 -287.93052)
			(xy 350.915347 -287.978052) (xy 350.892657 -288.022584) (xy 350.863281 -288.063017) (xy 350.827941 -288.098357)
			(xy 350.787508 -288.127733) (xy 350.742976 -288.150423) (xy 350.695444 -288.165867) (xy 350.646081 -288.173686)
			(xy 350.596103 -288.173686) (xy 350.54674 -288.165867) (xy 350.499208 -288.150423) (xy 350.454676 -288.127733)
			(xy 350.414243 -288.098357) (xy 350.378903 -288.063017) (xy 350.349527 -288.022584) (xy 350.326837 -287.978052)
			(xy 350.311393 -287.93052) (xy 350.303574 -287.881157) (xy 349.996257 -287.881157) (xy 349.996248 -287.881614)
			(xy 349.988084 -287.931848) (xy 349.971968 -287.980122) (xy 349.948317 -288.025185) (xy 349.917744 -288.065871)
			(xy 349.88104 -288.101126) (xy 349.839156 -288.130036) (xy 349.793177 -288.151853) (xy 349.744293 -288.166013)
			(xy 349.693772 -288.172147) (xy 349.64292 -288.170098) (xy 349.593056 -288.159918) (xy 349.54547 -288.141871)
			(xy 349.501396 -288.116425) (xy 349.461974 -288.084238) (xy 349.428226 -288.046144) (xy 349.401025 -288.00313)
			(xy 349.381077 -287.95631) (xy 349.368898 -287.906896) (xy 349.364803 -287.856168) (xy 349.05696 -287.856168)
			(xy 349.056448 -287.881614) (xy 349.048284 -287.931848) (xy 349.032168 -287.980122) (xy 349.008517 -288.025185)
			(xy 348.977944 -288.065871) (xy 348.94124 -288.101126) (xy 348.899356 -288.130036) (xy 348.853377 -288.151853)
			(xy 348.804493 -288.166013) (xy 348.753972 -288.172147) (xy 348.70312 -288.170098) (xy 348.653256 -288.159918)
			(xy 348.60567 -288.141871) (xy 348.561596 -288.116425) (xy 348.522174 -288.084238) (xy 348.488426 -288.046144)
			(xy 348.461225 -288.00313) (xy 348.441277 -287.95631) (xy 348.429098 -287.906896) (xy 348.425003 -287.856168)
			(xy 348.119192 -287.856168) (xy 348.118702 -287.881157) (xy 348.110883 -287.93052) (xy 348.095439 -287.978052)
			(xy 348.072749 -288.022584) (xy 348.043373 -288.063017) (xy 348.008033 -288.098357) (xy 347.9676 -288.127733)
			(xy 347.923068 -288.150423) (xy 347.875536 -288.165867) (xy 347.826173 -288.173686) (xy 347.776195 -288.173686)
			(xy 347.726832 -288.165867) (xy 347.6793 -288.150423) (xy 347.634768 -288.127733) (xy 347.594335 -288.098357)
			(xy 347.558995 -288.063017) (xy 347.529619 -288.022584) (xy 347.506929 -287.978052) (xy 347.491485 -287.93052)
			(xy 347.483666 -287.881157) (xy 347.176349 -287.881157) (xy 347.17634 -287.881614) (xy 347.168176 -287.931848)
			(xy 347.15206 -287.980122) (xy 347.128409 -288.025185) (xy 347.097836 -288.065871) (xy 347.061132 -288.101126)
			(xy 347.019248 -288.130036) (xy 346.973269 -288.151853) (xy 346.924385 -288.166013) (xy 346.873864 -288.172147)
			(xy 346.823012 -288.170098) (xy 346.773148 -288.159918) (xy 346.725562 -288.141871) (xy 346.681488 -288.116425)
			(xy 346.642066 -288.084238) (xy 346.608318 -288.046144) (xy 346.581117 -288.00313) (xy 346.561169 -287.95631)
			(xy 346.54899 -287.906896) (xy 346.544895 -287.856168) (xy 346.236798 -287.856168) (xy 346.236286 -287.881614)
			(xy 346.228122 -287.931848) (xy 346.212006 -287.980122) (xy 346.188355 -288.025185) (xy 346.157782 -288.065871)
			(xy 346.121078 -288.101126) (xy 346.079194 -288.130036) (xy 346.033215 -288.151853) (xy 345.984331 -288.166013)
			(xy 345.93381 -288.172147) (xy 345.882958 -288.170098) (xy 345.833094 -288.159918) (xy 345.785508 -288.141871)
			(xy 345.741434 -288.116425) (xy 345.702012 -288.084238) (xy 345.668264 -288.046144) (xy 345.641063 -288.00313)
			(xy 345.621115 -287.95631) (xy 345.608936 -287.906896) (xy 345.604841 -287.856168) (xy 345.298892 -287.856168)
			(xy 345.297297 -287.894102) (xy 345.287688 -287.942333) (xy 345.270766 -287.988509) (xy 345.246934 -288.031527)
			(xy 345.232228 -288.05124) (xy 345.214389 -288.073211) (xy 345.172314 -288.111053) (xy 345.124198 -288.140836)
			(xy 345.098116 -288.151824) (xy 345.097862 -288.151824) (xy 345.095068 -288.15284) (xy 345.086741 -288.157223)
			(xy 345.073744 -288.170806) (xy 345.066509 -288.188158) (xy 345.065858 -288.197544) (xy 345.065858 -288.35985)
			(xy 345.066311 -288.369689) (xy 345.073737 -288.387911) (xy 345.087505 -288.40197) (xy 345.096338 -288.406332)
			(xy 345.14155 -288.426144) (xy 345.17965 -288.442654) (xy 345.186544 -288.445383) (xy 345.201255 -288.447183)
			(xy 345.208606 -288.44621) (xy 345.215464 -288.44494) (xy 345.228672 -288.43859) (xy 345.23426 -288.433256)
			(xy 345.252026 -288.417296) (xy 345.291445 -288.390339) (xy 345.334451 -288.369575) (xy 345.380077 -288.355472)
			(xy 345.427298 -288.348346) (xy 345.451176 -288.347912) (xy 345.476167 -288.348375) (xy 345.525534 -288.356191)
			(xy 345.57307 -288.371633) (xy 345.617605 -288.394322) (xy 345.658042 -288.423698) (xy 345.693386 -288.459039)
			(xy 345.722766 -288.499474) (xy 345.745458 -288.544008) (xy 345.760904 -288.591543) (xy 345.768723 -288.640909)
			(xy 345.768723 -288.690891) (xy 345.76872 -288.690909) (xy 346.073712 -288.690909) (xy 346.073712 -288.640931)
			(xy 346.081531 -288.591568) (xy 346.096975 -288.544036) (xy 346.119665 -288.499504) (xy 346.149041 -288.459071)
			(xy 346.184381 -288.423731) (xy 346.224814 -288.394355) (xy 346.269346 -288.371665) (xy 346.316878 -288.356221)
			(xy 346.366241 -288.348402) (xy 346.416219 -288.348402) (xy 346.465582 -288.356221) (xy 346.513114 -288.371665)
			(xy 346.557646 -288.394355) (xy 346.598079 -288.423731) (xy 346.633419 -288.459071) (xy 346.662795 -288.499504)
			(xy 346.685485 -288.544036) (xy 346.700929 -288.591568) (xy 346.708748 -288.640931) (xy 346.709238 -288.66592)
			(xy 346.708748 -288.690909) (xy 347.013512 -288.690909) (xy 347.013512 -288.640931) (xy 347.021331 -288.591568)
			(xy 347.036775 -288.544036) (xy 347.059465 -288.499504) (xy 347.088841 -288.459071) (xy 347.124181 -288.423731)
			(xy 347.164614 -288.394355) (xy 347.209146 -288.371665) (xy 347.256678 -288.356221) (xy 347.306041 -288.348402)
			(xy 347.356019 -288.348402) (xy 347.405382 -288.356221) (xy 347.452914 -288.371665) (xy 347.497446 -288.394355)
			(xy 347.537879 -288.423731) (xy 347.573219 -288.459071) (xy 347.602595 -288.499504) (xy 347.625285 -288.544036)
			(xy 347.640729 -288.591568) (xy 347.648548 -288.640931) (xy 347.649038 -288.66592) (xy 347.648548 -288.690909)
			(xy 347.953566 -288.690909) (xy 347.953566 -288.640931) (xy 347.961385 -288.591568) (xy 347.976829 -288.544036)
			(xy 347.999519 -288.499504) (xy 348.028895 -288.459071) (xy 348.064235 -288.423731) (xy 348.104668 -288.394355)
			(xy 348.1492 -288.371665) (xy 348.196732 -288.356221) (xy 348.246095 -288.348402) (xy 348.296073 -288.348402)
			(xy 348.345436 -288.356221) (xy 348.392968 -288.371665) (xy 348.4375 -288.394355) (xy 348.477933 -288.423731)
			(xy 348.513273 -288.459071) (xy 348.542649 -288.499504) (xy 348.565339 -288.544036) (xy 348.580783 -288.591568)
			(xy 348.588602 -288.640931) (xy 348.589092 -288.66592) (xy 348.588602 -288.690909) (xy 348.89362 -288.690909)
			(xy 348.89362 -288.640931) (xy 348.901439 -288.591568) (xy 348.916883 -288.544036) (xy 348.939573 -288.499504)
			(xy 348.968949 -288.459071) (xy 349.004289 -288.423731) (xy 349.044722 -288.394355) (xy 349.089254 -288.371665)
			(xy 349.136786 -288.356221) (xy 349.186149 -288.348402) (xy 349.236127 -288.348402) (xy 349.28549 -288.356221)
			(xy 349.333022 -288.371665) (xy 349.377554 -288.394355) (xy 349.417987 -288.423731) (xy 349.453327 -288.459071)
			(xy 349.482703 -288.499504) (xy 349.505393 -288.544036) (xy 349.520837 -288.591568) (xy 349.528656 -288.640931)
			(xy 349.529146 -288.66592) (xy 349.528656 -288.690909) (xy 349.833674 -288.690909) (xy 349.833674 -288.640931)
			(xy 349.841493 -288.591568) (xy 349.856937 -288.544036) (xy 349.879627 -288.499504) (xy 349.909003 -288.459071)
			(xy 349.944343 -288.423731) (xy 349.984776 -288.394355) (xy 350.029308 -288.371665) (xy 350.07684 -288.356221)
			(xy 350.126203 -288.348402) (xy 350.176181 -288.348402) (xy 350.225544 -288.356221) (xy 350.273076 -288.371665)
			(xy 350.317608 -288.394355) (xy 350.358041 -288.423731) (xy 350.393381 -288.459071) (xy 350.422757 -288.499504)
			(xy 350.445447 -288.544036) (xy 350.460891 -288.591568) (xy 350.46871 -288.640931) (xy 350.4692 -288.66592)
			(xy 350.46871 -288.690909) (xy 350.773728 -288.690909) (xy 350.773728 -288.640931) (xy 350.781547 -288.591568)
			(xy 350.796991 -288.544036) (xy 350.819681 -288.499504) (xy 350.849057 -288.459071) (xy 350.884397 -288.423731)
			(xy 350.92483 -288.394355) (xy 350.969362 -288.371665) (xy 351.016894 -288.356221) (xy 351.066257 -288.348402)
			(xy 351.116235 -288.348402) (xy 351.165598 -288.356221) (xy 351.21313 -288.371665) (xy 351.257662 -288.394355)
			(xy 351.298095 -288.423731) (xy 351.333435 -288.459071) (xy 351.362811 -288.499504) (xy 351.385501 -288.544036)
			(xy 351.400945 -288.591568) (xy 351.408764 -288.640931) (xy 351.409254 -288.66592) (xy 351.408764 -288.690909)
			(xy 351.713528 -288.690909) (xy 351.713528 -288.640931) (xy 351.721347 -288.591568) (xy 351.736791 -288.544036)
			(xy 351.759481 -288.499504) (xy 351.788857 -288.459071) (xy 351.824197 -288.423731) (xy 351.86463 -288.394355)
			(xy 351.909162 -288.371665) (xy 351.956694 -288.356221) (xy 352.006057 -288.348402) (xy 352.056035 -288.348402)
			(xy 352.105398 -288.356221) (xy 352.15293 -288.371665) (xy 352.197462 -288.394355) (xy 352.237895 -288.423731)
			(xy 352.273235 -288.459071) (xy 352.302611 -288.499504) (xy 352.325301 -288.544036) (xy 352.340745 -288.591568)
			(xy 352.348564 -288.640931) (xy 352.349054 -288.66592) (xy 352.348564 -288.690909) (xy 352.653582 -288.690909)
			(xy 352.653582 -288.640931) (xy 352.661401 -288.591568) (xy 352.676845 -288.544036) (xy 352.699535 -288.499504)
			(xy 352.728911 -288.459071) (xy 352.764251 -288.423731) (xy 352.804684 -288.394355) (xy 352.849216 -288.371665)
			(xy 352.896748 -288.356221) (xy 352.946111 -288.348402) (xy 352.996089 -288.348402) (xy 353.045452 -288.356221)
			(xy 353.092984 -288.371665) (xy 353.137516 -288.394355) (xy 353.177949 -288.423731) (xy 353.213289 -288.459071)
			(xy 353.242665 -288.499504) (xy 353.265355 -288.544036) (xy 353.280799 -288.591568) (xy 353.288618 -288.640931)
			(xy 353.289108 -288.66592) (xy 353.288618 -288.690909) (xy 353.593636 -288.690909) (xy 353.593636 -288.640931)
			(xy 353.601455 -288.591568) (xy 353.616899 -288.544036) (xy 353.639589 -288.499504) (xy 353.668965 -288.459071)
			(xy 353.704305 -288.423731) (xy 353.744738 -288.394355) (xy 353.78927 -288.371665) (xy 353.836802 -288.356221)
			(xy 353.886165 -288.348402) (xy 353.936143 -288.348402) (xy 353.985506 -288.356221) (xy 354.033038 -288.371665)
			(xy 354.07757 -288.394355) (xy 354.118003 -288.423731) (xy 354.153343 -288.459071) (xy 354.182719 -288.499504)
			(xy 354.205409 -288.544036) (xy 354.220853 -288.591568) (xy 354.228672 -288.640931) (xy 354.229162 -288.66592)
			(xy 354.228672 -288.690909) (xy 354.53369 -288.690909) (xy 354.53369 -288.640931) (xy 354.541509 -288.591568)
			(xy 354.556953 -288.544036) (xy 354.579643 -288.499504) (xy 354.609019 -288.459071) (xy 354.644359 -288.423731)
			(xy 354.684792 -288.394355) (xy 354.729324 -288.371665) (xy 354.776856 -288.356221) (xy 354.826219 -288.348402)
			(xy 354.876197 -288.348402) (xy 354.92556 -288.356221) (xy 354.973092 -288.371665) (xy 355.017624 -288.394355)
			(xy 355.058057 -288.423731) (xy 355.093397 -288.459071) (xy 355.122773 -288.499504) (xy 355.145463 -288.544036)
			(xy 355.160907 -288.591568) (xy 355.168726 -288.640931) (xy 355.169216 -288.66592) (xy 355.168726 -288.690909)
			(xy 355.47349 -288.690909) (xy 355.47349 -288.640931) (xy 355.481309 -288.591568) (xy 355.496753 -288.544036)
			(xy 355.519443 -288.499504) (xy 355.548819 -288.459071) (xy 355.584159 -288.423731) (xy 355.624592 -288.394355)
			(xy 355.669124 -288.371665) (xy 355.716656 -288.356221) (xy 355.766019 -288.348402) (xy 355.815997 -288.348402)
			(xy 355.86536 -288.356221) (xy 355.912892 -288.371665) (xy 355.957424 -288.394355) (xy 355.997857 -288.423731)
			(xy 356.033197 -288.459071) (xy 356.062573 -288.499504) (xy 356.085263 -288.544036) (xy 356.100707 -288.591568)
			(xy 356.108526 -288.640931) (xy 356.109016 -288.66592) (xy 356.414827 -288.66592) (xy 356.418922 -288.615192)
			(xy 356.431101 -288.565778) (xy 356.451049 -288.518958) (xy 356.47825 -288.475944) (xy 356.511998 -288.43785)
			(xy 356.55142 -288.405663) (xy 356.595494 -288.380217) (xy 356.64308 -288.36217) (xy 356.692944 -288.35199)
			(xy 356.743796 -288.349941) (xy 356.794317 -288.356075) (xy 356.843201 -288.370235) (xy 356.88918 -288.392052)
			(xy 356.931064 -288.420962) (xy 356.967768 -288.456217) (xy 356.998341 -288.496903) (xy 357.021992 -288.541966)
			(xy 357.038108 -288.59024) (xy 357.046272 -288.640474) (xy 357.046784 -288.66592) (xy 357.354881 -288.66592)
			(xy 357.358976 -288.615192) (xy 357.371155 -288.565778) (xy 357.391103 -288.518958) (xy 357.418304 -288.475944)
			(xy 357.452052 -288.43785) (xy 357.491474 -288.405663) (xy 357.535548 -288.380217) (xy 357.583134 -288.36217)
			(xy 357.632998 -288.35199) (xy 357.68385 -288.349941) (xy 357.734371 -288.356075) (xy 357.783255 -288.370235)
			(xy 357.829234 -288.392052) (xy 357.871118 -288.420962) (xy 357.907822 -288.456217) (xy 357.938395 -288.496903)
			(xy 357.962046 -288.541966) (xy 357.978162 -288.59024) (xy 357.986326 -288.640474) (xy 357.986838 -288.66592)
			(xy 357.986335 -288.690909) (xy 358.293652 -288.690909) (xy 358.293652 -288.640931) (xy 358.301471 -288.591568)
			(xy 358.316915 -288.544036) (xy 358.339605 -288.499504) (xy 358.368981 -288.459071) (xy 358.404321 -288.423731)
			(xy 358.444754 -288.394355) (xy 358.489286 -288.371665) (xy 358.536818 -288.356221) (xy 358.586181 -288.348402)
			(xy 358.636159 -288.348402) (xy 358.685522 -288.356221) (xy 358.733054 -288.371665) (xy 358.777586 -288.394355)
			(xy 358.818019 -288.423731) (xy 358.853359 -288.459071) (xy 358.882735 -288.499504) (xy 358.905425 -288.544036)
			(xy 358.920869 -288.591568) (xy 358.928688 -288.640931) (xy 358.929178 -288.66592) (xy 358.928688 -288.690909)
			(xy 361.10721 -288.690909) (xy 361.10721 -288.640931) (xy 361.115029 -288.591568) (xy 361.130473 -288.544036)
			(xy 361.153163 -288.499504) (xy 361.182539 -288.459071) (xy 361.217879 -288.423731) (xy 361.258312 -288.394355)
			(xy 361.302844 -288.371665) (xy 361.350376 -288.356221) (xy 361.399739 -288.348402) (xy 361.449717 -288.348402)
			(xy 361.49908 -288.356221) (xy 361.546612 -288.371665) (xy 361.591144 -288.394355) (xy 361.631577 -288.423731)
			(xy 361.666917 -288.459071) (xy 361.696293 -288.499504) (xy 361.718983 -288.544036) (xy 361.734427 -288.591568)
			(xy 361.742246 -288.640931) (xy 361.742736 -288.66592) (xy 362.048547 -288.66592) (xy 362.052642 -288.615192)
			(xy 362.064821 -288.565778) (xy 362.084769 -288.518958) (xy 362.11197 -288.475944) (xy 362.145718 -288.43785)
			(xy 362.18514 -288.405663) (xy 362.229214 -288.380217) (xy 362.2768 -288.36217) (xy 362.326664 -288.35199)
			(xy 362.377516 -288.349941) (xy 362.428037 -288.356075) (xy 362.476921 -288.370235) (xy 362.5229 -288.392052)
			(xy 362.564784 -288.420962) (xy 362.601488 -288.456217) (xy 362.632061 -288.496903) (xy 362.655712 -288.541966)
			(xy 362.671828 -288.59024) (xy 362.679992 -288.640474) (xy 362.680504 -288.66592) (xy 362.988601 -288.66592)
			(xy 362.992696 -288.615192) (xy 363.004875 -288.565778) (xy 363.024823 -288.518958) (xy 363.052024 -288.475944)
			(xy 363.085772 -288.43785) (xy 363.125194 -288.405663) (xy 363.169268 -288.380217) (xy 363.216854 -288.36217)
			(xy 363.266718 -288.35199) (xy 363.31757 -288.349941) (xy 363.368091 -288.356075) (xy 363.416975 -288.370235)
			(xy 363.462954 -288.392052) (xy 363.504838 -288.420962) (xy 363.541542 -288.456217) (xy 363.572115 -288.496903)
			(xy 363.595766 -288.541966) (xy 363.611882 -288.59024) (xy 363.620046 -288.640474) (xy 363.620558 -288.66592)
			(xy 363.620055 -288.690909) (xy 363.927372 -288.690909) (xy 363.927372 -288.640931) (xy 363.935191 -288.591568)
			(xy 363.950635 -288.544036) (xy 363.973325 -288.499504) (xy 364.002701 -288.459071) (xy 364.038041 -288.423731)
			(xy 364.078474 -288.394355) (xy 364.123006 -288.371665) (xy 364.170538 -288.356221) (xy 364.219901 -288.348402)
			(xy 364.269879 -288.348402) (xy 364.319242 -288.356221) (xy 364.366774 -288.371665) (xy 364.411306 -288.394355)
			(xy 364.451739 -288.423731) (xy 364.487079 -288.459071) (xy 364.516455 -288.499504) (xy 364.539145 -288.544036)
			(xy 364.554589 -288.591568) (xy 364.562408 -288.640931) (xy 364.562898 -288.66592) (xy 364.562408 -288.690909)
			(xy 364.867172 -288.690909) (xy 364.867172 -288.640931) (xy 364.874991 -288.591568) (xy 364.890435 -288.544036)
			(xy 364.913125 -288.499504) (xy 364.942501 -288.459071) (xy 364.977841 -288.423731) (xy 365.018274 -288.394355)
			(xy 365.062806 -288.371665) (xy 365.110338 -288.356221) (xy 365.159701 -288.348402) (xy 365.209679 -288.348402)
			(xy 365.259042 -288.356221) (xy 365.306574 -288.371665) (xy 365.351106 -288.394355) (xy 365.391539 -288.423731)
			(xy 365.426879 -288.459071) (xy 365.456255 -288.499504) (xy 365.478945 -288.544036) (xy 365.494389 -288.591568)
			(xy 365.502208 -288.640931) (xy 365.502698 -288.66592) (xy 365.502208 -288.690909) (xy 365.807226 -288.690909)
			(xy 365.807226 -288.640931) (xy 365.815045 -288.591568) (xy 365.830489 -288.544036) (xy 365.853179 -288.499504)
			(xy 365.882555 -288.459071) (xy 365.917895 -288.423731) (xy 365.958328 -288.394355) (xy 366.00286 -288.371665)
			(xy 366.050392 -288.356221) (xy 366.099755 -288.348402) (xy 366.149733 -288.348402) (xy 366.199096 -288.356221)
			(xy 366.246628 -288.371665) (xy 366.29116 -288.394355) (xy 366.331593 -288.423731) (xy 366.366933 -288.459071)
			(xy 366.396309 -288.499504) (xy 366.418999 -288.544036) (xy 366.434443 -288.591568) (xy 366.442262 -288.640931)
			(xy 366.442752 -288.66592) (xy 366.442262 -288.690909) (xy 366.74728 -288.690909) (xy 366.74728 -288.640931)
			(xy 366.755099 -288.591568) (xy 366.770543 -288.544036) (xy 366.793233 -288.499504) (xy 366.822609 -288.459071)
			(xy 366.857949 -288.423731) (xy 366.898382 -288.394355) (xy 366.942914 -288.371665) (xy 366.990446 -288.356221)
			(xy 367.039809 -288.348402) (xy 367.089787 -288.348402) (xy 367.13915 -288.356221) (xy 367.186682 -288.371665)
			(xy 367.231214 -288.394355) (xy 367.271647 -288.423731) (xy 367.306987 -288.459071) (xy 367.336363 -288.499504)
			(xy 367.359053 -288.544036) (xy 367.374497 -288.591568) (xy 367.382316 -288.640931) (xy 367.382806 -288.66592)
			(xy 367.382316 -288.690909) (xy 367.687334 -288.690909) (xy 367.687334 -288.640931) (xy 367.695153 -288.591568)
			(xy 367.710597 -288.544036) (xy 367.733287 -288.499504) (xy 367.762663 -288.459071) (xy 367.798003 -288.423731)
			(xy 367.838436 -288.394355) (xy 367.882968 -288.371665) (xy 367.9305 -288.356221) (xy 367.979863 -288.348402)
			(xy 368.029841 -288.348402) (xy 368.079204 -288.356221) (xy 368.126736 -288.371665) (xy 368.171268 -288.394355)
			(xy 368.211701 -288.423731) (xy 368.247041 -288.459071) (xy 368.276417 -288.499504) (xy 368.299107 -288.544036)
			(xy 368.314551 -288.591568) (xy 368.32237 -288.640931) (xy 368.32286 -288.66592) (xy 368.32237 -288.690909)
			(xy 368.627388 -288.690909) (xy 368.627388 -288.640931) (xy 368.635207 -288.591568) (xy 368.650651 -288.544036)
			(xy 368.673341 -288.499504) (xy 368.702717 -288.459071) (xy 368.738057 -288.423731) (xy 368.77849 -288.394355)
			(xy 368.823022 -288.371665) (xy 368.870554 -288.356221) (xy 368.919917 -288.348402) (xy 368.969895 -288.348402)
			(xy 369.019258 -288.356221) (xy 369.06679 -288.371665) (xy 369.111322 -288.394355) (xy 369.151755 -288.423731)
			(xy 369.187095 -288.459071) (xy 369.216471 -288.499504) (xy 369.239161 -288.544036) (xy 369.254605 -288.591568)
			(xy 369.262424 -288.640931) (xy 369.262914 -288.66592) (xy 369.262424 -288.690909) (xy 369.567188 -288.690909)
			(xy 369.567188 -288.640931) (xy 369.575007 -288.591568) (xy 369.590451 -288.544036) (xy 369.613141 -288.499504)
			(xy 369.642517 -288.459071) (xy 369.677857 -288.423731) (xy 369.71829 -288.394355) (xy 369.762822 -288.371665)
			(xy 369.810354 -288.356221) (xy 369.859717 -288.348402) (xy 369.909695 -288.348402) (xy 369.959058 -288.356221)
			(xy 370.00659 -288.371665) (xy 370.051122 -288.394355) (xy 370.091555 -288.423731) (xy 370.126895 -288.459071)
			(xy 370.156271 -288.499504) (xy 370.178961 -288.544036) (xy 370.194405 -288.591568) (xy 370.202224 -288.640931)
			(xy 370.202714 -288.66592) (xy 370.202224 -288.690909) (xy 370.507242 -288.690909) (xy 370.507242 -288.640931)
			(xy 370.515061 -288.591568) (xy 370.530505 -288.544036) (xy 370.553195 -288.499504) (xy 370.582571 -288.459071)
			(xy 370.617911 -288.423731) (xy 370.658344 -288.394355) (xy 370.702876 -288.371665) (xy 370.750408 -288.356221)
			(xy 370.799771 -288.348402) (xy 370.849749 -288.348402) (xy 370.899112 -288.356221) (xy 370.946644 -288.371665)
			(xy 370.991176 -288.394355) (xy 371.031609 -288.423731) (xy 371.066949 -288.459071) (xy 371.096325 -288.499504)
			(xy 371.119015 -288.544036) (xy 371.134459 -288.591568) (xy 371.142278 -288.640931) (xy 371.142768 -288.66592)
			(xy 371.142278 -288.690909) (xy 371.447296 -288.690909) (xy 371.447296 -288.640931) (xy 371.455115 -288.591568)
			(xy 371.470559 -288.544036) (xy 371.493249 -288.499504) (xy 371.522625 -288.459071) (xy 371.557965 -288.423731)
			(xy 371.598398 -288.394355) (xy 371.64293 -288.371665) (xy 371.690462 -288.356221) (xy 371.739825 -288.348402)
			(xy 371.789803 -288.348402) (xy 371.839166 -288.356221) (xy 371.886698 -288.371665) (xy 371.93123 -288.394355)
			(xy 371.971663 -288.423731) (xy 372.007003 -288.459071) (xy 372.036379 -288.499504) (xy 372.059069 -288.544036)
			(xy 372.074513 -288.591568) (xy 372.082332 -288.640931) (xy 372.082822 -288.66592) (xy 372.082332 -288.690909)
			(xy 372.38735 -288.690909) (xy 372.38735 -288.640931) (xy 372.395169 -288.591568) (xy 372.410613 -288.544036)
			(xy 372.433303 -288.499504) (xy 372.462679 -288.459071) (xy 372.498019 -288.423731) (xy 372.538452 -288.394355)
			(xy 372.582984 -288.371665) (xy 372.630516 -288.356221) (xy 372.679879 -288.348402) (xy 372.729857 -288.348402)
			(xy 372.77922 -288.356221) (xy 372.826752 -288.371665) (xy 372.871284 -288.394355) (xy 372.911717 -288.423731)
			(xy 372.947057 -288.459071) (xy 372.976433 -288.499504) (xy 372.999123 -288.544036) (xy 373.014567 -288.591568)
			(xy 373.022386 -288.640931) (xy 373.022876 -288.66592) (xy 373.022386 -288.690909) (xy 373.327404 -288.690909)
			(xy 373.327404 -288.640931) (xy 373.335223 -288.591568) (xy 373.350667 -288.544036) (xy 373.373357 -288.499504)
			(xy 373.402733 -288.459071) (xy 373.438073 -288.423731) (xy 373.478506 -288.394355) (xy 373.523038 -288.371665)
			(xy 373.57057 -288.356221) (xy 373.619933 -288.348402) (xy 373.669911 -288.348402) (xy 373.719274 -288.356221)
			(xy 373.766806 -288.371665) (xy 373.811338 -288.394355) (xy 373.851771 -288.423731) (xy 373.887111 -288.459071)
			(xy 373.916487 -288.499504) (xy 373.939177 -288.544036) (xy 373.954621 -288.591568) (xy 373.96244 -288.640931)
			(xy 373.96293 -288.66592) (xy 373.96244 -288.690909) (xy 373.954621 -288.740272) (xy 373.939177 -288.787804)
			(xy 373.916487 -288.832336) (xy 373.887111 -288.872769) (xy 373.851771 -288.908109) (xy 373.811338 -288.937485)
			(xy 373.766806 -288.960175) (xy 373.719274 -288.975619) (xy 373.669911 -288.983438) (xy 373.619933 -288.983438)
			(xy 373.57057 -288.975619) (xy 373.523038 -288.960175) (xy 373.478506 -288.937485) (xy 373.438073 -288.908109)
			(xy 373.402733 -288.872769) (xy 373.373357 -288.832336) (xy 373.350667 -288.787804) (xy 373.335223 -288.740272)
			(xy 373.327404 -288.690909) (xy 373.022386 -288.690909) (xy 373.014567 -288.740272) (xy 372.999123 -288.787804)
			(xy 372.976433 -288.832336) (xy 372.947057 -288.872769) (xy 372.911717 -288.908109) (xy 372.871284 -288.937485)
			(xy 372.826752 -288.960175) (xy 372.77922 -288.975619) (xy 372.729857 -288.983438) (xy 372.679879 -288.983438)
			(xy 372.630516 -288.975619) (xy 372.582984 -288.960175) (xy 372.538452 -288.937485) (xy 372.498019 -288.908109)
			(xy 372.462679 -288.872769) (xy 372.433303 -288.832336) (xy 372.410613 -288.787804) (xy 372.395169 -288.740272)
			(xy 372.38735 -288.690909) (xy 372.082332 -288.690909) (xy 372.074513 -288.740272) (xy 372.059069 -288.787804)
			(xy 372.036379 -288.832336) (xy 372.007003 -288.872769) (xy 371.971663 -288.908109) (xy 371.93123 -288.937485)
			(xy 371.886698 -288.960175) (xy 371.839166 -288.975619) (xy 371.789803 -288.983438) (xy 371.739825 -288.983438)
			(xy 371.690462 -288.975619) (xy 371.64293 -288.960175) (xy 371.598398 -288.937485) (xy 371.557965 -288.908109)
			(xy 371.522625 -288.872769) (xy 371.493249 -288.832336) (xy 371.470559 -288.787804) (xy 371.455115 -288.740272)
			(xy 371.447296 -288.690909) (xy 371.142278 -288.690909) (xy 371.134459 -288.740272) (xy 371.119015 -288.787804)
			(xy 371.096325 -288.832336) (xy 371.066949 -288.872769) (xy 371.031609 -288.908109) (xy 370.991176 -288.937485)
			(xy 370.946644 -288.960175) (xy 370.899112 -288.975619) (xy 370.849749 -288.983438) (xy 370.799771 -288.983438)
			(xy 370.750408 -288.975619) (xy 370.702876 -288.960175) (xy 370.658344 -288.937485) (xy 370.617911 -288.908109)
			(xy 370.582571 -288.872769) (xy 370.553195 -288.832336) (xy 370.530505 -288.787804) (xy 370.515061 -288.740272)
			(xy 370.507242 -288.690909) (xy 370.202224 -288.690909) (xy 370.194405 -288.740272) (xy 370.178961 -288.787804)
			(xy 370.156271 -288.832336) (xy 370.126895 -288.872769) (xy 370.091555 -288.908109) (xy 370.051122 -288.937485)
			(xy 370.00659 -288.960175) (xy 369.959058 -288.975619) (xy 369.909695 -288.983438) (xy 369.859717 -288.983438)
			(xy 369.810354 -288.975619) (xy 369.762822 -288.960175) (xy 369.71829 -288.937485) (xy 369.677857 -288.908109)
			(xy 369.642517 -288.872769) (xy 369.613141 -288.832336) (xy 369.590451 -288.787804) (xy 369.575007 -288.740272)
			(xy 369.567188 -288.690909) (xy 369.262424 -288.690909) (xy 369.254605 -288.740272) (xy 369.239161 -288.787804)
			(xy 369.216471 -288.832336) (xy 369.187095 -288.872769) (xy 369.151755 -288.908109) (xy 369.111322 -288.937485)
			(xy 369.06679 -288.960175) (xy 369.019258 -288.975619) (xy 368.969895 -288.983438) (xy 368.919917 -288.983438)
			(xy 368.870554 -288.975619) (xy 368.823022 -288.960175) (xy 368.77849 -288.937485) (xy 368.738057 -288.908109)
			(xy 368.702717 -288.872769) (xy 368.673341 -288.832336) (xy 368.650651 -288.787804) (xy 368.635207 -288.740272)
			(xy 368.627388 -288.690909) (xy 368.32237 -288.690909) (xy 368.314551 -288.740272) (xy 368.299107 -288.787804)
			(xy 368.276417 -288.832336) (xy 368.247041 -288.872769) (xy 368.211701 -288.908109) (xy 368.171268 -288.937485)
			(xy 368.126736 -288.960175) (xy 368.079204 -288.975619) (xy 368.029841 -288.983438) (xy 367.979863 -288.983438)
			(xy 367.9305 -288.975619) (xy 367.882968 -288.960175) (xy 367.838436 -288.937485) (xy 367.798003 -288.908109)
			(xy 367.762663 -288.872769) (xy 367.733287 -288.832336) (xy 367.710597 -288.787804) (xy 367.695153 -288.740272)
			(xy 367.687334 -288.690909) (xy 367.382316 -288.690909) (xy 367.374497 -288.740272) (xy 367.359053 -288.787804)
			(xy 367.336363 -288.832336) (xy 367.306987 -288.872769) (xy 367.271647 -288.908109) (xy 367.231214 -288.937485)
			(xy 367.186682 -288.960175) (xy 367.13915 -288.975619) (xy 367.089787 -288.983438) (xy 367.039809 -288.983438)
			(xy 366.990446 -288.975619) (xy 366.942914 -288.960175) (xy 366.898382 -288.937485) (xy 366.857949 -288.908109)
			(xy 366.822609 -288.872769) (xy 366.793233 -288.832336) (xy 366.770543 -288.787804) (xy 366.755099 -288.740272)
			(xy 366.74728 -288.690909) (xy 366.442262 -288.690909) (xy 366.434443 -288.740272) (xy 366.418999 -288.787804)
			(xy 366.396309 -288.832336) (xy 366.366933 -288.872769) (xy 366.331593 -288.908109) (xy 366.29116 -288.937485)
			(xy 366.246628 -288.960175) (xy 366.199096 -288.975619) (xy 366.149733 -288.983438) (xy 366.099755 -288.983438)
			(xy 366.050392 -288.975619) (xy 366.00286 -288.960175) (xy 365.958328 -288.937485) (xy 365.917895 -288.908109)
			(xy 365.882555 -288.872769) (xy 365.853179 -288.832336) (xy 365.830489 -288.787804) (xy 365.815045 -288.740272)
			(xy 365.807226 -288.690909) (xy 365.502208 -288.690909) (xy 365.494389 -288.740272) (xy 365.478945 -288.787804)
			(xy 365.456255 -288.832336) (xy 365.426879 -288.872769) (xy 365.391539 -288.908109) (xy 365.351106 -288.937485)
			(xy 365.306574 -288.960175) (xy 365.259042 -288.975619) (xy 365.209679 -288.983438) (xy 365.159701 -288.983438)
			(xy 365.110338 -288.975619) (xy 365.062806 -288.960175) (xy 365.018274 -288.937485) (xy 364.977841 -288.908109)
			(xy 364.942501 -288.872769) (xy 364.913125 -288.832336) (xy 364.890435 -288.787804) (xy 364.874991 -288.740272)
			(xy 364.867172 -288.690909) (xy 364.562408 -288.690909) (xy 364.554589 -288.740272) (xy 364.539145 -288.787804)
			(xy 364.516455 -288.832336) (xy 364.487079 -288.872769) (xy 364.451739 -288.908109) (xy 364.411306 -288.937485)
			(xy 364.366774 -288.960175) (xy 364.319242 -288.975619) (xy 364.269879 -288.983438) (xy 364.219901 -288.983438)
			(xy 364.170538 -288.975619) (xy 364.123006 -288.960175) (xy 364.078474 -288.937485) (xy 364.038041 -288.908109)
			(xy 364.002701 -288.872769) (xy 363.973325 -288.832336) (xy 363.950635 -288.787804) (xy 363.935191 -288.740272)
			(xy 363.927372 -288.690909) (xy 363.620055 -288.690909) (xy 363.620046 -288.691366) (xy 363.611882 -288.7416)
			(xy 363.595766 -288.789874) (xy 363.572115 -288.834937) (xy 363.541542 -288.875623) (xy 363.504838 -288.910878)
			(xy 363.462954 -288.939788) (xy 363.416975 -288.961605) (xy 363.368091 -288.975765) (xy 363.31757 -288.981899)
			(xy 363.266718 -288.97985) (xy 363.216854 -288.96967) (xy 363.169268 -288.951623) (xy 363.125194 -288.926177)
			(xy 363.085772 -288.89399) (xy 363.052024 -288.855896) (xy 363.024823 -288.812882) (xy 363.004875 -288.766062)
			(xy 362.992696 -288.716648) (xy 362.988601 -288.66592) (xy 362.680504 -288.66592) (xy 362.679992 -288.691366)
			(xy 362.671828 -288.7416) (xy 362.655712 -288.789874) (xy 362.632061 -288.834937) (xy 362.601488 -288.875623)
			(xy 362.564784 -288.910878) (xy 362.5229 -288.939788) (xy 362.476921 -288.961605) (xy 362.428037 -288.975765)
			(xy 362.377516 -288.981899) (xy 362.326664 -288.97985) (xy 362.2768 -288.96967) (xy 362.229214 -288.951623)
			(xy 362.18514 -288.926177) (xy 362.145718 -288.89399) (xy 362.11197 -288.855896) (xy 362.084769 -288.812882)
			(xy 362.064821 -288.766062) (xy 362.052642 -288.716648) (xy 362.048547 -288.66592) (xy 361.742736 -288.66592)
			(xy 361.742246 -288.690909) (xy 361.734427 -288.740272) (xy 361.718983 -288.787804) (xy 361.696293 -288.832336)
			(xy 361.666917 -288.872769) (xy 361.631577 -288.908109) (xy 361.591144 -288.937485) (xy 361.546612 -288.960175)
			(xy 361.49908 -288.975619) (xy 361.449717 -288.983438) (xy 361.399739 -288.983438) (xy 361.350376 -288.975619)
			(xy 361.302844 -288.960175) (xy 361.258312 -288.937485) (xy 361.217879 -288.908109) (xy 361.182539 -288.872769)
			(xy 361.153163 -288.832336) (xy 361.130473 -288.787804) (xy 361.115029 -288.740272) (xy 361.10721 -288.690909)
			(xy 358.928688 -288.690909) (xy 358.920869 -288.740272) (xy 358.905425 -288.787804) (xy 358.882735 -288.832336)
			(xy 358.853359 -288.872769) (xy 358.818019 -288.908109) (xy 358.777586 -288.937485) (xy 358.733054 -288.960175)
			(xy 358.685522 -288.975619) (xy 358.636159 -288.983438) (xy 358.586181 -288.983438) (xy 358.536818 -288.975619)
			(xy 358.489286 -288.960175) (xy 358.444754 -288.937485) (xy 358.404321 -288.908109) (xy 358.368981 -288.872769)
			(xy 358.339605 -288.832336) (xy 358.316915 -288.787804) (xy 358.301471 -288.740272) (xy 358.293652 -288.690909)
			(xy 357.986335 -288.690909) (xy 357.986326 -288.691366) (xy 357.978162 -288.7416) (xy 357.962046 -288.789874)
			(xy 357.938395 -288.834937) (xy 357.907822 -288.875623) (xy 357.871118 -288.910878) (xy 357.829234 -288.939788)
			(xy 357.783255 -288.961605) (xy 357.734371 -288.975765) (xy 357.68385 -288.981899) (xy 357.632998 -288.97985)
			(xy 357.583134 -288.96967) (xy 357.535548 -288.951623) (xy 357.491474 -288.926177) (xy 357.452052 -288.89399)
			(xy 357.418304 -288.855896) (xy 357.391103 -288.812882) (xy 357.371155 -288.766062) (xy 357.358976 -288.716648)
			(xy 357.354881 -288.66592) (xy 357.046784 -288.66592) (xy 357.046272 -288.691366) (xy 357.038108 -288.7416)
			(xy 357.021992 -288.789874) (xy 356.998341 -288.834937) (xy 356.967768 -288.875623) (xy 356.931064 -288.910878)
			(xy 356.88918 -288.939788) (xy 356.843201 -288.961605) (xy 356.794317 -288.975765) (xy 356.743796 -288.981899)
			(xy 356.692944 -288.97985) (xy 356.64308 -288.96967) (xy 356.595494 -288.951623) (xy 356.55142 -288.926177)
			(xy 356.511998 -288.89399) (xy 356.47825 -288.855896) (xy 356.451049 -288.812882) (xy 356.431101 -288.766062)
			(xy 356.418922 -288.716648) (xy 356.414827 -288.66592) (xy 356.109016 -288.66592) (xy 356.108526 -288.690909)
			(xy 356.100707 -288.740272) (xy 356.085263 -288.787804) (xy 356.062573 -288.832336) (xy 356.033197 -288.872769)
			(xy 355.997857 -288.908109) (xy 355.957424 -288.937485) (xy 355.912892 -288.960175) (xy 355.86536 -288.975619)
			(xy 355.815997 -288.983438) (xy 355.766019 -288.983438) (xy 355.716656 -288.975619) (xy 355.669124 -288.960175)
			(xy 355.624592 -288.937485) (xy 355.584159 -288.908109) (xy 355.548819 -288.872769) (xy 355.519443 -288.832336)
			(xy 355.496753 -288.787804) (xy 355.481309 -288.740272) (xy 355.47349 -288.690909) (xy 355.168726 -288.690909)
			(xy 355.160907 -288.740272) (xy 355.145463 -288.787804) (xy 355.122773 -288.832336) (xy 355.093397 -288.872769)
			(xy 355.058057 -288.908109) (xy 355.017624 -288.937485) (xy 354.973092 -288.960175) (xy 354.92556 -288.975619)
			(xy 354.876197 -288.983438) (xy 354.826219 -288.983438) (xy 354.776856 -288.975619) (xy 354.729324 -288.960175)
			(xy 354.684792 -288.937485) (xy 354.644359 -288.908109) (xy 354.609019 -288.872769) (xy 354.579643 -288.832336)
			(xy 354.556953 -288.787804) (xy 354.541509 -288.740272) (xy 354.53369 -288.690909) (xy 354.228672 -288.690909)
			(xy 354.220853 -288.740272) (xy 354.205409 -288.787804) (xy 354.182719 -288.832336) (xy 354.153343 -288.872769)
			(xy 354.118003 -288.908109) (xy 354.07757 -288.937485) (xy 354.033038 -288.960175) (xy 353.985506 -288.975619)
			(xy 353.936143 -288.983438) (xy 353.886165 -288.983438) (xy 353.836802 -288.975619) (xy 353.78927 -288.960175)
			(xy 353.744738 -288.937485) (xy 353.704305 -288.908109) (xy 353.668965 -288.872769) (xy 353.639589 -288.832336)
			(xy 353.616899 -288.787804) (xy 353.601455 -288.740272) (xy 353.593636 -288.690909) (xy 353.288618 -288.690909)
			(xy 353.280799 -288.740272) (xy 353.265355 -288.787804) (xy 353.242665 -288.832336) (xy 353.213289 -288.872769)
			(xy 353.177949 -288.908109) (xy 353.137516 -288.937485) (xy 353.092984 -288.960175) (xy 353.045452 -288.975619)
			(xy 352.996089 -288.983438) (xy 352.946111 -288.983438) (xy 352.896748 -288.975619) (xy 352.849216 -288.960175)
			(xy 352.804684 -288.937485) (xy 352.764251 -288.908109) (xy 352.728911 -288.872769) (xy 352.699535 -288.832336)
			(xy 352.676845 -288.787804) (xy 352.661401 -288.740272) (xy 352.653582 -288.690909) (xy 352.348564 -288.690909)
			(xy 352.340745 -288.740272) (xy 352.325301 -288.787804) (xy 352.302611 -288.832336) (xy 352.273235 -288.872769)
			(xy 352.237895 -288.908109) (xy 352.197462 -288.937485) (xy 352.15293 -288.960175) (xy 352.105398 -288.975619)
			(xy 352.056035 -288.983438) (xy 352.006057 -288.983438) (xy 351.956694 -288.975619) (xy 351.909162 -288.960175)
			(xy 351.86463 -288.937485) (xy 351.824197 -288.908109) (xy 351.788857 -288.872769) (xy 351.759481 -288.832336)
			(xy 351.736791 -288.787804) (xy 351.721347 -288.740272) (xy 351.713528 -288.690909) (xy 351.408764 -288.690909)
			(xy 351.400945 -288.740272) (xy 351.385501 -288.787804) (xy 351.362811 -288.832336) (xy 351.333435 -288.872769)
			(xy 351.298095 -288.908109) (xy 351.257662 -288.937485) (xy 351.21313 -288.960175) (xy 351.165598 -288.975619)
			(xy 351.116235 -288.983438) (xy 351.066257 -288.983438) (xy 351.016894 -288.975619) (xy 350.969362 -288.960175)
			(xy 350.92483 -288.937485) (xy 350.884397 -288.908109) (xy 350.849057 -288.872769) (xy 350.819681 -288.832336)
			(xy 350.796991 -288.787804) (xy 350.781547 -288.740272) (xy 350.773728 -288.690909) (xy 350.46871 -288.690909)
			(xy 350.460891 -288.740272) (xy 350.445447 -288.787804) (xy 350.422757 -288.832336) (xy 350.393381 -288.872769)
			(xy 350.358041 -288.908109) (xy 350.317608 -288.937485) (xy 350.273076 -288.960175) (xy 350.225544 -288.975619)
			(xy 350.176181 -288.983438) (xy 350.126203 -288.983438) (xy 350.07684 -288.975619) (xy 350.029308 -288.960175)
			(xy 349.984776 -288.937485) (xy 349.944343 -288.908109) (xy 349.909003 -288.872769) (xy 349.879627 -288.832336)
			(xy 349.856937 -288.787804) (xy 349.841493 -288.740272) (xy 349.833674 -288.690909) (xy 349.528656 -288.690909)
			(xy 349.520837 -288.740272) (xy 349.505393 -288.787804) (xy 349.482703 -288.832336) (xy 349.453327 -288.872769)
			(xy 349.417987 -288.908109) (xy 349.377554 -288.937485) (xy 349.333022 -288.960175) (xy 349.28549 -288.975619)
			(xy 349.236127 -288.983438) (xy 349.186149 -288.983438) (xy 349.136786 -288.975619) (xy 349.089254 -288.960175)
			(xy 349.044722 -288.937485) (xy 349.004289 -288.908109) (xy 348.968949 -288.872769) (xy 348.939573 -288.832336)
			(xy 348.916883 -288.787804) (xy 348.901439 -288.740272) (xy 348.89362 -288.690909) (xy 348.588602 -288.690909)
			(xy 348.580783 -288.740272) (xy 348.565339 -288.787804) (xy 348.542649 -288.832336) (xy 348.513273 -288.872769)
			(xy 348.477933 -288.908109) (xy 348.4375 -288.937485) (xy 348.392968 -288.960175) (xy 348.345436 -288.975619)
			(xy 348.296073 -288.983438) (xy 348.246095 -288.983438) (xy 348.196732 -288.975619) (xy 348.1492 -288.960175)
			(xy 348.104668 -288.937485) (xy 348.064235 -288.908109) (xy 348.028895 -288.872769) (xy 347.999519 -288.832336)
			(xy 347.976829 -288.787804) (xy 347.961385 -288.740272) (xy 347.953566 -288.690909) (xy 347.648548 -288.690909)
			(xy 347.640729 -288.740272) (xy 347.625285 -288.787804) (xy 347.602595 -288.832336) (xy 347.573219 -288.872769)
			(xy 347.537879 -288.908109) (xy 347.497446 -288.937485) (xy 347.452914 -288.960175) (xy 347.405382 -288.975619)
			(xy 347.356019 -288.983438) (xy 347.306041 -288.983438) (xy 347.256678 -288.975619) (xy 347.209146 -288.960175)
			(xy 347.164614 -288.937485) (xy 347.124181 -288.908109) (xy 347.088841 -288.872769) (xy 347.059465 -288.832336)
			(xy 347.036775 -288.787804) (xy 347.021331 -288.740272) (xy 347.013512 -288.690909) (xy 346.708748 -288.690909)
			(xy 346.700929 -288.740272) (xy 346.685485 -288.787804) (xy 346.662795 -288.832336) (xy 346.633419 -288.872769)
			(xy 346.598079 -288.908109) (xy 346.557646 -288.937485) (xy 346.513114 -288.960175) (xy 346.465582 -288.975619)
			(xy 346.416219 -288.983438) (xy 346.366241 -288.983438) (xy 346.316878 -288.975619) (xy 346.269346 -288.960175)
			(xy 346.224814 -288.937485) (xy 346.184381 -288.908109) (xy 346.149041 -288.872769) (xy 346.119665 -288.832336)
			(xy 346.096975 -288.787804) (xy 346.081531 -288.740272) (xy 346.073712 -288.690909) (xy 345.76872 -288.690909)
			(xy 345.760904 -288.740257) (xy 345.745458 -288.787792) (xy 345.722766 -288.832326) (xy 345.693386 -288.872761)
			(xy 345.658042 -288.908102) (xy 345.617605 -288.937478) (xy 345.57307 -288.960167) (xy 345.525534 -288.975609)
			(xy 345.476167 -288.983425) (xy 345.451176 -288.983928) (xy 345.427298 -288.9835) (xy 345.380079 -288.976364)
			(xy 345.334454 -288.962258) (xy 345.291448 -288.941497) (xy 345.252024 -288.914546) (xy 345.23426 -288.898584)
			(xy 345.228659 -288.893714) (xy 345.215368 -288.88712) (xy 345.208098 -288.88563) (xy 345.20124 -288.88436)
			(xy 345.186508 -288.886138) (xy 345.14155 -288.905696) (xy 345.096338 -288.925508) (xy 345.087508 -288.929868)
			(xy 345.073767 -288.943948) (xy 345.066311 -288.962155) (xy 345.065858 -288.97199) (xy 345.065858 -289.13328)
			(xy 345.065858 -289.13455) (xy 345.06652 -289.143937) (xy 345.073737 -289.161298) (xy 345.086735 -289.174883)
			(xy 345.095068 -289.179254) (xy 345.097862 -289.18027) (xy 345.119797 -289.18939) (xy 345.160906 -289.213194)
			(xy 345.198012 -289.242854) (xy 345.230287 -289.277709) (xy 345.257011 -289.316982) (xy 345.277589 -289.359796)
			(xy 345.291561 -289.405198) (xy 345.298617 -289.452174) (xy 345.29903 -289.475926) (xy 345.604841 -289.475926)
			(xy 345.608936 -289.425198) (xy 345.621115 -289.375784) (xy 345.641063 -289.328964) (xy 345.668264 -289.28595)
			(xy 345.702012 -289.247856) (xy 345.741434 -289.215669) (xy 345.785508 -289.190223) (xy 345.833094 -289.172176)
			(xy 345.882958 -289.161996) (xy 345.93381 -289.159947) (xy 345.984331 -289.166081) (xy 346.033215 -289.180241)
			(xy 346.079194 -289.202058) (xy 346.121078 -289.230968) (xy 346.157782 -289.266223) (xy 346.188355 -289.306909)
			(xy 346.212006 -289.351972) (xy 346.228122 -289.400246) (xy 346.236286 -289.45048) (xy 346.236798 -289.475926)
			(xy 346.544895 -289.475926) (xy 346.54899 -289.425198) (xy 346.561169 -289.375784) (xy 346.581117 -289.328964)
			(xy 346.608318 -289.28595) (xy 346.642066 -289.247856) (xy 346.681488 -289.215669) (xy 346.725562 -289.190223)
			(xy 346.773148 -289.172176) (xy 346.823012 -289.161996) (xy 346.873864 -289.159947) (xy 346.924385 -289.166081)
			(xy 346.973269 -289.180241) (xy 347.019248 -289.202058) (xy 347.061132 -289.230968) (xy 347.097836 -289.266223)
			(xy 347.128409 -289.306909) (xy 347.15206 -289.351972) (xy 347.168176 -289.400246) (xy 347.17634 -289.45048)
			(xy 347.176852 -289.475926) (xy 347.176349 -289.500915) (xy 347.483666 -289.500915) (xy 347.483666 -289.450937)
			(xy 347.491485 -289.401574) (xy 347.506929 -289.354042) (xy 347.529619 -289.30951) (xy 347.558995 -289.269077)
			(xy 347.594335 -289.233737) (xy 347.634768 -289.204361) (xy 347.6793 -289.181671) (xy 347.726832 -289.166227)
			(xy 347.776195 -289.158408) (xy 347.826173 -289.158408) (xy 347.875536 -289.166227) (xy 347.923068 -289.181671)
			(xy 347.9676 -289.204361) (xy 348.008033 -289.233737) (xy 348.043373 -289.269077) (xy 348.072749 -289.30951)
			(xy 348.095439 -289.354042) (xy 348.110883 -289.401574) (xy 348.118702 -289.450937) (xy 348.119192 -289.475926)
			(xy 348.425003 -289.475926) (xy 348.429098 -289.425198) (xy 348.441277 -289.375784) (xy 348.461225 -289.328964)
			(xy 348.488426 -289.28595) (xy 348.522174 -289.247856) (xy 348.561596 -289.215669) (xy 348.60567 -289.190223)
			(xy 348.653256 -289.172176) (xy 348.70312 -289.161996) (xy 348.753972 -289.159947) (xy 348.804493 -289.166081)
			(xy 348.853377 -289.180241) (xy 348.899356 -289.202058) (xy 348.94124 -289.230968) (xy 348.977944 -289.266223)
			(xy 349.008517 -289.306909) (xy 349.032168 -289.351972) (xy 349.048284 -289.400246) (xy 349.056448 -289.45048)
			(xy 349.05696 -289.475926) (xy 349.364803 -289.475926) (xy 349.368898 -289.425198) (xy 349.381077 -289.375784)
			(xy 349.401025 -289.328964) (xy 349.428226 -289.28595) (xy 349.461974 -289.247856) (xy 349.501396 -289.215669)
			(xy 349.54547 -289.190223) (xy 349.593056 -289.172176) (xy 349.64292 -289.161996) (xy 349.693772 -289.159947)
			(xy 349.744293 -289.166081) (xy 349.793177 -289.180241) (xy 349.839156 -289.202058) (xy 349.88104 -289.230968)
			(xy 349.917744 -289.266223) (xy 349.948317 -289.306909) (xy 349.971968 -289.351972) (xy 349.988084 -289.400246)
			(xy 349.996248 -289.45048) (xy 349.99676 -289.475926) (xy 349.996257 -289.500915) (xy 350.303574 -289.500915)
			(xy 350.303574 -289.450937) (xy 350.311393 -289.401574) (xy 350.326837 -289.354042) (xy 350.349527 -289.30951)
			(xy 350.378903 -289.269077) (xy 350.414243 -289.233737) (xy 350.454676 -289.204361) (xy 350.499208 -289.181671)
			(xy 350.54674 -289.166227) (xy 350.596103 -289.158408) (xy 350.646081 -289.158408) (xy 350.695444 -289.166227)
			(xy 350.742976 -289.181671) (xy 350.787508 -289.204361) (xy 350.827941 -289.233737) (xy 350.863281 -289.269077)
			(xy 350.892657 -289.30951) (xy 350.915347 -289.354042) (xy 350.930791 -289.401574) (xy 350.93861 -289.450937)
			(xy 350.9391 -289.475926) (xy 351.244911 -289.475926) (xy 351.249006 -289.425198) (xy 351.261185 -289.375784)
			(xy 351.281133 -289.328964) (xy 351.308334 -289.28595) (xy 351.342082 -289.247856) (xy 351.381504 -289.215669)
			(xy 351.425578 -289.190223) (xy 351.473164 -289.172176) (xy 351.523028 -289.161996) (xy 351.57388 -289.159947)
			(xy 351.624401 -289.166081) (xy 351.673285 -289.180241) (xy 351.719264 -289.202058) (xy 351.761148 -289.230968)
			(xy 351.797852 -289.266223) (xy 351.828425 -289.306909) (xy 351.852076 -289.351972) (xy 351.868192 -289.400246)
			(xy 351.876356 -289.45048) (xy 351.876868 -289.475926) (xy 352.184965 -289.475926) (xy 352.18906 -289.425198)
			(xy 352.201239 -289.375784) (xy 352.221187 -289.328964) (xy 352.248388 -289.28595) (xy 352.282136 -289.247856)
			(xy 352.321558 -289.215669) (xy 352.365632 -289.190223) (xy 352.413218 -289.172176) (xy 352.463082 -289.161996)
			(xy 352.513934 -289.159947) (xy 352.564455 -289.166081) (xy 352.613339 -289.180241) (xy 352.659318 -289.202058)
			(xy 352.701202 -289.230968) (xy 352.737906 -289.266223) (xy 352.768479 -289.306909) (xy 352.79213 -289.351972)
			(xy 352.808246 -289.400246) (xy 352.81641 -289.45048) (xy 352.816922 -289.475926) (xy 352.816419 -289.500915)
			(xy 353.123482 -289.500915) (xy 353.123482 -289.450937) (xy 353.131301 -289.401574) (xy 353.146745 -289.354042)
			(xy 353.169435 -289.30951) (xy 353.198811 -289.269077) (xy 353.234151 -289.233737) (xy 353.274584 -289.204361)
			(xy 353.319116 -289.181671) (xy 353.366648 -289.166227) (xy 353.416011 -289.158408) (xy 353.465989 -289.158408)
			(xy 353.515352 -289.166227) (xy 353.562884 -289.181671) (xy 353.607416 -289.204361) (xy 353.647849 -289.233737)
			(xy 353.683189 -289.269077) (xy 353.712565 -289.30951) (xy 353.735255 -289.354042) (xy 353.750699 -289.401574)
			(xy 353.758518 -289.450937) (xy 353.759008 -289.475926) (xy 354.064819 -289.475926) (xy 354.068914 -289.425198)
			(xy 354.081093 -289.375784) (xy 354.101041 -289.328964) (xy 354.128242 -289.28595) (xy 354.16199 -289.247856)
			(xy 354.201412 -289.215669) (xy 354.245486 -289.190223) (xy 354.293072 -289.172176) (xy 354.342936 -289.161996)
			(xy 354.393788 -289.159947) (xy 354.444309 -289.166081) (xy 354.493193 -289.180241) (xy 354.539172 -289.202058)
			(xy 354.581056 -289.230968) (xy 354.61776 -289.266223) (xy 354.648333 -289.306909) (xy 354.671984 -289.351972)
			(xy 354.6881 -289.400246) (xy 354.696264 -289.45048) (xy 354.696776 -289.475926) (xy 355.004873 -289.475926)
			(xy 355.008968 -289.425198) (xy 355.021147 -289.375784) (xy 355.041095 -289.328964) (xy 355.068296 -289.28595)
			(xy 355.102044 -289.247856) (xy 355.141466 -289.215669) (xy 355.18554 -289.190223) (xy 355.233126 -289.172176)
			(xy 355.28299 -289.161996) (xy 355.333842 -289.159947) (xy 355.384363 -289.166081) (xy 355.433247 -289.180241)
			(xy 355.479226 -289.202058) (xy 355.52111 -289.230968) (xy 355.557814 -289.266223) (xy 355.588387 -289.306909)
			(xy 355.612038 -289.351972) (xy 355.628154 -289.400246) (xy 355.636318 -289.45048) (xy 355.63683 -289.475926)
			(xy 355.636327 -289.500915) (xy 355.943644 -289.500915) (xy 355.943644 -289.450937) (xy 355.951463 -289.401574)
			(xy 355.966907 -289.354042) (xy 355.989597 -289.30951) (xy 356.018973 -289.269077) (xy 356.054313 -289.233737)
			(xy 356.094746 -289.204361) (xy 356.139278 -289.181671) (xy 356.18681 -289.166227) (xy 356.236173 -289.158408)
			(xy 356.286151 -289.158408) (xy 356.335514 -289.166227) (xy 356.383046 -289.181671) (xy 356.427578 -289.204361)
			(xy 356.468011 -289.233737) (xy 356.503351 -289.269077) (xy 356.532727 -289.30951) (xy 356.555417 -289.354042)
			(xy 356.570861 -289.401574) (xy 356.57868 -289.450937) (xy 356.57917 -289.475926) (xy 356.57868 -289.500915)
			(xy 363.457218 -289.500915) (xy 363.457218 -289.450937) (xy 363.465037 -289.401574) (xy 363.480481 -289.354042)
			(xy 363.503171 -289.30951) (xy 363.532547 -289.269077) (xy 363.567887 -289.233737) (xy 363.60832 -289.204361)
			(xy 363.652852 -289.181671) (xy 363.700384 -289.166227) (xy 363.749747 -289.158408) (xy 363.799725 -289.158408)
			(xy 363.849088 -289.166227) (xy 363.89662 -289.181671) (xy 363.941152 -289.204361) (xy 363.981585 -289.233737)
			(xy 364.016925 -289.269077) (xy 364.046301 -289.30951) (xy 364.068991 -289.354042) (xy 364.084435 -289.401574)
			(xy 364.092254 -289.450937) (xy 364.092744 -289.475926) (xy 364.398555 -289.475926) (xy 364.40265 -289.425198)
			(xy 364.414829 -289.375784) (xy 364.434777 -289.328964) (xy 364.461978 -289.28595) (xy 364.495726 -289.247856)
			(xy 364.535148 -289.215669) (xy 364.579222 -289.190223) (xy 364.626808 -289.172176) (xy 364.676672 -289.161996)
			(xy 364.727524 -289.159947) (xy 364.778045 -289.166081) (xy 364.826929 -289.180241) (xy 364.872908 -289.202058)
			(xy 364.914792 -289.230968) (xy 364.951496 -289.266223) (xy 364.982069 -289.306909) (xy 365.00572 -289.351972)
			(xy 365.021836 -289.400246) (xy 365.03 -289.45048) (xy 365.030512 -289.475926) (xy 365.338609 -289.475926)
			(xy 365.342704 -289.425198) (xy 365.354883 -289.375784) (xy 365.374831 -289.328964) (xy 365.402032 -289.28595)
			(xy 365.43578 -289.247856) (xy 365.475202 -289.215669) (xy 365.519276 -289.190223) (xy 365.566862 -289.172176)
			(xy 365.616726 -289.161996) (xy 365.667578 -289.159947) (xy 365.718099 -289.166081) (xy 365.766983 -289.180241)
			(xy 365.812962 -289.202058) (xy 365.854846 -289.230968) (xy 365.89155 -289.266223) (xy 365.922123 -289.306909)
			(xy 365.945774 -289.351972) (xy 365.96189 -289.400246) (xy 365.970054 -289.45048) (xy 365.970566 -289.475926)
			(xy 365.970063 -289.500915) (xy 366.27738 -289.500915) (xy 366.27738 -289.450937) (xy 366.285199 -289.401574)
			(xy 366.300643 -289.354042) (xy 366.323333 -289.30951) (xy 366.352709 -289.269077) (xy 366.388049 -289.233737)
			(xy 366.428482 -289.204361) (xy 366.473014 -289.181671) (xy 366.520546 -289.166227) (xy 366.569909 -289.158408)
			(xy 366.619887 -289.158408) (xy 366.66925 -289.166227) (xy 366.716782 -289.181671) (xy 366.761314 -289.204361)
			(xy 366.801747 -289.233737) (xy 366.837087 -289.269077) (xy 366.866463 -289.30951) (xy 366.889153 -289.354042)
			(xy 366.904597 -289.401574) (xy 366.912416 -289.450937) (xy 366.912906 -289.475926) (xy 367.218463 -289.475926)
			(xy 367.222558 -289.425198) (xy 367.234737 -289.375784) (xy 367.254685 -289.328964) (xy 367.281886 -289.28595)
			(xy 367.315634 -289.247856) (xy 367.355056 -289.215669) (xy 367.39913 -289.190223) (xy 367.446716 -289.172176)
			(xy 367.49658 -289.161996) (xy 367.547432 -289.159947) (xy 367.597953 -289.166081) (xy 367.646837 -289.180241)
			(xy 367.692816 -289.202058) (xy 367.7347 -289.230968) (xy 367.771404 -289.266223) (xy 367.801977 -289.306909)
			(xy 367.825628 -289.351972) (xy 367.841744 -289.400246) (xy 367.849908 -289.45048) (xy 367.85042 -289.475926)
			(xy 368.158517 -289.475926) (xy 368.162612 -289.425198) (xy 368.174791 -289.375784) (xy 368.194739 -289.328964)
			(xy 368.22194 -289.28595) (xy 368.255688 -289.247856) (xy 368.29511 -289.215669) (xy 368.339184 -289.190223)
			(xy 368.38677 -289.172176) (xy 368.436634 -289.161996) (xy 368.487486 -289.159947) (xy 368.538007 -289.166081)
			(xy 368.586891 -289.180241) (xy 368.63287 -289.202058) (xy 368.674754 -289.230968) (xy 368.711458 -289.266223)
			(xy 368.742031 -289.306909) (xy 368.765682 -289.351972) (xy 368.781798 -289.400246) (xy 368.789962 -289.45048)
			(xy 368.790474 -289.475926) (xy 368.789971 -289.500915) (xy 369.097288 -289.500915) (xy 369.097288 -289.450937)
			(xy 369.105107 -289.401574) (xy 369.120551 -289.354042) (xy 369.143241 -289.30951) (xy 369.172617 -289.269077)
			(xy 369.207957 -289.233737) (xy 369.24839 -289.204361) (xy 369.292922 -289.181671) (xy 369.340454 -289.166227)
			(xy 369.389817 -289.158408) (xy 369.439795 -289.158408) (xy 369.489158 -289.166227) (xy 369.53669 -289.181671)
			(xy 369.581222 -289.204361) (xy 369.621655 -289.233737) (xy 369.656995 -289.269077) (xy 369.686371 -289.30951)
			(xy 369.709061 -289.354042) (xy 369.724505 -289.401574) (xy 369.732324 -289.450937) (xy 369.732814 -289.475926)
			(xy 370.038625 -289.475926) (xy 370.04272 -289.425198) (xy 370.054899 -289.375784) (xy 370.074847 -289.328964)
			(xy 370.102048 -289.28595) (xy 370.135796 -289.247856) (xy 370.175218 -289.215669) (xy 370.219292 -289.190223)
			(xy 370.266878 -289.172176) (xy 370.316742 -289.161996) (xy 370.367594 -289.159947) (xy 370.418115 -289.166081)
			(xy 370.466999 -289.180241) (xy 370.512978 -289.202058) (xy 370.554862 -289.230968) (xy 370.591566 -289.266223)
			(xy 370.622139 -289.306909) (xy 370.64579 -289.351972) (xy 370.661906 -289.400246) (xy 370.67007 -289.45048)
			(xy 370.670582 -289.475926) (xy 370.978679 -289.475926) (xy 370.982774 -289.425198) (xy 370.994953 -289.375784)
			(xy 371.014901 -289.328964) (xy 371.042102 -289.28595) (xy 371.07585 -289.247856) (xy 371.115272 -289.215669)
			(xy 371.159346 -289.190223) (xy 371.206932 -289.172176) (xy 371.256796 -289.161996) (xy 371.307648 -289.159947)
			(xy 371.358169 -289.166081) (xy 371.407053 -289.180241) (xy 371.453032 -289.202058) (xy 371.494916 -289.230968)
			(xy 371.53162 -289.266223) (xy 371.562193 -289.306909) (xy 371.585844 -289.351972) (xy 371.60196 -289.400246)
			(xy 371.610124 -289.45048) (xy 371.610636 -289.475926) (xy 371.610133 -289.500915) (xy 371.917196 -289.500915)
			(xy 371.917196 -289.450937) (xy 371.925015 -289.401574) (xy 371.940459 -289.354042) (xy 371.963149 -289.30951)
			(xy 371.992525 -289.269077) (xy 372.027865 -289.233737) (xy 372.068298 -289.204361) (xy 372.11283 -289.181671)
			(xy 372.160362 -289.166227) (xy 372.209725 -289.158408) (xy 372.259703 -289.158408) (xy 372.309066 -289.166227)
			(xy 372.356598 -289.181671) (xy 372.40113 -289.204361) (xy 372.441563 -289.233737) (xy 372.476903 -289.269077)
			(xy 372.506279 -289.30951) (xy 372.528969 -289.354042) (xy 372.544413 -289.401574) (xy 372.552232 -289.450937)
			(xy 372.552722 -289.475926) (xy 372.858533 -289.475926) (xy 372.862628 -289.425198) (xy 372.874807 -289.375784)
			(xy 372.894755 -289.328964) (xy 372.921956 -289.28595) (xy 372.955704 -289.247856) (xy 372.995126 -289.215669)
			(xy 373.0392 -289.190223) (xy 373.086786 -289.172176) (xy 373.13665 -289.161996) (xy 373.187502 -289.159947)
			(xy 373.238023 -289.166081) (xy 373.286907 -289.180241) (xy 373.332886 -289.202058) (xy 373.37477 -289.230968)
			(xy 373.411474 -289.266223) (xy 373.442047 -289.306909) (xy 373.465698 -289.351972) (xy 373.481814 -289.400246)
			(xy 373.489978 -289.45048) (xy 373.49049 -289.475926) (xy 373.798587 -289.475926) (xy 373.802682 -289.425198)
			(xy 373.814861 -289.375784) (xy 373.834809 -289.328964) (xy 373.86201 -289.28595) (xy 373.895758 -289.247856)
			(xy 373.93518 -289.215669) (xy 373.979254 -289.190223) (xy 374.02684 -289.172176) (xy 374.076704 -289.161996)
			(xy 374.127556 -289.159947) (xy 374.178077 -289.166081) (xy 374.226961 -289.180241) (xy 374.27294 -289.202058)
			(xy 374.314824 -289.230968) (xy 374.351528 -289.266223) (xy 374.382101 -289.306909) (xy 374.405752 -289.351972)
			(xy 374.421868 -289.400246) (xy 374.430032 -289.45048) (xy 374.430544 -289.475926) (xy 374.430032 -289.501372)
			(xy 374.421868 -289.551606) (xy 374.405752 -289.59988) (xy 374.382101 -289.644943) (xy 374.351528 -289.685629)
			(xy 374.314824 -289.720884) (xy 374.27294 -289.749794) (xy 374.226961 -289.771611) (xy 374.178077 -289.785771)
			(xy 374.127556 -289.791905) (xy 374.076704 -289.789856) (xy 374.02684 -289.779676) (xy 373.979254 -289.761629)
			(xy 373.93518 -289.736183) (xy 373.895758 -289.703996) (xy 373.86201 -289.665902) (xy 373.834809 -289.622888)
			(xy 373.814861 -289.576068) (xy 373.802682 -289.526654) (xy 373.798587 -289.475926) (xy 373.49049 -289.475926)
			(xy 373.489978 -289.501372) (xy 373.481814 -289.551606) (xy 373.465698 -289.59988) (xy 373.442047 -289.644943)
			(xy 373.411474 -289.685629) (xy 373.37477 -289.720884) (xy 373.332886 -289.749794) (xy 373.286907 -289.771611)
			(xy 373.238023 -289.785771) (xy 373.187502 -289.791905) (xy 373.13665 -289.789856) (xy 373.086786 -289.779676)
			(xy 373.0392 -289.761629) (xy 372.995126 -289.736183) (xy 372.955704 -289.703996) (xy 372.921956 -289.665902)
			(xy 372.894755 -289.622888) (xy 372.874807 -289.576068) (xy 372.862628 -289.526654) (xy 372.858533 -289.475926)
			(xy 372.552722 -289.475926) (xy 372.552232 -289.500915) (xy 372.544413 -289.550278) (xy 372.528969 -289.59781)
			(xy 372.506279 -289.642342) (xy 372.476903 -289.682775) (xy 372.441563 -289.718115) (xy 372.40113 -289.747491)
			(xy 372.356598 -289.770181) (xy 372.309066 -289.785625) (xy 372.259703 -289.793444) (xy 372.209725 -289.793444)
			(xy 372.160362 -289.785625) (xy 372.11283 -289.770181) (xy 372.068298 -289.747491) (xy 372.027865 -289.718115)
			(xy 371.992525 -289.682775) (xy 371.963149 -289.642342) (xy 371.940459 -289.59781) (xy 371.925015 -289.550278)
			(xy 371.917196 -289.500915) (xy 371.610133 -289.500915) (xy 371.610124 -289.501372) (xy 371.60196 -289.551606)
			(xy 371.585844 -289.59988) (xy 371.562193 -289.644943) (xy 371.53162 -289.685629) (xy 371.494916 -289.720884)
			(xy 371.453032 -289.749794) (xy 371.407053 -289.771611) (xy 371.358169 -289.785771) (xy 371.307648 -289.791905)
			(xy 371.256796 -289.789856) (xy 371.206932 -289.779676) (xy 371.159346 -289.761629) (xy 371.115272 -289.736183)
			(xy 371.07585 -289.703996) (xy 371.042102 -289.665902) (xy 371.014901 -289.622888) (xy 370.994953 -289.576068)
			(xy 370.982774 -289.526654) (xy 370.978679 -289.475926) (xy 370.670582 -289.475926) (xy 370.67007 -289.501372)
			(xy 370.661906 -289.551606) (xy 370.64579 -289.59988) (xy 370.622139 -289.644943) (xy 370.591566 -289.685629)
			(xy 370.554862 -289.720884) (xy 370.512978 -289.749794) (xy 370.466999 -289.771611) (xy 370.418115 -289.785771)
			(xy 370.367594 -289.791905) (xy 370.316742 -289.789856) (xy 370.266878 -289.779676) (xy 370.219292 -289.761629)
			(xy 370.175218 -289.736183) (xy 370.135796 -289.703996) (xy 370.102048 -289.665902) (xy 370.074847 -289.622888)
			(xy 370.054899 -289.576068) (xy 370.04272 -289.526654) (xy 370.038625 -289.475926) (xy 369.732814 -289.475926)
			(xy 369.732324 -289.500915) (xy 369.724505 -289.550278) (xy 369.709061 -289.59781) (xy 369.686371 -289.642342)
			(xy 369.656995 -289.682775) (xy 369.621655 -289.718115) (xy 369.581222 -289.747491) (xy 369.53669 -289.770181)
			(xy 369.489158 -289.785625) (xy 369.439795 -289.793444) (xy 369.389817 -289.793444) (xy 369.340454 -289.785625)
			(xy 369.292922 -289.770181) (xy 369.24839 -289.747491) (xy 369.207957 -289.718115) (xy 369.172617 -289.682775)
			(xy 369.143241 -289.642342) (xy 369.120551 -289.59781) (xy 369.105107 -289.550278) (xy 369.097288 -289.500915)
			(xy 368.789971 -289.500915) (xy 368.789962 -289.501372) (xy 368.781798 -289.551606) (xy 368.765682 -289.59988)
			(xy 368.742031 -289.644943) (xy 368.711458 -289.685629) (xy 368.674754 -289.720884) (xy 368.63287 -289.749794)
			(xy 368.586891 -289.771611) (xy 368.538007 -289.785771) (xy 368.487486 -289.791905) (xy 368.436634 -289.789856)
			(xy 368.38677 -289.779676) (xy 368.339184 -289.761629) (xy 368.29511 -289.736183) (xy 368.255688 -289.703996)
			(xy 368.22194 -289.665902) (xy 368.194739 -289.622888) (xy 368.174791 -289.576068) (xy 368.162612 -289.526654)
			(xy 368.158517 -289.475926) (xy 367.85042 -289.475926) (xy 367.849908 -289.501372) (xy 367.841744 -289.551606)
			(xy 367.825628 -289.59988) (xy 367.801977 -289.644943) (xy 367.771404 -289.685629) (xy 367.7347 -289.720884)
			(xy 367.692816 -289.749794) (xy 367.646837 -289.771611) (xy 367.597953 -289.785771) (xy 367.547432 -289.791905)
			(xy 367.49658 -289.789856) (xy 367.446716 -289.779676) (xy 367.39913 -289.761629) (xy 367.355056 -289.736183)
			(xy 367.315634 -289.703996) (xy 367.281886 -289.665902) (xy 367.254685 -289.622888) (xy 367.234737 -289.576068)
			(xy 367.222558 -289.526654) (xy 367.218463 -289.475926) (xy 366.912906 -289.475926) (xy 366.912416 -289.500915)
			(xy 366.904597 -289.550278) (xy 366.889153 -289.59781) (xy 366.866463 -289.642342) (xy 366.837087 -289.682775)
			(xy 366.801747 -289.718115) (xy 366.761314 -289.747491) (xy 366.716782 -289.770181) (xy 366.66925 -289.785625)
			(xy 366.619887 -289.793444) (xy 366.569909 -289.793444) (xy 366.520546 -289.785625) (xy 366.473014 -289.770181)
			(xy 366.428482 -289.747491) (xy 366.388049 -289.718115) (xy 366.352709 -289.682775) (xy 366.323333 -289.642342)
			(xy 366.300643 -289.59781) (xy 366.285199 -289.550278) (xy 366.27738 -289.500915) (xy 365.970063 -289.500915)
			(xy 365.970054 -289.501372) (xy 365.96189 -289.551606) (xy 365.945774 -289.59988) (xy 365.922123 -289.644943)
			(xy 365.89155 -289.685629) (xy 365.854846 -289.720884) (xy 365.812962 -289.749794) (xy 365.766983 -289.771611)
			(xy 365.718099 -289.785771) (xy 365.667578 -289.791905) (xy 365.616726 -289.789856) (xy 365.566862 -289.779676)
			(xy 365.519276 -289.761629) (xy 365.475202 -289.736183) (xy 365.43578 -289.703996) (xy 365.402032 -289.665902)
			(xy 365.374831 -289.622888) (xy 365.354883 -289.576068) (xy 365.342704 -289.526654) (xy 365.338609 -289.475926)
			(xy 365.030512 -289.475926) (xy 365.03 -289.501372) (xy 365.021836 -289.551606) (xy 365.00572 -289.59988)
			(xy 364.982069 -289.644943) (xy 364.951496 -289.685629) (xy 364.914792 -289.720884) (xy 364.872908 -289.749794)
			(xy 364.826929 -289.771611) (xy 364.778045 -289.785771) (xy 364.727524 -289.791905) (xy 364.676672 -289.789856)
			(xy 364.626808 -289.779676) (xy 364.579222 -289.761629) (xy 364.535148 -289.736183) (xy 364.495726 -289.703996)
			(xy 364.461978 -289.665902) (xy 364.434777 -289.622888) (xy 364.414829 -289.576068) (xy 364.40265 -289.526654)
			(xy 364.398555 -289.475926) (xy 364.092744 -289.475926) (xy 364.092254 -289.500915) (xy 364.084435 -289.550278)
			(xy 364.068991 -289.59781) (xy 364.046301 -289.642342) (xy 364.016925 -289.682775) (xy 363.981585 -289.718115)
			(xy 363.941152 -289.747491) (xy 363.89662 -289.770181) (xy 363.849088 -289.785625) (xy 363.799725 -289.793444)
			(xy 363.749747 -289.793444) (xy 363.700384 -289.785625) (xy 363.652852 -289.770181) (xy 363.60832 -289.747491)
			(xy 363.567887 -289.718115) (xy 363.532547 -289.682775) (xy 363.503171 -289.642342) (xy 363.480481 -289.59781)
			(xy 363.465037 -289.550278) (xy 363.457218 -289.500915) (xy 356.57868 -289.500915) (xy 356.570861 -289.550278)
			(xy 356.555417 -289.59781) (xy 356.532727 -289.642342) (xy 356.503351 -289.682775) (xy 356.468011 -289.718115)
			(xy 356.427578 -289.747491) (xy 356.383046 -289.770181) (xy 356.335514 -289.785625) (xy 356.286151 -289.793444)
			(xy 356.236173 -289.793444) (xy 356.18681 -289.785625) (xy 356.139278 -289.770181) (xy 356.094746 -289.747491)
			(xy 356.054313 -289.718115) (xy 356.018973 -289.682775) (xy 355.989597 -289.642342) (xy 355.966907 -289.59781)
			(xy 355.951463 -289.550278) (xy 355.943644 -289.500915) (xy 355.636327 -289.500915) (xy 355.636318 -289.501372)
			(xy 355.628154 -289.551606) (xy 355.612038 -289.59988) (xy 355.588387 -289.644943) (xy 355.557814 -289.685629)
			(xy 355.52111 -289.720884) (xy 355.479226 -289.749794) (xy 355.433247 -289.771611) (xy 355.384363 -289.785771)
			(xy 355.333842 -289.791905) (xy 355.28299 -289.789856) (xy 355.233126 -289.779676) (xy 355.18554 -289.761629)
			(xy 355.141466 -289.736183) (xy 355.102044 -289.703996) (xy 355.068296 -289.665902) (xy 355.041095 -289.622888)
			(xy 355.021147 -289.576068) (xy 355.008968 -289.526654) (xy 355.004873 -289.475926) (xy 354.696776 -289.475926)
			(xy 354.696264 -289.501372) (xy 354.6881 -289.551606) (xy 354.671984 -289.59988) (xy 354.648333 -289.644943)
			(xy 354.61776 -289.685629) (xy 354.581056 -289.720884) (xy 354.539172 -289.749794) (xy 354.493193 -289.771611)
			(xy 354.444309 -289.785771) (xy 354.393788 -289.791905) (xy 354.342936 -289.789856) (xy 354.293072 -289.779676)
			(xy 354.245486 -289.761629) (xy 354.201412 -289.736183) (xy 354.16199 -289.703996) (xy 354.128242 -289.665902)
			(xy 354.101041 -289.622888) (xy 354.081093 -289.576068) (xy 354.068914 -289.526654) (xy 354.064819 -289.475926)
			(xy 353.759008 -289.475926) (xy 353.758518 -289.500915) (xy 353.750699 -289.550278) (xy 353.735255 -289.59781)
			(xy 353.712565 -289.642342) (xy 353.683189 -289.682775) (xy 353.647849 -289.718115) (xy 353.607416 -289.747491)
			(xy 353.562884 -289.770181) (xy 353.515352 -289.785625) (xy 353.465989 -289.793444) (xy 353.416011 -289.793444)
			(xy 353.366648 -289.785625) (xy 353.319116 -289.770181) (xy 353.274584 -289.747491) (xy 353.234151 -289.718115)
			(xy 353.198811 -289.682775) (xy 353.169435 -289.642342) (xy 353.146745 -289.59781) (xy 353.131301 -289.550278)
			(xy 353.123482 -289.500915) (xy 352.816419 -289.500915) (xy 352.81641 -289.501372) (xy 352.808246 -289.551606)
			(xy 352.79213 -289.59988) (xy 352.768479 -289.644943) (xy 352.737906 -289.685629) (xy 352.701202 -289.720884)
			(xy 352.659318 -289.749794) (xy 352.613339 -289.771611) (xy 352.564455 -289.785771) (xy 352.513934 -289.791905)
			(xy 352.463082 -289.789856) (xy 352.413218 -289.779676) (xy 352.365632 -289.761629) (xy 352.321558 -289.736183)
			(xy 352.282136 -289.703996) (xy 352.248388 -289.665902) (xy 352.221187 -289.622888) (xy 352.201239 -289.576068)
			(xy 352.18906 -289.526654) (xy 352.184965 -289.475926) (xy 351.876868 -289.475926) (xy 351.876356 -289.501372)
			(xy 351.868192 -289.551606) (xy 351.852076 -289.59988) (xy 351.828425 -289.644943) (xy 351.797852 -289.685629)
			(xy 351.761148 -289.720884) (xy 351.719264 -289.749794) (xy 351.673285 -289.771611) (xy 351.624401 -289.785771)
			(xy 351.57388 -289.791905) (xy 351.523028 -289.789856) (xy 351.473164 -289.779676) (xy 351.425578 -289.761629)
			(xy 351.381504 -289.736183) (xy 351.342082 -289.703996) (xy 351.308334 -289.665902) (xy 351.281133 -289.622888)
			(xy 351.261185 -289.576068) (xy 351.249006 -289.526654) (xy 351.244911 -289.475926) (xy 350.9391 -289.475926)
			(xy 350.93861 -289.500915) (xy 350.930791 -289.550278) (xy 350.915347 -289.59781) (xy 350.892657 -289.642342)
			(xy 350.863281 -289.682775) (xy 350.827941 -289.718115) (xy 350.787508 -289.747491) (xy 350.742976 -289.770181)
			(xy 350.695444 -289.785625) (xy 350.646081 -289.793444) (xy 350.596103 -289.793444) (xy 350.54674 -289.785625)
			(xy 350.499208 -289.770181) (xy 350.454676 -289.747491) (xy 350.414243 -289.718115) (xy 350.378903 -289.682775)
			(xy 350.349527 -289.642342) (xy 350.326837 -289.59781) (xy 350.311393 -289.550278) (xy 350.303574 -289.500915)
			(xy 349.996257 -289.500915) (xy 349.996248 -289.501372) (xy 349.988084 -289.551606) (xy 349.971968 -289.59988)
			(xy 349.948317 -289.644943) (xy 349.917744 -289.685629) (xy 349.88104 -289.720884) (xy 349.839156 -289.749794)
			(xy 349.793177 -289.771611) (xy 349.744293 -289.785771) (xy 349.693772 -289.791905) (xy 349.64292 -289.789856)
			(xy 349.593056 -289.779676) (xy 349.54547 -289.761629) (xy 349.501396 -289.736183) (xy 349.461974 -289.703996)
			(xy 349.428226 -289.665902) (xy 349.401025 -289.622888) (xy 349.381077 -289.576068) (xy 349.368898 -289.526654)
			(xy 349.364803 -289.475926) (xy 349.05696 -289.475926) (xy 349.056448 -289.501372) (xy 349.048284 -289.551606)
			(xy 349.032168 -289.59988) (xy 349.008517 -289.644943) (xy 348.977944 -289.685629) (xy 348.94124 -289.720884)
			(xy 348.899356 -289.749794) (xy 348.853377 -289.771611) (xy 348.804493 -289.785771) (xy 348.753972 -289.791905)
			(xy 348.70312 -289.789856) (xy 348.653256 -289.779676) (xy 348.60567 -289.761629) (xy 348.561596 -289.736183)
			(xy 348.522174 -289.703996) (xy 348.488426 -289.665902) (xy 348.461225 -289.622888) (xy 348.441277 -289.576068)
			(xy 348.429098 -289.526654) (xy 348.425003 -289.475926) (xy 348.119192 -289.475926) (xy 348.118702 -289.500915)
			(xy 348.110883 -289.550278) (xy 348.095439 -289.59781) (xy 348.072749 -289.642342) (xy 348.043373 -289.682775)
			(xy 348.008033 -289.718115) (xy 347.9676 -289.747491) (xy 347.923068 -289.770181) (xy 347.875536 -289.785625)
			(xy 347.826173 -289.793444) (xy 347.776195 -289.793444) (xy 347.726832 -289.785625) (xy 347.6793 -289.770181)
			(xy 347.634768 -289.747491) (xy 347.594335 -289.718115) (xy 347.558995 -289.682775) (xy 347.529619 -289.642342)
			(xy 347.506929 -289.59781) (xy 347.491485 -289.550278) (xy 347.483666 -289.500915) (xy 347.176349 -289.500915)
			(xy 347.17634 -289.501372) (xy 347.168176 -289.551606) (xy 347.15206 -289.59988) (xy 347.128409 -289.644943)
			(xy 347.097836 -289.685629) (xy 347.061132 -289.720884) (xy 347.019248 -289.749794) (xy 346.973269 -289.771611)
			(xy 346.924385 -289.785771) (xy 346.873864 -289.791905) (xy 346.823012 -289.789856) (xy 346.773148 -289.779676)
			(xy 346.725562 -289.761629) (xy 346.681488 -289.736183) (xy 346.642066 -289.703996) (xy 346.608318 -289.665902)
			(xy 346.581117 -289.622888) (xy 346.561169 -289.576068) (xy 346.54899 -289.526654) (xy 346.544895 -289.475926)
			(xy 346.236798 -289.475926) (xy 346.236286 -289.501372) (xy 346.228122 -289.551606) (xy 346.212006 -289.59988)
			(xy 346.188355 -289.644943) (xy 346.157782 -289.685629) (xy 346.121078 -289.720884) (xy 346.079194 -289.749794)
			(xy 346.033215 -289.771611) (xy 345.984331 -289.785771) (xy 345.93381 -289.791905) (xy 345.882958 -289.789856)
			(xy 345.833094 -289.779676) (xy 345.785508 -289.761629) (xy 345.741434 -289.736183) (xy 345.702012 -289.703996)
			(xy 345.668264 -289.665902) (xy 345.641063 -289.622888) (xy 345.621115 -289.576068) (xy 345.608936 -289.526654)
			(xy 345.604841 -289.475926) (xy 345.29903 -289.475926) (xy 345.298538 -289.500914) (xy 345.290716 -289.550276)
			(xy 345.27527 -289.597806) (xy 345.252579 -289.642335) (xy 345.223203 -289.682767) (xy 345.187863 -289.718105)
			(xy 345.147431 -289.747482) (xy 345.102902 -289.770172) (xy 345.055372 -289.785617) (xy 345.00601 -289.793438)
			(xy 344.981022 -289.793934) (xy 344.980768 -289.793934) (xy 344.956019 -289.793467) (xy 344.907119 -289.785805)
			(xy 344.859998 -289.770654) (xy 344.815795 -289.748382) (xy 344.775579 -289.719527) (xy 344.740322 -289.684786)
			(xy 344.725244 -289.665156) (xy 344.724228 -289.663632) (xy 344.722704 -289.6616) (xy 344.71737 -289.656266)
			(xy 344.710852 -289.650189) (xy 344.694715 -289.642658) (xy 344.685874 -289.641534) (xy 344.673936 -289.640518)
			(xy 344.609928 -289.635692) (xy 344.599152 -289.635521) (xy 344.579016 -289.643148) (xy 344.571066 -289.650424)
			(xy 344.424254 -289.797236) (xy 344.423492 -289.797998) (xy 344.422222 -289.799522) (xy 344.416447 -289.806696)
			(xy 344.409967 -289.823921) (xy 344.409976 -289.842324) (xy 344.412824 -289.851084) (xy 344.43924 -289.911028)
			(xy 344.43924 -289.911536) (xy 344.451178 -289.939222) (xy 344.452448 -289.941254) (xy 344.454226 -289.944048)
			(xy 344.457893 -289.949759) (xy 344.467676 -289.959157) (xy 344.47353 -289.96259) (xy 344.48496 -289.968686)
			(xy 344.49258 -289.968432) (xy 344.498676 -289.968178) (xy 344.499184 -289.968178) (xy 344.510868 -289.967924)
			(xy 344.511376 -289.967924) (xy 344.53635 -289.968435) (xy 344.585678 -289.976288) (xy 344.633171 -289.991757)
			(xy 344.677662 -290.014462) (xy 344.718055 -290.043843) (xy 344.753357 -290.07918) (xy 344.7827 -290.119601)
			(xy 344.805361 -290.164114) (xy 344.820784 -290.211622) (xy 344.828589 -290.260957) (xy 344.82913 -290.285932)
			(xy 344.82864 -290.310921) (xy 347.013512 -290.310921) (xy 347.013512 -290.260943) (xy 347.021331 -290.21158)
			(xy 347.036775 -290.164048) (xy 347.059465 -290.119516) (xy 347.088841 -290.079083) (xy 347.124181 -290.043743)
			(xy 347.164614 -290.014367) (xy 347.209146 -289.991677) (xy 347.256678 -289.976233) (xy 347.306041 -289.968414)
			(xy 347.356019 -289.968414) (xy 347.405382 -289.976233) (xy 347.452914 -289.991677) (xy 347.497446 -290.014367)
			(xy 347.537879 -290.043743) (xy 347.573219 -290.079083) (xy 347.602595 -290.119516) (xy 347.625285 -290.164048)
			(xy 347.640729 -290.21158) (xy 347.648548 -290.260943) (xy 347.649038 -290.285932) (xy 347.648548 -290.310921)
			(xy 349.833674 -290.310921) (xy 349.833674 -290.260943) (xy 349.841493 -290.21158) (xy 349.856937 -290.164048)
			(xy 349.879627 -290.119516) (xy 349.909003 -290.079083) (xy 349.944343 -290.043743) (xy 349.984776 -290.014367)
			(xy 350.029308 -289.991677) (xy 350.07684 -289.976233) (xy 350.126203 -289.968414) (xy 350.176181 -289.968414)
			(xy 350.225544 -289.976233) (xy 350.273076 -289.991677) (xy 350.317608 -290.014367) (xy 350.358041 -290.043743)
			(xy 350.393381 -290.079083) (xy 350.422757 -290.119516) (xy 350.445447 -290.164048) (xy 350.460891 -290.21158)
			(xy 350.46871 -290.260943) (xy 350.4692 -290.285932) (xy 350.46871 -290.310921) (xy 352.653582 -290.310921)
			(xy 352.653582 -290.260943) (xy 352.661401 -290.21158) (xy 352.676845 -290.164048) (xy 352.699535 -290.119516)
			(xy 352.728911 -290.079083) (xy 352.764251 -290.043743) (xy 352.804684 -290.014367) (xy 352.849216 -289.991677)
			(xy 352.896748 -289.976233) (xy 352.946111 -289.968414) (xy 352.996089 -289.968414) (xy 353.045452 -289.976233)
			(xy 353.092984 -289.991677) (xy 353.137516 -290.014367) (xy 353.177949 -290.043743) (xy 353.213289 -290.079083)
			(xy 353.242665 -290.119516) (xy 353.265355 -290.164048) (xy 353.280799 -290.21158) (xy 353.288618 -290.260943)
			(xy 353.289108 -290.285932) (xy 353.288618 -290.310921) (xy 355.47349 -290.310921) (xy 355.47349 -290.260943)
			(xy 355.481309 -290.21158) (xy 355.496753 -290.164048) (xy 355.519443 -290.119516) (xy 355.548819 -290.079083)
			(xy 355.584159 -290.043743) (xy 355.624592 -290.014367) (xy 355.669124 -289.991677) (xy 355.716656 -289.976233)
			(xy 355.766019 -289.968414) (xy 355.815997 -289.968414) (xy 355.86536 -289.976233) (xy 355.912892 -289.991677)
			(xy 355.957424 -290.014367) (xy 355.997857 -290.043743) (xy 356.033197 -290.079083) (xy 356.062573 -290.119516)
			(xy 356.085263 -290.164048) (xy 356.100707 -290.21158) (xy 356.108526 -290.260943) (xy 356.109016 -290.285932)
			(xy 356.414827 -290.285932) (xy 356.418922 -290.235204) (xy 356.431101 -290.18579) (xy 356.451049 -290.13897)
			(xy 356.47825 -290.095956) (xy 356.511998 -290.057862) (xy 356.55142 -290.025675) (xy 356.595494 -290.000229)
			(xy 356.64308 -289.982182) (xy 356.692944 -289.972002) (xy 356.743796 -289.969953) (xy 356.794317 -289.976087)
			(xy 356.843201 -289.990247) (xy 356.88918 -290.012064) (xy 356.931064 -290.040974) (xy 356.967768 -290.076229)
			(xy 356.998341 -290.116915) (xy 357.021992 -290.161978) (xy 357.038108 -290.210252) (xy 357.046272 -290.260486)
			(xy 357.046784 -290.285932) (xy 357.354881 -290.285932) (xy 357.358976 -290.235204) (xy 357.371155 -290.18579)
			(xy 357.391103 -290.13897) (xy 357.418304 -290.095956) (xy 357.452052 -290.057862) (xy 357.491474 -290.025675)
			(xy 357.535548 -290.000229) (xy 357.583134 -289.982182) (xy 357.632998 -289.972002) (xy 357.68385 -289.969953)
			(xy 357.734371 -289.976087) (xy 357.783255 -289.990247) (xy 357.829234 -290.012064) (xy 357.871118 -290.040974)
			(xy 357.907822 -290.076229) (xy 357.938395 -290.116915) (xy 357.962046 -290.161978) (xy 357.978162 -290.210252)
			(xy 357.986326 -290.260486) (xy 357.986838 -290.285932) (xy 357.986335 -290.310921) (xy 358.293652 -290.310921)
			(xy 358.293652 -290.260943) (xy 358.301471 -290.21158) (xy 358.316915 -290.164048) (xy 358.339605 -290.119516)
			(xy 358.368981 -290.079083) (xy 358.404321 -290.043743) (xy 358.444754 -290.014367) (xy 358.489286 -289.991677)
			(xy 358.536818 -289.976233) (xy 358.586181 -289.968414) (xy 358.636159 -289.968414) (xy 358.685522 -289.976233)
			(xy 358.733054 -289.991677) (xy 358.777586 -290.014367) (xy 358.818019 -290.043743) (xy 358.853359 -290.079083)
			(xy 358.882735 -290.119516) (xy 358.905425 -290.164048) (xy 358.920869 -290.21158) (xy 358.928688 -290.260943)
			(xy 358.929178 -290.285932) (xy 358.928688 -290.310921) (xy 361.10721 -290.310921) (xy 361.10721 -290.260943)
			(xy 361.115029 -290.21158) (xy 361.130473 -290.164048) (xy 361.153163 -290.119516) (xy 361.182539 -290.079083)
			(xy 361.217879 -290.043743) (xy 361.258312 -290.014367) (xy 361.302844 -289.991677) (xy 361.350376 -289.976233)
			(xy 361.399739 -289.968414) (xy 361.449717 -289.968414) (xy 361.49908 -289.976233) (xy 361.546612 -289.991677)
			(xy 361.591144 -290.014367) (xy 361.631577 -290.043743) (xy 361.666917 -290.079083) (xy 361.696293 -290.119516)
			(xy 361.718983 -290.164048) (xy 361.734427 -290.21158) (xy 361.742246 -290.260943) (xy 361.742736 -290.285932)
			(xy 362.048547 -290.285932) (xy 362.052642 -290.235204) (xy 362.064821 -290.18579) (xy 362.084769 -290.13897)
			(xy 362.11197 -290.095956) (xy 362.145718 -290.057862) (xy 362.18514 -290.025675) (xy 362.229214 -290.000229)
			(xy 362.2768 -289.982182) (xy 362.326664 -289.972002) (xy 362.377516 -289.969953) (xy 362.428037 -289.976087)
			(xy 362.476921 -289.990247) (xy 362.5229 -290.012064) (xy 362.564784 -290.040974) (xy 362.601488 -290.076229)
			(xy 362.632061 -290.116915) (xy 362.655712 -290.161978) (xy 362.671828 -290.210252) (xy 362.679992 -290.260486)
			(xy 362.680504 -290.285932) (xy 362.988601 -290.285932) (xy 362.992696 -290.235204) (xy 363.004875 -290.18579)
			(xy 363.024823 -290.13897) (xy 363.052024 -290.095956) (xy 363.085772 -290.057862) (xy 363.125194 -290.025675)
			(xy 363.169268 -290.000229) (xy 363.216854 -289.982182) (xy 363.266718 -289.972002) (xy 363.31757 -289.969953)
			(xy 363.368091 -289.976087) (xy 363.416975 -289.990247) (xy 363.462954 -290.012064) (xy 363.504838 -290.040974)
			(xy 363.541542 -290.076229) (xy 363.572115 -290.116915) (xy 363.595766 -290.161978) (xy 363.611882 -290.210252)
			(xy 363.620046 -290.260486) (xy 363.620558 -290.285932) (xy 363.620055 -290.310921) (xy 363.927372 -290.310921)
			(xy 363.927372 -290.260943) (xy 363.935191 -290.21158) (xy 363.950635 -290.164048) (xy 363.973325 -290.119516)
			(xy 364.002701 -290.079083) (xy 364.038041 -290.043743) (xy 364.078474 -290.014367) (xy 364.123006 -289.991677)
			(xy 364.170538 -289.976233) (xy 364.219901 -289.968414) (xy 364.269879 -289.968414) (xy 364.319242 -289.976233)
			(xy 364.366774 -289.991677) (xy 364.411306 -290.014367) (xy 364.451739 -290.043743) (xy 364.487079 -290.079083)
			(xy 364.516455 -290.119516) (xy 364.539145 -290.164048) (xy 364.554589 -290.21158) (xy 364.562408 -290.260943)
			(xy 364.562898 -290.285932) (xy 364.562408 -290.310921) (xy 366.74728 -290.310921) (xy 366.74728 -290.260943)
			(xy 366.755099 -290.21158) (xy 366.770543 -290.164048) (xy 366.793233 -290.119516) (xy 366.822609 -290.079083)
			(xy 366.857949 -290.043743) (xy 366.898382 -290.014367) (xy 366.942914 -289.991677) (xy 366.990446 -289.976233)
			(xy 367.039809 -289.968414) (xy 367.089787 -289.968414) (xy 367.13915 -289.976233) (xy 367.186682 -289.991677)
			(xy 367.231214 -290.014367) (xy 367.271647 -290.043743) (xy 367.306987 -290.079083) (xy 367.336363 -290.119516)
			(xy 367.359053 -290.164048) (xy 367.374497 -290.21158) (xy 367.382316 -290.260943) (xy 367.382806 -290.285932)
			(xy 367.382316 -290.310921) (xy 369.567188 -290.310921) (xy 369.567188 -290.260943) (xy 369.575007 -290.21158)
			(xy 369.590451 -290.164048) (xy 369.613141 -290.119516) (xy 369.642517 -290.079083) (xy 369.677857 -290.043743)
			(xy 369.71829 -290.014367) (xy 369.762822 -289.991677) (xy 369.810354 -289.976233) (xy 369.859717 -289.968414)
			(xy 369.909695 -289.968414) (xy 369.959058 -289.976233) (xy 370.00659 -289.991677) (xy 370.051122 -290.014367)
			(xy 370.091555 -290.043743) (xy 370.126895 -290.079083) (xy 370.156271 -290.119516) (xy 370.178961 -290.164048)
			(xy 370.194405 -290.21158) (xy 370.202224 -290.260943) (xy 370.202714 -290.285932) (xy 370.202224 -290.310921)
			(xy 372.38735 -290.310921) (xy 372.38735 -290.260943) (xy 372.395169 -290.21158) (xy 372.410613 -290.164048)
			(xy 372.433303 -290.119516) (xy 372.462679 -290.079083) (xy 372.498019 -290.043743) (xy 372.538452 -290.014367)
			(xy 372.582984 -289.991677) (xy 372.630516 -289.976233) (xy 372.679879 -289.968414) (xy 372.729857 -289.968414)
			(xy 372.77922 -289.976233) (xy 372.826752 -289.991677) (xy 372.871284 -290.014367) (xy 372.911717 -290.043743)
			(xy 372.947057 -290.079083) (xy 372.976433 -290.119516) (xy 372.999123 -290.164048) (xy 373.014567 -290.21158)
			(xy 373.022386 -290.260943) (xy 373.022876 -290.285932) (xy 373.022386 -290.310921) (xy 373.014567 -290.360284)
			(xy 372.999123 -290.407816) (xy 372.976433 -290.452348) (xy 372.947057 -290.492781) (xy 372.911717 -290.528121)
			(xy 372.871284 -290.557497) (xy 372.826752 -290.580187) (xy 372.77922 -290.595631) (xy 372.729857 -290.60345)
			(xy 372.679879 -290.60345) (xy 372.630516 -290.595631) (xy 372.582984 -290.580187) (xy 372.538452 -290.557497)
			(xy 372.498019 -290.528121) (xy 372.462679 -290.492781) (xy 372.433303 -290.452348) (xy 372.410613 -290.407816)
			(xy 372.395169 -290.360284) (xy 372.38735 -290.310921) (xy 370.202224 -290.310921) (xy 370.194405 -290.360284)
			(xy 370.178961 -290.407816) (xy 370.156271 -290.452348) (xy 370.126895 -290.492781) (xy 370.091555 -290.528121)
			(xy 370.051122 -290.557497) (xy 370.00659 -290.580187) (xy 369.959058 -290.595631) (xy 369.909695 -290.60345)
			(xy 369.859717 -290.60345) (xy 369.810354 -290.595631) (xy 369.762822 -290.580187) (xy 369.71829 -290.557497)
			(xy 369.677857 -290.528121) (xy 369.642517 -290.492781) (xy 369.613141 -290.452348) (xy 369.590451 -290.407816)
			(xy 369.575007 -290.360284) (xy 369.567188 -290.310921) (xy 367.382316 -290.310921) (xy 367.374497 -290.360284)
			(xy 367.359053 -290.407816) (xy 367.336363 -290.452348) (xy 367.306987 -290.492781) (xy 367.271647 -290.528121)
			(xy 367.231214 -290.557497) (xy 367.186682 -290.580187) (xy 367.13915 -290.595631) (xy 367.089787 -290.60345)
			(xy 367.039809 -290.60345) (xy 366.990446 -290.595631) (xy 366.942914 -290.580187) (xy 366.898382 -290.557497)
			(xy 366.857949 -290.528121) (xy 366.822609 -290.492781) (xy 366.793233 -290.452348) (xy 366.770543 -290.407816)
			(xy 366.755099 -290.360284) (xy 366.74728 -290.310921) (xy 364.562408 -290.310921) (xy 364.554589 -290.360284)
			(xy 364.539145 -290.407816) (xy 364.516455 -290.452348) (xy 364.487079 -290.492781) (xy 364.451739 -290.528121)
			(xy 364.411306 -290.557497) (xy 364.366774 -290.580187) (xy 364.319242 -290.595631) (xy 364.269879 -290.60345)
			(xy 364.219901 -290.60345) (xy 364.170538 -290.595631) (xy 364.123006 -290.580187) (xy 364.078474 -290.557497)
			(xy 364.038041 -290.528121) (xy 364.002701 -290.492781) (xy 363.973325 -290.452348) (xy 363.950635 -290.407816)
			(xy 363.935191 -290.360284) (xy 363.927372 -290.310921) (xy 363.620055 -290.310921) (xy 363.620046 -290.311378)
			(xy 363.611882 -290.361612) (xy 363.595766 -290.409886) (xy 363.572115 -290.454949) (xy 363.541542 -290.495635)
			(xy 363.504838 -290.53089) (xy 363.462954 -290.5598) (xy 363.416975 -290.581617) (xy 363.368091 -290.595777)
			(xy 363.31757 -290.601911) (xy 363.266718 -290.599862) (xy 363.216854 -290.589682) (xy 363.169268 -290.571635)
			(xy 363.125194 -290.546189) (xy 363.085772 -290.514002) (xy 363.052024 -290.475908) (xy 363.024823 -290.432894)
			(xy 363.004875 -290.386074) (xy 362.992696 -290.33666) (xy 362.988601 -290.285932) (xy 362.680504 -290.285932)
			(xy 362.679992 -290.311378) (xy 362.671828 -290.361612) (xy 362.655712 -290.409886) (xy 362.632061 -290.454949)
			(xy 362.601488 -290.495635) (xy 362.564784 -290.53089) (xy 362.5229 -290.5598) (xy 362.476921 -290.581617)
			(xy 362.428037 -290.595777) (xy 362.377516 -290.601911) (xy 362.326664 -290.599862) (xy 362.2768 -290.589682)
			(xy 362.229214 -290.571635) (xy 362.18514 -290.546189) (xy 362.145718 -290.514002) (xy 362.11197 -290.475908)
			(xy 362.084769 -290.432894) (xy 362.064821 -290.386074) (xy 362.052642 -290.33666) (xy 362.048547 -290.285932)
			(xy 361.742736 -290.285932) (xy 361.742246 -290.310921) (xy 361.734427 -290.360284) (xy 361.718983 -290.407816)
			(xy 361.696293 -290.452348) (xy 361.666917 -290.492781) (xy 361.631577 -290.528121) (xy 361.591144 -290.557497)
			(xy 361.546612 -290.580187) (xy 361.49908 -290.595631) (xy 361.449717 -290.60345) (xy 361.399739 -290.60345)
			(xy 361.350376 -290.595631) (xy 361.302844 -290.580187) (xy 361.258312 -290.557497) (xy 361.217879 -290.528121)
			(xy 361.182539 -290.492781) (xy 361.153163 -290.452348) (xy 361.130473 -290.407816) (xy 361.115029 -290.360284)
			(xy 361.10721 -290.310921) (xy 358.928688 -290.310921) (xy 358.920869 -290.360284) (xy 358.905425 -290.407816)
			(xy 358.882735 -290.452348) (xy 358.853359 -290.492781) (xy 358.818019 -290.528121) (xy 358.777586 -290.557497)
			(xy 358.733054 -290.580187) (xy 358.685522 -290.595631) (xy 358.636159 -290.60345) (xy 358.586181 -290.60345)
			(xy 358.536818 -290.595631) (xy 358.489286 -290.580187) (xy 358.444754 -290.557497) (xy 358.404321 -290.528121)
			(xy 358.368981 -290.492781) (xy 358.339605 -290.452348) (xy 358.316915 -290.407816) (xy 358.301471 -290.360284)
			(xy 358.293652 -290.310921) (xy 357.986335 -290.310921) (xy 357.986326 -290.311378) (xy 357.978162 -290.361612)
			(xy 357.962046 -290.409886) (xy 357.938395 -290.454949) (xy 357.907822 -290.495635) (xy 357.871118 -290.53089)
			(xy 357.829234 -290.5598) (xy 357.783255 -290.581617) (xy 357.734371 -290.595777) (xy 357.68385 -290.601911)
			(xy 357.632998 -290.599862) (xy 357.583134 -290.589682) (xy 357.535548 -290.571635) (xy 357.491474 -290.546189)
			(xy 357.452052 -290.514002) (xy 357.418304 -290.475908) (xy 357.391103 -290.432894) (xy 357.371155 -290.386074)
			(xy 357.358976 -290.33666) (xy 357.354881 -290.285932) (xy 357.046784 -290.285932) (xy 357.046272 -290.311378)
			(xy 357.038108 -290.361612) (xy 357.021992 -290.409886) (xy 356.998341 -290.454949) (xy 356.967768 -290.495635)
			(xy 356.931064 -290.53089) (xy 356.88918 -290.5598) (xy 356.843201 -290.581617) (xy 356.794317 -290.595777)
			(xy 356.743796 -290.601911) (xy 356.692944 -290.599862) (xy 356.64308 -290.589682) (xy 356.595494 -290.571635)
			(xy 356.55142 -290.546189) (xy 356.511998 -290.514002) (xy 356.47825 -290.475908) (xy 356.451049 -290.432894)
			(xy 356.431101 -290.386074) (xy 356.418922 -290.33666) (xy 356.414827 -290.285932) (xy 356.109016 -290.285932)
			(xy 356.108526 -290.310921) (xy 356.100707 -290.360284) (xy 356.085263 -290.407816) (xy 356.062573 -290.452348)
			(xy 356.033197 -290.492781) (xy 355.997857 -290.528121) (xy 355.957424 -290.557497) (xy 355.912892 -290.580187)
			(xy 355.86536 -290.595631) (xy 355.815997 -290.60345) (xy 355.766019 -290.60345) (xy 355.716656 -290.595631)
			(xy 355.669124 -290.580187) (xy 355.624592 -290.557497) (xy 355.584159 -290.528121) (xy 355.548819 -290.492781)
			(xy 355.519443 -290.452348) (xy 355.496753 -290.407816) (xy 355.481309 -290.360284) (xy 355.47349 -290.310921)
			(xy 353.288618 -290.310921) (xy 353.280799 -290.360284) (xy 353.265355 -290.407816) (xy 353.242665 -290.452348)
			(xy 353.213289 -290.492781) (xy 353.177949 -290.528121) (xy 353.137516 -290.557497) (xy 353.092984 -290.580187)
			(xy 353.045452 -290.595631) (xy 352.996089 -290.60345) (xy 352.946111 -290.60345) (xy 352.896748 -290.595631)
			(xy 352.849216 -290.580187) (xy 352.804684 -290.557497) (xy 352.764251 -290.528121) (xy 352.728911 -290.492781)
			(xy 352.699535 -290.452348) (xy 352.676845 -290.407816) (xy 352.661401 -290.360284) (xy 352.653582 -290.310921)
			(xy 350.46871 -290.310921) (xy 350.460891 -290.360284) (xy 350.445447 -290.407816) (xy 350.422757 -290.452348)
			(xy 350.393381 -290.492781) (xy 350.358041 -290.528121) (xy 350.317608 -290.557497) (xy 350.273076 -290.580187)
			(xy 350.225544 -290.595631) (xy 350.176181 -290.60345) (xy 350.126203 -290.60345) (xy 350.07684 -290.595631)
			(xy 350.029308 -290.580187) (xy 349.984776 -290.557497) (xy 349.944343 -290.528121) (xy 349.909003 -290.492781)
			(xy 349.879627 -290.452348) (xy 349.856937 -290.407816) (xy 349.841493 -290.360284) (xy 349.833674 -290.310921)
			(xy 347.648548 -290.310921) (xy 347.640729 -290.360284) (xy 347.625285 -290.407816) (xy 347.602595 -290.452348)
			(xy 347.573219 -290.492781) (xy 347.537879 -290.528121) (xy 347.497446 -290.557497) (xy 347.452914 -290.580187)
			(xy 347.405382 -290.595631) (xy 347.356019 -290.60345) (xy 347.306041 -290.60345) (xy 347.256678 -290.595631)
			(xy 347.209146 -290.580187) (xy 347.164614 -290.557497) (xy 347.124181 -290.528121) (xy 347.088841 -290.492781)
			(xy 347.059465 -290.452348) (xy 347.036775 -290.407816) (xy 347.021331 -290.360284) (xy 347.013512 -290.310921)
			(xy 344.82864 -290.310921) (xy 344.820821 -290.360284) (xy 344.805377 -290.407816) (xy 344.782687 -290.452348)
			(xy 344.753311 -290.492781) (xy 344.717971 -290.528121) (xy 344.677538 -290.557497) (xy 344.633006 -290.580187)
			(xy 344.585474 -290.595631) (xy 344.536111 -290.60345) (xy 344.486133 -290.60345) (xy 344.43677 -290.595631)
			(xy 344.389238 -290.580187) (xy 344.344706 -290.557497) (xy 344.304273 -290.528121) (xy 344.268933 -290.492781)
			(xy 344.239557 -290.452348) (xy 344.216867 -290.407816) (xy 344.201423 -290.360284) (xy 344.193604 -290.310921)
			(xy 344.193114 -290.285932) (xy 344.193368 -290.273994) (xy 344.193368 -290.273486) (xy 344.193353 -290.265935)
			(xy 344.189478 -290.251349) (xy 344.185748 -290.244784) (xy 344.181684 -290.238688) (xy 344.170508 -290.229036)
			(xy 344.120724 -290.207192) (xy 344.07856 -290.18865) (xy 344.071424 -290.185817) (xy 344.05617 -290.184137)
			(xy 344.048588 -290.185348) (xy 344.040968 -290.186618) (xy 344.02776 -290.19373) (xy 343.90711 -290.31438)
			(xy 343.904404 -290.317231) (xy 343.899811 -290.323609) (xy 343.897966 -290.32708) (xy 343.894664 -290.33343)
			(xy 343.89314 -290.341558) (xy 343.888411 -290.366225) (xy 343.872386 -290.413825) (xy 343.849268 -290.458413)
			(xy 343.819601 -290.498939) (xy 343.784083 -290.534449) (xy 343.74355 -290.564107) (xy 343.698957 -290.587215)
			(xy 343.651353 -290.603229) (xy 343.626694 -290.608004) (xy 343.618566 -290.609528) (xy 343.612216 -290.61283)
			(xy 343.608741 -290.614669) (xy 343.602361 -290.619261) (xy 343.599516 -290.621974) (xy 343.379806 -290.841684)
			(xy 343.375996 -290.84524) (xy 343.36863 -290.851082) (xy 343.367868 -290.85159) (xy 343.357962 -290.86937)
			(xy 343.356692 -290.881054) (xy 343.356227 -290.886713) (xy 343.357519 -290.897992) (xy 343.359232 -290.903406)
			(xy 343.360756 -290.907978) (xy 343.363296 -290.915598) (xy 343.367106 -290.92144) (xy 343.379413 -290.940987)
			(xy 343.398871 -290.982878) (xy 343.412076 -291.027139) (xy 343.418754 -291.072843) (xy 343.419176 -291.095938)
			(xy 343.724987 -291.095938) (xy 343.729082 -291.04521) (xy 343.741261 -290.995796) (xy 343.761209 -290.948976)
			(xy 343.78841 -290.905962) (xy 343.822158 -290.867868) (xy 343.86158 -290.835681) (xy 343.905654 -290.810235)
			(xy 343.95324 -290.792188) (xy 344.003104 -290.782008) (xy 344.053956 -290.779959) (xy 344.104477 -290.786093)
			(xy 344.153361 -290.800253) (xy 344.19934 -290.82207) (xy 344.241224 -290.85098) (xy 344.277928 -290.886235)
			(xy 344.308501 -290.926921) (xy 344.332152 -290.971984) (xy 344.348268 -291.020258) (xy 344.356432 -291.070492)
			(xy 344.356944 -291.095938) (xy 344.356441 -291.120927) (xy 344.663504 -291.120927) (xy 344.663504 -291.070949)
			(xy 344.671323 -291.021586) (xy 344.686767 -290.974054) (xy 344.709457 -290.929522) (xy 344.738833 -290.889089)
			(xy 344.774173 -290.853749) (xy 344.814606 -290.824373) (xy 344.859138 -290.801683) (xy 344.90667 -290.786239)
			(xy 344.956033 -290.77842) (xy 345.006011 -290.77842) (xy 345.055374 -290.786239) (xy 345.102906 -290.801683)
			(xy 345.147438 -290.824373) (xy 345.187871 -290.853749) (xy 345.223211 -290.889089) (xy 345.252587 -290.929522)
			(xy 345.275277 -290.974054) (xy 345.290721 -291.021586) (xy 345.29854 -291.070949) (xy 345.29903 -291.095938)
			(xy 345.604841 -291.095938) (xy 345.608936 -291.04521) (xy 345.621115 -290.995796) (xy 345.641063 -290.948976)
			(xy 345.668264 -290.905962) (xy 345.702012 -290.867868) (xy 345.741434 -290.835681) (xy 345.785508 -290.810235)
			(xy 345.833094 -290.792188) (xy 345.882958 -290.782008) (xy 345.93381 -290.779959) (xy 345.984331 -290.786093)
			(xy 346.033215 -290.800253) (xy 346.079194 -290.82207) (xy 346.121078 -290.85098) (xy 346.157782 -290.886235)
			(xy 346.188355 -290.926921) (xy 346.212006 -290.971984) (xy 346.228122 -291.020258) (xy 346.236286 -291.070492)
			(xy 346.236798 -291.095938) (xy 346.544895 -291.095938) (xy 346.54899 -291.04521) (xy 346.561169 -290.995796)
			(xy 346.581117 -290.948976) (xy 346.608318 -290.905962) (xy 346.642066 -290.867868) (xy 346.681488 -290.835681)
			(xy 346.725562 -290.810235) (xy 346.773148 -290.792188) (xy 346.823012 -290.782008) (xy 346.873864 -290.779959)
			(xy 346.924385 -290.786093) (xy 346.973269 -290.800253) (xy 347.019248 -290.82207) (xy 347.061132 -290.85098)
			(xy 347.097836 -290.886235) (xy 347.128409 -290.926921) (xy 347.15206 -290.971984) (xy 347.168176 -291.020258)
			(xy 347.17634 -291.070492) (xy 347.176852 -291.095938) (xy 347.176349 -291.120927) (xy 347.483666 -291.120927)
			(xy 347.483666 -291.070949) (xy 347.491485 -291.021586) (xy 347.506929 -290.974054) (xy 347.529619 -290.929522)
			(xy 347.558995 -290.889089) (xy 347.594335 -290.853749) (xy 347.634768 -290.824373) (xy 347.6793 -290.801683)
			(xy 347.726832 -290.786239) (xy 347.776195 -290.77842) (xy 347.826173 -290.77842) (xy 347.875536 -290.786239)
			(xy 347.923068 -290.801683) (xy 347.9676 -290.824373) (xy 348.008033 -290.853749) (xy 348.043373 -290.889089)
			(xy 348.072749 -290.929522) (xy 348.095439 -290.974054) (xy 348.110883 -291.021586) (xy 348.118702 -291.070949)
			(xy 348.119192 -291.095938) (xy 348.425003 -291.095938) (xy 348.429098 -291.04521) (xy 348.441277 -290.995796)
			(xy 348.461225 -290.948976) (xy 348.488426 -290.905962) (xy 348.522174 -290.867868) (xy 348.561596 -290.835681)
			(xy 348.60567 -290.810235) (xy 348.653256 -290.792188) (xy 348.70312 -290.782008) (xy 348.753972 -290.779959)
			(xy 348.804493 -290.786093) (xy 348.853377 -290.800253) (xy 348.899356 -290.82207) (xy 348.94124 -290.85098)
			(xy 348.977944 -290.886235) (xy 349.008517 -290.926921) (xy 349.032168 -290.971984) (xy 349.048284 -291.020258)
			(xy 349.056448 -291.070492) (xy 349.05696 -291.095938) (xy 349.364803 -291.095938) (xy 349.368898 -291.04521)
			(xy 349.381077 -290.995796) (xy 349.401025 -290.948976) (xy 349.428226 -290.905962) (xy 349.461974 -290.867868)
			(xy 349.501396 -290.835681) (xy 349.54547 -290.810235) (xy 349.593056 -290.792188) (xy 349.64292 -290.782008)
			(xy 349.693772 -290.779959) (xy 349.744293 -290.786093) (xy 349.793177 -290.800253) (xy 349.839156 -290.82207)
			(xy 349.88104 -290.85098) (xy 349.917744 -290.886235) (xy 349.948317 -290.926921) (xy 349.971968 -290.971984)
			(xy 349.988084 -291.020258) (xy 349.996248 -291.070492) (xy 349.99676 -291.095938) (xy 349.996257 -291.120927)
			(xy 350.303574 -291.120927) (xy 350.303574 -291.070949) (xy 350.311393 -291.021586) (xy 350.326837 -290.974054)
			(xy 350.349527 -290.929522) (xy 350.378903 -290.889089) (xy 350.414243 -290.853749) (xy 350.454676 -290.824373)
			(xy 350.499208 -290.801683) (xy 350.54674 -290.786239) (xy 350.596103 -290.77842) (xy 350.646081 -290.77842)
			(xy 350.695444 -290.786239) (xy 350.742976 -290.801683) (xy 350.787508 -290.824373) (xy 350.827941 -290.853749)
			(xy 350.863281 -290.889089) (xy 350.892657 -290.929522) (xy 350.915347 -290.974054) (xy 350.930791 -291.021586)
			(xy 350.93861 -291.070949) (xy 350.9391 -291.095938) (xy 351.244911 -291.095938) (xy 351.249006 -291.04521)
			(xy 351.261185 -290.995796) (xy 351.281133 -290.948976) (xy 351.308334 -290.905962) (xy 351.342082 -290.867868)
			(xy 351.381504 -290.835681) (xy 351.425578 -290.810235) (xy 351.473164 -290.792188) (xy 351.523028 -290.782008)
			(xy 351.57388 -290.779959) (xy 351.624401 -290.786093) (xy 351.673285 -290.800253) (xy 351.719264 -290.82207)
			(xy 351.761148 -290.85098) (xy 351.797852 -290.886235) (xy 351.828425 -290.926921) (xy 351.852076 -290.971984)
			(xy 351.868192 -291.020258) (xy 351.876356 -291.070492) (xy 351.876868 -291.095938) (xy 352.184965 -291.095938)
			(xy 352.18906 -291.04521) (xy 352.201239 -290.995796) (xy 352.221187 -290.948976) (xy 352.248388 -290.905962)
			(xy 352.282136 -290.867868) (xy 352.321558 -290.835681) (xy 352.365632 -290.810235) (xy 352.413218 -290.792188)
			(xy 352.463082 -290.782008) (xy 352.513934 -290.779959) (xy 352.564455 -290.786093) (xy 352.613339 -290.800253)
			(xy 352.659318 -290.82207) (xy 352.701202 -290.85098) (xy 352.737906 -290.886235) (xy 352.768479 -290.926921)
			(xy 352.79213 -290.971984) (xy 352.808246 -291.020258) (xy 352.81641 -291.070492) (xy 352.816922 -291.095938)
			(xy 352.816419 -291.120927) (xy 353.123482 -291.120927) (xy 353.123482 -291.070949) (xy 353.131301 -291.021586)
			(xy 353.146745 -290.974054) (xy 353.169435 -290.929522) (xy 353.198811 -290.889089) (xy 353.234151 -290.853749)
			(xy 353.274584 -290.824373) (xy 353.319116 -290.801683) (xy 353.366648 -290.786239) (xy 353.416011 -290.77842)
			(xy 353.465989 -290.77842) (xy 353.515352 -290.786239) (xy 353.562884 -290.801683) (xy 353.607416 -290.824373)
			(xy 353.647849 -290.853749) (xy 353.683189 -290.889089) (xy 353.712565 -290.929522) (xy 353.735255 -290.974054)
			(xy 353.750699 -291.021586) (xy 353.758518 -291.070949) (xy 353.759008 -291.095938) (xy 354.064819 -291.095938)
			(xy 354.068914 -291.04521) (xy 354.081093 -290.995796) (xy 354.101041 -290.948976) (xy 354.128242 -290.905962)
			(xy 354.16199 -290.867868) (xy 354.201412 -290.835681) (xy 354.245486 -290.810235) (xy 354.293072 -290.792188)
			(xy 354.342936 -290.782008) (xy 354.393788 -290.779959) (xy 354.444309 -290.786093) (xy 354.493193 -290.800253)
			(xy 354.539172 -290.82207) (xy 354.581056 -290.85098) (xy 354.61776 -290.886235) (xy 354.648333 -290.926921)
			(xy 354.671984 -290.971984) (xy 354.6881 -291.020258) (xy 354.696264 -291.070492) (xy 354.696776 -291.095938)
			(xy 355.004873 -291.095938) (xy 355.008968 -291.04521) (xy 355.021147 -290.995796) (xy 355.041095 -290.948976)
			(xy 355.068296 -290.905962) (xy 355.102044 -290.867868) (xy 355.141466 -290.835681) (xy 355.18554 -290.810235)
			(xy 355.233126 -290.792188) (xy 355.28299 -290.782008) (xy 355.333842 -290.779959) (xy 355.384363 -290.786093)
			(xy 355.433247 -290.800253) (xy 355.479226 -290.82207) (xy 355.52111 -290.85098) (xy 355.557814 -290.886235)
			(xy 355.588387 -290.926921) (xy 355.612038 -290.971984) (xy 355.628154 -291.020258) (xy 355.636318 -291.070492)
			(xy 355.63683 -291.095938) (xy 355.636327 -291.120927) (xy 355.943644 -291.120927) (xy 355.943644 -291.070949)
			(xy 355.951463 -291.021586) (xy 355.966907 -290.974054) (xy 355.989597 -290.929522) (xy 356.018973 -290.889089)
			(xy 356.054313 -290.853749) (xy 356.094746 -290.824373) (xy 356.139278 -290.801683) (xy 356.18681 -290.786239)
			(xy 356.236173 -290.77842) (xy 356.286151 -290.77842) (xy 356.335514 -290.786239) (xy 356.383046 -290.801683)
			(xy 356.427578 -290.824373) (xy 356.468011 -290.853749) (xy 356.503351 -290.889089) (xy 356.532727 -290.929522)
			(xy 356.555417 -290.974054) (xy 356.570861 -291.021586) (xy 356.57868 -291.070949) (xy 356.57917 -291.095938)
			(xy 356.57868 -291.120927) (xy 363.457218 -291.120927) (xy 363.457218 -291.070949) (xy 363.465037 -291.021586)
			(xy 363.480481 -290.974054) (xy 363.503171 -290.929522) (xy 363.532547 -290.889089) (xy 363.567887 -290.853749)
			(xy 363.60832 -290.824373) (xy 363.652852 -290.801683) (xy 363.700384 -290.786239) (xy 363.749747 -290.77842)
			(xy 363.799725 -290.77842) (xy 363.849088 -290.786239) (xy 363.89662 -290.801683) (xy 363.941152 -290.824373)
			(xy 363.981585 -290.853749) (xy 364.016925 -290.889089) (xy 364.046301 -290.929522) (xy 364.068991 -290.974054)
			(xy 364.084435 -291.021586) (xy 364.092254 -291.070949) (xy 364.092744 -291.095938) (xy 364.398555 -291.095938)
			(xy 364.40265 -291.04521) (xy 364.414829 -290.995796) (xy 364.434777 -290.948976) (xy 364.461978 -290.905962)
			(xy 364.495726 -290.867868) (xy 364.535148 -290.835681) (xy 364.579222 -290.810235) (xy 364.626808 -290.792188)
			(xy 364.676672 -290.782008) (xy 364.727524 -290.779959) (xy 364.778045 -290.786093) (xy 364.826929 -290.800253)
			(xy 364.872908 -290.82207) (xy 364.914792 -290.85098) (xy 364.951496 -290.886235) (xy 364.982069 -290.926921)
			(xy 365.00572 -290.971984) (xy 365.021836 -291.020258) (xy 365.03 -291.070492) (xy 365.030512 -291.095938)
			(xy 365.338609 -291.095938) (xy 365.342704 -291.04521) (xy 365.354883 -290.995796) (xy 365.374831 -290.948976)
			(xy 365.402032 -290.905962) (xy 365.43578 -290.867868) (xy 365.475202 -290.835681) (xy 365.519276 -290.810235)
			(xy 365.566862 -290.792188) (xy 365.616726 -290.782008) (xy 365.667578 -290.779959) (xy 365.718099 -290.786093)
			(xy 365.766983 -290.800253) (xy 365.812962 -290.82207) (xy 365.854846 -290.85098) (xy 365.89155 -290.886235)
			(xy 365.922123 -290.926921) (xy 365.945774 -290.971984) (xy 365.96189 -291.020258) (xy 365.970054 -291.070492)
			(xy 365.970566 -291.095938) (xy 365.970063 -291.120927) (xy 366.27738 -291.120927) (xy 366.27738 -291.070949)
			(xy 366.285199 -291.021586) (xy 366.300643 -290.974054) (xy 366.323333 -290.929522) (xy 366.352709 -290.889089)
			(xy 366.388049 -290.853749) (xy 366.428482 -290.824373) (xy 366.473014 -290.801683) (xy 366.520546 -290.786239)
			(xy 366.569909 -290.77842) (xy 366.619887 -290.77842) (xy 366.66925 -290.786239) (xy 366.716782 -290.801683)
			(xy 366.761314 -290.824373) (xy 366.801747 -290.853749) (xy 366.837087 -290.889089) (xy 366.866463 -290.929522)
			(xy 366.889153 -290.974054) (xy 366.904597 -291.021586) (xy 366.912416 -291.070949) (xy 366.912906 -291.095938)
			(xy 367.218463 -291.095938) (xy 367.222558 -291.04521) (xy 367.234737 -290.995796) (xy 367.254685 -290.948976)
			(xy 367.281886 -290.905962) (xy 367.315634 -290.867868) (xy 367.355056 -290.835681) (xy 367.39913 -290.810235)
			(xy 367.446716 -290.792188) (xy 367.49658 -290.782008) (xy 367.547432 -290.779959) (xy 367.597953 -290.786093)
			(xy 367.646837 -290.800253) (xy 367.692816 -290.82207) (xy 367.7347 -290.85098) (xy 367.771404 -290.886235)
			(xy 367.801977 -290.926921) (xy 367.825628 -290.971984) (xy 367.841744 -291.020258) (xy 367.849908 -291.070492)
			(xy 367.85042 -291.095938) (xy 368.158517 -291.095938) (xy 368.162612 -291.04521) (xy 368.174791 -290.995796)
			(xy 368.194739 -290.948976) (xy 368.22194 -290.905962) (xy 368.255688 -290.867868) (xy 368.29511 -290.835681)
			(xy 368.339184 -290.810235) (xy 368.38677 -290.792188) (xy 368.436634 -290.782008) (xy 368.487486 -290.779959)
			(xy 368.538007 -290.786093) (xy 368.586891 -290.800253) (xy 368.63287 -290.82207) (xy 368.674754 -290.85098)
			(xy 368.711458 -290.886235) (xy 368.742031 -290.926921) (xy 368.765682 -290.971984) (xy 368.781798 -291.020258)
			(xy 368.789962 -291.070492) (xy 368.790474 -291.095938) (xy 368.789971 -291.120927) (xy 369.097288 -291.120927)
			(xy 369.097288 -291.070949) (xy 369.105107 -291.021586) (xy 369.120551 -290.974054) (xy 369.143241 -290.929522)
			(xy 369.172617 -290.889089) (xy 369.207957 -290.853749) (xy 369.24839 -290.824373) (xy 369.292922 -290.801683)
			(xy 369.340454 -290.786239) (xy 369.389817 -290.77842) (xy 369.439795 -290.77842) (xy 369.489158 -290.786239)
			(xy 369.53669 -290.801683) (xy 369.581222 -290.824373) (xy 369.621655 -290.853749) (xy 369.656995 -290.889089)
			(xy 369.686371 -290.929522) (xy 369.709061 -290.974054) (xy 369.724505 -291.021586) (xy 369.732324 -291.070949)
			(xy 369.732814 -291.095938) (xy 370.038625 -291.095938) (xy 370.04272 -291.04521) (xy 370.054899 -290.995796)
			(xy 370.074847 -290.948976) (xy 370.102048 -290.905962) (xy 370.135796 -290.867868) (xy 370.175218 -290.835681)
			(xy 370.219292 -290.810235) (xy 370.266878 -290.792188) (xy 370.316742 -290.782008) (xy 370.367594 -290.779959)
			(xy 370.418115 -290.786093) (xy 370.466999 -290.800253) (xy 370.512978 -290.82207) (xy 370.554862 -290.85098)
			(xy 370.591566 -290.886235) (xy 370.622139 -290.926921) (xy 370.64579 -290.971984) (xy 370.661906 -291.020258)
			(xy 370.67007 -291.070492) (xy 370.670582 -291.095938) (xy 370.978679 -291.095938) (xy 370.982774 -291.04521)
			(xy 370.994953 -290.995796) (xy 371.014901 -290.948976) (xy 371.042102 -290.905962) (xy 371.07585 -290.867868)
			(xy 371.115272 -290.835681) (xy 371.159346 -290.810235) (xy 371.206932 -290.792188) (xy 371.256796 -290.782008)
			(xy 371.307648 -290.779959) (xy 371.358169 -290.786093) (xy 371.407053 -290.800253) (xy 371.453032 -290.82207)
			(xy 371.494916 -290.85098) (xy 371.53162 -290.886235) (xy 371.562193 -290.926921) (xy 371.585844 -290.971984)
			(xy 371.60196 -291.020258) (xy 371.610124 -291.070492) (xy 371.610636 -291.095938) (xy 371.610133 -291.120927)
			(xy 371.917196 -291.120927) (xy 371.917196 -291.070949) (xy 371.925015 -291.021586) (xy 371.940459 -290.974054)
			(xy 371.963149 -290.929522) (xy 371.992525 -290.889089) (xy 372.027865 -290.853749) (xy 372.068298 -290.824373)
			(xy 372.11283 -290.801683) (xy 372.160362 -290.786239) (xy 372.209725 -290.77842) (xy 372.259703 -290.77842)
			(xy 372.309066 -290.786239) (xy 372.356598 -290.801683) (xy 372.40113 -290.824373) (xy 372.441563 -290.853749)
			(xy 372.476903 -290.889089) (xy 372.506279 -290.929522) (xy 372.528969 -290.974054) (xy 372.544413 -291.021586)
			(xy 372.552232 -291.070949) (xy 372.552722 -291.095938) (xy 372.858533 -291.095938) (xy 372.862628 -291.04521)
			(xy 372.874807 -290.995796) (xy 372.894755 -290.948976) (xy 372.921956 -290.905962) (xy 372.955704 -290.867868)
			(xy 372.995126 -290.835681) (xy 373.0392 -290.810235) (xy 373.086786 -290.792188) (xy 373.13665 -290.782008)
			(xy 373.187502 -290.779959) (xy 373.238023 -290.786093) (xy 373.286907 -290.800253) (xy 373.332886 -290.82207)
			(xy 373.37477 -290.85098) (xy 373.411474 -290.886235) (xy 373.442047 -290.926921) (xy 373.465698 -290.971984)
			(xy 373.481814 -291.020258) (xy 373.489978 -291.070492) (xy 373.49049 -291.095938) (xy 373.798587 -291.095938)
			(xy 373.802682 -291.04521) (xy 373.814861 -290.995796) (xy 373.834809 -290.948976) (xy 373.86201 -290.905962)
			(xy 373.895758 -290.867868) (xy 373.93518 -290.835681) (xy 373.979254 -290.810235) (xy 374.02684 -290.792188)
			(xy 374.076704 -290.782008) (xy 374.127556 -290.779959) (xy 374.178077 -290.786093) (xy 374.226961 -290.800253)
			(xy 374.27294 -290.82207) (xy 374.314824 -290.85098) (xy 374.351528 -290.886235) (xy 374.382101 -290.926921)
			(xy 374.405752 -290.971984) (xy 374.421868 -291.020258) (xy 374.430032 -291.070492) (xy 374.430544 -291.095938)
			(xy 374.430041 -291.120927) (xy 374.737358 -291.120927) (xy 374.737358 -291.070949) (xy 374.745177 -291.021586)
			(xy 374.760621 -290.974054) (xy 374.783311 -290.929522) (xy 374.812687 -290.889089) (xy 374.848027 -290.853749)
			(xy 374.88846 -290.824373) (xy 374.932992 -290.801683) (xy 374.980524 -290.786239) (xy 375.029887 -290.77842)
			(xy 375.079865 -290.77842) (xy 375.129228 -290.786239) (xy 375.17676 -290.801683) (xy 375.221292 -290.824373)
			(xy 375.261725 -290.853749) (xy 375.297065 -290.889089) (xy 375.326441 -290.929522) (xy 375.349131 -290.974054)
			(xy 375.364575 -291.021586) (xy 375.372394 -291.070949) (xy 375.372884 -291.095938) (xy 375.372394 -291.120927)
			(xy 375.364575 -291.17029) (xy 375.349131 -291.217822) (xy 375.326441 -291.262354) (xy 375.297065 -291.302787)
			(xy 375.261725 -291.338127) (xy 375.221292 -291.367503) (xy 375.17676 -291.390193) (xy 375.129228 -291.405637)
			(xy 375.079865 -291.413456) (xy 375.029887 -291.413456) (xy 374.980524 -291.405637) (xy 374.932992 -291.390193)
			(xy 374.88846 -291.367503) (xy 374.848027 -291.338127) (xy 374.812687 -291.302787) (xy 374.783311 -291.262354)
			(xy 374.760621 -291.217822) (xy 374.745177 -291.17029) (xy 374.737358 -291.120927) (xy 374.430041 -291.120927)
			(xy 374.430032 -291.121384) (xy 374.421868 -291.171618) (xy 374.405752 -291.219892) (xy 374.382101 -291.264955)
			(xy 374.351528 -291.305641) (xy 374.314824 -291.340896) (xy 374.27294 -291.369806) (xy 374.226961 -291.391623)
			(xy 374.178077 -291.405783) (xy 374.127556 -291.411917) (xy 374.076704 -291.409868) (xy 374.02684 -291.399688)
			(xy 373.979254 -291.381641) (xy 373.93518 -291.356195) (xy 373.895758 -291.324008) (xy 373.86201 -291.285914)
			(xy 373.834809 -291.2429) (xy 373.814861 -291.19608) (xy 373.802682 -291.146666) (xy 373.798587 -291.095938)
			(xy 373.49049 -291.095938) (xy 373.489978 -291.121384) (xy 373.481814 -291.171618) (xy 373.465698 -291.219892)
			(xy 373.442047 -291.264955) (xy 373.411474 -291.305641) (xy 373.37477 -291.340896) (xy 373.332886 -291.369806)
			(xy 373.286907 -291.391623) (xy 373.238023 -291.405783) (xy 373.187502 -291.411917) (xy 373.13665 -291.409868)
			(xy 373.086786 -291.399688) (xy 373.0392 -291.381641) (xy 372.995126 -291.356195) (xy 372.955704 -291.324008)
			(xy 372.921956 -291.285914) (xy 372.894755 -291.2429) (xy 372.874807 -291.19608) (xy 372.862628 -291.146666)
			(xy 372.858533 -291.095938) (xy 372.552722 -291.095938) (xy 372.552232 -291.120927) (xy 372.544413 -291.17029)
			(xy 372.528969 -291.217822) (xy 372.506279 -291.262354) (xy 372.476903 -291.302787) (xy 372.441563 -291.338127)
			(xy 372.40113 -291.367503) (xy 372.356598 -291.390193) (xy 372.309066 -291.405637) (xy 372.259703 -291.413456)
			(xy 372.209725 -291.413456) (xy 372.160362 -291.405637) (xy 372.11283 -291.390193) (xy 372.068298 -291.367503)
			(xy 372.027865 -291.338127) (xy 371.992525 -291.302787) (xy 371.963149 -291.262354) (xy 371.940459 -291.217822)
			(xy 371.925015 -291.17029) (xy 371.917196 -291.120927) (xy 371.610133 -291.120927) (xy 371.610124 -291.121384)
			(xy 371.60196 -291.171618) (xy 371.585844 -291.219892) (xy 371.562193 -291.264955) (xy 371.53162 -291.305641)
			(xy 371.494916 -291.340896) (xy 371.453032 -291.369806) (xy 371.407053 -291.391623) (xy 371.358169 -291.405783)
			(xy 371.307648 -291.411917) (xy 371.256796 -291.409868) (xy 371.206932 -291.399688) (xy 371.159346 -291.381641)
			(xy 371.115272 -291.356195) (xy 371.07585 -291.324008) (xy 371.042102 -291.285914) (xy 371.014901 -291.2429)
			(xy 370.994953 -291.19608) (xy 370.982774 -291.146666) (xy 370.978679 -291.095938) (xy 370.670582 -291.095938)
			(xy 370.67007 -291.121384) (xy 370.661906 -291.171618) (xy 370.64579 -291.219892) (xy 370.622139 -291.264955)
			(xy 370.591566 -291.305641) (xy 370.554862 -291.340896) (xy 370.512978 -291.369806) (xy 370.466999 -291.391623)
			(xy 370.418115 -291.405783) (xy 370.367594 -291.411917) (xy 370.316742 -291.409868) (xy 370.266878 -291.399688)
			(xy 370.219292 -291.381641) (xy 370.175218 -291.356195) (xy 370.135796 -291.324008) (xy 370.102048 -291.285914)
			(xy 370.074847 -291.2429) (xy 370.054899 -291.19608) (xy 370.04272 -291.146666) (xy 370.038625 -291.095938)
			(xy 369.732814 -291.095938) (xy 369.732324 -291.120927) (xy 369.724505 -291.17029) (xy 369.709061 -291.217822)
			(xy 369.686371 -291.262354) (xy 369.656995 -291.302787) (xy 369.621655 -291.338127) (xy 369.581222 -291.367503)
			(xy 369.53669 -291.390193) (xy 369.489158 -291.405637) (xy 369.439795 -291.413456) (xy 369.389817 -291.413456)
			(xy 369.340454 -291.405637) (xy 369.292922 -291.390193) (xy 369.24839 -291.367503) (xy 369.207957 -291.338127)
			(xy 369.172617 -291.302787) (xy 369.143241 -291.262354) (xy 369.120551 -291.217822) (xy 369.105107 -291.17029)
			(xy 369.097288 -291.120927) (xy 368.789971 -291.120927) (xy 368.789962 -291.121384) (xy 368.781798 -291.171618)
			(xy 368.765682 -291.219892) (xy 368.742031 -291.264955) (xy 368.711458 -291.305641) (xy 368.674754 -291.340896)
			(xy 368.63287 -291.369806) (xy 368.586891 -291.391623) (xy 368.538007 -291.405783) (xy 368.487486 -291.411917)
			(xy 368.436634 -291.409868) (xy 368.38677 -291.399688) (xy 368.339184 -291.381641) (xy 368.29511 -291.356195)
			(xy 368.255688 -291.324008) (xy 368.22194 -291.285914) (xy 368.194739 -291.2429) (xy 368.174791 -291.19608)
			(xy 368.162612 -291.146666) (xy 368.158517 -291.095938) (xy 367.85042 -291.095938) (xy 367.849908 -291.121384)
			(xy 367.841744 -291.171618) (xy 367.825628 -291.219892) (xy 367.801977 -291.264955) (xy 367.771404 -291.305641)
			(xy 367.7347 -291.340896) (xy 367.692816 -291.369806) (xy 367.646837 -291.391623) (xy 367.597953 -291.405783)
			(xy 367.547432 -291.411917) (xy 367.49658 -291.409868) (xy 367.446716 -291.399688) (xy 367.39913 -291.381641)
			(xy 367.355056 -291.356195) (xy 367.315634 -291.324008) (xy 367.281886 -291.285914) (xy 367.254685 -291.2429)
			(xy 367.234737 -291.19608) (xy 367.222558 -291.146666) (xy 367.218463 -291.095938) (xy 366.912906 -291.095938)
			(xy 366.912416 -291.120927) (xy 366.904597 -291.17029) (xy 366.889153 -291.217822) (xy 366.866463 -291.262354)
			(xy 366.837087 -291.302787) (xy 366.801747 -291.338127) (xy 366.761314 -291.367503) (xy 366.716782 -291.390193)
			(xy 366.66925 -291.405637) (xy 366.619887 -291.413456) (xy 366.569909 -291.413456) (xy 366.520546 -291.405637)
			(xy 366.473014 -291.390193) (xy 366.428482 -291.367503) (xy 366.388049 -291.338127) (xy 366.352709 -291.302787)
			(xy 366.323333 -291.262354) (xy 366.300643 -291.217822) (xy 366.285199 -291.17029) (xy 366.27738 -291.120927)
			(xy 365.970063 -291.120927) (xy 365.970054 -291.121384) (xy 365.96189 -291.171618) (xy 365.945774 -291.219892)
			(xy 365.922123 -291.264955) (xy 365.89155 -291.305641) (xy 365.854846 -291.340896) (xy 365.812962 -291.369806)
			(xy 365.766983 -291.391623) (xy 365.718099 -291.405783) (xy 365.667578 -291.411917) (xy 365.616726 -291.409868)
			(xy 365.566862 -291.399688) (xy 365.519276 -291.381641) (xy 365.475202 -291.356195) (xy 365.43578 -291.324008)
			(xy 365.402032 -291.285914) (xy 365.374831 -291.2429) (xy 365.354883 -291.19608) (xy 365.342704 -291.146666)
			(xy 365.338609 -291.095938) (xy 365.030512 -291.095938) (xy 365.03 -291.121384) (xy 365.021836 -291.171618)
			(xy 365.00572 -291.219892) (xy 364.982069 -291.264955) (xy 364.951496 -291.305641) (xy 364.914792 -291.340896)
			(xy 364.872908 -291.369806) (xy 364.826929 -291.391623) (xy 364.778045 -291.405783) (xy 364.727524 -291.411917)
			(xy 364.676672 -291.409868) (xy 364.626808 -291.399688) (xy 364.579222 -291.381641) (xy 364.535148 -291.356195)
			(xy 364.495726 -291.324008) (xy 364.461978 -291.285914) (xy 364.434777 -291.2429) (xy 364.414829 -291.19608)
			(xy 364.40265 -291.146666) (xy 364.398555 -291.095938) (xy 364.092744 -291.095938) (xy 364.092254 -291.120927)
			(xy 364.084435 -291.17029) (xy 364.068991 -291.217822) (xy 364.046301 -291.262354) (xy 364.016925 -291.302787)
			(xy 363.981585 -291.338127) (xy 363.941152 -291.367503) (xy 363.89662 -291.390193) (xy 363.849088 -291.405637)
			(xy 363.799725 -291.413456) (xy 363.749747 -291.413456) (xy 363.700384 -291.405637) (xy 363.652852 -291.390193)
			(xy 363.60832 -291.367503) (xy 363.567887 -291.338127) (xy 363.532547 -291.302787) (xy 363.503171 -291.262354)
			(xy 363.480481 -291.217822) (xy 363.465037 -291.17029) (xy 363.457218 -291.120927) (xy 356.57868 -291.120927)
			(xy 356.570861 -291.17029) (xy 356.555417 -291.217822) (xy 356.532727 -291.262354) (xy 356.503351 -291.302787)
			(xy 356.468011 -291.338127) (xy 356.427578 -291.367503) (xy 356.383046 -291.390193) (xy 356.335514 -291.405637)
			(xy 356.286151 -291.413456) (xy 356.236173 -291.413456) (xy 356.18681 -291.405637) (xy 356.139278 -291.390193)
			(xy 356.094746 -291.367503) (xy 356.054313 -291.338127) (xy 356.018973 -291.302787) (xy 355.989597 -291.262354)
			(xy 355.966907 -291.217822) (xy 355.951463 -291.17029) (xy 355.943644 -291.120927) (xy 355.636327 -291.120927)
			(xy 355.636318 -291.121384) (xy 355.628154 -291.171618) (xy 355.612038 -291.219892) (xy 355.588387 -291.264955)
			(xy 355.557814 -291.305641) (xy 355.52111 -291.340896) (xy 355.479226 -291.369806) (xy 355.433247 -291.391623)
			(xy 355.384363 -291.405783) (xy 355.333842 -291.411917) (xy 355.28299 -291.409868) (xy 355.233126 -291.399688)
			(xy 355.18554 -291.381641) (xy 355.141466 -291.356195) (xy 355.102044 -291.324008) (xy 355.068296 -291.285914)
			(xy 355.041095 -291.2429) (xy 355.021147 -291.19608) (xy 355.008968 -291.146666) (xy 355.004873 -291.095938)
			(xy 354.696776 -291.095938) (xy 354.696264 -291.121384) (xy 354.6881 -291.171618) (xy 354.671984 -291.219892)
			(xy 354.648333 -291.264955) (xy 354.61776 -291.305641) (xy 354.581056 -291.340896) (xy 354.539172 -291.369806)
			(xy 354.493193 -291.391623) (xy 354.444309 -291.405783) (xy 354.393788 -291.411917) (xy 354.342936 -291.409868)
			(xy 354.293072 -291.399688) (xy 354.245486 -291.381641) (xy 354.201412 -291.356195) (xy 354.16199 -291.324008)
			(xy 354.128242 -291.285914) (xy 354.101041 -291.2429) (xy 354.081093 -291.19608) (xy 354.068914 -291.146666)
			(xy 354.064819 -291.095938) (xy 353.759008 -291.095938) (xy 353.758518 -291.120927) (xy 353.750699 -291.17029)
			(xy 353.735255 -291.217822) (xy 353.712565 -291.262354) (xy 353.683189 -291.302787) (xy 353.647849 -291.338127)
			(xy 353.607416 -291.367503) (xy 353.562884 -291.390193) (xy 353.515352 -291.405637) (xy 353.465989 -291.413456)
			(xy 353.416011 -291.413456) (xy 353.366648 -291.405637) (xy 353.319116 -291.390193) (xy 353.274584 -291.367503)
			(xy 353.234151 -291.338127) (xy 353.198811 -291.302787) (xy 353.169435 -291.262354) (xy 353.146745 -291.217822)
			(xy 353.131301 -291.17029) (xy 353.123482 -291.120927) (xy 352.816419 -291.120927) (xy 352.81641 -291.121384)
			(xy 352.808246 -291.171618) (xy 352.79213 -291.219892) (xy 352.768479 -291.264955) (xy 352.737906 -291.305641)
			(xy 352.701202 -291.340896) (xy 352.659318 -291.369806) (xy 352.613339 -291.391623) (xy 352.564455 -291.405783)
			(xy 352.513934 -291.411917) (xy 352.463082 -291.409868) (xy 352.413218 -291.399688) (xy 352.365632 -291.381641)
			(xy 352.321558 -291.356195) (xy 352.282136 -291.324008) (xy 352.248388 -291.285914) (xy 352.221187 -291.2429)
			(xy 352.201239 -291.19608) (xy 352.18906 -291.146666) (xy 352.184965 -291.095938) (xy 351.876868 -291.095938)
			(xy 351.876356 -291.121384) (xy 351.868192 -291.171618) (xy 351.852076 -291.219892) (xy 351.828425 -291.264955)
			(xy 351.797852 -291.305641) (xy 351.761148 -291.340896) (xy 351.719264 -291.369806) (xy 351.673285 -291.391623)
			(xy 351.624401 -291.405783) (xy 351.57388 -291.411917) (xy 351.523028 -291.409868) (xy 351.473164 -291.399688)
			(xy 351.425578 -291.381641) (xy 351.381504 -291.356195) (xy 351.342082 -291.324008) (xy 351.308334 -291.285914)
			(xy 351.281133 -291.2429) (xy 351.261185 -291.19608) (xy 351.249006 -291.146666) (xy 351.244911 -291.095938)
			(xy 350.9391 -291.095938) (xy 350.93861 -291.120927) (xy 350.930791 -291.17029) (xy 350.915347 -291.217822)
			(xy 350.892657 -291.262354) (xy 350.863281 -291.302787) (xy 350.827941 -291.338127) (xy 350.787508 -291.367503)
			(xy 350.742976 -291.390193) (xy 350.695444 -291.405637) (xy 350.646081 -291.413456) (xy 350.596103 -291.413456)
			(xy 350.54674 -291.405637) (xy 350.499208 -291.390193) (xy 350.454676 -291.367503) (xy 350.414243 -291.338127)
			(xy 350.378903 -291.302787) (xy 350.349527 -291.262354) (xy 350.326837 -291.217822) (xy 350.311393 -291.17029)
			(xy 350.303574 -291.120927) (xy 349.996257 -291.120927) (xy 349.996248 -291.121384) (xy 349.988084 -291.171618)
			(xy 349.971968 -291.219892) (xy 349.948317 -291.264955) (xy 349.917744 -291.305641) (xy 349.88104 -291.340896)
			(xy 349.839156 -291.369806) (xy 349.793177 -291.391623) (xy 349.744293 -291.405783) (xy 349.693772 -291.411917)
			(xy 349.64292 -291.409868) (xy 349.593056 -291.399688) (xy 349.54547 -291.381641) (xy 349.501396 -291.356195)
			(xy 349.461974 -291.324008) (xy 349.428226 -291.285914) (xy 349.401025 -291.2429) (xy 349.381077 -291.19608)
			(xy 349.368898 -291.146666) (xy 349.364803 -291.095938) (xy 349.05696 -291.095938) (xy 349.056448 -291.121384)
			(xy 349.048284 -291.171618) (xy 349.032168 -291.219892) (xy 349.008517 -291.264955) (xy 348.977944 -291.305641)
			(xy 348.94124 -291.340896) (xy 348.899356 -291.369806) (xy 348.853377 -291.391623) (xy 348.804493 -291.405783)
			(xy 348.753972 -291.411917) (xy 348.70312 -291.409868) (xy 348.653256 -291.399688) (xy 348.60567 -291.381641)
			(xy 348.561596 -291.356195) (xy 348.522174 -291.324008) (xy 348.488426 -291.285914) (xy 348.461225 -291.2429)
			(xy 348.441277 -291.19608) (xy 348.429098 -291.146666) (xy 348.425003 -291.095938) (xy 348.119192 -291.095938)
			(xy 348.118702 -291.120927) (xy 348.110883 -291.17029) (xy 348.095439 -291.217822) (xy 348.072749 -291.262354)
			(xy 348.043373 -291.302787) (xy 348.008033 -291.338127) (xy 347.9676 -291.367503) (xy 347.923068 -291.390193)
			(xy 347.875536 -291.405637) (xy 347.826173 -291.413456) (xy 347.776195 -291.413456) (xy 347.726832 -291.405637)
			(xy 347.6793 -291.390193) (xy 347.634768 -291.367503) (xy 347.594335 -291.338127) (xy 347.558995 -291.302787)
			(xy 347.529619 -291.262354) (xy 347.506929 -291.217822) (xy 347.491485 -291.17029) (xy 347.483666 -291.120927)
			(xy 347.176349 -291.120927) (xy 347.17634 -291.121384) (xy 347.168176 -291.171618) (xy 347.15206 -291.219892)
			(xy 347.128409 -291.264955) (xy 347.097836 -291.305641) (xy 347.061132 -291.340896) (xy 347.019248 -291.369806)
			(xy 346.973269 -291.391623) (xy 346.924385 -291.405783) (xy 346.873864 -291.411917) (xy 346.823012 -291.409868)
			(xy 346.773148 -291.399688) (xy 346.725562 -291.381641) (xy 346.681488 -291.356195) (xy 346.642066 -291.324008)
			(xy 346.608318 -291.285914) (xy 346.581117 -291.2429) (xy 346.561169 -291.19608) (xy 346.54899 -291.146666)
			(xy 346.544895 -291.095938) (xy 346.236798 -291.095938) (xy 346.236286 -291.121384) (xy 346.228122 -291.171618)
			(xy 346.212006 -291.219892) (xy 346.188355 -291.264955) (xy 346.157782 -291.305641) (xy 346.121078 -291.340896)
			(xy 346.079194 -291.369806) (xy 346.033215 -291.391623) (xy 345.984331 -291.405783) (xy 345.93381 -291.411917)
			(xy 345.882958 -291.409868) (xy 345.833094 -291.399688) (xy 345.785508 -291.381641) (xy 345.741434 -291.356195)
			(xy 345.702012 -291.324008) (xy 345.668264 -291.285914) (xy 345.641063 -291.2429) (xy 345.621115 -291.19608)
			(xy 345.608936 -291.146666) (xy 345.604841 -291.095938) (xy 345.29903 -291.095938) (xy 345.29854 -291.120927)
			(xy 345.290721 -291.17029) (xy 345.275277 -291.217822) (xy 345.252587 -291.262354) (xy 345.223211 -291.302787)
			(xy 345.187871 -291.338127) (xy 345.147438 -291.367503) (xy 345.102906 -291.390193) (xy 345.055374 -291.405637)
			(xy 345.006011 -291.413456) (xy 344.956033 -291.413456) (xy 344.90667 -291.405637) (xy 344.859138 -291.390193)
			(xy 344.814606 -291.367503) (xy 344.774173 -291.338127) (xy 344.738833 -291.302787) (xy 344.709457 -291.262354)
			(xy 344.686767 -291.217822) (xy 344.671323 -291.17029) (xy 344.663504 -291.120927) (xy 344.356441 -291.120927)
			(xy 344.356432 -291.121384) (xy 344.348268 -291.171618) (xy 344.332152 -291.219892) (xy 344.308501 -291.264955)
			(xy 344.277928 -291.305641) (xy 344.241224 -291.340896) (xy 344.19934 -291.369806) (xy 344.153361 -291.391623)
			(xy 344.104477 -291.405783) (xy 344.053956 -291.411917) (xy 344.003104 -291.409868) (xy 343.95324 -291.399688)
			(xy 343.905654 -291.381641) (xy 343.86158 -291.356195) (xy 343.822158 -291.324008) (xy 343.78841 -291.285914)
			(xy 343.761209 -291.2429) (xy 343.741261 -291.19608) (xy 343.729082 -291.146666) (xy 343.724987 -291.095938)
			(xy 343.419176 -291.095938) (xy 343.418683 -291.120924) (xy 343.41086 -291.170281) (xy 343.395412 -291.217806)
			(xy 343.372719 -291.262329) (xy 343.343342 -291.302755) (xy 343.308002 -291.338087) (xy 343.26757 -291.367456)
			(xy 343.223041 -291.390138) (xy 343.175513 -291.405576) (xy 343.126154 -291.413388) (xy 343.101168 -291.413946)
			(xy 343.100406 -291.413946) (xy 343.077185 -291.413509) (xy 343.031241 -291.406724) (xy 342.986773 -291.393327)
			(xy 342.944727 -291.373603) (xy 342.925146 -291.361114) (xy 342.918796 -291.35705) (xy 342.904064 -291.352732)
			(xy 342.895461 -291.350895) (xy 342.877959 -291.352534) (xy 342.86205 -291.36001) (xy 342.85555 -291.36594)
			(xy 342.755982 -291.465508) (xy 342.748364 -291.474082) (xy 342.740835 -291.495715) (xy 342.741504 -291.507164)
			(xy 342.745314 -291.531294) (xy 342.745314 -291.531802) (xy 342.75268 -291.579808) (xy 342.755305 -291.589933)
			(xy 342.767367 -291.606994) (xy 342.776048 -291.612828) (xy 342.77935 -291.614606) (xy 342.802037 -291.62669)
			(xy 342.843632 -291.656886) (xy 342.879988 -291.69322) (xy 342.910209 -291.734798) (xy 342.93355 -291.780593)
			(xy 342.949435 -291.829476) (xy 342.957474 -291.880244) (xy 342.957912 -291.905944) (xy 343.254833 -291.905944)
			(xy 343.258928 -291.855216) (xy 343.271107 -291.805802) (xy 343.291055 -291.758982) (xy 343.318256 -291.715968)
			(xy 343.352004 -291.677874) (xy 343.391426 -291.645687) (xy 343.4355 -291.620241) (xy 343.483086 -291.602194)
			(xy 343.53295 -291.592014) (xy 343.583802 -291.589965) (xy 343.634323 -291.596099) (xy 343.683207 -291.610259)
			(xy 343.729186 -291.632076) (xy 343.77107 -291.660986) (xy 343.807774 -291.696241) (xy 343.838347 -291.736927)
			(xy 343.861998 -291.78199) (xy 343.878114 -291.830264) (xy 343.886278 -291.880498) (xy 343.88679 -291.905944)
			(xy 343.886287 -291.930933) (xy 345.133658 -291.930933) (xy 345.133658 -291.880955) (xy 345.141477 -291.831592)
			(xy 345.156921 -291.78406) (xy 345.179611 -291.739528) (xy 345.208987 -291.699095) (xy 345.244327 -291.663755)
			(xy 345.28476 -291.634379) (xy 345.329292 -291.611689) (xy 345.376824 -291.596245) (xy 345.426187 -291.588426)
			(xy 345.476165 -291.588426) (xy 345.525528 -291.596245) (xy 345.57306 -291.611689) (xy 345.617592 -291.634379)
			(xy 345.658025 -291.663755) (xy 345.693365 -291.699095) (xy 345.722741 -291.739528) (xy 345.745431 -291.78406)
			(xy 345.760875 -291.831592) (xy 345.768694 -291.880955) (xy 345.769184 -291.905944) (xy 345.768694 -291.930933)
			(xy 346.073712 -291.930933) (xy 346.073712 -291.880955) (xy 346.081531 -291.831592) (xy 346.096975 -291.78406)
			(xy 346.119665 -291.739528) (xy 346.149041 -291.699095) (xy 346.184381 -291.663755) (xy 346.224814 -291.634379)
			(xy 346.269346 -291.611689) (xy 346.316878 -291.596245) (xy 346.366241 -291.588426) (xy 346.416219 -291.588426)
			(xy 346.465582 -291.596245) (xy 346.513114 -291.611689) (xy 346.557646 -291.634379) (xy 346.598079 -291.663755)
			(xy 346.633419 -291.699095) (xy 346.662795 -291.739528) (xy 346.685485 -291.78406) (xy 346.700929 -291.831592)
			(xy 346.708748 -291.880955) (xy 346.709238 -291.905944) (xy 346.708748 -291.930933) (xy 347.953566 -291.930933)
			(xy 347.953566 -291.880955) (xy 347.961385 -291.831592) (xy 347.976829 -291.78406) (xy 347.999519 -291.739528)
			(xy 348.028895 -291.699095) (xy 348.064235 -291.663755) (xy 348.104668 -291.634379) (xy 348.1492 -291.611689)
			(xy 348.196732 -291.596245) (xy 348.246095 -291.588426) (xy 348.296073 -291.588426) (xy 348.345436 -291.596245)
			(xy 348.392968 -291.611689) (xy 348.4375 -291.634379) (xy 348.477933 -291.663755) (xy 348.513273 -291.699095)
			(xy 348.542649 -291.739528) (xy 348.565339 -291.78406) (xy 348.580783 -291.831592) (xy 348.588602 -291.880955)
			(xy 348.589092 -291.905944) (xy 348.588602 -291.930933) (xy 348.89362 -291.930933) (xy 348.89362 -291.880955)
			(xy 348.901439 -291.831592) (xy 348.916883 -291.78406) (xy 348.939573 -291.739528) (xy 348.968949 -291.699095)
			(xy 349.004289 -291.663755) (xy 349.044722 -291.634379) (xy 349.089254 -291.611689) (xy 349.136786 -291.596245)
			(xy 349.186149 -291.588426) (xy 349.236127 -291.588426) (xy 349.28549 -291.596245) (xy 349.333022 -291.611689)
			(xy 349.377554 -291.634379) (xy 349.417987 -291.663755) (xy 349.453327 -291.699095) (xy 349.482703 -291.739528)
			(xy 349.505393 -291.78406) (xy 349.520837 -291.831592) (xy 349.528656 -291.880955) (xy 349.529146 -291.905944)
			(xy 349.528656 -291.930933) (xy 350.773728 -291.930933) (xy 350.773728 -291.880955) (xy 350.781547 -291.831592)
			(xy 350.796991 -291.78406) (xy 350.819681 -291.739528) (xy 350.849057 -291.699095) (xy 350.884397 -291.663755)
			(xy 350.92483 -291.634379) (xy 350.969362 -291.611689) (xy 351.016894 -291.596245) (xy 351.066257 -291.588426)
			(xy 351.116235 -291.588426) (xy 351.165598 -291.596245) (xy 351.21313 -291.611689) (xy 351.257662 -291.634379)
			(xy 351.298095 -291.663755) (xy 351.333435 -291.699095) (xy 351.362811 -291.739528) (xy 351.385501 -291.78406)
			(xy 351.400945 -291.831592) (xy 351.408764 -291.880955) (xy 351.409254 -291.905944) (xy 351.408764 -291.930933)
			(xy 351.713528 -291.930933) (xy 351.713528 -291.880955) (xy 351.721347 -291.831592) (xy 351.736791 -291.78406)
			(xy 351.759481 -291.739528) (xy 351.788857 -291.699095) (xy 351.824197 -291.663755) (xy 351.86463 -291.634379)
			(xy 351.909162 -291.611689) (xy 351.956694 -291.596245) (xy 352.006057 -291.588426) (xy 352.056035 -291.588426)
			(xy 352.105398 -291.596245) (xy 352.15293 -291.611689) (xy 352.197462 -291.634379) (xy 352.237895 -291.663755)
			(xy 352.273235 -291.699095) (xy 352.302611 -291.739528) (xy 352.325301 -291.78406) (xy 352.340745 -291.831592)
			(xy 352.348564 -291.880955) (xy 352.349054 -291.905944) (xy 352.348564 -291.930933) (xy 353.593636 -291.930933)
			(xy 353.593636 -291.880955) (xy 353.601455 -291.831592) (xy 353.616899 -291.78406) (xy 353.639589 -291.739528)
			(xy 353.668965 -291.699095) (xy 353.704305 -291.663755) (xy 353.744738 -291.634379) (xy 353.78927 -291.611689)
			(xy 353.836802 -291.596245) (xy 353.886165 -291.588426) (xy 353.936143 -291.588426) (xy 353.985506 -291.596245)
			(xy 354.033038 -291.611689) (xy 354.07757 -291.634379) (xy 354.118003 -291.663755) (xy 354.153343 -291.699095)
			(xy 354.182719 -291.739528) (xy 354.205409 -291.78406) (xy 354.220853 -291.831592) (xy 354.228672 -291.880955)
			(xy 354.229162 -291.905944) (xy 354.228672 -291.930933) (xy 354.53369 -291.930933) (xy 354.53369 -291.880955)
			(xy 354.541509 -291.831592) (xy 354.556953 -291.78406) (xy 354.579643 -291.739528) (xy 354.609019 -291.699095)
			(xy 354.644359 -291.663755) (xy 354.684792 -291.634379) (xy 354.729324 -291.611689) (xy 354.776856 -291.596245)
			(xy 354.826219 -291.588426) (xy 354.876197 -291.588426) (xy 354.92556 -291.596245) (xy 354.973092 -291.611689)
			(xy 355.017624 -291.634379) (xy 355.058057 -291.663755) (xy 355.093397 -291.699095) (xy 355.122773 -291.739528)
			(xy 355.145463 -291.78406) (xy 355.160907 -291.831592) (xy 355.168726 -291.880955) (xy 355.169216 -291.905944)
			(xy 355.168726 -291.930933) (xy 356.413544 -291.930933) (xy 356.413544 -291.880955) (xy 356.421363 -291.831592)
			(xy 356.436807 -291.78406) (xy 356.459497 -291.739528) (xy 356.488873 -291.699095) (xy 356.524213 -291.663755)
			(xy 356.564646 -291.634379) (xy 356.609178 -291.611689) (xy 356.65671 -291.596245) (xy 356.706073 -291.588426)
			(xy 356.756051 -291.588426) (xy 356.805414 -291.596245) (xy 356.852946 -291.611689) (xy 356.897478 -291.634379)
			(xy 356.937911 -291.663755) (xy 356.973251 -291.699095) (xy 357.002627 -291.739528) (xy 357.025317 -291.78406)
			(xy 357.040761 -291.831592) (xy 357.04858 -291.880955) (xy 357.04907 -291.905944) (xy 357.04858 -291.930933)
			(xy 357.353598 -291.930933) (xy 357.353598 -291.880955) (xy 357.361417 -291.831592) (xy 357.376861 -291.78406)
			(xy 357.399551 -291.739528) (xy 357.428927 -291.699095) (xy 357.464267 -291.663755) (xy 357.5047 -291.634379)
			(xy 357.549232 -291.611689) (xy 357.596764 -291.596245) (xy 357.646127 -291.588426) (xy 357.696105 -291.588426)
			(xy 357.745468 -291.596245) (xy 357.793 -291.611689) (xy 357.837532 -291.634379) (xy 357.877965 -291.663755)
			(xy 357.913305 -291.699095) (xy 357.942681 -291.739528) (xy 357.965371 -291.78406) (xy 357.980815 -291.831592)
			(xy 357.988634 -291.880955) (xy 357.989124 -291.905944) (xy 357.988634 -291.930933) (xy 358.293652 -291.930933)
			(xy 358.293652 -291.880955) (xy 358.301471 -291.831592) (xy 358.316915 -291.78406) (xy 358.339605 -291.739528)
			(xy 358.368981 -291.699095) (xy 358.404321 -291.663755) (xy 358.444754 -291.634379) (xy 358.489286 -291.611689)
			(xy 358.536818 -291.596245) (xy 358.586181 -291.588426) (xy 358.636159 -291.588426) (xy 358.685522 -291.596245)
			(xy 358.733054 -291.611689) (xy 358.777586 -291.634379) (xy 358.818019 -291.663755) (xy 358.853359 -291.699095)
			(xy 358.882735 -291.739528) (xy 358.905425 -291.78406) (xy 358.920869 -291.831592) (xy 358.928688 -291.880955)
			(xy 358.929178 -291.905944) (xy 358.928688 -291.930933) (xy 361.10721 -291.930933) (xy 361.10721 -291.880955)
			(xy 361.115029 -291.831592) (xy 361.130473 -291.78406) (xy 361.153163 -291.739528) (xy 361.182539 -291.699095)
			(xy 361.217879 -291.663755) (xy 361.258312 -291.634379) (xy 361.302844 -291.611689) (xy 361.350376 -291.596245)
			(xy 361.399739 -291.588426) (xy 361.449717 -291.588426) (xy 361.49908 -291.596245) (xy 361.546612 -291.611689)
			(xy 361.591144 -291.634379) (xy 361.631577 -291.663755) (xy 361.666917 -291.699095) (xy 361.696293 -291.739528)
			(xy 361.718983 -291.78406) (xy 361.734427 -291.831592) (xy 361.742246 -291.880955) (xy 361.742736 -291.905944)
			(xy 361.742246 -291.930933) (xy 362.047264 -291.930933) (xy 362.047264 -291.880955) (xy 362.055083 -291.831592)
			(xy 362.070527 -291.78406) (xy 362.093217 -291.739528) (xy 362.122593 -291.699095) (xy 362.157933 -291.663755)
			(xy 362.198366 -291.634379) (xy 362.242898 -291.611689) (xy 362.29043 -291.596245) (xy 362.339793 -291.588426)
			(xy 362.389771 -291.588426) (xy 362.439134 -291.596245) (xy 362.486666 -291.611689) (xy 362.531198 -291.634379)
			(xy 362.571631 -291.663755) (xy 362.606971 -291.699095) (xy 362.636347 -291.739528) (xy 362.659037 -291.78406)
			(xy 362.674481 -291.831592) (xy 362.6823 -291.880955) (xy 362.68279 -291.905944) (xy 362.6823 -291.930933)
			(xy 362.987318 -291.930933) (xy 362.987318 -291.880955) (xy 362.995137 -291.831592) (xy 363.010581 -291.78406)
			(xy 363.033271 -291.739528) (xy 363.062647 -291.699095) (xy 363.097987 -291.663755) (xy 363.13842 -291.634379)
			(xy 363.182952 -291.611689) (xy 363.230484 -291.596245) (xy 363.279847 -291.588426) (xy 363.329825 -291.588426)
			(xy 363.379188 -291.596245) (xy 363.42672 -291.611689) (xy 363.471252 -291.634379) (xy 363.511685 -291.663755)
			(xy 363.547025 -291.699095) (xy 363.576401 -291.739528) (xy 363.599091 -291.78406) (xy 363.614535 -291.831592)
			(xy 363.622354 -291.880955) (xy 363.622844 -291.905944) (xy 363.622354 -291.930933) (xy 364.867172 -291.930933)
			(xy 364.867172 -291.880955) (xy 364.874991 -291.831592) (xy 364.890435 -291.78406) (xy 364.913125 -291.739528)
			(xy 364.942501 -291.699095) (xy 364.977841 -291.663755) (xy 365.018274 -291.634379) (xy 365.062806 -291.611689)
			(xy 365.110338 -291.596245) (xy 365.159701 -291.588426) (xy 365.209679 -291.588426) (xy 365.259042 -291.596245)
			(xy 365.306574 -291.611689) (xy 365.351106 -291.634379) (xy 365.391539 -291.663755) (xy 365.426879 -291.699095)
			(xy 365.456255 -291.739528) (xy 365.478945 -291.78406) (xy 365.494389 -291.831592) (xy 365.502208 -291.880955)
			(xy 365.502698 -291.905944) (xy 365.502208 -291.930933) (xy 365.807226 -291.930933) (xy 365.807226 -291.880955)
			(xy 365.815045 -291.831592) (xy 365.830489 -291.78406) (xy 365.853179 -291.739528) (xy 365.882555 -291.699095)
			(xy 365.917895 -291.663755) (xy 365.958328 -291.634379) (xy 366.00286 -291.611689) (xy 366.050392 -291.596245)
			(xy 366.099755 -291.588426) (xy 366.149733 -291.588426) (xy 366.199096 -291.596245) (xy 366.246628 -291.611689)
			(xy 366.29116 -291.634379) (xy 366.331593 -291.663755) (xy 366.366933 -291.699095) (xy 366.396309 -291.739528)
			(xy 366.418999 -291.78406) (xy 366.434443 -291.831592) (xy 366.442262 -291.880955) (xy 366.442752 -291.905944)
			(xy 366.442262 -291.930933) (xy 367.687334 -291.930933) (xy 367.687334 -291.880955) (xy 367.695153 -291.831592)
			(xy 367.710597 -291.78406) (xy 367.733287 -291.739528) (xy 367.762663 -291.699095) (xy 367.798003 -291.663755)
			(xy 367.838436 -291.634379) (xy 367.882968 -291.611689) (xy 367.9305 -291.596245) (xy 367.979863 -291.588426)
			(xy 368.029841 -291.588426) (xy 368.079204 -291.596245) (xy 368.126736 -291.611689) (xy 368.171268 -291.634379)
			(xy 368.211701 -291.663755) (xy 368.247041 -291.699095) (xy 368.276417 -291.739528) (xy 368.299107 -291.78406)
			(xy 368.314551 -291.831592) (xy 368.32237 -291.880955) (xy 368.32286 -291.905944) (xy 368.32237 -291.930933)
			(xy 368.627388 -291.930933) (xy 368.627388 -291.880955) (xy 368.635207 -291.831592) (xy 368.650651 -291.78406)
			(xy 368.673341 -291.739528) (xy 368.702717 -291.699095) (xy 368.738057 -291.663755) (xy 368.77849 -291.634379)
			(xy 368.823022 -291.611689) (xy 368.870554 -291.596245) (xy 368.919917 -291.588426) (xy 368.969895 -291.588426)
			(xy 369.019258 -291.596245) (xy 369.06679 -291.611689) (xy 369.111322 -291.634379) (xy 369.151755 -291.663755)
			(xy 369.187095 -291.699095) (xy 369.216471 -291.739528) (xy 369.239161 -291.78406) (xy 369.254605 -291.831592)
			(xy 369.262424 -291.880955) (xy 369.262914 -291.905944) (xy 369.262424 -291.930933) (xy 369.254605 -291.980296)
			(xy 369.239161 -292.027828) (xy 369.216471 -292.07236) (xy 369.187095 -292.112793) (xy 369.151755 -292.148133)
			(xy 369.111322 -292.177509) (xy 369.06679 -292.200199) (xy 369.019258 -292.215643) (xy 368.969895 -292.223462)
			(xy 368.919917 -292.223462) (xy 368.870554 -292.215643) (xy 368.823022 -292.200199) (xy 368.77849 -292.177509)
			(xy 368.738057 -292.148133) (xy 368.702717 -292.112793) (xy 368.673341 -292.07236) (xy 368.650651 -292.027828)
			(xy 368.635207 -291.980296) (xy 368.627388 -291.930933) (xy 368.32237 -291.930933) (xy 368.314551 -291.980296)
			(xy 368.299107 -292.027828) (xy 368.276417 -292.07236) (xy 368.247041 -292.112793) (xy 368.211701 -292.148133)
			(xy 368.171268 -292.177509) (xy 368.126736 -292.200199) (xy 368.079204 -292.215643) (xy 368.029841 -292.223462)
			(xy 367.979863 -292.223462) (xy 367.9305 -292.215643) (xy 367.882968 -292.200199) (xy 367.838436 -292.177509)
			(xy 367.798003 -292.148133) (xy 367.762663 -292.112793) (xy 367.733287 -292.07236) (xy 367.710597 -292.027828)
			(xy 367.695153 -291.980296) (xy 367.687334 -291.930933) (xy 366.442262 -291.930933) (xy 366.434443 -291.980296)
			(xy 366.418999 -292.027828) (xy 366.396309 -292.07236) (xy 366.366933 -292.112793) (xy 366.331593 -292.148133)
			(xy 366.29116 -292.177509) (xy 366.246628 -292.200199) (xy 366.199096 -292.215643) (xy 366.149733 -292.223462)
			(xy 366.099755 -292.223462) (xy 366.050392 -292.215643) (xy 366.00286 -292.200199) (xy 365.958328 -292.177509)
			(xy 365.917895 -292.148133) (xy 365.882555 -292.112793) (xy 365.853179 -292.07236) (xy 365.830489 -292.027828)
			(xy 365.815045 -291.980296) (xy 365.807226 -291.930933) (xy 365.502208 -291.930933) (xy 365.494389 -291.980296)
			(xy 365.478945 -292.027828) (xy 365.456255 -292.07236) (xy 365.426879 -292.112793) (xy 365.391539 -292.148133)
			(xy 365.351106 -292.177509) (xy 365.306574 -292.200199) (xy 365.259042 -292.215643) (xy 365.209679 -292.223462)
			(xy 365.159701 -292.223462) (xy 365.110338 -292.215643) (xy 365.062806 -292.200199) (xy 365.018274 -292.177509)
			(xy 364.977841 -292.148133) (xy 364.942501 -292.112793) (xy 364.913125 -292.07236) (xy 364.890435 -292.027828)
			(xy 364.874991 -291.980296) (xy 364.867172 -291.930933) (xy 363.622354 -291.930933) (xy 363.614535 -291.980296)
			(xy 363.599091 -292.027828) (xy 363.576401 -292.07236) (xy 363.547025 -292.112793) (xy 363.511685 -292.148133)
			(xy 363.471252 -292.177509) (xy 363.42672 -292.200199) (xy 363.379188 -292.215643) (xy 363.329825 -292.223462)
			(xy 363.279847 -292.223462) (xy 363.230484 -292.215643) (xy 363.182952 -292.200199) (xy 363.13842 -292.177509)
			(xy 363.097987 -292.148133) (xy 363.062647 -292.112793) (xy 363.033271 -292.07236) (xy 363.010581 -292.027828)
			(xy 362.995137 -291.980296) (xy 362.987318 -291.930933) (xy 362.6823 -291.930933) (xy 362.674481 -291.980296)
			(xy 362.659037 -292.027828) (xy 362.636347 -292.07236) (xy 362.606971 -292.112793) (xy 362.571631 -292.148133)
			(xy 362.531198 -292.177509) (xy 362.486666 -292.200199) (xy 362.439134 -292.215643) (xy 362.389771 -292.223462)
			(xy 362.339793 -292.223462) (xy 362.29043 -292.215643) (xy 362.242898 -292.200199) (xy 362.198366 -292.177509)
			(xy 362.157933 -292.148133) (xy 362.122593 -292.112793) (xy 362.093217 -292.07236) (xy 362.070527 -292.027828)
			(xy 362.055083 -291.980296) (xy 362.047264 -291.930933) (xy 361.742246 -291.930933) (xy 361.734427 -291.980296)
			(xy 361.718983 -292.027828) (xy 361.696293 -292.07236) (xy 361.666917 -292.112793) (xy 361.631577 -292.148133)
			(xy 361.591144 -292.177509) (xy 361.546612 -292.200199) (xy 361.49908 -292.215643) (xy 361.449717 -292.223462)
			(xy 361.399739 -292.223462) (xy 361.350376 -292.215643) (xy 361.302844 -292.200199) (xy 361.258312 -292.177509)
			(xy 361.217879 -292.148133) (xy 361.182539 -292.112793) (xy 361.153163 -292.07236) (xy 361.130473 -292.027828)
			(xy 361.115029 -291.980296) (xy 361.10721 -291.930933) (xy 358.928688 -291.930933) (xy 358.920869 -291.980296)
			(xy 358.905425 -292.027828) (xy 358.882735 -292.07236) (xy 358.853359 -292.112793) (xy 358.818019 -292.148133)
			(xy 358.777586 -292.177509) (xy 358.733054 -292.200199) (xy 358.685522 -292.215643) (xy 358.636159 -292.223462)
			(xy 358.586181 -292.223462) (xy 358.536818 -292.215643) (xy 358.489286 -292.200199) (xy 358.444754 -292.177509)
			(xy 358.404321 -292.148133) (xy 358.368981 -292.112793) (xy 358.339605 -292.07236) (xy 358.316915 -292.027828)
			(xy 358.301471 -291.980296) (xy 358.293652 -291.930933) (xy 357.988634 -291.930933) (xy 357.980815 -291.980296)
			(xy 357.965371 -292.027828) (xy 357.942681 -292.07236) (xy 357.913305 -292.112793) (xy 357.877965 -292.148133)
			(xy 357.837532 -292.177509) (xy 357.793 -292.200199) (xy 357.745468 -292.215643) (xy 357.696105 -292.223462)
			(xy 357.646127 -292.223462) (xy 357.596764 -292.215643) (xy 357.549232 -292.200199) (xy 357.5047 -292.177509)
			(xy 357.464267 -292.148133) (xy 357.428927 -292.112793) (xy 357.399551 -292.07236) (xy 357.376861 -292.027828)
			(xy 357.361417 -291.980296) (xy 357.353598 -291.930933) (xy 357.04858 -291.930933) (xy 357.040761 -291.980296)
			(xy 357.025317 -292.027828) (xy 357.002627 -292.07236) (xy 356.973251 -292.112793) (xy 356.937911 -292.148133)
			(xy 356.897478 -292.177509) (xy 356.852946 -292.200199) (xy 356.805414 -292.215643) (xy 356.756051 -292.223462)
			(xy 356.706073 -292.223462) (xy 356.65671 -292.215643) (xy 356.609178 -292.200199) (xy 356.564646 -292.177509)
			(xy 356.524213 -292.148133) (xy 356.488873 -292.112793) (xy 356.459497 -292.07236) (xy 356.436807 -292.027828)
			(xy 356.421363 -291.980296) (xy 356.413544 -291.930933) (xy 355.168726 -291.930933) (xy 355.160907 -291.980296)
			(xy 355.145463 -292.027828) (xy 355.122773 -292.07236) (xy 355.093397 -292.112793) (xy 355.058057 -292.148133)
			(xy 355.017624 -292.177509) (xy 354.973092 -292.200199) (xy 354.92556 -292.215643) (xy 354.876197 -292.223462)
			(xy 354.826219 -292.223462) (xy 354.776856 -292.215643) (xy 354.729324 -292.200199) (xy 354.684792 -292.177509)
			(xy 354.644359 -292.148133) (xy 354.609019 -292.112793) (xy 354.579643 -292.07236) (xy 354.556953 -292.027828)
			(xy 354.541509 -291.980296) (xy 354.53369 -291.930933) (xy 354.228672 -291.930933) (xy 354.220853 -291.980296)
			(xy 354.205409 -292.027828) (xy 354.182719 -292.07236) (xy 354.153343 -292.112793) (xy 354.118003 -292.148133)
			(xy 354.07757 -292.177509) (xy 354.033038 -292.200199) (xy 353.985506 -292.215643) (xy 353.936143 -292.223462)
			(xy 353.886165 -292.223462) (xy 353.836802 -292.215643) (xy 353.78927 -292.200199) (xy 353.744738 -292.177509)
			(xy 353.704305 -292.148133) (xy 353.668965 -292.112793) (xy 353.639589 -292.07236) (xy 353.616899 -292.027828)
			(xy 353.601455 -291.980296) (xy 353.593636 -291.930933) (xy 352.348564 -291.930933) (xy 352.340745 -291.980296)
			(xy 352.325301 -292.027828) (xy 352.302611 -292.07236) (xy 352.273235 -292.112793) (xy 352.237895 -292.148133)
			(xy 352.197462 -292.177509) (xy 352.15293 -292.200199) (xy 352.105398 -292.215643) (xy 352.056035 -292.223462)
			(xy 352.006057 -292.223462) (xy 351.956694 -292.215643) (xy 351.909162 -292.200199) (xy 351.86463 -292.177509)
			(xy 351.824197 -292.148133) (xy 351.788857 -292.112793) (xy 351.759481 -292.07236) (xy 351.736791 -292.027828)
			(xy 351.721347 -291.980296) (xy 351.713528 -291.930933) (xy 351.408764 -291.930933) (xy 351.400945 -291.980296)
			(xy 351.385501 -292.027828) (xy 351.362811 -292.07236) (xy 351.333435 -292.112793) (xy 351.298095 -292.148133)
			(xy 351.257662 -292.177509) (xy 351.21313 -292.200199) (xy 351.165598 -292.215643) (xy 351.116235 -292.223462)
			(xy 351.066257 -292.223462) (xy 351.016894 -292.215643) (xy 350.969362 -292.200199) (xy 350.92483 -292.177509)
			(xy 350.884397 -292.148133) (xy 350.849057 -292.112793) (xy 350.819681 -292.07236) (xy 350.796991 -292.027828)
			(xy 350.781547 -291.980296) (xy 350.773728 -291.930933) (xy 349.528656 -291.930933) (xy 349.520837 -291.980296)
			(xy 349.505393 -292.027828) (xy 349.482703 -292.07236) (xy 349.453327 -292.112793) (xy 349.417987 -292.148133)
			(xy 349.377554 -292.177509) (xy 349.333022 -292.200199) (xy 349.28549 -292.215643) (xy 349.236127 -292.223462)
			(xy 349.186149 -292.223462) (xy 349.136786 -292.215643) (xy 349.089254 -292.200199) (xy 349.044722 -292.177509)
			(xy 349.004289 -292.148133) (xy 348.968949 -292.112793) (xy 348.939573 -292.07236) (xy 348.916883 -292.027828)
			(xy 348.901439 -291.980296) (xy 348.89362 -291.930933) (xy 348.588602 -291.930933) (xy 348.580783 -291.980296)
			(xy 348.565339 -292.027828) (xy 348.542649 -292.07236) (xy 348.513273 -292.112793) (xy 348.477933 -292.148133)
			(xy 348.4375 -292.177509) (xy 348.392968 -292.200199) (xy 348.345436 -292.215643) (xy 348.296073 -292.223462)
			(xy 348.246095 -292.223462) (xy 348.196732 -292.215643) (xy 348.1492 -292.200199) (xy 348.104668 -292.177509)
			(xy 348.064235 -292.148133) (xy 348.028895 -292.112793) (xy 347.999519 -292.07236) (xy 347.976829 -292.027828)
			(xy 347.961385 -291.980296) (xy 347.953566 -291.930933) (xy 346.708748 -291.930933) (xy 346.700929 -291.980296)
			(xy 346.685485 -292.027828) (xy 346.662795 -292.07236) (xy 346.633419 -292.112793) (xy 346.598079 -292.148133)
			(xy 346.557646 -292.177509) (xy 346.513114 -292.200199) (xy 346.465582 -292.215643) (xy 346.416219 -292.223462)
			(xy 346.366241 -292.223462) (xy 346.316878 -292.215643) (xy 346.269346 -292.200199) (xy 346.224814 -292.177509)
			(xy 346.184381 -292.148133) (xy 346.149041 -292.112793) (xy 346.119665 -292.07236) (xy 346.096975 -292.027828)
			(xy 346.081531 -291.980296) (xy 346.073712 -291.930933) (xy 345.768694 -291.930933) (xy 345.760875 -291.980296)
			(xy 345.745431 -292.027828) (xy 345.722741 -292.07236) (xy 345.693365 -292.112793) (xy 345.658025 -292.148133)
			(xy 345.617592 -292.177509) (xy 345.57306 -292.200199) (xy 345.525528 -292.215643) (xy 345.476165 -292.223462)
			(xy 345.426187 -292.223462) (xy 345.376824 -292.215643) (xy 345.329292 -292.200199) (xy 345.28476 -292.177509)
			(xy 345.244327 -292.148133) (xy 345.208987 -292.112793) (xy 345.179611 -292.07236) (xy 345.156921 -292.027828)
			(xy 345.141477 -291.980296) (xy 345.133658 -291.930933) (xy 343.886287 -291.930933) (xy 343.886278 -291.93139)
			(xy 343.878114 -291.981624) (xy 343.861998 -292.029898) (xy 343.838347 -292.074961) (xy 343.807774 -292.115647)
			(xy 343.77107 -292.150902) (xy 343.729186 -292.179812) (xy 343.683207 -292.201629) (xy 343.634323 -292.215789)
			(xy 343.583802 -292.221923) (xy 343.53295 -292.219874) (xy 343.483086 -292.209694) (xy 343.4355 -292.191647)
			(xy 343.391426 -292.166201) (xy 343.352004 -292.134014) (xy 343.318256 -292.09592) (xy 343.291055 -292.052906)
			(xy 343.271107 -292.006086) (xy 343.258928 -291.956672) (xy 343.254833 -291.905944) (xy 342.957912 -291.905944)
			(xy 342.957405 -291.93163) (xy 342.949363 -291.982368) (xy 342.933483 -292.031225) (xy 342.910157 -292.076995)
			(xy 342.879959 -292.118554) (xy 342.843631 -292.154878) (xy 342.80207 -292.185073) (xy 342.756297 -292.208395)
			(xy 342.707439 -292.22427) (xy 342.6567 -292.232307) (xy 342.631014 -292.232842) (xy 342.605317 -292.232339)
			(xy 342.554554 -292.224302) (xy 342.505674 -292.208423) (xy 342.459879 -292.185094) (xy 342.418297 -292.154888)
			(xy 342.381952 -292.11855) (xy 342.351739 -292.076974) (xy 342.339676 -292.05428) (xy 342.337898 -292.050978)
			(xy 342.332037 -292.042325) (xy 342.314985 -292.030277) (xy 342.304878 -292.02761) (xy 342.256872 -292.020244)
			(xy 342.256364 -292.020244) (xy 342.232234 -292.016434) (xy 342.220771 -292.015649) (xy 342.199096 -292.023199)
			(xy 342.190578 -292.030912) (xy 341.553546 -292.667944) (xy 341.549917 -292.671771) (xy 341.544163 -292.680609)
			(xy 341.542116 -292.68547) (xy 341.538306 -292.695122) (xy 341.539068 -292.715442) (xy 341.539068 -292.71595)
			(xy 341.844879 -292.71595) (xy 341.848974 -292.665222) (xy 341.861153 -292.615808) (xy 341.881101 -292.568988)
			(xy 341.908302 -292.525974) (xy 341.94205 -292.48788) (xy 341.981472 -292.455693) (xy 342.025546 -292.430247)
			(xy 342.073132 -292.4122) (xy 342.122996 -292.40202) (xy 342.173848 -292.399971) (xy 342.224369 -292.406105)
			(xy 342.273253 -292.420265) (xy 342.319232 -292.442082) (xy 342.361116 -292.470992) (xy 342.39782 -292.506247)
			(xy 342.428393 -292.546933) (xy 342.452044 -292.591996) (xy 342.46816 -292.64027) (xy 342.476324 -292.690504)
			(xy 342.476836 -292.71595) (xy 342.476333 -292.740939) (xy 342.78365 -292.740939) (xy 342.78365 -292.690961)
			(xy 342.791469 -292.641598) (xy 342.806913 -292.594066) (xy 342.829603 -292.549534) (xy 342.858979 -292.509101)
			(xy 342.894319 -292.473761) (xy 342.934752 -292.444385) (xy 342.979284 -292.421695) (xy 343.026816 -292.406251)
			(xy 343.076179 -292.398432) (xy 343.126157 -292.398432) (xy 343.17552 -292.406251) (xy 343.223052 -292.421695)
			(xy 343.267584 -292.444385) (xy 343.308017 -292.473761) (xy 343.343357 -292.509101) (xy 343.372733 -292.549534)
			(xy 343.395423 -292.594066) (xy 343.410867 -292.641598) (xy 343.418686 -292.690961) (xy 343.419176 -292.71595)
			(xy 343.724987 -292.71595) (xy 343.729082 -292.665222) (xy 343.741261 -292.615808) (xy 343.761209 -292.568988)
			(xy 343.78841 -292.525974) (xy 343.822158 -292.48788) (xy 343.86158 -292.455693) (xy 343.905654 -292.430247)
			(xy 343.95324 -292.4122) (xy 344.003104 -292.40202) (xy 344.053956 -292.399971) (xy 344.104477 -292.406105)
			(xy 344.153361 -292.420265) (xy 344.19934 -292.442082) (xy 344.241224 -292.470992) (xy 344.277928 -292.506247)
			(xy 344.308501 -292.546933) (xy 344.332152 -292.591996) (xy 344.348268 -292.64027) (xy 344.356432 -292.690504)
			(xy 344.356944 -292.71595) (xy 345.604841 -292.71595) (xy 345.608936 -292.665222) (xy 345.621115 -292.615808)
			(xy 345.641063 -292.568988) (xy 345.668264 -292.525974) (xy 345.702012 -292.48788) (xy 345.741434 -292.455693)
			(xy 345.785508 -292.430247) (xy 345.833094 -292.4122) (xy 345.882958 -292.40202) (xy 345.93381 -292.399971)
			(xy 345.984331 -292.406105) (xy 346.033215 -292.420265) (xy 346.079194 -292.442082) (xy 346.121078 -292.470992)
			(xy 346.157782 -292.506247) (xy 346.188355 -292.546933) (xy 346.212006 -292.591996) (xy 346.228122 -292.64027)
			(xy 346.236286 -292.690504) (xy 346.236798 -292.71595) (xy 346.544895 -292.71595) (xy 346.54899 -292.665222)
			(xy 346.561169 -292.615808) (xy 346.581117 -292.568988) (xy 346.608318 -292.525974) (xy 346.642066 -292.48788)
			(xy 346.681488 -292.455693) (xy 346.725562 -292.430247) (xy 346.773148 -292.4122) (xy 346.823012 -292.40202)
			(xy 346.873864 -292.399971) (xy 346.924385 -292.406105) (xy 346.973269 -292.420265) (xy 347.019248 -292.442082)
			(xy 347.061132 -292.470992) (xy 347.097836 -292.506247) (xy 347.128409 -292.546933) (xy 347.15206 -292.591996)
			(xy 347.168176 -292.64027) (xy 347.17634 -292.690504) (xy 347.176852 -292.71595) (xy 348.425003 -292.71595)
			(xy 348.429098 -292.665222) (xy 348.441277 -292.615808) (xy 348.461225 -292.568988) (xy 348.488426 -292.525974)
			(xy 348.522174 -292.48788) (xy 348.561596 -292.455693) (xy 348.60567 -292.430247) (xy 348.653256 -292.4122)
			(xy 348.70312 -292.40202) (xy 348.753972 -292.399971) (xy 348.804493 -292.406105) (xy 348.853377 -292.420265)
			(xy 348.899356 -292.442082) (xy 348.94124 -292.470992) (xy 348.977944 -292.506247) (xy 349.008517 -292.546933)
			(xy 349.032168 -292.591996) (xy 349.048284 -292.64027) (xy 349.056448 -292.690504) (xy 349.05696 -292.71595)
			(xy 349.364803 -292.71595) (xy 349.368898 -292.665222) (xy 349.381077 -292.615808) (xy 349.401025 -292.568988)
			(xy 349.428226 -292.525974) (xy 349.461974 -292.48788) (xy 349.501396 -292.455693) (xy 349.54547 -292.430247)
			(xy 349.593056 -292.4122) (xy 349.64292 -292.40202) (xy 349.693772 -292.399971) (xy 349.744293 -292.406105)
			(xy 349.793177 -292.420265) (xy 349.839156 -292.442082) (xy 349.88104 -292.470992) (xy 349.917744 -292.506247)
			(xy 349.948317 -292.546933) (xy 349.971968 -292.591996) (xy 349.988084 -292.64027) (xy 349.996248 -292.690504)
			(xy 349.99676 -292.71595) (xy 351.244911 -292.71595) (xy 351.249006 -292.665222) (xy 351.261185 -292.615808)
			(xy 351.281133 -292.568988) (xy 351.308334 -292.525974) (xy 351.342082 -292.48788) (xy 351.381504 -292.455693)
			(xy 351.425578 -292.430247) (xy 351.473164 -292.4122) (xy 351.523028 -292.40202) (xy 351.57388 -292.399971)
			(xy 351.624401 -292.406105) (xy 351.673285 -292.420265) (xy 351.719264 -292.442082) (xy 351.761148 -292.470992)
			(xy 351.797852 -292.506247) (xy 351.828425 -292.546933) (xy 351.852076 -292.591996) (xy 351.868192 -292.64027)
			(xy 351.876356 -292.690504) (xy 351.876868 -292.71595) (xy 352.184965 -292.71595) (xy 352.18906 -292.665222)
			(xy 352.201239 -292.615808) (xy 352.221187 -292.568988) (xy 352.248388 -292.525974) (xy 352.282136 -292.48788)
			(xy 352.321558 -292.455693) (xy 352.365632 -292.430247) (xy 352.413218 -292.4122) (xy 352.463082 -292.40202)
			(xy 352.513934 -292.399971) (xy 352.564455 -292.406105) (xy 352.613339 -292.420265) (xy 352.659318 -292.442082)
			(xy 352.701202 -292.470992) (xy 352.737906 -292.506247) (xy 352.768479 -292.546933) (xy 352.79213 -292.591996)
			(xy 352.808246 -292.64027) (xy 352.81641 -292.690504) (xy 352.816922 -292.71595) (xy 354.064819 -292.71595)
			(xy 354.068914 -292.665222) (xy 354.081093 -292.615808) (xy 354.101041 -292.568988) (xy 354.128242 -292.525974)
			(xy 354.16199 -292.48788) (xy 354.201412 -292.455693) (xy 354.245486 -292.430247) (xy 354.293072 -292.4122)
			(xy 354.342936 -292.40202) (xy 354.393788 -292.399971) (xy 354.444309 -292.406105) (xy 354.493193 -292.420265)
			(xy 354.539172 -292.442082) (xy 354.581056 -292.470992) (xy 354.61776 -292.506247) (xy 354.648333 -292.546933)
			(xy 354.671984 -292.591996) (xy 354.6881 -292.64027) (xy 354.696264 -292.690504) (xy 354.696776 -292.71595)
			(xy 355.004873 -292.71595) (xy 355.008968 -292.665222) (xy 355.021147 -292.615808) (xy 355.041095 -292.568988)
			(xy 355.068296 -292.525974) (xy 355.102044 -292.48788) (xy 355.141466 -292.455693) (xy 355.18554 -292.430247)
			(xy 355.233126 -292.4122) (xy 355.28299 -292.40202) (xy 355.333842 -292.399971) (xy 355.384363 -292.406105)
			(xy 355.433247 -292.420265) (xy 355.479226 -292.442082) (xy 355.52111 -292.470992) (xy 355.557814 -292.506247)
			(xy 355.588387 -292.546933) (xy 355.612038 -292.591996) (xy 355.628154 -292.64027) (xy 355.636318 -292.690504)
			(xy 355.63683 -292.71595) (xy 355.636318 -292.741396) (xy 355.628154 -292.79163) (xy 355.612038 -292.839904)
			(xy 355.588387 -292.884967) (xy 355.557814 -292.925653) (xy 355.52111 -292.960908) (xy 355.479226 -292.989818)
			(xy 355.433247 -293.011635) (xy 355.384363 -293.025795) (xy 355.333842 -293.031929) (xy 355.28299 -293.02988)
			(xy 355.233126 -293.0197) (xy 355.18554 -293.001653) (xy 355.141466 -292.976207) (xy 355.102044 -292.94402)
			(xy 355.068296 -292.905926) (xy 355.041095 -292.862912) (xy 355.021147 -292.816092) (xy 355.008968 -292.766678)
			(xy 355.004873 -292.71595) (xy 354.696776 -292.71595) (xy 354.696264 -292.741396) (xy 354.6881 -292.79163)
			(xy 354.671984 -292.839904) (xy 354.648333 -292.884967) (xy 354.61776 -292.925653) (xy 354.581056 -292.960908)
			(xy 354.539172 -292.989818) (xy 354.493193 -293.011635) (xy 354.444309 -293.025795) (xy 354.393788 -293.031929)
			(xy 354.342936 -293.02988) (xy 354.293072 -293.0197) (xy 354.245486 -293.001653) (xy 354.201412 -292.976207)
			(xy 354.16199 -292.94402) (xy 354.128242 -292.905926) (xy 354.101041 -292.862912) (xy 354.081093 -292.816092)
			(xy 354.068914 -292.766678) (xy 354.064819 -292.71595) (xy 352.816922 -292.71595) (xy 352.81641 -292.741396)
			(xy 352.808246 -292.79163) (xy 352.79213 -292.839904) (xy 352.768479 -292.884967) (xy 352.737906 -292.925653)
			(xy 352.701202 -292.960908) (xy 352.659318 -292.989818) (xy 352.613339 -293.011635) (xy 352.564455 -293.025795)
			(xy 352.513934 -293.031929) (xy 352.463082 -293.02988) (xy 352.413218 -293.0197) (xy 352.365632 -293.001653)
			(xy 352.321558 -292.976207) (xy 352.282136 -292.94402) (xy 352.248388 -292.905926) (xy 352.221187 -292.862912)
			(xy 352.201239 -292.816092) (xy 352.18906 -292.766678) (xy 352.184965 -292.71595) (xy 351.876868 -292.71595)
			(xy 351.876356 -292.741396) (xy 351.868192 -292.79163) (xy 351.852076 -292.839904) (xy 351.828425 -292.884967)
			(xy 351.797852 -292.925653) (xy 351.761148 -292.960908) (xy 351.719264 -292.989818) (xy 351.673285 -293.011635)
			(xy 351.624401 -293.025795) (xy 351.57388 -293.031929) (xy 351.523028 -293.02988) (xy 351.473164 -293.0197)
			(xy 351.425578 -293.001653) (xy 351.381504 -292.976207) (xy 351.342082 -292.94402) (xy 351.308334 -292.905926)
			(xy 351.281133 -292.862912) (xy 351.261185 -292.816092) (xy 351.249006 -292.766678) (xy 351.244911 -292.71595)
			(xy 349.99676 -292.71595) (xy 349.996248 -292.741396) (xy 349.988084 -292.79163) (xy 349.971968 -292.839904)
			(xy 349.948317 -292.884967) (xy 349.917744 -292.925653) (xy 349.88104 -292.960908) (xy 349.839156 -292.989818)
			(xy 349.793177 -293.011635) (xy 349.744293 -293.025795) (xy 349.693772 -293.031929) (xy 349.64292 -293.02988)
			(xy 349.593056 -293.0197) (xy 349.54547 -293.001653) (xy 349.501396 -292.976207) (xy 349.461974 -292.94402)
			(xy 349.428226 -292.905926) (xy 349.401025 -292.862912) (xy 349.381077 -292.816092) (xy 349.368898 -292.766678)
			(xy 349.364803 -292.71595) (xy 349.05696 -292.71595) (xy 349.056448 -292.741396) (xy 349.048284 -292.79163)
			(xy 349.032168 -292.839904) (xy 349.008517 -292.884967) (xy 348.977944 -292.925653) (xy 348.94124 -292.960908)
			(xy 348.899356 -292.989818) (xy 348.853377 -293.011635) (xy 348.804493 -293.025795) (xy 348.753972 -293.031929)
			(xy 348.70312 -293.02988) (xy 348.653256 -293.0197) (xy 348.60567 -293.001653) (xy 348.561596 -292.976207)
			(xy 348.522174 -292.94402) (xy 348.488426 -292.905926) (xy 348.461225 -292.862912) (xy 348.441277 -292.816092)
			(xy 348.429098 -292.766678) (xy 348.425003 -292.71595) (xy 347.176852 -292.71595) (xy 347.17634 -292.741396)
			(xy 347.168176 -292.79163) (xy 347.15206 -292.839904) (xy 347.128409 -292.884967) (xy 347.097836 -292.925653)
			(xy 347.061132 -292.960908) (xy 347.019248 -292.989818) (xy 346.973269 -293.011635) (xy 346.924385 -293.025795)
			(xy 346.873864 -293.031929) (xy 346.823012 -293.02988) (xy 346.773148 -293.0197) (xy 346.725562 -293.001653)
			(xy 346.681488 -292.976207) (xy 346.642066 -292.94402) (xy 346.608318 -292.905926) (xy 346.581117 -292.862912)
			(xy 346.561169 -292.816092) (xy 346.54899 -292.766678) (xy 346.544895 -292.71595) (xy 346.236798 -292.71595)
			(xy 346.236286 -292.741396) (xy 346.228122 -292.79163) (xy 346.212006 -292.839904) (xy 346.188355 -292.884967)
			(xy 346.157782 -292.925653) (xy 346.121078 -292.960908) (xy 346.079194 -292.989818) (xy 346.033215 -293.011635)
			(xy 345.984331 -293.025795) (xy 345.93381 -293.031929) (xy 345.882958 -293.02988) (xy 345.833094 -293.0197)
			(xy 345.785508 -293.001653) (xy 345.741434 -292.976207) (xy 345.702012 -292.94402) (xy 345.668264 -292.905926)
			(xy 345.641063 -292.862912) (xy 345.621115 -292.816092) (xy 345.608936 -292.766678) (xy 345.604841 -292.71595)
			(xy 344.356944 -292.71595) (xy 344.356432 -292.741396) (xy 344.348268 -292.79163) (xy 344.332152 -292.839904)
			(xy 344.308501 -292.884967) (xy 344.277928 -292.925653) (xy 344.241224 -292.960908) (xy 344.19934 -292.989818)
			(xy 344.153361 -293.011635) (xy 344.104477 -293.025795) (xy 344.053956 -293.031929) (xy 344.003104 -293.02988)
			(xy 343.95324 -293.0197) (xy 343.905654 -293.001653) (xy 343.86158 -292.976207) (xy 343.822158 -292.94402)
			(xy 343.78841 -292.905926) (xy 343.761209 -292.862912) (xy 343.741261 -292.816092) (xy 343.729082 -292.766678)
			(xy 343.724987 -292.71595) (xy 343.419176 -292.71595) (xy 343.418686 -292.740939) (xy 343.410867 -292.790302)
			(xy 343.395423 -292.837834) (xy 343.372733 -292.882366) (xy 343.343357 -292.922799) (xy 343.308017 -292.958139)
			(xy 343.267584 -292.987515) (xy 343.223052 -293.010205) (xy 343.17552 -293.025649) (xy 343.126157 -293.033468)
			(xy 343.076179 -293.033468) (xy 343.026816 -293.025649) (xy 342.979284 -293.010205) (xy 342.934752 -292.987515)
			(xy 342.894319 -292.958139) (xy 342.858979 -292.922799) (xy 342.829603 -292.882366) (xy 342.806913 -292.837834)
			(xy 342.791469 -292.790302) (xy 342.78365 -292.740939) (xy 342.476333 -292.740939) (xy 342.476324 -292.741396)
			(xy 342.46816 -292.79163) (xy 342.452044 -292.839904) (xy 342.428393 -292.884967) (xy 342.39782 -292.925653)
			(xy 342.361116 -292.960908) (xy 342.319232 -292.989818) (xy 342.273253 -293.011635) (xy 342.224369 -293.025795)
			(xy 342.173848 -293.031929) (xy 342.122996 -293.02988) (xy 342.073132 -293.0197) (xy 342.025546 -293.001653)
			(xy 341.981472 -292.976207) (xy 341.94205 -292.94402) (xy 341.908302 -292.905926) (xy 341.881101 -292.862912)
			(xy 341.861153 -292.816092) (xy 341.848974 -292.766678) (xy 341.844879 -292.71595) (xy 341.539068 -292.71595)
			(xy 341.539068 -292.716204) (xy 341.538563 -292.741169) (xy 341.530727 -292.790481) (xy 341.51528 -292.837961)
			(xy 341.492601 -292.882444) (xy 341.463248 -292.922835) (xy 341.427943 -292.958142) (xy 341.387552 -292.987496)
			(xy 341.343071 -293.010176) (xy 341.29559 -293.025625) (xy 341.246279 -293.033463) (xy 341.221314 -293.033958)
			(xy 341.220552 -293.033958) (xy 341.210392 -293.033704) (xy 341.205193 -293.033684) (xy 341.194955 -293.035476)
			(xy 341.190072 -293.03726) (xy 341.180674 -293.040816) (xy 341.140796 -293.080694) (xy 341.134251 -293.087946)
			(xy 341.126817 -293.105988) (xy 341.126318 -293.115746) (xy 341.126318 -293.550945) (xy 341.373696 -293.550945)
			(xy 341.373696 -293.500967) (xy 341.381515 -293.451604) (xy 341.396959 -293.404072) (xy 341.419649 -293.35954)
			(xy 341.449025 -293.319107) (xy 341.484365 -293.283767) (xy 341.524798 -293.254391) (xy 341.56933 -293.231701)
			(xy 341.616862 -293.216257) (xy 341.666225 -293.208438) (xy 341.716203 -293.208438) (xy 341.765566 -293.216257)
			(xy 341.813098 -293.231701) (xy 341.85763 -293.254391) (xy 341.898063 -293.283767) (xy 341.933403 -293.319107)
			(xy 341.962779 -293.35954) (xy 341.985469 -293.404072) (xy 342.000913 -293.451604) (xy 342.008732 -293.500967)
			(xy 342.009222 -293.525956) (xy 342.008732 -293.550945) (xy 342.313496 -293.550945) (xy 342.313496 -293.500967)
			(xy 342.321315 -293.451604) (xy 342.336759 -293.404072) (xy 342.359449 -293.35954) (xy 342.388825 -293.319107)
			(xy 342.424165 -293.283767) (xy 342.464598 -293.254391) (xy 342.50913 -293.231701) (xy 342.556662 -293.216257)
			(xy 342.606025 -293.208438) (xy 342.656003 -293.208438) (xy 342.705366 -293.216257) (xy 342.752898 -293.231701)
			(xy 342.79743 -293.254391) (xy 342.837863 -293.283767) (xy 342.873203 -293.319107) (xy 342.902579 -293.35954)
			(xy 342.925269 -293.404072) (xy 342.940713 -293.451604) (xy 342.948532 -293.500967) (xy 342.949022 -293.525956)
			(xy 343.254833 -293.525956) (xy 343.258928 -293.475228) (xy 343.271107 -293.425814) (xy 343.291055 -293.378994)
			(xy 343.318256 -293.33598) (xy 343.352004 -293.297886) (xy 343.391426 -293.265699) (xy 343.4355 -293.240253)
			(xy 343.483086 -293.222206) (xy 343.53295 -293.212026) (xy 343.583802 -293.209977) (xy 343.634323 -293.216111)
			(xy 343.683207 -293.230271) (xy 343.729186 -293.252088) (xy 343.77107 -293.280998) (xy 343.807774 -293.316253)
			(xy 343.838347 -293.356939) (xy 343.861998 -293.402002) (xy 343.878114 -293.450276) (xy 343.886278 -293.50051)
			(xy 343.88679 -293.525956) (xy 343.886287 -293.550945) (xy 344.193604 -293.550945) (xy 344.193604 -293.500967)
			(xy 344.201423 -293.451604) (xy 344.216867 -293.404072) (xy 344.239557 -293.35954) (xy 344.268933 -293.319107)
			(xy 344.304273 -293.283767) (xy 344.344706 -293.254391) (xy 344.389238 -293.231701) (xy 344.43677 -293.216257)
			(xy 344.486133 -293.208438) (xy 344.536111 -293.208438) (xy 344.585474 -293.216257) (xy 344.633006 -293.231701)
			(xy 344.677538 -293.254391) (xy 344.717971 -293.283767) (xy 344.753311 -293.319107) (xy 344.782687 -293.35954)
			(xy 344.805377 -293.404072) (xy 344.820821 -293.451604) (xy 344.82864 -293.500967) (xy 344.82913 -293.525956)
			(xy 344.82864 -293.550945) (xy 345.133658 -293.550945) (xy 345.133658 -293.500967) (xy 345.141477 -293.451604)
			(xy 345.156921 -293.404072) (xy 345.179611 -293.35954) (xy 345.208987 -293.319107) (xy 345.244327 -293.283767)
			(xy 345.28476 -293.254391) (xy 345.329292 -293.231701) (xy 345.376824 -293.216257) (xy 345.426187 -293.208438)
			(xy 345.476165 -293.208438) (xy 345.525528 -293.216257) (xy 345.57306 -293.231701) (xy 345.617592 -293.254391)
			(xy 345.658025 -293.283767) (xy 345.693365 -293.319107) (xy 345.722741 -293.35954) (xy 345.745431 -293.404072)
			(xy 345.760875 -293.451604) (xy 345.768694 -293.500967) (xy 345.769184 -293.525956) (xy 345.768694 -293.550945)
			(xy 346.073712 -293.550945) (xy 346.073712 -293.500967) (xy 346.081531 -293.451604) (xy 346.096975 -293.404072)
			(xy 346.119665 -293.35954) (xy 346.149041 -293.319107) (xy 346.184381 -293.283767) (xy 346.224814 -293.254391)
			(xy 346.269346 -293.231701) (xy 346.316878 -293.216257) (xy 346.366241 -293.208438) (xy 346.416219 -293.208438)
			(xy 346.465582 -293.216257) (xy 346.513114 -293.231701) (xy 346.557646 -293.254391) (xy 346.598079 -293.283767)
			(xy 346.633419 -293.319107) (xy 346.662795 -293.35954) (xy 346.685485 -293.404072) (xy 346.700929 -293.451604)
			(xy 346.708748 -293.500967) (xy 346.709238 -293.525956) (xy 346.708748 -293.550945) (xy 347.013512 -293.550945)
			(xy 347.013512 -293.500967) (xy 347.021331 -293.451604) (xy 347.036775 -293.404072) (xy 347.059465 -293.35954)
			(xy 347.088841 -293.319107) (xy 347.124181 -293.283767) (xy 347.164614 -293.254391) (xy 347.209146 -293.231701)
			(xy 347.256678 -293.216257) (xy 347.306041 -293.208438) (xy 347.356019 -293.208438) (xy 347.405382 -293.216257)
			(xy 347.452914 -293.231701) (xy 347.497446 -293.254391) (xy 347.537879 -293.283767) (xy 347.573219 -293.319107)
			(xy 347.602595 -293.35954) (xy 347.625285 -293.404072) (xy 347.640729 -293.451604) (xy 347.648548 -293.500967)
			(xy 347.649038 -293.525956) (xy 347.648548 -293.550945) (xy 347.953566 -293.550945) (xy 347.953566 -293.500967)
			(xy 347.961385 -293.451604) (xy 347.976829 -293.404072) (xy 347.999519 -293.35954) (xy 348.028895 -293.319107)
			(xy 348.064235 -293.283767) (xy 348.104668 -293.254391) (xy 348.1492 -293.231701) (xy 348.196732 -293.216257)
			(xy 348.246095 -293.208438) (xy 348.296073 -293.208438) (xy 348.345436 -293.216257) (xy 348.392968 -293.231701)
			(xy 348.4375 -293.254391) (xy 348.477933 -293.283767) (xy 348.513273 -293.319107) (xy 348.542649 -293.35954)
			(xy 348.565339 -293.404072) (xy 348.580783 -293.451604) (xy 348.588602 -293.500967) (xy 348.589092 -293.525956)
			(xy 348.588602 -293.550945) (xy 348.89362 -293.550945) (xy 348.89362 -293.500967) (xy 348.901439 -293.451604)
			(xy 348.916883 -293.404072) (xy 348.939573 -293.35954) (xy 348.968949 -293.319107) (xy 349.004289 -293.283767)
			(xy 349.044722 -293.254391) (xy 349.089254 -293.231701) (xy 349.136786 -293.216257) (xy 349.186149 -293.208438)
			(xy 349.236127 -293.208438) (xy 349.28549 -293.216257) (xy 349.333022 -293.231701) (xy 349.377554 -293.254391)
			(xy 349.417987 -293.283767) (xy 349.453327 -293.319107) (xy 349.482703 -293.35954) (xy 349.505393 -293.404072)
			(xy 349.520837 -293.451604) (xy 349.528656 -293.500967) (xy 349.529146 -293.525956) (xy 349.528656 -293.550945)
			(xy 349.833674 -293.550945) (xy 349.833674 -293.500967) (xy 349.841493 -293.451604) (xy 349.856937 -293.404072)
			(xy 349.879627 -293.35954) (xy 349.909003 -293.319107) (xy 349.944343 -293.283767) (xy 349.984776 -293.254391)
			(xy 350.029308 -293.231701) (xy 350.07684 -293.216257) (xy 350.126203 -293.208438) (xy 350.176181 -293.208438)
			(xy 350.225544 -293.216257) (xy 350.273076 -293.231701) (xy 350.317608 -293.254391) (xy 350.358041 -293.283767)
			(xy 350.393381 -293.319107) (xy 350.422757 -293.35954) (xy 350.445447 -293.404072) (xy 350.460891 -293.451604)
			(xy 350.46871 -293.500967) (xy 350.4692 -293.525956) (xy 350.46871 -293.550945) (xy 350.773728 -293.550945)
			(xy 350.773728 -293.500967) (xy 350.781547 -293.451604) (xy 350.796991 -293.404072) (xy 350.819681 -293.35954)
			(xy 350.849057 -293.319107) (xy 350.884397 -293.283767) (xy 350.92483 -293.254391) (xy 350.969362 -293.231701)
			(xy 351.016894 -293.216257) (xy 351.066257 -293.208438) (xy 351.116235 -293.208438) (xy 351.165598 -293.216257)
			(xy 351.21313 -293.231701) (xy 351.257662 -293.254391) (xy 351.298095 -293.283767) (xy 351.333435 -293.319107)
			(xy 351.362811 -293.35954) (xy 351.385501 -293.404072) (xy 351.400945 -293.451604) (xy 351.408764 -293.500967)
			(xy 351.409254 -293.525956) (xy 351.408764 -293.550945) (xy 351.713528 -293.550945) (xy 351.713528 -293.500967)
			(xy 351.721347 -293.451604) (xy 351.736791 -293.404072) (xy 351.759481 -293.35954) (xy 351.788857 -293.319107)
			(xy 351.824197 -293.283767) (xy 351.86463 -293.254391) (xy 351.909162 -293.231701) (xy 351.956694 -293.216257)
			(xy 352.006057 -293.208438) (xy 352.056035 -293.208438) (xy 352.105398 -293.216257) (xy 352.15293 -293.231701)
			(xy 352.197462 -293.254391) (xy 352.237895 -293.283767) (xy 352.273235 -293.319107) (xy 352.302611 -293.35954)
			(xy 352.325301 -293.404072) (xy 352.340745 -293.451604) (xy 352.348564 -293.500967) (xy 352.349054 -293.525956)
			(xy 352.348564 -293.550945) (xy 352.653582 -293.550945) (xy 352.653582 -293.500967) (xy 352.661401 -293.451604)
			(xy 352.676845 -293.404072) (xy 352.699535 -293.35954) (xy 352.728911 -293.319107) (xy 352.764251 -293.283767)
			(xy 352.804684 -293.254391) (xy 352.849216 -293.231701) (xy 352.896748 -293.216257) (xy 352.946111 -293.208438)
			(xy 352.996089 -293.208438) (xy 353.045452 -293.216257) (xy 353.092984 -293.231701) (xy 353.137516 -293.254391)
			(xy 353.177949 -293.283767) (xy 353.213289 -293.319107) (xy 353.242665 -293.35954) (xy 353.265355 -293.404072)
			(xy 353.280799 -293.451604) (xy 353.288618 -293.500967) (xy 353.289108 -293.525956) (xy 353.288618 -293.550945)
			(xy 353.593636 -293.550945) (xy 353.593636 -293.500967) (xy 353.601455 -293.451604) (xy 353.616899 -293.404072)
			(xy 353.639589 -293.35954) (xy 353.668965 -293.319107) (xy 353.704305 -293.283767) (xy 353.744738 -293.254391)
			(xy 353.78927 -293.231701) (xy 353.836802 -293.216257) (xy 353.886165 -293.208438) (xy 353.936143 -293.208438)
			(xy 353.985506 -293.216257) (xy 354.033038 -293.231701) (xy 354.07757 -293.254391) (xy 354.118003 -293.283767)
			(xy 354.153343 -293.319107) (xy 354.182719 -293.35954) (xy 354.205409 -293.404072) (xy 354.220853 -293.451604)
			(xy 354.228672 -293.500967) (xy 354.229162 -293.525956) (xy 354.228672 -293.550945) (xy 354.53369 -293.550945)
			(xy 354.53369 -293.500967) (xy 354.541509 -293.451604) (xy 354.556953 -293.404072) (xy 354.579643 -293.35954)
			(xy 354.609019 -293.319107) (xy 354.644359 -293.283767) (xy 354.684792 -293.254391) (xy 354.729324 -293.231701)
			(xy 354.776856 -293.216257) (xy 354.826219 -293.208438) (xy 354.876197 -293.208438) (xy 354.92556 -293.216257)
			(xy 354.973092 -293.231701) (xy 355.017624 -293.254391) (xy 355.058057 -293.283767) (xy 355.093397 -293.319107)
			(xy 355.122773 -293.35954) (xy 355.145463 -293.404072) (xy 355.160907 -293.451604) (xy 355.168726 -293.500967)
			(xy 355.169216 -293.525956) (xy 355.168726 -293.550945) (xy 355.47349 -293.550945) (xy 355.47349 -293.500967)
			(xy 355.481309 -293.451604) (xy 355.496753 -293.404072) (xy 355.519443 -293.35954) (xy 355.548819 -293.319107)
			(xy 355.584159 -293.283767) (xy 355.624592 -293.254391) (xy 355.669124 -293.231701) (xy 355.716656 -293.216257)
			(xy 355.766019 -293.208438) (xy 355.815997 -293.208438) (xy 355.86536 -293.216257) (xy 355.912892 -293.231701)
			(xy 355.957424 -293.254391) (xy 355.997857 -293.283767) (xy 356.033197 -293.319107) (xy 356.062573 -293.35954)
			(xy 356.085263 -293.404072) (xy 356.100707 -293.451604) (xy 356.108526 -293.500967) (xy 356.109016 -293.525956)
			(xy 356.108526 -293.550945) (xy 356.100707 -293.600308) (xy 356.085263 -293.64784) (xy 356.062573 -293.692372)
			(xy 356.033197 -293.732805) (xy 355.997857 -293.768145) (xy 355.957424 -293.797521) (xy 355.912892 -293.820211)
			(xy 355.86536 -293.835655) (xy 355.815997 -293.843474) (xy 355.766019 -293.843474) (xy 355.716656 -293.835655)
			(xy 355.669124 -293.820211) (xy 355.624592 -293.797521) (xy 355.584159 -293.768145) (xy 355.548819 -293.732805)
			(xy 355.519443 -293.692372) (xy 355.496753 -293.64784) (xy 355.481309 -293.600308) (xy 355.47349 -293.550945)
			(xy 355.168726 -293.550945) (xy 355.160907 -293.600308) (xy 355.145463 -293.64784) (xy 355.122773 -293.692372)
			(xy 355.093397 -293.732805) (xy 355.058057 -293.768145) (xy 355.017624 -293.797521) (xy 354.973092 -293.820211)
			(xy 354.92556 -293.835655) (xy 354.876197 -293.843474) (xy 354.826219 -293.843474) (xy 354.776856 -293.835655)
			(xy 354.729324 -293.820211) (xy 354.684792 -293.797521) (xy 354.644359 -293.768145) (xy 354.609019 -293.732805)
			(xy 354.579643 -293.692372) (xy 354.556953 -293.64784) (xy 354.541509 -293.600308) (xy 354.53369 -293.550945)
			(xy 354.228672 -293.550945) (xy 354.220853 -293.600308) (xy 354.205409 -293.64784) (xy 354.182719 -293.692372)
			(xy 354.153343 -293.732805) (xy 354.118003 -293.768145) (xy 354.07757 -293.797521) (xy 354.033038 -293.820211)
			(xy 353.985506 -293.835655) (xy 353.936143 -293.843474) (xy 353.886165 -293.843474) (xy 353.836802 -293.835655)
			(xy 353.78927 -293.820211) (xy 353.744738 -293.797521) (xy 353.704305 -293.768145) (xy 353.668965 -293.732805)
			(xy 353.639589 -293.692372) (xy 353.616899 -293.64784) (xy 353.601455 -293.600308) (xy 353.593636 -293.550945)
			(xy 353.288618 -293.550945) (xy 353.280799 -293.600308) (xy 353.265355 -293.64784) (xy 353.242665 -293.692372)
			(xy 353.213289 -293.732805) (xy 353.177949 -293.768145) (xy 353.137516 -293.797521) (xy 353.092984 -293.820211)
			(xy 353.045452 -293.835655) (xy 352.996089 -293.843474) (xy 352.946111 -293.843474) (xy 352.896748 -293.835655)
			(xy 352.849216 -293.820211) (xy 352.804684 -293.797521) (xy 352.764251 -293.768145) (xy 352.728911 -293.732805)
			(xy 352.699535 -293.692372) (xy 352.676845 -293.64784) (xy 352.661401 -293.600308) (xy 352.653582 -293.550945)
			(xy 352.348564 -293.550945) (xy 352.340745 -293.600308) (xy 352.325301 -293.64784) (xy 352.302611 -293.692372)
			(xy 352.273235 -293.732805) (xy 352.237895 -293.768145) (xy 352.197462 -293.797521) (xy 352.15293 -293.820211)
			(xy 352.105398 -293.835655) (xy 352.056035 -293.843474) (xy 352.006057 -293.843474) (xy 351.956694 -293.835655)
			(xy 351.909162 -293.820211) (xy 351.86463 -293.797521) (xy 351.824197 -293.768145) (xy 351.788857 -293.732805)
			(xy 351.759481 -293.692372) (xy 351.736791 -293.64784) (xy 351.721347 -293.600308) (xy 351.713528 -293.550945)
			(xy 351.408764 -293.550945) (xy 351.400945 -293.600308) (xy 351.385501 -293.64784) (xy 351.362811 -293.692372)
			(xy 351.333435 -293.732805) (xy 351.298095 -293.768145) (xy 351.257662 -293.797521) (xy 351.21313 -293.820211)
			(xy 351.165598 -293.835655) (xy 351.116235 -293.843474) (xy 351.066257 -293.843474) (xy 351.016894 -293.835655)
			(xy 350.969362 -293.820211) (xy 350.92483 -293.797521) (xy 350.884397 -293.768145) (xy 350.849057 -293.732805)
			(xy 350.819681 -293.692372) (xy 350.796991 -293.64784) (xy 350.781547 -293.600308) (xy 350.773728 -293.550945)
			(xy 350.46871 -293.550945) (xy 350.460891 -293.600308) (xy 350.445447 -293.64784) (xy 350.422757 -293.692372)
			(xy 350.393381 -293.732805) (xy 350.358041 -293.768145) (xy 350.317608 -293.797521) (xy 350.273076 -293.820211)
			(xy 350.225544 -293.835655) (xy 350.176181 -293.843474) (xy 350.126203 -293.843474) (xy 350.07684 -293.835655)
			(xy 350.029308 -293.820211) (xy 349.984776 -293.797521) (xy 349.944343 -293.768145) (xy 349.909003 -293.732805)
			(xy 349.879627 -293.692372) (xy 349.856937 -293.64784) (xy 349.841493 -293.600308) (xy 349.833674 -293.550945)
			(xy 349.528656 -293.550945) (xy 349.520837 -293.600308) (xy 349.505393 -293.64784) (xy 349.482703 -293.692372)
			(xy 349.453327 -293.732805) (xy 349.417987 -293.768145) (xy 349.377554 -293.797521) (xy 349.333022 -293.820211)
			(xy 349.28549 -293.835655) (xy 349.236127 -293.843474) (xy 349.186149 -293.843474) (xy 349.136786 -293.835655)
			(xy 349.089254 -293.820211) (xy 349.044722 -293.797521) (xy 349.004289 -293.768145) (xy 348.968949 -293.732805)
			(xy 348.939573 -293.692372) (xy 348.916883 -293.64784) (xy 348.901439 -293.600308) (xy 348.89362 -293.550945)
			(xy 348.588602 -293.550945) (xy 348.580783 -293.600308) (xy 348.565339 -293.64784) (xy 348.542649 -293.692372)
			(xy 348.513273 -293.732805) (xy 348.477933 -293.768145) (xy 348.4375 -293.797521) (xy 348.392968 -293.820211)
			(xy 348.345436 -293.835655) (xy 348.296073 -293.843474) (xy 348.246095 -293.843474) (xy 348.196732 -293.835655)
			(xy 348.1492 -293.820211) (xy 348.104668 -293.797521) (xy 348.064235 -293.768145) (xy 348.028895 -293.732805)
			(xy 347.999519 -293.692372) (xy 347.976829 -293.64784) (xy 347.961385 -293.600308) (xy 347.953566 -293.550945)
			(xy 347.648548 -293.550945) (xy 347.640729 -293.600308) (xy 347.625285 -293.64784) (xy 347.602595 -293.692372)
			(xy 347.573219 -293.732805) (xy 347.537879 -293.768145) (xy 347.497446 -293.797521) (xy 347.452914 -293.820211)
			(xy 347.405382 -293.835655) (xy 347.356019 -293.843474) (xy 347.306041 -293.843474) (xy 347.256678 -293.835655)
			(xy 347.209146 -293.820211) (xy 347.164614 -293.797521) (xy 347.124181 -293.768145) (xy 347.088841 -293.732805)
			(xy 347.059465 -293.692372) (xy 347.036775 -293.64784) (xy 347.021331 -293.600308) (xy 347.013512 -293.550945)
			(xy 346.708748 -293.550945) (xy 346.700929 -293.600308) (xy 346.685485 -293.64784) (xy 346.662795 -293.692372)
			(xy 346.633419 -293.732805) (xy 346.598079 -293.768145) (xy 346.557646 -293.797521) (xy 346.513114 -293.820211)
			(xy 346.465582 -293.835655) (xy 346.416219 -293.843474) (xy 346.366241 -293.843474) (xy 346.316878 -293.835655)
			(xy 346.269346 -293.820211) (xy 346.224814 -293.797521) (xy 346.184381 -293.768145) (xy 346.149041 -293.732805)
			(xy 346.119665 -293.692372) (xy 346.096975 -293.64784) (xy 346.081531 -293.600308) (xy 346.073712 -293.550945)
			(xy 345.768694 -293.550945) (xy 345.760875 -293.600308) (xy 345.745431 -293.64784) (xy 345.722741 -293.692372)
			(xy 345.693365 -293.732805) (xy 345.658025 -293.768145) (xy 345.617592 -293.797521) (xy 345.57306 -293.820211)
			(xy 345.525528 -293.835655) (xy 345.476165 -293.843474) (xy 345.426187 -293.843474) (xy 345.376824 -293.835655)
			(xy 345.329292 -293.820211) (xy 345.28476 -293.797521) (xy 345.244327 -293.768145) (xy 345.208987 -293.732805)
			(xy 345.179611 -293.692372) (xy 345.156921 -293.64784) (xy 345.141477 -293.600308) (xy 345.133658 -293.550945)
			(xy 344.82864 -293.550945) (xy 344.820821 -293.600308) (xy 344.805377 -293.64784) (xy 344.782687 -293.692372)
			(xy 344.753311 -293.732805) (xy 344.717971 -293.768145) (xy 344.677538 -293.797521) (xy 344.633006 -293.820211)
			(xy 344.585474 -293.835655) (xy 344.536111 -293.843474) (xy 344.486133 -293.843474) (xy 344.43677 -293.835655)
			(xy 344.389238 -293.820211) (xy 344.344706 -293.797521) (xy 344.304273 -293.768145) (xy 344.268933 -293.732805)
			(xy 344.239557 -293.692372) (xy 344.216867 -293.64784) (xy 344.201423 -293.600308) (xy 344.193604 -293.550945)
			(xy 343.886287 -293.550945) (xy 343.886278 -293.551402) (xy 343.878114 -293.601636) (xy 343.861998 -293.64991)
			(xy 343.838347 -293.694973) (xy 343.807774 -293.735659) (xy 343.77107 -293.770914) (xy 343.729186 -293.799824)
			(xy 343.683207 -293.821641) (xy 343.634323 -293.835801) (xy 343.583802 -293.841935) (xy 343.53295 -293.839886)
			(xy 343.483086 -293.829706) (xy 343.4355 -293.811659) (xy 343.391426 -293.786213) (xy 343.352004 -293.754026)
			(xy 343.318256 -293.715932) (xy 343.291055 -293.672918) (xy 343.271107 -293.626098) (xy 343.258928 -293.576684)
			(xy 343.254833 -293.525956) (xy 342.949022 -293.525956) (xy 342.948532 -293.550945) (xy 342.940713 -293.600308)
			(xy 342.925269 -293.64784) (xy 342.902579 -293.692372) (xy 342.873203 -293.732805) (xy 342.837863 -293.768145)
			(xy 342.79743 -293.797521) (xy 342.752898 -293.820211) (xy 342.705366 -293.835655) (xy 342.656003 -293.843474)
			(xy 342.606025 -293.843474) (xy 342.556662 -293.835655) (xy 342.50913 -293.820211) (xy 342.464598 -293.797521)
			(xy 342.424165 -293.768145) (xy 342.388825 -293.732805) (xy 342.359449 -293.692372) (xy 342.336759 -293.64784)
			(xy 342.321315 -293.600308) (xy 342.313496 -293.550945) (xy 342.008732 -293.550945) (xy 342.000913 -293.600308)
			(xy 341.985469 -293.64784) (xy 341.962779 -293.692372) (xy 341.933403 -293.732805) (xy 341.898063 -293.768145)
			(xy 341.85763 -293.797521) (xy 341.813098 -293.820211) (xy 341.765566 -293.835655) (xy 341.716203 -293.843474)
			(xy 341.666225 -293.843474) (xy 341.616862 -293.835655) (xy 341.56933 -293.820211) (xy 341.524798 -293.797521)
			(xy 341.484365 -293.768145) (xy 341.449025 -293.732805) (xy 341.419649 -293.692372) (xy 341.396959 -293.64784)
			(xy 341.381515 -293.600308) (xy 341.373696 -293.550945) (xy 341.126318 -293.550945) (xy 341.126318 -293.917624)
			(xy 341.126797 -293.927589) (xy 341.134376 -293.946023) (xy 341.14105 -293.953438) (xy 341.182706 -293.995348)
			(xy 341.189818 -294.00246) (xy 341.21471 -294.013128) (xy 341.22106 -294.01516) (xy 341.234522 -294.018208)
			(xy 341.23884 -294.018462) (xy 341.264146 -294.020371) (xy 341.31372 -294.031212) (xy 341.360945 -294.049787)
			(xy 341.40462 -294.075625) (xy 341.443638 -294.108071) (xy 341.477008 -294.146302) (xy 341.503885 -294.189346)
			(xy 341.523585 -294.236112) (xy 341.535608 -294.285413) (xy 341.539651 -294.335998) (xy 341.537657 -294.360951)
			(xy 342.78365 -294.360951) (xy 342.78365 -294.310973) (xy 342.791469 -294.26161) (xy 342.806913 -294.214078)
			(xy 342.829603 -294.169546) (xy 342.858979 -294.129113) (xy 342.894319 -294.093773) (xy 342.934752 -294.064397)
			(xy 342.979284 -294.041707) (xy 343.026816 -294.026263) (xy 343.076179 -294.018444) (xy 343.126157 -294.018444)
			(xy 343.17552 -294.026263) (xy 343.223052 -294.041707) (xy 343.267584 -294.064397) (xy 343.308017 -294.093773)
			(xy 343.343357 -294.129113) (xy 343.372733 -294.169546) (xy 343.395423 -294.214078) (xy 343.410867 -294.26161)
			(xy 343.418686 -294.310973) (xy 343.419176 -294.335962) (xy 343.418686 -294.360951) (xy 343.723704 -294.360951)
			(xy 343.723704 -294.310973) (xy 343.731523 -294.26161) (xy 343.746967 -294.214078) (xy 343.769657 -294.169546)
			(xy 343.799033 -294.129113) (xy 343.834373 -294.093773) (xy 343.874806 -294.064397) (xy 343.919338 -294.041707)
			(xy 343.96687 -294.026263) (xy 344.016233 -294.018444) (xy 344.066211 -294.018444) (xy 344.115574 -294.026263)
			(xy 344.163106 -294.041707) (xy 344.207638 -294.064397) (xy 344.248071 -294.093773) (xy 344.283411 -294.129113)
			(xy 344.312787 -294.169546) (xy 344.335477 -294.214078) (xy 344.350921 -294.26161) (xy 344.35874 -294.310973)
			(xy 344.35923 -294.335962) (xy 344.664787 -294.335962) (xy 344.668882 -294.285234) (xy 344.681061 -294.23582)
			(xy 344.701009 -294.189) (xy 344.72821 -294.145986) (xy 344.761958 -294.107892) (xy 344.80138 -294.075705)
			(xy 344.845454 -294.050259) (xy 344.89304 -294.032212) (xy 344.942904 -294.022032) (xy 344.993756 -294.019983)
			(xy 345.044277 -294.026117) (xy 345.093161 -294.040277) (xy 345.13914 -294.062094) (xy 345.181024 -294.091004)
			(xy 345.217728 -294.126259) (xy 345.248301 -294.166945) (xy 345.271952 -294.212008) (xy 345.288068 -294.260282)
			(xy 345.296232 -294.310516) (xy 345.296744 -294.335962) (xy 345.604841 -294.335962) (xy 345.608936 -294.285234)
			(xy 345.621115 -294.23582) (xy 345.641063 -294.189) (xy 345.668264 -294.145986) (xy 345.702012 -294.107892)
			(xy 345.741434 -294.075705) (xy 345.785508 -294.050259) (xy 345.833094 -294.032212) (xy 345.882958 -294.022032)
			(xy 345.93381 -294.019983) (xy 345.984331 -294.026117) (xy 346.033215 -294.040277) (xy 346.079194 -294.062094)
			(xy 346.121078 -294.091004) (xy 346.157782 -294.126259) (xy 346.188355 -294.166945) (xy 346.212006 -294.212008)
			(xy 346.228122 -294.260282) (xy 346.236286 -294.310516) (xy 346.236798 -294.335962) (xy 346.236295 -294.360951)
			(xy 346.543612 -294.360951) (xy 346.543612 -294.310973) (xy 346.551431 -294.26161) (xy 346.566875 -294.214078)
			(xy 346.589565 -294.169546) (xy 346.618941 -294.129113) (xy 346.654281 -294.093773) (xy 346.694714 -294.064397)
			(xy 346.739246 -294.041707) (xy 346.786778 -294.026263) (xy 346.836141 -294.018444) (xy 346.886119 -294.018444)
			(xy 346.935482 -294.026263) (xy 346.983014 -294.041707) (xy 347.027546 -294.064397) (xy 347.067979 -294.093773)
			(xy 347.103319 -294.129113) (xy 347.132695 -294.169546) (xy 347.155385 -294.214078) (xy 347.170829 -294.26161)
			(xy 347.178648 -294.310973) (xy 347.179138 -294.335962) (xy 347.484949 -294.335962) (xy 347.489044 -294.285234)
			(xy 347.501223 -294.23582) (xy 347.521171 -294.189) (xy 347.548372 -294.145986) (xy 347.58212 -294.107892)
			(xy 347.621542 -294.075705) (xy 347.665616 -294.050259) (xy 347.713202 -294.032212) (xy 347.763066 -294.022032)
			(xy 347.813918 -294.019983) (xy 347.864439 -294.026117) (xy 347.913323 -294.040277) (xy 347.959302 -294.062094)
			(xy 348.001186 -294.091004) (xy 348.03789 -294.126259) (xy 348.068463 -294.166945) (xy 348.092114 -294.212008)
			(xy 348.10823 -294.260282) (xy 348.116394 -294.310516) (xy 348.116906 -294.335962) (xy 348.425003 -294.335962)
			(xy 348.429098 -294.285234) (xy 348.441277 -294.23582) (xy 348.461225 -294.189) (xy 348.488426 -294.145986)
			(xy 348.522174 -294.107892) (xy 348.561596 -294.075705) (xy 348.60567 -294.050259) (xy 348.653256 -294.032212)
			(xy 348.70312 -294.022032) (xy 348.753972 -294.019983) (xy 348.804493 -294.026117) (xy 348.853377 -294.040277)
			(xy 348.899356 -294.062094) (xy 348.94124 -294.091004) (xy 348.977944 -294.126259) (xy 349.008517 -294.166945)
			(xy 349.032168 -294.212008) (xy 349.048284 -294.260282) (xy 349.056448 -294.310516) (xy 349.05696 -294.335962)
			(xy 349.056457 -294.360951) (xy 349.36352 -294.360951) (xy 349.36352 -294.310973) (xy 349.371339 -294.26161)
			(xy 349.386783 -294.214078) (xy 349.409473 -294.169546) (xy 349.438849 -294.129113) (xy 349.474189 -294.093773)
			(xy 349.514622 -294.064397) (xy 349.559154 -294.041707) (xy 349.606686 -294.026263) (xy 349.656049 -294.018444)
			(xy 349.706027 -294.018444) (xy 349.75539 -294.026263) (xy 349.802922 -294.041707) (xy 349.847454 -294.064397)
			(xy 349.887887 -294.093773) (xy 349.923227 -294.129113) (xy 349.952603 -294.169546) (xy 349.975293 -294.214078)
			(xy 349.990737 -294.26161) (xy 349.998556 -294.310973) (xy 349.999046 -294.335962) (xy 350.304857 -294.335962)
			(xy 350.308952 -294.285234) (xy 350.321131 -294.23582) (xy 350.341079 -294.189) (xy 350.36828 -294.145986)
			(xy 350.402028 -294.107892) (xy 350.44145 -294.075705) (xy 350.485524 -294.050259) (xy 350.53311 -294.032212)
			(xy 350.582974 -294.022032) (xy 350.633826 -294.019983) (xy 350.684347 -294.026117) (xy 350.733231 -294.040277)
			(xy 350.77921 -294.062094) (xy 350.821094 -294.091004) (xy 350.857798 -294.126259) (xy 350.888371 -294.166945)
			(xy 350.912022 -294.212008) (xy 350.928138 -294.260282) (xy 350.936302 -294.310516) (xy 350.936814 -294.335962)
			(xy 351.244911 -294.335962) (xy 351.249006 -294.285234) (xy 351.261185 -294.23582) (xy 351.281133 -294.189)
			(xy 351.308334 -294.145986) (xy 351.342082 -294.107892) (xy 351.381504 -294.075705) (xy 351.425578 -294.050259)
			(xy 351.473164 -294.032212) (xy 351.523028 -294.022032) (xy 351.57388 -294.019983) (xy 351.624401 -294.026117)
			(xy 351.673285 -294.040277) (xy 351.719264 -294.062094) (xy 351.761148 -294.091004) (xy 351.797852 -294.126259)
			(xy 351.828425 -294.166945) (xy 351.852076 -294.212008) (xy 351.868192 -294.260282) (xy 351.876356 -294.310516)
			(xy 351.876868 -294.335962) (xy 351.876365 -294.360951) (xy 352.183682 -294.360951) (xy 352.183682 -294.310973)
			(xy 352.191501 -294.26161) (xy 352.206945 -294.214078) (xy 352.229635 -294.169546) (xy 352.259011 -294.129113)
			(xy 352.294351 -294.093773) (xy 352.334784 -294.064397) (xy 352.379316 -294.041707) (xy 352.426848 -294.026263)
			(xy 352.476211 -294.018444) (xy 352.526189 -294.018444) (xy 352.575552 -294.026263) (xy 352.623084 -294.041707)
			(xy 352.667616 -294.064397) (xy 352.708049 -294.093773) (xy 352.743389 -294.129113) (xy 352.772765 -294.169546)
			(xy 352.795455 -294.214078) (xy 352.810899 -294.26161) (xy 352.818718 -294.310973) (xy 352.819208 -294.335962)
			(xy 353.124765 -294.335962) (xy 353.12886 -294.285234) (xy 353.141039 -294.23582) (xy 353.160987 -294.189)
			(xy 353.188188 -294.145986) (xy 353.221936 -294.107892) (xy 353.261358 -294.075705) (xy 353.305432 -294.050259)
			(xy 353.353018 -294.032212) (xy 353.402882 -294.022032) (xy 353.453734 -294.019983) (xy 353.504255 -294.026117)
			(xy 353.553139 -294.040277) (xy 353.599118 -294.062094) (xy 353.641002 -294.091004) (xy 353.677706 -294.126259)
			(xy 353.708279 -294.166945) (xy 353.73193 -294.212008) (xy 353.748046 -294.260282) (xy 353.75621 -294.310516)
			(xy 353.756722 -294.335962) (xy 354.064819 -294.335962) (xy 354.068914 -294.285234) (xy 354.081093 -294.23582)
			(xy 354.101041 -294.189) (xy 354.128242 -294.145986) (xy 354.16199 -294.107892) (xy 354.201412 -294.075705)
			(xy 354.245486 -294.050259) (xy 354.293072 -294.032212) (xy 354.342936 -294.022032) (xy 354.393788 -294.019983)
			(xy 354.444309 -294.026117) (xy 354.493193 -294.040277) (xy 354.539172 -294.062094) (xy 354.581056 -294.091004)
			(xy 354.61776 -294.126259) (xy 354.648333 -294.166945) (xy 354.671984 -294.212008) (xy 354.6881 -294.260282)
			(xy 354.696264 -294.310516) (xy 354.696776 -294.335962) (xy 354.696273 -294.360951) (xy 355.00359 -294.360951)
			(xy 355.00359 -294.310973) (xy 355.011409 -294.26161) (xy 355.026853 -294.214078) (xy 355.049543 -294.169546)
			(xy 355.078919 -294.129113) (xy 355.114259 -294.093773) (xy 355.154692 -294.064397) (xy 355.199224 -294.041707)
			(xy 355.246756 -294.026263) (xy 355.296119 -294.018444) (xy 355.346097 -294.018444) (xy 355.39546 -294.026263)
			(xy 355.442992 -294.041707) (xy 355.487524 -294.064397) (xy 355.527957 -294.093773) (xy 355.563297 -294.129113)
			(xy 355.592673 -294.169546) (xy 355.615363 -294.214078) (xy 355.630807 -294.26161) (xy 355.638626 -294.310973)
			(xy 355.639116 -294.335962) (xy 355.638626 -294.360951) (xy 356.883698 -294.360951) (xy 356.883698 -294.310973)
			(xy 356.891517 -294.26161) (xy 356.906961 -294.214078) (xy 356.929651 -294.169546) (xy 356.959027 -294.129113)
			(xy 356.994367 -294.093773) (xy 357.0348 -294.064397) (xy 357.079332 -294.041707) (xy 357.126864 -294.026263)
			(xy 357.176227 -294.018444) (xy 357.226205 -294.018444) (xy 357.275568 -294.026263) (xy 357.3231 -294.041707)
			(xy 357.367632 -294.064397) (xy 357.408065 -294.093773) (xy 357.443405 -294.129113) (xy 357.472781 -294.169546)
			(xy 357.495471 -294.214078) (xy 357.510915 -294.26161) (xy 357.518734 -294.310973) (xy 357.519224 -294.335962)
			(xy 357.518734 -294.360951) (xy 357.510915 -294.410314) (xy 357.495471 -294.457846) (xy 357.472781 -294.502378)
			(xy 357.443405 -294.542811) (xy 357.408065 -294.578151) (xy 357.367632 -294.607527) (xy 357.3231 -294.630217)
			(xy 357.275568 -294.645661) (xy 357.226205 -294.65348) (xy 357.176227 -294.65348) (xy 357.126864 -294.645661)
			(xy 357.079332 -294.630217) (xy 357.0348 -294.607527) (xy 356.994367 -294.578151) (xy 356.959027 -294.542811)
			(xy 356.929651 -294.502378) (xy 356.906961 -294.457846) (xy 356.891517 -294.410314) (xy 356.883698 -294.360951)
			(xy 355.638626 -294.360951) (xy 355.630807 -294.410314) (xy 355.615363 -294.457846) (xy 355.592673 -294.502378)
			(xy 355.563297 -294.542811) (xy 355.527957 -294.578151) (xy 355.487524 -294.607527) (xy 355.442992 -294.630217)
			(xy 355.39546 -294.645661) (xy 355.346097 -294.65348) (xy 355.296119 -294.65348) (xy 355.246756 -294.645661)
			(xy 355.199224 -294.630217) (xy 355.154692 -294.607527) (xy 355.114259 -294.578151) (xy 355.078919 -294.542811)
			(xy 355.049543 -294.502378) (xy 355.026853 -294.457846) (xy 355.011409 -294.410314) (xy 355.00359 -294.360951)
			(xy 354.696273 -294.360951) (xy 354.696264 -294.361408) (xy 354.6881 -294.411642) (xy 354.671984 -294.459916)
			(xy 354.648333 -294.504979) (xy 354.61776 -294.545665) (xy 354.581056 -294.58092) (xy 354.539172 -294.60983)
			(xy 354.493193 -294.631647) (xy 354.444309 -294.645807) (xy 354.393788 -294.651941) (xy 354.342936 -294.649892)
			(xy 354.293072 -294.639712) (xy 354.245486 -294.621665) (xy 354.201412 -294.596219) (xy 354.16199 -294.564032)
			(xy 354.128242 -294.525938) (xy 354.101041 -294.482924) (xy 354.081093 -294.436104) (xy 354.068914 -294.38669)
			(xy 354.064819 -294.335962) (xy 353.756722 -294.335962) (xy 353.75621 -294.361408) (xy 353.748046 -294.411642)
			(xy 353.73193 -294.459916) (xy 353.708279 -294.504979) (xy 353.677706 -294.545665) (xy 353.641002 -294.58092)
			(xy 353.599118 -294.60983) (xy 353.553139 -294.631647) (xy 353.504255 -294.645807) (xy 353.453734 -294.651941)
			(xy 353.402882 -294.649892) (xy 353.353018 -294.639712) (xy 353.305432 -294.621665) (xy 353.261358 -294.596219)
			(xy 353.221936 -294.564032) (xy 353.188188 -294.525938) (xy 353.160987 -294.482924) (xy 353.141039 -294.436104)
			(xy 353.12886 -294.38669) (xy 353.124765 -294.335962) (xy 352.819208 -294.335962) (xy 352.818718 -294.360951)
			(xy 352.810899 -294.410314) (xy 352.795455 -294.457846) (xy 352.772765 -294.502378) (xy 352.743389 -294.542811)
			(xy 352.708049 -294.578151) (xy 352.667616 -294.607527) (xy 352.623084 -294.630217) (xy 352.575552 -294.645661)
			(xy 352.526189 -294.65348) (xy 352.476211 -294.65348) (xy 352.426848 -294.645661) (xy 352.379316 -294.630217)
			(xy 352.334784 -294.607527) (xy 352.294351 -294.578151) (xy 352.259011 -294.542811) (xy 352.229635 -294.502378)
			(xy 352.206945 -294.457846) (xy 352.191501 -294.410314) (xy 352.183682 -294.360951) (xy 351.876365 -294.360951)
			(xy 351.876356 -294.361408) (xy 351.868192 -294.411642) (xy 351.852076 -294.459916) (xy 351.828425 -294.504979)
			(xy 351.797852 -294.545665) (xy 351.761148 -294.58092) (xy 351.719264 -294.60983) (xy 351.673285 -294.631647)
			(xy 351.624401 -294.645807) (xy 351.57388 -294.651941) (xy 351.523028 -294.649892) (xy 351.473164 -294.639712)
			(xy 351.425578 -294.621665) (xy 351.381504 -294.596219) (xy 351.342082 -294.564032) (xy 351.308334 -294.525938)
			(xy 351.281133 -294.482924) (xy 351.261185 -294.436104) (xy 351.249006 -294.38669) (xy 351.244911 -294.335962)
			(xy 350.936814 -294.335962) (xy 350.936302 -294.361408) (xy 350.928138 -294.411642) (xy 350.912022 -294.459916)
			(xy 350.888371 -294.504979) (xy 350.857798 -294.545665) (xy 350.821094 -294.58092) (xy 350.77921 -294.60983)
			(xy 350.733231 -294.631647) (xy 350.684347 -294.645807) (xy 350.633826 -294.651941) (xy 350.582974 -294.649892)
			(xy 350.53311 -294.639712) (xy 350.485524 -294.621665) (xy 350.44145 -294.596219) (xy 350.402028 -294.564032)
			(xy 350.36828 -294.525938) (xy 350.341079 -294.482924) (xy 350.321131 -294.436104) (xy 350.308952 -294.38669)
			(xy 350.304857 -294.335962) (xy 349.999046 -294.335962) (xy 349.998556 -294.360951) (xy 349.990737 -294.410314)
			(xy 349.975293 -294.457846) (xy 349.952603 -294.502378) (xy 349.923227 -294.542811) (xy 349.887887 -294.578151)
			(xy 349.847454 -294.607527) (xy 349.802922 -294.630217) (xy 349.75539 -294.645661) (xy 349.706027 -294.65348)
			(xy 349.656049 -294.65348) (xy 349.606686 -294.645661) (xy 349.559154 -294.630217) (xy 349.514622 -294.607527)
			(xy 349.474189 -294.578151) (xy 349.438849 -294.542811) (xy 349.409473 -294.502378) (xy 349.386783 -294.457846)
			(xy 349.371339 -294.410314) (xy 349.36352 -294.360951) (xy 349.056457 -294.360951) (xy 349.056448 -294.361408)
			(xy 349.048284 -294.411642) (xy 349.032168 -294.459916) (xy 349.008517 -294.504979) (xy 348.977944 -294.545665)
			(xy 348.94124 -294.58092) (xy 348.899356 -294.60983) (xy 348.853377 -294.631647) (xy 348.804493 -294.645807)
			(xy 348.753972 -294.651941) (xy 348.70312 -294.649892) (xy 348.653256 -294.639712) (xy 348.60567 -294.621665)
			(xy 348.561596 -294.596219) (xy 348.522174 -294.564032) (xy 348.488426 -294.525938) (xy 348.461225 -294.482924)
			(xy 348.441277 -294.436104) (xy 348.429098 -294.38669) (xy 348.425003 -294.335962) (xy 348.116906 -294.335962)
			(xy 348.116394 -294.361408) (xy 348.10823 -294.411642) (xy 348.092114 -294.459916) (xy 348.068463 -294.504979)
			(xy 348.03789 -294.545665) (xy 348.001186 -294.58092) (xy 347.959302 -294.60983) (xy 347.913323 -294.631647)
			(xy 347.864439 -294.645807) (xy 347.813918 -294.651941) (xy 347.763066 -294.649892) (xy 347.713202 -294.639712)
			(xy 347.665616 -294.621665) (xy 347.621542 -294.596219) (xy 347.58212 -294.564032) (xy 347.548372 -294.525938)
			(xy 347.521171 -294.482924) (xy 347.501223 -294.436104) (xy 347.489044 -294.38669) (xy 347.484949 -294.335962)
			(xy 347.179138 -294.335962) (xy 347.178648 -294.360951) (xy 347.170829 -294.410314) (xy 347.155385 -294.457846)
			(xy 347.132695 -294.502378) (xy 347.103319 -294.542811) (xy 347.067979 -294.578151) (xy 347.027546 -294.607527)
			(xy 346.983014 -294.630217) (xy 346.935482 -294.645661) (xy 346.886119 -294.65348) (xy 346.836141 -294.65348)
			(xy 346.786778 -294.645661) (xy 346.739246 -294.630217) (xy 346.694714 -294.607527) (xy 346.654281 -294.578151)
			(xy 346.618941 -294.542811) (xy 346.589565 -294.502378) (xy 346.566875 -294.457846) (xy 346.551431 -294.410314)
			(xy 346.543612 -294.360951) (xy 346.236295 -294.360951) (xy 346.236286 -294.361408) (xy 346.228122 -294.411642)
			(xy 346.212006 -294.459916) (xy 346.188355 -294.504979) (xy 346.157782 -294.545665) (xy 346.121078 -294.58092)
			(xy 346.079194 -294.60983) (xy 346.033215 -294.631647) (xy 345.984331 -294.645807) (xy 345.93381 -294.651941)
			(xy 345.882958 -294.649892) (xy 345.833094 -294.639712) (xy 345.785508 -294.621665) (xy 345.741434 -294.596219)
			(xy 345.702012 -294.564032) (xy 345.668264 -294.525938) (xy 345.641063 -294.482924) (xy 345.621115 -294.436104)
			(xy 345.608936 -294.38669) (xy 345.604841 -294.335962) (xy 345.296744 -294.335962) (xy 345.296232 -294.361408)
			(xy 345.288068 -294.411642) (xy 345.271952 -294.459916) (xy 345.248301 -294.504979) (xy 345.217728 -294.545665)
			(xy 345.181024 -294.58092) (xy 345.13914 -294.60983) (xy 345.093161 -294.631647) (xy 345.044277 -294.645807)
			(xy 344.993756 -294.651941) (xy 344.942904 -294.649892) (xy 344.89304 -294.639712) (xy 344.845454 -294.621665)
			(xy 344.80138 -294.596219) (xy 344.761958 -294.564032) (xy 344.72821 -294.525938) (xy 344.701009 -294.482924)
			(xy 344.681061 -294.436104) (xy 344.668882 -294.38669) (xy 344.664787 -294.335962) (xy 344.35923 -294.335962)
			(xy 344.35874 -294.360951) (xy 344.350921 -294.410314) (xy 344.335477 -294.457846) (xy 344.312787 -294.502378)
			(xy 344.283411 -294.542811) (xy 344.248071 -294.578151) (xy 344.207638 -294.607527) (xy 344.163106 -294.630217)
			(xy 344.115574 -294.645661) (xy 344.066211 -294.65348) (xy 344.016233 -294.65348) (xy 343.96687 -294.645661)
			(xy 343.919338 -294.630217) (xy 343.874806 -294.607527) (xy 343.834373 -294.578151) (xy 343.799033 -294.542811)
			(xy 343.769657 -294.502378) (xy 343.746967 -294.457846) (xy 343.731523 -294.410314) (xy 343.723704 -294.360951)
			(xy 343.418686 -294.360951) (xy 343.410867 -294.410314) (xy 343.395423 -294.457846) (xy 343.372733 -294.502378)
			(xy 343.343357 -294.542811) (xy 343.308017 -294.578151) (xy 343.267584 -294.607527) (xy 343.223052 -294.630217)
			(xy 343.17552 -294.645661) (xy 343.126157 -294.65348) (xy 343.076179 -294.65348) (xy 343.026816 -294.645661)
			(xy 342.979284 -294.630217) (xy 342.934752 -294.607527) (xy 342.894319 -294.578151) (xy 342.858979 -294.542811)
			(xy 342.829603 -294.502378) (xy 342.806913 -294.457846) (xy 342.791469 -294.410314) (xy 342.78365 -294.360951)
			(xy 341.537657 -294.360951) (xy 341.535609 -294.386583) (xy 341.523586 -294.435884) (xy 341.503887 -294.48265)
			(xy 341.477011 -294.525695) (xy 341.443641 -294.563926) (xy 341.404623 -294.596372) (xy 341.360948 -294.622211)
			(xy 341.313725 -294.640787) (xy 341.26415 -294.651628) (xy 341.23884 -294.653462) (xy 341.234522 -294.653716)
			(xy 341.22106 -294.656764) (xy 341.21471 -294.658796) (xy 341.198962 -294.665654) (xy 341.194457 -294.667664)
			(xy 341.18627 -294.673165) (xy 341.182706 -294.676576) (xy 341.169244 -294.690292) (xy 341.14105 -294.718486)
			(xy 341.134369 -294.725897) (xy 341.12679 -294.744333) (xy 341.126318 -294.7543) (xy 341.126318 -295.170957)
			(xy 343.25355 -295.170957) (xy 343.25355 -295.120979) (xy 343.261369 -295.071616) (xy 343.276813 -295.024084)
			(xy 343.299503 -294.979552) (xy 343.328879 -294.939119) (xy 343.364219 -294.903779) (xy 343.404652 -294.874403)
			(xy 343.449184 -294.851713) (xy 343.496716 -294.836269) (xy 343.546079 -294.82845) (xy 343.596057 -294.82845)
			(xy 343.64542 -294.836269) (xy 343.692952 -294.851713) (xy 343.737484 -294.874403) (xy 343.777917 -294.903779)
			(xy 343.813257 -294.939119) (xy 343.842633 -294.979552) (xy 343.865323 -295.024084) (xy 343.880767 -295.071616)
			(xy 343.888586 -295.120979) (xy 343.889076 -295.145968) (xy 343.888586 -295.170957) (xy 346.073712 -295.170957)
			(xy 346.073712 -295.120979) (xy 346.081531 -295.071616) (xy 346.096975 -295.024084) (xy 346.119665 -294.979552)
			(xy 346.149041 -294.939119) (xy 346.184381 -294.903779) (xy 346.224814 -294.874403) (xy 346.269346 -294.851713)
			(xy 346.316878 -294.836269) (xy 346.366241 -294.82845) (xy 346.416219 -294.82845) (xy 346.465582 -294.836269)
			(xy 346.513114 -294.851713) (xy 346.557646 -294.874403) (xy 346.598079 -294.903779) (xy 346.633419 -294.939119)
			(xy 346.662795 -294.979552) (xy 346.685485 -295.024084) (xy 346.700929 -295.071616) (xy 346.708748 -295.120979)
			(xy 346.709238 -295.145968) (xy 346.708748 -295.170957) (xy 348.89362 -295.170957) (xy 348.89362 -295.120979)
			(xy 348.901439 -295.071616) (xy 348.916883 -295.024084) (xy 348.939573 -294.979552) (xy 348.968949 -294.939119)
			(xy 349.004289 -294.903779) (xy 349.044722 -294.874403) (xy 349.089254 -294.851713) (xy 349.136786 -294.836269)
			(xy 349.186149 -294.82845) (xy 349.236127 -294.82845) (xy 349.28549 -294.836269) (xy 349.333022 -294.851713)
			(xy 349.377554 -294.874403) (xy 349.417987 -294.903779) (xy 349.453327 -294.939119) (xy 349.482703 -294.979552)
			(xy 349.505393 -295.024084) (xy 349.520837 -295.071616) (xy 349.528656 -295.120979) (xy 349.529146 -295.145968)
			(xy 349.528656 -295.170957) (xy 351.713528 -295.170957) (xy 351.713528 -295.120979) (xy 351.721347 -295.071616)
			(xy 351.736791 -295.024084) (xy 351.759481 -294.979552) (xy 351.788857 -294.939119) (xy 351.824197 -294.903779)
			(xy 351.86463 -294.874403) (xy 351.909162 -294.851713) (xy 351.956694 -294.836269) (xy 352.006057 -294.82845)
			(xy 352.056035 -294.82845) (xy 352.105398 -294.836269) (xy 352.15293 -294.851713) (xy 352.197462 -294.874403)
			(xy 352.237895 -294.903779) (xy 352.273235 -294.939119) (xy 352.302611 -294.979552) (xy 352.325301 -295.024084)
			(xy 352.340745 -295.071616) (xy 352.348564 -295.120979) (xy 352.349054 -295.145968) (xy 352.348564 -295.170957)
			(xy 354.53369 -295.170957) (xy 354.53369 -295.120979) (xy 354.541509 -295.071616) (xy 354.556953 -295.024084)
			(xy 354.579643 -294.979552) (xy 354.609019 -294.939119) (xy 354.644359 -294.903779) (xy 354.684792 -294.874403)
			(xy 354.729324 -294.851713) (xy 354.776856 -294.836269) (xy 354.826219 -294.82845) (xy 354.876197 -294.82845)
			(xy 354.92556 -294.836269) (xy 354.973092 -294.851713) (xy 355.017624 -294.874403) (xy 355.058057 -294.903779)
			(xy 355.093397 -294.939119) (xy 355.122773 -294.979552) (xy 355.145463 -295.024084) (xy 355.160907 -295.071616)
			(xy 355.168726 -295.120979) (xy 355.169216 -295.145968) (xy 355.168726 -295.170957) (xy 355.160907 -295.22032)
			(xy 355.145463 -295.267852) (xy 355.122773 -295.312384) (xy 355.093397 -295.352817) (xy 355.058057 -295.388157)
			(xy 355.017624 -295.417533) (xy 354.973092 -295.440223) (xy 354.92556 -295.455667) (xy 354.876197 -295.463486)
			(xy 354.826219 -295.463486) (xy 354.776856 -295.455667) (xy 354.729324 -295.440223) (xy 354.684792 -295.417533)
			(xy 354.644359 -295.388157) (xy 354.609019 -295.352817) (xy 354.579643 -295.312384) (xy 354.556953 -295.267852)
			(xy 354.541509 -295.22032) (xy 354.53369 -295.170957) (xy 352.348564 -295.170957) (xy 352.340745 -295.22032)
			(xy 352.325301 -295.267852) (xy 352.302611 -295.312384) (xy 352.273235 -295.352817) (xy 352.237895 -295.388157)
			(xy 352.197462 -295.417533) (xy 352.15293 -295.440223) (xy 352.105398 -295.455667) (xy 352.056035 -295.463486)
			(xy 352.006057 -295.463486) (xy 351.956694 -295.455667) (xy 351.909162 -295.440223) (xy 351.86463 -295.417533)
			(xy 351.824197 -295.388157) (xy 351.788857 -295.352817) (xy 351.759481 -295.312384) (xy 351.736791 -295.267852)
			(xy 351.721347 -295.22032) (xy 351.713528 -295.170957) (xy 349.528656 -295.170957) (xy 349.520837 -295.22032)
			(xy 349.505393 -295.267852) (xy 349.482703 -295.312384) (xy 349.453327 -295.352817) (xy 349.417987 -295.388157)
			(xy 349.377554 -295.417533) (xy 349.333022 -295.440223) (xy 349.28549 -295.455667) (xy 349.236127 -295.463486)
			(xy 349.186149 -295.463486) (xy 349.136786 -295.455667) (xy 349.089254 -295.440223) (xy 349.044722 -295.417533)
			(xy 349.004289 -295.388157) (xy 348.968949 -295.352817) (xy 348.939573 -295.312384) (xy 348.916883 -295.267852)
			(xy 348.901439 -295.22032) (xy 348.89362 -295.170957) (xy 346.708748 -295.170957) (xy 346.700929 -295.22032)
			(xy 346.685485 -295.267852) (xy 346.662795 -295.312384) (xy 346.633419 -295.352817) (xy 346.598079 -295.388157)
			(xy 346.557646 -295.417533) (xy 346.513114 -295.440223) (xy 346.465582 -295.455667) (xy 346.416219 -295.463486)
			(xy 346.366241 -295.463486) (xy 346.316878 -295.455667) (xy 346.269346 -295.440223) (xy 346.224814 -295.417533)
			(xy 346.184381 -295.388157) (xy 346.149041 -295.352817) (xy 346.119665 -295.312384) (xy 346.096975 -295.267852)
			(xy 346.081531 -295.22032) (xy 346.073712 -295.170957) (xy 343.888586 -295.170957) (xy 343.880767 -295.22032)
			(xy 343.865323 -295.267852) (xy 343.842633 -295.312384) (xy 343.813257 -295.352817) (xy 343.777917 -295.388157)
			(xy 343.737484 -295.417533) (xy 343.692952 -295.440223) (xy 343.64542 -295.455667) (xy 343.596057 -295.463486)
			(xy 343.546079 -295.463486) (xy 343.496716 -295.455667) (xy 343.449184 -295.440223) (xy 343.404652 -295.417533)
			(xy 343.364219 -295.388157) (xy 343.328879 -295.352817) (xy 343.299503 -295.312384) (xy 343.276813 -295.267852)
			(xy 343.261369 -295.22032) (xy 343.25355 -295.170957) (xy 341.126318 -295.170957) (xy 341.126318 -295.31945)
			(xy 341.12708 -295.327832) (xy 341.128598 -295.335435) (xy 341.135589 -295.349264) (xy 341.140796 -295.35501)
			(xy 341.35568 -295.569894) (xy 341.363083 -295.576728) (xy 341.381681 -295.584435) (xy 341.391748 -295.58488)
			(xy 343.448894 -295.58488) (xy 343.488474 -295.585456) (xy 343.567122 -295.594448) (xy 343.644252 -295.612261)
			(xy 343.718879 -295.638668) (xy 343.75471 -295.655492) (xy 343.75999 -295.657864) (xy 343.771276 -295.66042)
			(xy 343.777062 -295.660572) (xy 349.562928 -295.660572)
		)
		(stroke
			(width 0)
			(type solid)
		)
		(fill yes)
		(layer "B.Cu")
		(net "PVDDCR_CPU1_P0")
	)
	(gr_poly
		(pts
			(xy 368.598958 -251.27331) (xy 368.608708 -251.272795) (xy 368.626735 -251.265345) (xy 368.63401 -251.258832)
			(xy 368.7318 -251.161042) (xy 368.734697 -251.157979) (xy 368.739551 -251.151088) (xy 368.741452 -251.147326)
			(xy 368.742214 -251.145294) (xy 368.74422 -251.140455) (xy 368.746405 -251.130211) (xy 368.746532 -251.124974)
			(xy 368.746532 -250.785884) (xy 368.747059 -250.776043) (xy 368.754636 -250.757871) (xy 368.761264 -250.750578)
			(xy 368.9858 -250.526042) (xy 368.99304 -250.519332) (xy 369.011244 -250.511741) (xy 369.021106 -250.51131)
			(xy 370.195094 -250.51131) (xy 370.204163 -250.51092) (xy 370.221123 -250.504495) (xy 370.234706 -250.492476)
			(xy 370.23929 -250.48464) (xy 370.249196 -250.464066) (xy 370.280946 -250.399042) (xy 370.284944 -250.387277)
			(xy 370.282147 -250.36262) (xy 370.275612 -250.352052) (xy 370.274342 -250.350274) (xy 370.273834 -250.349512)
			(xy 370.27358 -250.349512) (xy 370.257943 -250.32852) (xy 370.233036 -250.282484) (xy 370.216013 -250.232989)
			(xy 370.207334 -250.181372) (xy 370.206778 -250.155202) (xy 370.206778 -250.147836) (xy 370.20773 -250.123171)
			(xy 370.216316 -250.074566) (xy 370.232309 -250.027871) (xy 370.255324 -249.984208) (xy 370.28481 -249.944626)
			(xy 370.320058 -249.910075) (xy 370.360221 -249.881385) (xy 370.404335 -249.859246) (xy 370.45134 -249.844189)
			(xy 370.500107 -249.836576) (xy 370.524786 -249.836178) (xy 370.54947 -249.83665) (xy 370.598243 -249.84429)
			(xy 370.64525 -249.859372) (xy 370.689363 -249.881535) (xy 370.729523 -249.910246) (xy 370.764766 -249.944817)
			(xy 370.794245 -249.984417) (xy 370.817253 -250.028095) (xy 370.833237 -250.074804) (xy 370.841814 -250.123421)
			(xy 370.842794 -250.14809) (xy 370.842794 -250.154186) (xy 370.842297 -250.179175) (xy 372.087376 -250.179175)
			(xy 372.087376 -250.129197) (xy 372.095195 -250.079834) (xy 372.110639 -250.032302) (xy 372.133329 -249.98777)
			(xy 372.162705 -249.947337) (xy 372.198045 -249.911997) (xy 372.238478 -249.882621) (xy 372.28301 -249.859931)
			(xy 372.330542 -249.844487) (xy 372.379905 -249.836668) (xy 372.429883 -249.836668) (xy 372.479246 -249.844487)
			(xy 372.526778 -249.859931) (xy 372.57131 -249.882621) (xy 372.611743 -249.911997) (xy 372.647083 -249.947337)
			(xy 372.676459 -249.98777) (xy 372.699149 -250.032302) (xy 372.714593 -250.079834) (xy 372.722412 -250.129197)
			(xy 372.722902 -250.154186) (xy 372.722412 -250.179175) (xy 372.714593 -250.228538) (xy 372.699149 -250.27607)
			(xy 372.676459 -250.320602) (xy 372.647083 -250.361035) (xy 372.611743 -250.396375) (xy 372.57131 -250.425751)
			(xy 372.526778 -250.448441) (xy 372.479246 -250.463885) (xy 372.429883 -250.471704) (xy 372.379905 -250.471704)
			(xy 372.330542 -250.463885) (xy 372.28301 -250.448441) (xy 372.238478 -250.425751) (xy 372.198045 -250.396375)
			(xy 372.162705 -250.361035) (xy 372.133329 -250.320602) (xy 372.110639 -250.27607) (xy 372.095195 -250.228538)
			(xy 372.087376 -250.179175) (xy 370.842297 -250.179175) (xy 370.842271 -250.180481) (xy 370.833664 -250.232361)
			(xy 370.816649 -250.282122) (xy 370.791688 -250.32841) (xy 370.775992 -250.349512) (xy 370.77396 -250.352052)
			(xy 370.770577 -250.357297) (xy 370.766221 -250.368989) (xy 370.765324 -250.375166) (xy 370.764818 -250.381731)
			(xy 370.76688 -250.394732) (xy 370.769388 -250.40082) (xy 370.789962 -250.442984) (xy 370.80952 -250.483116)
			(xy 370.810282 -250.48464) (xy 370.812568 -250.489466) (xy 370.822474 -250.500388) (xy 370.827808 -250.50369)
			(xy 370.833916 -250.507186) (xy 370.847445 -250.51104) (xy 370.854478 -250.51131) (xy 371.392958 -250.51131)
			(xy 371.402796 -250.511844) (xy 371.420959 -250.519429) (xy 371.428264 -250.526042) (xy 371.475508 -250.573286)
			(xy 371.48276 -250.579831) (xy 371.500803 -250.587262) (xy 371.51056 -250.587764) (xy 371.512338 -250.587764)
			(xy 371.541294 -250.61672) (xy 371.541294 -250.618498) (xy 371.541817 -250.628244) (xy 371.549278 -250.646261)
			(xy 371.555772 -250.65355) (xy 371.6528 -250.750578) (xy 371.65952 -250.757814) (xy 371.667128 -250.776019)
			(xy 371.667532 -250.785884) (xy 371.667532 -251.125736) (xy 371.668294 -251.134372) (xy 371.671342 -251.14504)
			(xy 371.675152 -251.15393) (xy 371.7798 -251.258578) (xy 371.782866 -251.261469) (xy 371.789763 -251.266312)
			(xy 371.793516 -251.26823) (xy 371.795548 -251.268992) (xy 371.800388 -251.270995) (xy 371.810632 -251.273172)
			(xy 371.815868 -251.27331) (xy 372.408958 -251.27331) (xy 372.418708 -251.272795) (xy 372.436735 -251.265345)
			(xy 372.44401 -251.258832) (xy 372.5418 -251.161042) (xy 372.544697 -251.157979) (xy 372.549551 -251.151088)
			(xy 372.551452 -251.147326) (xy 372.552214 -251.145294) (xy 372.55422 -251.140455) (xy 372.556405 -251.130211)
			(xy 372.556532 -251.124974) (xy 372.556532 -250.785884) (xy 372.557059 -250.776043) (xy 372.564636 -250.757871)
			(xy 372.571264 -250.750578) (xy 372.573042 -250.7488) (xy 372.57832 -250.743156) (xy 372.585419 -250.729439)
			(xy 372.587012 -250.721876) (xy 372.587266 -250.718574) (xy 372.589952 -250.698003) (xy 372.60222 -250.658378)
			(xy 372.6219 -250.621863) (xy 372.648254 -250.58983) (xy 372.680291 -250.563482) (xy 372.716808 -250.543807)
			(xy 372.756435 -250.531545) (xy 372.777004 -250.528836) (xy 372.780306 -250.528582) (xy 372.787861 -250.52697)
			(xy 372.801571 -250.519869) (xy 372.80723 -250.514612) (xy 372.9228 -250.399042) (xy 372.93004 -250.392332)
			(xy 372.948244 -250.384741) (xy 372.958106 -250.38431) (xy 373.551958 -250.38431) (xy 373.561708 -250.383795)
			(xy 373.579735 -250.376345) (xy 373.58701 -250.369832) (xy 374.44299 -249.513852) (xy 374.4497 -249.506613)
			(xy 374.457284 -249.488408) (xy 374.457722 -249.478546) (xy 374.457722 -249.457718) (xy 374.454928 -249.44959)
			(xy 374.446523 -249.424051) (xy 374.437456 -249.37106) (xy 374.436894 -249.34418) (xy 374.436894 -249.330464)
			(xy 374.438666 -249.302962) (xy 374.450483 -249.249137) (xy 374.471386 -249.198149) (xy 374.500752 -249.151519)
			(xy 374.537705 -249.110639) (xy 374.559068 -249.093228) (xy 374.563894 -249.089418) (xy 374.567196 -249.085354)
			(xy 374.571768 -249.079004) (xy 374.581674 -249.060462) (xy 374.582944 -249.057922) (xy 374.585555 -249.052573)
			(xy 374.588378 -249.041012) (xy 374.588532 -249.035062) (xy 374.588532 -248.958354) (xy 374.588278 -248.955814)
			(xy 374.588278 -248.112534) (xy 374.588532 -248.109994) (xy 374.588532 -248.033286) (xy 374.588313 -248.027345)
			(xy 374.585484 -248.015801) (xy 374.582944 -248.010426) (xy 374.572784 -247.991376) (xy 374.567196 -247.982994)
			(xy 374.564148 -247.97893) (xy 374.559068 -247.97512) (xy 374.538689 -247.958507) (xy 374.503148 -247.919766)
			(xy 374.474452 -247.875715) (xy 374.45338 -247.827549) (xy 374.440505 -247.776576) (xy 374.436176 -247.72418)
			(xy 374.440511 -247.671785) (xy 374.453393 -247.620814) (xy 374.47447 -247.572651) (xy 374.503172 -247.528603)
			(xy 374.538718 -247.489867) (xy 374.559068 -247.473216) (xy 374.563894 -247.469406) (xy 374.567196 -247.465342)
			(xy 374.571768 -247.458992) (xy 374.581674 -247.44045) (xy 374.582944 -247.43791) (xy 374.585553 -247.43256)
			(xy 374.588374 -247.421) (xy 374.588532 -247.41505) (xy 374.588532 -247.338342) (xy 374.588278 -247.335802)
			(xy 374.588278 -247.278906) (xy 374.587601 -247.266366) (xy 374.575598 -247.244349) (xy 374.565418 -247.236996)
			(xy 374.489218 -247.192546) (xy 374.48342 -247.189349) (xy 374.470686 -247.185739) (xy 374.464072 -247.185434)
			(xy 374.451372 -247.185434) (xy 374.445276 -247.188736) (xy 374.439688 -247.191784) (xy 374.439434 -247.192038)
			(xy 374.415621 -247.204647) (xy 374.364799 -247.222541) (xy 374.311688 -247.231605) (xy 374.284748 -247.23217)
			(xy 374.259755 -247.231709) (xy 374.210385 -247.223895) (xy 374.162845 -247.208454) (xy 374.118306 -247.185764)
			(xy 374.077866 -247.156385) (xy 374.042521 -247.121041) (xy 374.013141 -247.080602) (xy 373.99045 -247.036064)
			(xy 373.975007 -246.988525) (xy 373.967192 -246.939155) (xy 373.96674 -246.914162) (xy 373.967185 -246.890101)
			(xy 373.97444 -246.84253) (xy 373.988778 -246.796594) (xy 374.009873 -246.753343) (xy 374.037242 -246.713762)
			(xy 374.070262 -246.678757) (xy 374.108178 -246.649125) (xy 374.150125 -246.625543) (xy 374.195146 -246.608549)
			(xy 374.242214 -246.598532) (xy 374.266206 -246.596662) (xy 374.26646 -246.596662) (xy 374.27789 -246.5959)
			(xy 374.284748 -246.5959) (xy 374.311731 -246.596441) (xy 374.364931 -246.605493) (xy 374.41584 -246.623398)
			(xy 374.439688 -246.636032) (xy 374.442482 -246.637556) (xy 374.447882 -246.63997) (xy 374.459427 -246.642529)
			(xy 374.465342 -246.642636) (xy 374.478042 -246.642636) (xy 374.56364 -246.592344) (xy 374.570922 -246.58765)
			(xy 374.582002 -246.574346) (xy 374.587912 -246.558074) (xy 374.588278 -246.549418) (xy 374.588278 -246.492522)
			(xy 374.588532 -246.489982) (xy 374.588532 -246.413274) (xy 374.588311 -246.407333) (xy 374.585481 -246.395791)
			(xy 374.582944 -246.390414) (xy 374.572784 -246.371364) (xy 374.567196 -246.362982) (xy 374.564148 -246.358918)
			(xy 374.559068 -246.355108) (xy 374.53869 -246.338495) (xy 374.503151 -246.299755) (xy 374.474456 -246.255704)
			(xy 374.453386 -246.207538) (xy 374.440513 -246.156567) (xy 374.436185 -246.104173) (xy 374.440522 -246.05178)
			(xy 374.453404 -246.00081) (xy 374.474482 -245.952648) (xy 374.503184 -245.908603) (xy 374.53873 -245.869869)
			(xy 374.559068 -245.853204) (xy 374.563894 -245.849394) (xy 374.567196 -245.84533) (xy 374.571768 -245.83898)
			(xy 374.581674 -245.820438) (xy 374.582944 -245.817898) (xy 374.585552 -245.812548) (xy 374.58837 -245.800988)
			(xy 374.588532 -245.795038) (xy 374.588532 -245.71833) (xy 374.588278 -245.71579) (xy 374.588278 -244.87251)
			(xy 374.588532 -244.86997) (xy 374.588532 -244.793262) (xy 374.58831 -244.787322) (xy 374.585477 -244.775781)
			(xy 374.582944 -244.770402) (xy 374.572784 -244.751352) (xy 374.567196 -244.74297) (xy 374.564148 -244.738906)
			(xy 374.559068 -244.735096) (xy 374.538683 -244.718483) (xy 374.503129 -244.67974) (xy 374.474421 -244.635685)
			(xy 374.453338 -244.587512) (xy 374.440453 -244.536532) (xy 374.436116 -244.484127) (xy 374.440444 -244.431722)
			(xy 374.45332 -244.380739) (xy 374.474395 -244.332563) (xy 374.503096 -244.288503) (xy 374.538643 -244.249754)
			(xy 374.559068 -244.233192) (xy 374.563894 -244.229382) (xy 374.567196 -244.225318) (xy 374.571768 -244.218968)
			(xy 374.581674 -244.200426) (xy 374.582944 -244.197886) (xy 374.585551 -244.192536) (xy 374.588365 -244.180976)
			(xy 374.588532 -244.175026) (xy 374.588532 -244.098318) (xy 374.588278 -244.095778) (xy 374.588278 -244.038882)
			(xy 374.587596 -244.026345) (xy 374.575587 -244.004337) (xy 374.565418 -243.996972) (xy 374.489218 -243.952522)
			(xy 374.483419 -243.949327) (xy 374.470685 -243.945718) (xy 374.464072 -243.94541) (xy 374.451372 -243.94541)
			(xy 374.445276 -243.948712) (xy 374.439688 -243.95176) (xy 374.439434 -243.952014) (xy 374.415621 -243.964624)
			(xy 374.3648 -243.982519) (xy 374.311688 -243.991584) (xy 374.284748 -243.992146) (xy 374.259753 -243.991685)
			(xy 374.210378 -243.983872) (xy 374.162833 -243.968432) (xy 374.118289 -243.945743) (xy 374.077843 -243.916366)
			(xy 374.04249 -243.881023) (xy 374.013102 -243.840584) (xy 373.990401 -243.796046) (xy 373.974948 -243.748506)
			(xy 373.967122 -243.699133) (xy 373.96674 -243.674138) (xy 373.967187 -243.650078) (xy 373.974444 -243.60251)
			(xy 373.988785 -243.556577) (xy 374.009881 -243.513329) (xy 374.037251 -243.473752) (xy 374.07027 -243.438749)
			(xy 374.108186 -243.40912) (xy 374.150132 -243.38554) (xy 374.195151 -243.368548) (xy 374.242216 -243.358531)
			(xy 374.266206 -243.356638) (xy 374.26646 -243.356638) (xy 374.27789 -243.355876) (xy 374.284748 -243.355876)
			(xy 374.311731 -243.356417) (xy 374.36493 -243.365471) (xy 374.415836 -243.38338) (xy 374.439688 -243.396008)
			(xy 374.442482 -243.397532) (xy 374.447882 -243.399947) (xy 374.459427 -243.402507) (xy 374.465342 -243.402612)
			(xy 374.478042 -243.402612) (xy 374.56364 -243.35232) (xy 374.570919 -243.347624) (xy 374.581992 -243.33432)
			(xy 374.587895 -243.318048) (xy 374.588278 -243.309394) (xy 374.588278 -243.252498) (xy 374.588532 -243.249958)
			(xy 374.588532 -243.17325) (xy 374.58832 -243.167307) (xy 374.585505 -243.155757) (xy 374.582944 -243.15039)
			(xy 374.572784 -243.13134) (xy 374.567196 -243.122958) (xy 374.564148 -243.118894) (xy 374.559068 -243.115084)
			(xy 374.538684 -243.098471) (xy 374.503132 -243.059729) (xy 374.474426 -243.015674) (xy 374.453344 -242.967502)
			(xy 374.440461 -242.916523) (xy 374.436125 -242.86412) (xy 374.440454 -242.811716) (xy 374.453332 -242.760735)
			(xy 374.474407 -242.712561) (xy 374.503108 -242.668503) (xy 374.538655 -242.629756) (xy 374.559068 -242.61318)
			(xy 374.563894 -242.60937) (xy 374.567196 -242.605306) (xy 374.571768 -242.598956) (xy 374.581674 -242.580414)
			(xy 374.582944 -242.577874) (xy 374.58556 -242.572526) (xy 374.588396 -242.560966) (xy 374.588532 -242.555014)
			(xy 374.588532 -242.478306) (xy 374.588278 -242.475766) (xy 374.588278 -241.632486) (xy 374.588532 -241.629946)
			(xy 374.588532 -241.553238) (xy 374.588318 -241.547295) (xy 374.585501 -241.535746) (xy 374.582944 -241.530378)
			(xy 374.572784 -241.511328) (xy 374.567196 -241.502946) (xy 374.564148 -241.498882) (xy 374.559068 -241.495072)
			(xy 374.538685 -241.478459) (xy 374.503135 -241.439717) (xy 374.47443 -241.395663) (xy 374.453351 -241.347492)
			(xy 374.440469 -241.296514) (xy 374.436134 -241.244112) (xy 374.440465 -241.19171) (xy 374.453343 -241.140731)
			(xy 374.474419 -241.092559) (xy 374.50312 -241.048503) (xy 374.538667 -241.009758) (xy 374.559068 -240.993168)
			(xy 374.563894 -240.989358) (xy 374.567196 -240.985294) (xy 374.571768 -240.978944) (xy 374.581674 -240.960402)
			(xy 374.582944 -240.957862) (xy 374.585559 -240.952514) (xy 374.588392 -240.940953) (xy 374.588532 -240.935002)
			(xy 374.588532 -240.858294) (xy 374.588278 -240.855754) (xy 374.588278 -240.798858) (xy 374.58759 -240.786324)
			(xy 374.575576 -240.764325) (xy 374.565418 -240.756948) (xy 374.489218 -240.712498) (xy 374.483419 -240.709304)
			(xy 374.470685 -240.705697) (xy 374.464072 -240.705386) (xy 374.451372 -240.705386) (xy 374.445276 -240.708688)
			(xy 374.439688 -240.711736) (xy 374.439434 -240.71199) (xy 374.41562 -240.724598) (xy 374.364799 -240.742489)
			(xy 374.311688 -240.751551) (xy 374.284748 -240.752122) (xy 374.259754 -240.751661) (xy 374.21038 -240.743848)
			(xy 374.162837 -240.728407) (xy 374.118294 -240.705718) (xy 374.07785 -240.676341) (xy 374.0425 -240.640997)
			(xy 374.013114 -240.600559) (xy 373.990416 -240.556021) (xy 373.974966 -240.50848) (xy 373.967144 -240.459108)
			(xy 373.96674 -240.434114) (xy 373.967181 -240.410051) (xy 373.97443 -240.362473) (xy 373.988763 -240.316531)
			(xy 374.009855 -240.273273) (xy 374.037223 -240.233686) (xy 374.070243 -240.198674) (xy 374.108161 -240.169036)
			(xy 374.150111 -240.14545) (xy 374.195136 -240.128452) (xy 374.242208 -240.118432) (xy 374.266206 -240.116614)
			(xy 374.26646 -240.116614) (xy 374.27789 -240.115852) (xy 374.284748 -240.115852) (xy 374.311731 -240.116393)
			(xy 374.364931 -240.125447) (xy 374.415837 -240.143354) (xy 374.439688 -240.155984) (xy 374.442482 -240.157508)
			(xy 374.447883 -240.15992) (xy 374.459428 -240.162476) (xy 374.465342 -240.162588) (xy 374.478042 -240.162588)
			(xy 374.56364 -240.112296) (xy 374.570917 -240.107599) (xy 374.581983 -240.094294) (xy 374.587878 -240.078023)
			(xy 374.588278 -240.06937) (xy 374.588278 -240.012474) (xy 374.588532 -240.009934) (xy 374.588532 -239.933226)
			(xy 374.588317 -239.927284) (xy 374.585497 -239.915736) (xy 374.582944 -239.910366) (xy 374.572784 -239.891316)
			(xy 374.567196 -239.882934) (xy 374.564148 -239.87887) (xy 374.559068 -239.87506) (xy 374.538686 -239.858447)
			(xy 374.503138 -239.819705) (xy 374.474435 -239.775652) (xy 374.453357 -239.727482) (xy 374.440477 -239.676505)
			(xy 374.436144 -239.624105) (xy 374.440476 -239.571705) (xy 374.453354 -239.520727) (xy 374.47443 -239.472557)
			(xy 374.503132 -239.428502) (xy 374.538679 -239.38976) (xy 374.559068 -239.373156) (xy 374.563894 -239.369346)
			(xy 374.567196 -239.365282) (xy 374.571768 -239.358932) (xy 374.581674 -239.34039) (xy 374.582944 -239.33785)
			(xy 374.585558 -239.332501) (xy 374.588388 -239.320941) (xy 374.588532 -239.31499) (xy 374.588532 -239.238282)
			(xy 374.588278 -239.235742) (xy 374.588278 -238.313468) (xy 374.588136 -238.307803) (xy 374.58558 -238.296766)
			(xy 374.583198 -238.291624) (xy 374.574816 -238.275368) (xy 374.571768 -238.270796) (xy 374.559322 -238.255302)
			(xy 374.555258 -238.252) (xy 374.535441 -238.235393) (xy 374.500945 -238.196884) (xy 374.473126 -238.153305)
			(xy 374.452716 -238.105804) (xy 374.440251 -238.055628) (xy 374.43606 -238.004097) (xy 374.440252 -237.952567)
			(xy 374.452718 -237.902391) (xy 374.473128 -237.85489) (xy 374.500948 -237.811312) (xy 374.535445 -237.772803)
			(xy 374.555258 -237.756192) (xy 374.559322 -237.75289) (xy 374.571768 -237.737396) (xy 374.574816 -237.732824)
			(xy 374.583198 -237.716568) (xy 374.585518 -237.711405) (xy 374.588072 -237.700381) (xy 374.588278 -237.694724)
			(xy 374.588278 -237.558834) (xy 374.587607 -237.546291) (xy 374.575611 -237.524262) (xy 374.565418 -237.516924)
			(xy 374.489218 -237.472474) (xy 374.48342 -237.469276) (xy 374.470686 -237.465663) (xy 374.464072 -237.465362)
			(xy 374.451372 -237.465362) (xy 374.445276 -237.468664) (xy 374.439688 -237.471712) (xy 374.439434 -237.471966)
			(xy 374.41562 -237.484574) (xy 374.364799 -237.502467) (xy 374.311688 -237.51153) (xy 374.284748 -237.512098)
			(xy 374.259755 -237.511637) (xy 374.210382 -237.503824) (xy 374.16284 -237.488383) (xy 374.1183 -237.465694)
			(xy 374.077857 -237.436315) (xy 374.042509 -237.400972) (xy 374.013126 -237.360533) (xy 373.990432 -237.315995)
			(xy 373.974985 -237.268455) (xy 373.967166 -237.219083) (xy 373.96674 -237.19409) (xy 373.967183 -237.170028)
			(xy 373.974434 -237.122453) (xy 373.98877 -237.076514) (xy 374.009863 -237.033259) (xy 374.037232 -236.993675)
			(xy 374.070252 -236.958666) (xy 374.108169 -236.929031) (xy 374.150118 -236.905447) (xy 374.195141 -236.888451)
			(xy 374.242211 -236.878432) (xy 374.266206 -236.87659) (xy 374.26646 -236.87659) (xy 374.27789 -236.875828)
			(xy 374.284748 -236.875828) (xy 374.311731 -236.876369) (xy 374.364931 -236.885422) (xy 374.415838 -236.903328)
			(xy 374.439688 -236.91596) (xy 374.442482 -236.917484) (xy 374.447882 -236.919897) (xy 374.459428 -236.922454)
			(xy 374.465342 -236.922564) (xy 374.478042 -236.922564) (xy 374.56364 -236.872272) (xy 374.570914 -236.867575)
			(xy 374.581974 -236.854268) (xy 374.587862 -236.837997) (xy 374.588278 -236.829346) (xy 374.588278 -236.77245)
			(xy 374.588532 -236.76991) (xy 374.588532 -236.693202) (xy 374.588314 -236.687261) (xy 374.585489 -236.675715)
			(xy 374.582944 -236.670342) (xy 374.572784 -236.651292) (xy 374.567196 -236.64291) (xy 374.564148 -236.638846)
			(xy 374.559068 -236.635036) (xy 374.538688 -236.618423) (xy 374.503144 -236.579682) (xy 374.474445 -236.53563)
			(xy 374.453371 -236.487462) (xy 374.440493 -236.436487) (xy 374.436163 -236.38409) (xy 374.440497 -236.331693)
			(xy 374.453377 -236.280719) (xy 374.474454 -236.232553) (xy 374.503156 -236.188502) (xy 374.538702 -236.149764)
			(xy 374.559068 -236.133132) (xy 374.563894 -236.129322) (xy 374.567196 -236.125258) (xy 374.571768 -236.118908)
			(xy 374.581674 -236.100366) (xy 374.582944 -236.097826) (xy 374.585555 -236.092477) (xy 374.588379 -236.080917)
			(xy 374.588532 -236.074966) (xy 374.588532 -235.998258) (xy 374.588278 -235.995718) (xy 374.588278 -235.938822)
			(xy 374.587605 -235.92628) (xy 374.575605 -235.904257) (xy 374.565418 -235.896912) (xy 374.489218 -235.852462)
			(xy 374.48342 -235.849264) (xy 374.470686 -235.845653) (xy 374.464072 -235.84535) (xy 374.451372 -235.84535)
			(xy 374.445276 -235.848652) (xy 374.439688 -235.8517) (xy 374.439434 -235.851954) (xy 374.415621 -235.864563)
			(xy 374.364799 -235.882456) (xy 374.311688 -235.891519) (xy 374.284748 -235.892086) (xy 374.259755 -235.891625)
			(xy 374.210383 -235.883812) (xy 374.162842 -235.86837) (xy 374.118303 -235.845681) (xy 374.077861 -235.816302)
			(xy 374.042515 -235.780958) (xy 374.013133 -235.740519) (xy 373.99044 -235.695982) (xy 373.974995 -235.648442)
			(xy 373.967177 -235.599071) (xy 373.96674 -235.574078) (xy 373.967184 -235.550017) (xy 373.974437 -235.502443)
			(xy 373.988774 -235.456505) (xy 374.009867 -235.413252) (xy 374.037236 -235.37367) (xy 374.070256 -235.338662)
			(xy 374.108173 -235.309028) (xy 374.150121 -235.285445) (xy 374.195143 -235.26845) (xy 374.242212 -235.258432)
			(xy 374.266206 -235.256578) (xy 374.26646 -235.256578) (xy 374.27789 -235.255816) (xy 374.284748 -235.255816)
			(xy 374.311731 -235.256357) (xy 374.364931 -235.26541) (xy 374.415839 -235.283315) (xy 374.439688 -235.295948)
			(xy 374.442482 -235.297472) (xy 374.447882 -235.299886) (xy 374.459428 -235.302443) (xy 374.465342 -235.302552)
			(xy 374.478042 -235.302552) (xy 374.56364 -235.25226) (xy 374.570924 -235.247567) (xy 374.582007 -235.234264)
			(xy 374.587923 -235.217991) (xy 374.588278 -235.209334) (xy 374.588278 -235.152438) (xy 374.588532 -235.149898)
			(xy 374.588532 -235.07319) (xy 374.588313 -235.067249) (xy 374.585486 -235.055705) (xy 374.582944 -235.05033)
			(xy 374.572784 -235.03128) (xy 374.567196 -235.022898) (xy 374.564148 -235.018834) (xy 374.559068 -235.015024)
			(xy 374.538689 -234.998411) (xy 374.503147 -234.95967) (xy 374.47445 -234.915619) (xy 374.453377 -234.867452)
			(xy 374.440501 -234.816479) (xy 374.436172 -234.764083) (xy 374.440507 -234.711687) (xy 374.453388 -234.660715)
			(xy 374.474466 -234.612551) (xy 374.503168 -234.568502) (xy 374.538714 -234.529766) (xy 374.559068 -234.51312)
			(xy 374.563894 -234.50931) (xy 374.567196 -234.505246) (xy 374.571768 -234.498896) (xy 374.581674 -234.480354)
			(xy 374.582944 -234.477814) (xy 374.585554 -234.472465) (xy 374.588375 -234.460904) (xy 374.588532 -234.454954)
			(xy 374.588532 -234.378246) (xy 374.588278 -234.375706) (xy 374.588278 -233.532426) (xy 374.588532 -233.529886)
			(xy 374.588532 -233.453178) (xy 374.588312 -233.447237) (xy 374.585482 -233.435694) (xy 374.582944 -233.430318)
			(xy 374.572784 -233.411268) (xy 374.567196 -233.402886) (xy 374.564148 -233.398822) (xy 374.559068 -233.395012)
			(xy 374.53869 -233.378399) (xy 374.50315 -233.339658) (xy 374.474455 -233.295607) (xy 374.453384 -233.247442)
			(xy 374.44051 -233.19647) (xy 374.436182 -233.144075) (xy 374.440518 -233.091682) (xy 374.4534 -233.040711)
			(xy 374.474478 -232.992549) (xy 374.50318 -232.948503) (xy 374.538726 -232.909768) (xy 374.559068 -232.893108)
			(xy 374.563894 -232.889298) (xy 374.567196 -232.885234) (xy 374.571768 -232.878884) (xy 374.581674 -232.860342)
			(xy 374.582944 -232.857802) (xy 374.585552 -232.852452) (xy 374.588371 -232.840892) (xy 374.588532 -232.834942)
			(xy 374.588532 -232.758234) (xy 374.588278 -232.755694) (xy 374.588278 -232.698798) (xy 374.587599 -232.686259)
			(xy 374.575594 -232.664245) (xy 374.565418 -232.656888) (xy 374.489218 -232.612438) (xy 374.483419 -232.609242)
			(xy 374.470686 -232.605632) (xy 374.464072 -232.605326) (xy 374.451372 -232.605326) (xy 374.445276 -232.608628)
			(xy 374.439688 -232.611676) (xy 374.439434 -232.61193) (xy 374.415621 -232.624539) (xy 374.3648 -232.642434)
			(xy 374.311688 -232.651498) (xy 374.284748 -232.652062) (xy 374.259756 -232.651601) (xy 374.210386 -232.643787)
			(xy 374.162846 -232.628346) (xy 374.118308 -232.605656) (xy 374.077869 -232.576277) (xy 374.042524 -232.540933)
			(xy 374.013145 -232.500494) (xy 373.990455 -232.455956) (xy 373.975013 -232.408416) (xy 373.9672 -232.359046)
			(xy 373.96674 -232.334054) (xy 373.967185 -232.309994) (xy 373.974441 -232.262423) (xy 373.98878 -232.216488)
			(xy 374.009876 -232.173238) (xy 374.037245 -232.133659) (xy 374.070265 -232.098654) (xy 374.108181 -232.069023)
			(xy 374.150127 -232.045442) (xy 374.195148 -232.028449) (xy 374.242214 -232.018432) (xy 374.266206 -232.016554)
			(xy 374.26646 -232.016554) (xy 374.27789 -232.015792) (xy 374.284748 -232.015792) (xy 374.311731 -232.016333)
			(xy 374.364932 -232.025385) (xy 374.41584 -232.043289) (xy 374.439688 -232.055924) (xy 374.442482 -232.057448)
			(xy 374.447882 -232.059863) (xy 374.459427 -232.062421) (xy 374.465342 -232.062528) (xy 374.478042 -232.062528)
			(xy 374.56364 -232.012236) (xy 374.570921 -232.007542) (xy 374.581999 -231.994238) (xy 374.587906 -231.977965)
			(xy 374.588278 -231.96931) (xy 374.588278 -231.912414) (xy 374.588532 -231.909874) (xy 374.588532 -231.833166)
			(xy 374.58831 -231.827226) (xy 374.585478 -231.815684) (xy 374.582944 -231.810306) (xy 374.572784 -231.791256)
			(xy 374.567196 -231.782874) (xy 374.564148 -231.77881) (xy 374.559068 -231.775) (xy 374.538683 -231.758387)
			(xy 374.503128 -231.719644) (xy 374.474419 -231.675588) (xy 374.453336 -231.627416) (xy 374.44045 -231.576435)
			(xy 374.436112 -231.52403) (xy 374.44044 -231.471624) (xy 374.453316 -231.42064) (xy 374.474391 -231.372464)
			(xy 374.503092 -231.328403) (xy 374.538639 -231.289654) (xy 374.559068 -231.273096) (xy 374.563894 -231.269286)
			(xy 374.567196 -231.265222) (xy 374.571768 -231.258872) (xy 374.581674 -231.24033) (xy 374.582944 -231.23779)
			(xy 374.585551 -231.23244) (xy 374.588367 -231.22088) (xy 374.588532 -231.21493) (xy 374.588532 -231.138222)
			(xy 374.588278 -231.135682) (xy 374.588278 -230.292402) (xy 374.588532 -230.289862) (xy 374.588532 -230.213154)
			(xy 374.58832 -230.207211) (xy 374.585506 -230.19566) (xy 374.582944 -230.190294) (xy 374.572784 -230.171244)
			(xy 374.567196 -230.162862) (xy 374.564148 -230.158798) (xy 374.559068 -230.154988) (xy 374.538684 -230.138375)
			(xy 374.503131 -230.099632) (xy 374.474424 -230.055577) (xy 374.453342 -230.007406) (xy 374.440458 -229.956426)
			(xy 374.436122 -229.904022) (xy 374.440451 -229.851618) (xy 374.453328 -229.800636) (xy 374.474403 -229.752462)
			(xy 374.503104 -229.708403) (xy 374.538651 -229.669655) (xy 374.559068 -229.653084) (xy 374.563894 -229.649274)
			(xy 374.567196 -229.64521) (xy 374.571768 -229.63886) (xy 374.581674 -229.620318) (xy 374.582944 -229.617778)
			(xy 374.585561 -229.61243) (xy 374.588397 -229.60087) (xy 374.588532 -229.594918) (xy 374.588532 -229.51821)
			(xy 374.588278 -229.51567) (xy 374.588278 -229.459028) (xy 374.587606 -229.446485) (xy 374.575608 -229.424459)
			(xy 374.565418 -229.417118) (xy 374.489218 -229.372668) (xy 374.48342 -229.36947) (xy 374.470686 -229.365858)
			(xy 374.464072 -229.365556) (xy 374.451372 -229.365556) (xy 374.445276 -229.368858) (xy 374.439688 -229.371906)
			(xy 374.439434 -229.37216) (xy 374.41562 -229.384769) (xy 374.364799 -229.402661) (xy 374.311688 -229.411725)
			(xy 374.284748 -229.412292) (xy 374.259755 -229.411831) (xy 374.210383 -229.404018) (xy 374.162841 -229.388577)
			(xy 374.118301 -229.365887) (xy 374.077859 -229.336509) (xy 374.042512 -229.301165) (xy 374.013129 -229.260726)
			(xy 373.990436 -229.216188) (xy 373.974989 -229.168648) (xy 373.967171 -229.119277) (xy 373.96674 -229.094284)
			(xy 373.967183 -229.070222) (xy 373.974436 -229.022648) (xy 373.988772 -228.97671) (xy 374.009865 -228.933455)
			(xy 374.037234 -228.893872) (xy 374.070254 -228.858864) (xy 374.108171 -228.82923) (xy 374.150119 -228.805646)
			(xy 374.195142 -228.788651) (xy 374.242211 -228.778632) (xy 374.266206 -228.776784) (xy 374.26646 -228.776784)
			(xy 374.27789 -228.776022) (xy 374.284748 -228.776022) (xy 374.311731 -228.776563) (xy 374.364931 -228.785616)
			(xy 374.415839 -228.803522) (xy 374.439688 -228.816154) (xy 374.442482 -228.817678) (xy 374.447882 -228.820091)
			(xy 374.459428 -228.822648) (xy 374.465342 -228.822758) (xy 374.478042 -228.822758) (xy 374.56364 -228.772466)
			(xy 374.570925 -228.767773) (xy 374.58201 -228.75447) (xy 374.587927 -228.738197) (xy 374.588278 -228.72954)
			(xy 374.588278 -228.672644) (xy 374.588532 -228.670104) (xy 374.588532 -228.593396) (xy 374.588314 -228.587455)
			(xy 374.585488 -228.57591) (xy 374.582944 -228.570536) (xy 374.572784 -228.551486) (xy 374.567196 -228.543104)
			(xy 374.564148 -228.53904) (xy 374.559068 -228.53523) (xy 374.538688 -228.518617) (xy 374.503145 -228.479876)
			(xy 374.474447 -228.435824) (xy 374.453374 -228.387657) (xy 374.440497 -228.336683) (xy 374.436168 -228.284286)
			(xy 374.440502 -228.23189) (xy 374.453383 -228.180917) (xy 374.47446 -228.132752) (xy 374.503162 -228.088702)
			(xy 374.538708 -228.049965) (xy 374.559068 -228.033326) (xy 374.563894 -228.029516) (xy 374.567196 -228.025452)
			(xy 374.571768 -228.019102) (xy 374.581674 -228.00056) (xy 374.582944 -227.99802) (xy 374.585554 -227.992671)
			(xy 374.588377 -227.98111) (xy 374.588532 -227.97516) (xy 374.588532 -227.883466) (xy 374.589062 -227.873626)
			(xy 374.596644 -227.855459) (xy 374.603264 -227.84816) (xy 374.89511 -227.556314) (xy 374.899139 -227.552108)
			(xy 374.905294 -227.542224) (xy 374.907302 -227.536756) (xy 374.910858 -227.526342) (xy 374.909334 -227.514658)
			(xy 374.909334 -227.514404) (xy 374.90908 -227.51288) (xy 374.908037 -227.503708) (xy 374.906891 -227.485281)
			(xy 374.906794 -227.47605) (xy 374.906794 -227.472748) (xy 374.907393 -227.447915) (xy 374.915356 -227.398885)
			(xy 374.930844 -227.35169) (xy 374.953482 -227.307477) (xy 374.98272 -227.267321) (xy 375.017844 -227.2322)
			(xy 375.058003 -227.202967) (xy 375.102218 -227.180333) (xy 375.149415 -227.164849) (xy 375.198445 -227.156891)
			(xy 375.223278 -227.156264) (xy 375.225056 -227.156264) (xy 375.235053 -227.15635) (xy 375.255007 -227.157621)
			(xy 375.264934 -227.158804) (xy 375.265188 -227.158804) (xy 375.27663 -227.159691) (xy 375.298321 -227.152268)
			(xy 375.306844 -227.14458) (xy 375.406666 -227.044758) (xy 375.413379 -227.037521) (xy 375.42097 -227.019315)
			(xy 375.421398 -227.009452) (xy 375.421398 -226.864418) (xy 375.41962 -226.85121) (xy 375.414286 -226.832414)
			(xy 375.412762 -226.82962) (xy 375.410984 -226.826572) (xy 375.397447 -226.801683) (xy 375.378214 -226.748395)
			(xy 375.368437 -226.692592) (xy 375.367804 -226.664266) (xy 375.368404 -226.635937) (xy 375.378172 -226.580127)
			(xy 375.397427 -226.526842) (xy 375.410984 -226.50196) (xy 375.412762 -226.498912) (xy 375.414286 -226.496118)
			(xy 375.41962 -226.477322) (xy 375.421398 -226.464114) (xy 375.421398 -225.220022) (xy 375.421302 -225.216079)
			(xy 375.420023 -225.208296) (xy 375.418858 -225.204528) (xy 375.418604 -225.203766) (xy 375.415048 -225.195892)
			(xy 375.414032 -225.193606) (xy 375.412762 -225.191066) (xy 375.412254 -225.19005) (xy 375.401415 -225.168155)
			(xy 375.385853 -225.121845) (xy 375.381266 -225.097848) (xy 375.379742 -225.08972) (xy 375.37644 -225.08337)
			(xy 375.374601 -225.079895) (xy 375.370009 -225.073515) (xy 375.367296 -225.07067) (xy 375.230644 -224.934018)
			(xy 375.223395 -224.927465) (xy 375.205352 -224.920014) (xy 375.195592 -224.91954) (xy 374.395492 -224.91954)
			(xy 374.385648 -224.920063) (xy 374.367465 -224.927628) (xy 374.360186 -224.934272) (xy 374.089168 -225.20529)
			(xy 374.085612 -225.211132) (xy 374.070982 -225.233846) (xy 374.035277 -225.274389) (xy 373.993232 -225.308313)
			(xy 373.946058 -225.334642) (xy 373.895112 -225.352619) (xy 373.84186 -225.361725) (xy 373.814848 -225.362262)
			(xy 373.789856 -225.361801) (xy 373.740486 -225.353987) (xy 373.692946 -225.338546) (xy 373.648408 -225.315856)
			(xy 373.607969 -225.286477) (xy 373.572624 -225.251133) (xy 373.543245 -225.210694) (xy 373.520555 -225.166156)
			(xy 373.505113 -225.118616) (xy 373.4973 -225.069246) (xy 373.49684 -225.044254) (xy 373.49727 -225.020685)
			(xy 373.504232 -224.974064) (xy 373.517997 -224.92898) (xy 373.538262 -224.88642) (xy 373.564585 -224.847317)
			(xy 373.59639 -224.812525) (xy 373.63298 -224.782807) (xy 373.65305 -224.770442) (xy 373.653812 -224.769934)
			(xy 374.135904 -224.287842) (xy 374.143144 -224.281133) (xy 374.161348 -224.273543) (xy 374.17121 -224.27311)
			(xy 375.79681 -224.27311) (xy 375.806619 -224.272607) (xy 375.824774 -224.265157) (xy 375.832116 -224.258632)
			(xy 375.84634 -224.244916) (xy 375.84634 -224.2439) (xy 375.846848 -224.227898) (xy 375.847102 -224.223834)
			(xy 375.848443 -224.198112) (xy 375.858406 -224.147582) (xy 375.876383 -224.099318) (xy 375.901905 -224.054583)
			(xy 375.934304 -224.014546) (xy 375.972733 -223.980256) (xy 376.016187 -223.952609) (xy 376.063529 -223.932328)
			(xy 376.113521 -223.919943) (xy 376.164856 -223.915778) (xy 376.216191 -223.919943) (xy 376.266183 -223.932328)
			(xy 376.313525 -223.952609) (xy 376.356979 -223.980256) (xy 376.395408 -224.014546) (xy 376.427807 -224.054583)
			(xy 376.453329 -224.099318) (xy 376.471306 -224.147582) (xy 376.481269 -224.198112) (xy 376.48261 -224.223834)
			(xy 376.482864 -224.227898) (xy 376.483372 -224.2439) (xy 376.483372 -224.244916) (xy 376.497596 -224.258632)
			(xy 376.504925 -224.265175) (xy 376.523089 -224.272611) (xy 376.532902 -224.27311) (xy 376.736864 -224.27311)
			(xy 376.746677 -224.272615) (xy 376.764843 -224.265177) (xy 376.77217 -224.258632) (xy 376.786394 -224.244916)
			(xy 376.786394 -224.2439) (xy 376.786902 -224.227898) (xy 376.787156 -224.223834) (xy 376.788497 -224.198112)
			(xy 376.79846 -224.147582) (xy 376.816437 -224.099318) (xy 376.841959 -224.054583) (xy 376.874358 -224.014546)
			(xy 376.912787 -223.980256) (xy 376.956241 -223.952609) (xy 377.003583 -223.932328) (xy 377.053575 -223.919943)
			(xy 377.10491 -223.915778) (xy 377.156245 -223.919943) (xy 377.206237 -223.932328) (xy 377.253579 -223.952609)
			(xy 377.297033 -223.980256) (xy 377.335462 -224.014546) (xy 377.367861 -224.054583) (xy 377.393383 -224.099318)
			(xy 377.41136 -224.147582) (xy 377.421323 -224.198112) (xy 377.422664 -224.223834) (xy 377.422918 -224.227898)
			(xy 377.423426 -224.2439) (xy 377.423426 -224.244916) (xy 377.43765 -224.258632) (xy 377.444976 -224.265182)
			(xy 377.46314 -224.272635) (xy 377.472956 -224.27311) (xy 377.676664 -224.27311) (xy 377.686477 -224.272615)
			(xy 377.704643 -224.265177) (xy 377.71197 -224.258632) (xy 377.726194 -224.244916) (xy 377.726194 -224.2439)
			(xy 377.726702 -224.227898) (xy 377.726956 -224.223834) (xy 377.728212 -224.199371) (xy 377.737309 -224.151241)
			(xy 377.753675 -224.105074) (xy 377.776925 -224.061962) (xy 377.806508 -224.022923) (xy 377.841725 -223.988879)
			(xy 377.881745 -223.960637) (xy 377.925621 -223.938862) (xy 377.972316 -223.92407) (xy 378.020727 -223.91661)
			(xy 378.045218 -223.91624) (xy 378.049028 -223.91624) (xy 378.073335 -223.917031) (xy 378.121297 -223.925061)
			(xy 378.144532 -223.932242) (xy 378.144786 -223.932242) (xy 378.150702 -223.934063) (xy 378.163035 -223.935096)
			(xy 378.16917 -223.934274) (xy 378.180092 -223.932496) (xy 378.258578 -223.8756) (xy 378.266586 -223.868173)
			(xy 378.27582 -223.848408) (xy 378.276358 -223.8375) (xy 378.276358 -223.661224) (xy 378.276267 -223.657281)
			(xy 378.274985 -223.649498) (xy 378.273818 -223.64573) (xy 378.265436 -223.621854) (xy 378.260864 -223.615758)
			(xy 378.24578 -223.594935) (xy 378.221829 -223.54944) (xy 378.205504 -223.500686) (xy 378.197232 -223.449941)
			(xy 378.197226 -223.398526) (xy 378.205488 -223.34778) (xy 378.221802 -223.299022) (xy 378.245744 -223.253522)
			(xy 378.260864 -223.232726) (xy 378.265436 -223.22663) (xy 378.273818 -223.202754) (xy 378.274966 -223.198982)
			(xy 378.276246 -223.191201) (xy 378.276358 -223.18726) (xy 378.276358 -223.026478) (xy 378.275707 -223.014501)
			(xy 378.264829 -222.993162) (xy 378.25553 -222.985584) (xy 378.179838 -222.929958) (xy 378.155708 -222.926148)
			(xy 378.144278 -222.929704) (xy 378.120194 -222.936798) (xy 378.070574 -222.94445) (xy 378.045472 -222.944944)
			(xy 378.04471 -222.944944) (xy 378.020219 -222.944504) (xy 377.971771 -222.93729) (xy 377.924914 -222.923018)
			(xy 377.880671 -222.901999) (xy 377.840006 -222.874692) (xy 377.803808 -222.841693) (xy 377.772866 -222.803722)
			(xy 377.759976 -222.782892) (xy 377.755912 -222.77578) (xy 377.730258 -222.753428) (xy 377.727972 -222.752666)
			(xy 377.722384 -222.75038) (xy 377.681236 -222.731838) (xy 377.653655 -222.717692) (xy 377.601419 -222.684316)
			(xy 377.553091 -222.645497) (xy 377.530868 -222.623888) (xy 377.219972 -222.312738) (xy 377.214267 -222.307403)
			(xy 377.200428 -222.300176) (xy 377.192794 -222.298514) (xy 377.183904 -222.297752) (xy 377.128532 -222.297752)
			(xy 377.118693 -222.298287) (xy 377.100527 -222.305868) (xy 377.093226 -222.312484) (xy 376.44705 -222.95866)
			(xy 376.439808 -222.965362) (xy 376.421603 -222.972934) (xy 376.411744 -222.973392) (xy 376.34926 -222.973392)
			(xy 376.340116 -222.974408) (xy 376.338846 -222.974662) (xy 376.338592 -222.974662) (xy 376.335798 -222.97517)
			(xy 376.327416 -222.976948) (xy 376.320812 -222.97898) (xy 376.30862 -222.98406) (xy 376.303794 -222.985838)
			(xy 376.30354 -222.985838) (xy 376.287892 -222.991522) (xy 376.255846 -223.000552) (xy 376.239532 -223.003872)
			(xy 376.22988 -223.00565) (xy 376.195748 -223.010639) (xy 376.126775 -223.010126) (xy 376.09272 -223.004634)
			(xy 376.084846 -223.002856) (xy 376.058938 -222.996506) (xy 376.048227 -222.993474) (xy 376.027132 -222.986358)
			(xy 376.016774 -222.982282) (xy 375.99747 -222.9739) (xy 375.995184 -222.972884) (xy 375.983555 -222.973869)
			(xy 375.961455 -222.966452) (xy 375.952766 -222.95866) (xy 375.921778 -222.927672) (xy 375.919238 -222.92564)
			(xy 375.903163 -222.912668) (xy 375.873513 -222.883907) (xy 375.860056 -222.868236) (xy 375.853706 -222.860362)
			(xy 375.852944 -222.859346) (xy 375.849642 -222.855536) (xy 375.56059 -222.566484) (xy 375.553877 -222.559246)
			(xy 375.546284 -222.541041) (xy 375.545858 -222.531178) (xy 375.545858 -222.308166) (xy 375.545348 -222.298413)
			(xy 375.537909 -222.280375) (xy 375.53138 -222.273114) (xy 375.484136 -222.22587) (xy 375.476889 -222.219312)
			(xy 375.458846 -222.211856) (xy 375.449084 -222.211392) (xy 374.537478 -222.211392) (xy 374.532918 -222.211559)
			(xy 374.523969 -222.213343) (xy 374.519698 -222.214948) (xy 374.513856 -222.217234) (xy 374.509288 -222.218986)
			(xy 374.499696 -222.220905) (xy 374.494806 -222.221044) (xy 373.807736 -222.221044) (xy 373.802841 -222.22094)
			(xy 373.793241 -222.219027) (xy 373.788686 -222.217234) (xy 373.771414 -222.210122) (xy 373.762016 -222.206312)
			(xy 373.627396 -222.206312) (xy 373.617507 -222.206852) (xy 373.599272 -222.214522) (xy 373.58535 -222.228578)
			(xy 373.581168 -222.237554) (xy 373.563896 -222.281496) (xy 373.546116 -222.326962) (xy 373.543858 -222.334537)
			(xy 373.54374 -222.350335) (xy 373.545862 -222.35795) (xy 373.547894 -222.3643) (xy 373.554244 -222.374714)
			(xy 373.560086 -222.380048) (xy 373.579103 -222.398263) (xy 373.61143 -222.439829) (xy 373.63647 -222.48615)
			(xy 373.65354 -222.535963) (xy 373.662174 -222.587907) (xy 373.662702 -222.614236) (xy 373.662702 -222.618046)
			(xy 373.662293 -222.634569) (xy 373.658475 -222.667402) (xy 373.655082 -222.683578) (xy 373.649355 -222.707135)
			(xy 373.631731 -222.752295) (xy 373.607455 -222.794257) (xy 373.57709 -222.832046) (xy 373.54134 -222.864788)
			(xy 373.501034 -222.891722) (xy 373.457106 -222.912225) (xy 373.410574 -222.925822) (xy 373.386604 -222.92945)
			(xy 373.381778 -222.930212) (xy 373.372539 -222.931189) (xy 373.353985 -222.932204) (xy 373.344694 -222.932244)
			(xy 373.320031 -222.93178) (xy 373.271296 -222.924166) (xy 373.22432 -222.909121) (xy 373.180229 -222.887007)
			(xy 373.14008 -222.858353) (xy 373.104834 -222.823845) (xy 373.075336 -222.784311) (xy 373.052293 -222.740698)
			(xy 373.036258 -222.694052) (xy 373.027614 -222.645489) (xy 373.026686 -222.62084) (xy 373.026686 -222.613982)
			(xy 373.027201 -222.587678) (xy 373.035864 -222.535788) (xy 373.052951 -222.486033) (xy 373.077995 -222.439769)
			(xy 373.110313 -222.398258) (xy 373.129302 -222.380048) (xy 373.129556 -222.380048) (xy 373.12981 -222.379794)
			(xy 373.13657 -222.372912) (xy 373.144736 -222.355455) (xy 373.145761 -222.336209) (xy 373.143018 -222.326962)
			(xy 373.107204 -222.23476) (xy 373.102786 -222.226422) (xy 373.088983 -222.213578) (xy 373.071421 -222.206713)
			(xy 373.061992 -222.206312) (xy 372.533672 -222.206312) (xy 372.530624 -222.206312) (xy 372.5219 -222.207192)
			(xy 372.505788 -222.214072) (xy 372.499128 -222.219774) (xy 372.493032 -222.226632) (xy 372.46179 -222.26524)
			(xy 372.436877 -222.293012) (xy 372.382076 -222.343647) (xy 372.322201 -222.388165) (xy 372.25793 -222.426061)
			(xy 372.189993 -222.456907) (xy 372.11916 -222.480351) (xy 372.046235 -222.496127) (xy 371.972046 -222.504057)
			(xy 371.93474 -222.504508) (xy 371.895734 -222.50396) (xy 371.818208 -222.495263) (xy 371.742127 -222.478007)
			(xy 371.668436 -222.452405) (xy 371.598045 -222.418773) (xy 371.564662 -222.39859) (xy 371.548731 -222.388529)
			(xy 371.517854 -222.366925) (xy 371.50294 -222.35541) (xy 371.496336 -222.35033) (xy 371.481858 -222.34525)
			(xy 371.473542 -222.342664) (xy 371.456138 -222.342664) (xy 371.447822 -222.34525) (xy 371.433344 -222.35033)
			(xy 371.42674 -222.35541) (xy 371.395869 -222.378934) (xy 371.329854 -222.419757) (xy 371.25973 -222.453033)
			(xy 371.186359 -222.478353) (xy 371.110637 -222.495407) (xy 371.033495 -222.503986) (xy 370.994686 -222.504508)
			(xy 370.954554 -222.503238) (xy 370.950744 -222.502984) (xy 370.95049 -222.502984) (xy 370.939822 -222.502476)
			(xy 370.930424 -222.506032) (xy 370.92558 -222.507941) (xy 370.916744 -222.513445) (xy 370.912898 -222.516954)
			(xy 370.856002 -222.57131) (xy 370.849788 -222.578759) (xy 370.843013 -222.596917) (xy 370.842794 -222.606616)
			(xy 370.842794 -222.617538) (xy 370.842051 -222.642781) (xy 370.833561 -222.692559) (xy 370.817308 -222.74037)
			(xy 370.793701 -222.78501) (xy 370.763335 -222.825357) (xy 370.726972 -222.860396) (xy 370.685527 -222.889246)
			(xy 370.640042 -222.911181) (xy 370.591662 -222.92565) (xy 370.566696 -222.92945) (xy 370.56187 -222.930212)
			(xy 370.552631 -222.931189) (xy 370.534077 -222.932204) (xy 370.524786 -222.932244) (xy 370.500123 -222.931779)
			(xy 370.451389 -222.924164) (xy 370.404415 -222.909119) (xy 370.360325 -222.887004) (xy 370.320176 -222.85835)
			(xy 370.284931 -222.823843) (xy 370.255434 -222.784309) (xy 370.232392 -222.740696) (xy 370.216357 -222.69405)
			(xy 370.207714 -222.645488) (xy 370.206778 -222.62084) (xy 370.206778 -222.613982) (xy 370.207293 -222.587678)
			(xy 370.215956 -222.535788) (xy 370.233042 -222.486032) (xy 370.258086 -222.439768) (xy 370.290404 -222.398257)
			(xy 370.309394 -222.380048) (xy 370.309648 -222.380048) (xy 370.309902 -222.379794) (xy 370.316662 -222.372912)
			(xy 370.324831 -222.355455) (xy 370.325855 -222.336209) (xy 370.32311 -222.326962) (xy 370.287296 -222.23476)
			(xy 370.282882 -222.226412) (xy 370.269083 -222.213542) (xy 370.251519 -222.206647) (xy 370.242084 -222.206312)
			(xy 369.713764 -222.206312) (xy 369.710716 -222.206312) (xy 369.701993 -222.207193) (xy 369.685882 -222.214075)
			(xy 369.67922 -222.219774) (xy 369.673124 -222.226632) (xy 369.641882 -222.26524) (xy 369.616969 -222.293012)
			(xy 369.562168 -222.343646) (xy 369.502293 -222.388163) (xy 369.438022 -222.426059) (xy 369.370084 -222.456904)
			(xy 369.299251 -222.480347) (xy 369.226327 -222.496122) (xy 369.152138 -222.504051) (xy 369.114832 -222.504508)
			(xy 369.075826 -222.503959) (xy 368.9983 -222.495262) (xy 368.92222 -222.478005) (xy 368.848529 -222.452402)
			(xy 368.778138 -222.41877) (xy 368.744754 -222.39859) (xy 368.728823 -222.388528) (xy 368.697947 -222.366924)
			(xy 368.683032 -222.35541) (xy 368.676428 -222.35033) (xy 368.66195 -222.34525) (xy 368.653634 -222.342664)
			(xy 368.63623 -222.342664) (xy 368.627914 -222.34525) (xy 368.613436 -222.35033) (xy 368.606832 -222.35541)
			(xy 368.575961 -222.378933) (xy 368.509945 -222.419756) (xy 368.439822 -222.453031) (xy 368.36645 -222.47835)
			(xy 368.290729 -222.495403) (xy 368.213587 -222.503981) (xy 368.174778 -222.504508) (xy 368.134646 -222.503238)
			(xy 368.130836 -222.502984) (xy 368.130582 -222.502984) (xy 368.119914 -222.502476) (xy 368.110516 -222.506032)
			(xy 368.105673 -222.507942) (xy 368.096838 -222.513447) (xy 368.09299 -222.516954) (xy 368.036094 -222.57131)
			(xy 368.029881 -222.578759) (xy 368.023107 -222.596917) (xy 368.022886 -222.606616) (xy 368.022886 -222.614236)
			(xy 368.022396 -222.639225) (xy 368.014577 -222.688588) (xy 367.999133 -222.73612) (xy 367.976443 -222.780652)
			(xy 367.947067 -222.821085) (xy 367.911727 -222.856425) (xy 367.871294 -222.885801) (xy 367.826762 -222.908491)
			(xy 367.77923 -222.923935) (xy 367.729867 -222.931754) (xy 367.679889 -222.931754) (xy 367.630526 -222.923935)
			(xy 367.582994 -222.908491) (xy 367.538462 -222.885801) (xy 367.498029 -222.856425) (xy 367.462689 -222.821085)
			(xy 367.433313 -222.780652) (xy 367.410623 -222.73612) (xy 367.395179 -222.688588) (xy 367.38736 -222.639225)
			(xy 367.38687 -222.614236) (xy 367.387307 -222.590494) (xy 367.39436 -222.543535) (xy 367.408314 -222.498147)
			(xy 367.42886 -222.455337) (xy 367.455541 -222.416057) (xy 367.487764 -222.381178) (xy 367.524813 -222.351477)
			(xy 367.545112 -222.339154) (xy 367.553748 -222.334328) (xy 367.572036 -222.310452) (xy 367.575182 -222.306221)
			(xy 367.579801 -222.296745) (xy 367.58118 -222.291656) (xy 367.597182 -222.227902) (xy 367.598734 -222.218664)
			(xy 367.595872 -222.200167) (xy 367.591594 -222.191834) (xy 367.59007 -222.189294) (xy 367.570826 -222.159276)
			(xy 367.537864 -222.096045) (xy 367.511514 -222.029784) (xy 367.492051 -221.961185) (xy 367.485422 -221.92615)
			(xy 367.484152 -221.918276) (xy 367.480342 -221.911164) (xy 367.478506 -221.90791) (xy 367.474045 -221.901916)
			(xy 367.471452 -221.899226) (xy 366.380014 -220.807788) (xy 366.372767 -220.801232) (xy 366.354723 -220.793781)
			(xy 366.344962 -220.79331) (xy 355.336348 -220.79331) (xy 355.326321 -220.793721) (xy 355.307789 -220.801383)
			(xy 355.293604 -220.815557) (xy 355.285929 -220.834083) (xy 355.285548 -220.84411) (xy 355.285548 -221.203266)
			(xy 355.285034 -221.238779) (xy 355.276291 -221.309264) (xy 355.258899 -221.378127) (xy 355.233124 -221.44431)
			(xy 355.216714 -221.475808) (xy 355.212931 -221.483546) (xy 355.210216 -221.500546) (xy 355.21138 -221.509082)
			(xy 355.216714 -221.538292) (xy 355.218603 -221.546503) (xy 355.226895 -221.561156) (xy 355.23297 -221.566994)
			(xy 355.252587 -221.585251) (xy 355.286011 -221.627134) (xy 355.311938 -221.674029) (xy 355.329634 -221.724607)
			(xy 355.338598 -221.777437) (xy 355.339142 -221.80423) (xy 355.339142 -221.813628) (xy 355.338251 -221.829219)
			(xy 363.157244 -221.829219) (xy 363.157244 -221.779241) (xy 363.165063 -221.729878) (xy 363.180507 -221.682346)
			(xy 363.203197 -221.637814) (xy 363.232573 -221.597381) (xy 363.267913 -221.562041) (xy 363.308346 -221.532665)
			(xy 363.352878 -221.509975) (xy 363.40041 -221.494531) (xy 363.449773 -221.486712) (xy 363.499751 -221.486712)
			(xy 363.549114 -221.494531) (xy 363.596646 -221.509975) (xy 363.641178 -221.532665) (xy 363.681611 -221.562041)
			(xy 363.716951 -221.597381) (xy 363.746327 -221.637814) (xy 363.769017 -221.682346) (xy 363.784461 -221.729878)
			(xy 363.79228 -221.779241) (xy 363.79277 -221.80423) (xy 363.79228 -221.829219) (xy 364.097298 -221.829219)
			(xy 364.097298 -221.779241) (xy 364.105117 -221.729878) (xy 364.120561 -221.682346) (xy 364.143251 -221.637814)
			(xy 364.172627 -221.597381) (xy 364.207967 -221.562041) (xy 364.2484 -221.532665) (xy 364.292932 -221.509975)
			(xy 364.340464 -221.494531) (xy 364.389827 -221.486712) (xy 364.439805 -221.486712) (xy 364.489168 -221.494531)
			(xy 364.5367 -221.509975) (xy 364.581232 -221.532665) (xy 364.621665 -221.562041) (xy 364.657005 -221.597381)
			(xy 364.686381 -221.637814) (xy 364.709071 -221.682346) (xy 364.724515 -221.729878) (xy 364.732334 -221.779241)
			(xy 364.732824 -221.80423) (xy 364.732334 -221.829219) (xy 365.037352 -221.829219) (xy 365.037352 -221.779241)
			(xy 365.045171 -221.729878) (xy 365.060615 -221.682346) (xy 365.083305 -221.637814) (xy 365.112681 -221.597381)
			(xy 365.148021 -221.562041) (xy 365.188454 -221.532665) (xy 365.232986 -221.509975) (xy 365.280518 -221.494531)
			(xy 365.329881 -221.486712) (xy 365.379859 -221.486712) (xy 365.429222 -221.494531) (xy 365.476754 -221.509975)
			(xy 365.521286 -221.532665) (xy 365.561719 -221.562041) (xy 365.597059 -221.597381) (xy 365.626435 -221.637814)
			(xy 365.649125 -221.682346) (xy 365.664569 -221.729878) (xy 365.672388 -221.779241) (xy 365.672878 -221.80423)
			(xy 365.672388 -221.829219) (xy 365.664569 -221.878582) (xy 365.649125 -221.926114) (xy 365.626435 -221.970646)
			(xy 365.597059 -222.011079) (xy 365.561719 -222.046419) (xy 365.521286 -222.075795) (xy 365.476754 -222.098485)
			(xy 365.429222 -222.113929) (xy 365.379859 -222.121748) (xy 365.329881 -222.121748) (xy 365.280518 -222.113929)
			(xy 365.232986 -222.098485) (xy 365.188454 -222.075795) (xy 365.148021 -222.046419) (xy 365.112681 -222.011079)
			(xy 365.083305 -221.970646) (xy 365.060615 -221.926114) (xy 365.045171 -221.878582) (xy 365.037352 -221.829219)
			(xy 364.732334 -221.829219) (xy 364.724515 -221.878582) (xy 364.709071 -221.926114) (xy 364.686381 -221.970646)
			(xy 364.657005 -222.011079) (xy 364.621665 -222.046419) (xy 364.581232 -222.075795) (xy 364.5367 -222.098485)
			(xy 364.489168 -222.113929) (xy 364.439805 -222.121748) (xy 364.389827 -222.121748) (xy 364.340464 -222.113929)
			(xy 364.292932 -222.098485) (xy 364.2484 -222.075795) (xy 364.207967 -222.046419) (xy 364.172627 -222.011079)
			(xy 364.143251 -221.970646) (xy 364.120561 -221.926114) (xy 364.105117 -221.878582) (xy 364.097298 -221.829219)
			(xy 363.79228 -221.829219) (xy 363.784461 -221.878582) (xy 363.769017 -221.926114) (xy 363.746327 -221.970646)
			(xy 363.716951 -222.011079) (xy 363.681611 -222.046419) (xy 363.641178 -222.075795) (xy 363.596646 -222.098485)
			(xy 363.549114 -222.113929) (xy 363.499751 -222.121748) (xy 363.449773 -222.121748) (xy 363.40041 -222.113929)
			(xy 363.352878 -222.098485) (xy 363.308346 -222.075795) (xy 363.267913 -222.046419) (xy 363.232573 -222.011079)
			(xy 363.203197 -221.970646) (xy 363.180507 -221.926114) (xy 363.165063 -221.878582) (xy 363.157244 -221.829219)
			(xy 355.338251 -221.829219) (xy 355.338126 -221.831408) (xy 355.369478 -221.863484) (xy 355.427506 -221.931891)
			(xy 355.479841 -222.004745) (xy 355.526145 -222.081573) (xy 355.566117 -222.161878) (xy 355.599498 -222.245139)
			(xy 355.613208 -222.287846) (xy 355.616653 -222.297543) (xy 355.6299 -222.313266) (xy 355.638862 -222.318326)
			(xy 355.662044 -222.33049) (xy 355.704582 -222.361003) (xy 355.741788 -222.39783) (xy 355.772737 -222.440052)
			(xy 355.796656 -222.486618) (xy 355.81295 -222.536368) (xy 355.821212 -222.588061) (xy 355.821742 -222.614236)
			(xy 355.821271 -222.639225) (xy 357.993678 -222.639225) (xy 357.993678 -222.589247) (xy 358.001497 -222.539884)
			(xy 358.016941 -222.492352) (xy 358.039631 -222.44782) (xy 358.069007 -222.407387) (xy 358.104347 -222.372047)
			(xy 358.14478 -222.342671) (xy 358.189312 -222.319981) (xy 358.236844 -222.304537) (xy 358.286207 -222.296718)
			(xy 358.336185 -222.296718) (xy 358.385548 -222.304537) (xy 358.43308 -222.319981) (xy 358.477612 -222.342671)
			(xy 358.518045 -222.372047) (xy 358.553385 -222.407387) (xy 358.582761 -222.44782) (xy 358.605451 -222.492352)
			(xy 358.620895 -222.539884) (xy 358.628714 -222.589247) (xy 358.629204 -222.614236) (xy 358.628714 -222.639225)
			(xy 360.807236 -222.639225) (xy 360.807236 -222.589247) (xy 360.815055 -222.539884) (xy 360.830499 -222.492352)
			(xy 360.853189 -222.44782) (xy 360.882565 -222.407387) (xy 360.917905 -222.372047) (xy 360.958338 -222.342671)
			(xy 361.00287 -222.319981) (xy 361.050402 -222.304537) (xy 361.099765 -222.296718) (xy 361.149743 -222.296718)
			(xy 361.199106 -222.304537) (xy 361.246638 -222.319981) (xy 361.29117 -222.342671) (xy 361.331603 -222.372047)
			(xy 361.366943 -222.407387) (xy 361.396319 -222.44782) (xy 361.419009 -222.492352) (xy 361.434453 -222.539884)
			(xy 361.442272 -222.589247) (xy 361.442762 -222.614236) (xy 361.442272 -222.639225) (xy 364.567198 -222.639225)
			(xy 364.567198 -222.589247) (xy 364.575017 -222.539884) (xy 364.590461 -222.492352) (xy 364.613151 -222.44782)
			(xy 364.642527 -222.407387) (xy 364.677867 -222.372047) (xy 364.7183 -222.342671) (xy 364.762832 -222.319981)
			(xy 364.810364 -222.304537) (xy 364.859727 -222.296718) (xy 364.909705 -222.296718) (xy 364.959068 -222.304537)
			(xy 365.0066 -222.319981) (xy 365.051132 -222.342671) (xy 365.091565 -222.372047) (xy 365.126905 -222.407387)
			(xy 365.156281 -222.44782) (xy 365.178971 -222.492352) (xy 365.194415 -222.539884) (xy 365.202234 -222.589247)
			(xy 365.202724 -222.614236) (xy 365.202234 -222.639225) (xy 365.194415 -222.688588) (xy 365.178971 -222.73612)
			(xy 365.156281 -222.780652) (xy 365.126905 -222.821085) (xy 365.091565 -222.856425) (xy 365.051132 -222.885801)
			(xy 365.0066 -222.908491) (xy 364.959068 -222.923935) (xy 364.909705 -222.931754) (xy 364.859727 -222.931754)
			(xy 364.810364 -222.923935) (xy 364.762832 -222.908491) (xy 364.7183 -222.885801) (xy 364.677867 -222.856425)
			(xy 364.642527 -222.821085) (xy 364.613151 -222.780652) (xy 364.590461 -222.73612) (xy 364.575017 -222.688588)
			(xy 364.567198 -222.639225) (xy 361.442272 -222.639225) (xy 361.434453 -222.688588) (xy 361.419009 -222.73612)
			(xy 361.396319 -222.780652) (xy 361.366943 -222.821085) (xy 361.331603 -222.856425) (xy 361.29117 -222.885801)
			(xy 361.246638 -222.908491) (xy 361.199106 -222.923935) (xy 361.149743 -222.931754) (xy 361.099765 -222.931754)
			(xy 361.050402 -222.923935) (xy 361.00287 -222.908491) (xy 360.958338 -222.885801) (xy 360.917905 -222.856425)
			(xy 360.882565 -222.821085) (xy 360.853189 -222.780652) (xy 360.830499 -222.73612) (xy 360.815055 -222.688588)
			(xy 360.807236 -222.639225) (xy 358.628714 -222.639225) (xy 358.620895 -222.688588) (xy 358.605451 -222.73612)
			(xy 358.582761 -222.780652) (xy 358.553385 -222.821085) (xy 358.518045 -222.856425) (xy 358.477612 -222.885801)
			(xy 358.43308 -222.908491) (xy 358.385548 -222.923935) (xy 358.336185 -222.931754) (xy 358.286207 -222.931754)
			(xy 358.236844 -222.923935) (xy 358.189312 -222.908491) (xy 358.14478 -222.885801) (xy 358.104347 -222.856425)
			(xy 358.069007 -222.821085) (xy 358.039631 -222.780652) (xy 358.016941 -222.73612) (xy 358.001497 -222.688588)
			(xy 357.993678 -222.639225) (xy 355.821271 -222.639225) (xy 355.821252 -222.64025) (xy 355.813088 -222.691633)
			(xy 355.796968 -222.741101) (xy 355.773291 -222.787429) (xy 355.742643 -222.829472) (xy 355.705782 -222.866188)
			(xy 355.663619 -222.896671) (xy 355.64064 -222.908876) (xy 355.63166 -222.914004) (xy 355.618406 -222.929853)
			(xy 355.614986 -222.93961) (xy 355.601951 -222.981244) (xy 355.570235 -223.062525) (xy 355.532252 -223.141073)
			(xy 355.488237 -223.216407) (xy 355.438459 -223.288063) (xy 355.383223 -223.355602) (xy 355.353366 -223.387412)
			(xy 355.346843 -223.394815) (xy 355.339513 -223.413113) (xy 355.339142 -223.422972) (xy 355.339142 -223.423988)
			(xy 355.339142 -223.424496) (xy 355.339142 -223.430592) (xy 355.339335 -223.440715) (xy 355.342652 -223.449231)
			(xy 355.643924 -223.449231) (xy 355.643924 -223.399253) (xy 355.651743 -223.34989) (xy 355.667187 -223.302358)
			(xy 355.689877 -223.257826) (xy 355.719253 -223.217393) (xy 355.754593 -223.182053) (xy 355.795026 -223.152677)
			(xy 355.839558 -223.129987) (xy 355.88709 -223.114543) (xy 355.936453 -223.106724) (xy 355.986431 -223.106724)
			(xy 356.035794 -223.114543) (xy 356.083326 -223.129987) (xy 356.127858 -223.152677) (xy 356.168291 -223.182053)
			(xy 356.203631 -223.217393) (xy 356.233007 -223.257826) (xy 356.255697 -223.302358) (xy 356.271141 -223.34989)
			(xy 356.27896 -223.399253) (xy 356.27945 -223.424242) (xy 356.27896 -223.449231) (xy 356.583724 -223.449231)
			(xy 356.583724 -223.399253) (xy 356.591543 -223.34989) (xy 356.606987 -223.302358) (xy 356.629677 -223.257826)
			(xy 356.659053 -223.217393) (xy 356.694393 -223.182053) (xy 356.734826 -223.152677) (xy 356.779358 -223.129987)
			(xy 356.82689 -223.114543) (xy 356.876253 -223.106724) (xy 356.926231 -223.106724) (xy 356.975594 -223.114543)
			(xy 357.023126 -223.129987) (xy 357.067658 -223.152677) (xy 357.108091 -223.182053) (xy 357.143431 -223.217393)
			(xy 357.172807 -223.257826) (xy 357.195497 -223.302358) (xy 357.210941 -223.34989) (xy 357.21876 -223.399253)
			(xy 357.21925 -223.424242) (xy 357.21876 -223.449231) (xy 357.523524 -223.449231) (xy 357.523524 -223.399253)
			(xy 357.531343 -223.34989) (xy 357.546787 -223.302358) (xy 357.569477 -223.257826) (xy 357.598853 -223.217393)
			(xy 357.634193 -223.182053) (xy 357.674626 -223.152677) (xy 357.719158 -223.129987) (xy 357.76669 -223.114543)
			(xy 357.816053 -223.106724) (xy 357.866031 -223.106724) (xy 357.915394 -223.114543) (xy 357.962926 -223.129987)
			(xy 358.007458 -223.152677) (xy 358.047891 -223.182053) (xy 358.083231 -223.217393) (xy 358.112607 -223.257826)
			(xy 358.135297 -223.302358) (xy 358.150741 -223.34989) (xy 358.15856 -223.399253) (xy 358.15905 -223.424242)
			(xy 358.15856 -223.449231) (xy 361.27739 -223.449231) (xy 361.27739 -223.399253) (xy 361.285209 -223.34989)
			(xy 361.300653 -223.302358) (xy 361.323343 -223.257826) (xy 361.352719 -223.217393) (xy 361.388059 -223.182053)
			(xy 361.428492 -223.152677) (xy 361.473024 -223.129987) (xy 361.520556 -223.114543) (xy 361.569919 -223.106724)
			(xy 361.619897 -223.106724) (xy 361.66926 -223.114543) (xy 361.716792 -223.129987) (xy 361.761324 -223.152677)
			(xy 361.801757 -223.182053) (xy 361.837097 -223.217393) (xy 361.866473 -223.257826) (xy 361.889163 -223.302358)
			(xy 361.904607 -223.34989) (xy 361.912426 -223.399253) (xy 361.912916 -223.424242) (xy 361.912426 -223.449231)
			(xy 364.097298 -223.449231) (xy 364.097298 -223.399253) (xy 364.105117 -223.34989) (xy 364.120561 -223.302358)
			(xy 364.143251 -223.257826) (xy 364.172627 -223.217393) (xy 364.207967 -223.182053) (xy 364.2484 -223.152677)
			(xy 364.292932 -223.129987) (xy 364.340464 -223.114543) (xy 364.389827 -223.106724) (xy 364.439805 -223.106724)
			(xy 364.489168 -223.114543) (xy 364.5367 -223.129987) (xy 364.581232 -223.152677) (xy 364.621665 -223.182053)
			(xy 364.657005 -223.217393) (xy 364.686381 -223.257826) (xy 364.709071 -223.302358) (xy 364.724515 -223.34989)
			(xy 364.732334 -223.399253) (xy 364.732824 -223.424242) (xy 364.732334 -223.449231) (xy 365.037352 -223.449231)
			(xy 365.037352 -223.399253) (xy 365.045171 -223.34989) (xy 365.060615 -223.302358) (xy 365.083305 -223.257826)
			(xy 365.112681 -223.217393) (xy 365.148021 -223.182053) (xy 365.188454 -223.152677) (xy 365.232986 -223.129987)
			(xy 365.280518 -223.114543) (xy 365.329881 -223.106724) (xy 365.379859 -223.106724) (xy 365.429222 -223.114543)
			(xy 365.476754 -223.129987) (xy 365.521286 -223.152677) (xy 365.561719 -223.182053) (xy 365.597059 -223.217393)
			(xy 365.626435 -223.257826) (xy 365.649125 -223.302358) (xy 365.664569 -223.34989) (xy 365.672388 -223.399253)
			(xy 365.672878 -223.424242) (xy 365.672388 -223.449231) (xy 366.917206 -223.449231) (xy 366.917206 -223.399253)
			(xy 366.925025 -223.34989) (xy 366.940469 -223.302358) (xy 366.963159 -223.257826) (xy 366.992535 -223.217393)
			(xy 367.027875 -223.182053) (xy 367.068308 -223.152677) (xy 367.11284 -223.129987) (xy 367.160372 -223.114543)
			(xy 367.209735 -223.106724) (xy 367.259713 -223.106724) (xy 367.309076 -223.114543) (xy 367.356608 -223.129987)
			(xy 367.40114 -223.152677) (xy 367.441573 -223.182053) (xy 367.476913 -223.217393) (xy 367.506289 -223.257826)
			(xy 367.528979 -223.302358) (xy 367.544423 -223.34989) (xy 367.552242 -223.399253) (xy 367.552732 -223.424242)
			(xy 367.552242 -223.449231) (xy 369.737368 -223.449231) (xy 369.737368 -223.399253) (xy 369.745187 -223.34989)
			(xy 369.760631 -223.302358) (xy 369.783321 -223.257826) (xy 369.812697 -223.217393) (xy 369.848037 -223.182053)
			(xy 369.88847 -223.152677) (xy 369.933002 -223.129987) (xy 369.980534 -223.114543) (xy 370.029897 -223.106724)
			(xy 370.079875 -223.106724) (xy 370.129238 -223.114543) (xy 370.17677 -223.129987) (xy 370.221302 -223.152677)
			(xy 370.261735 -223.182053) (xy 370.297075 -223.217393) (xy 370.326451 -223.257826) (xy 370.349141 -223.302358)
			(xy 370.364585 -223.34989) (xy 370.372404 -223.399253) (xy 370.372894 -223.424242) (xy 370.678451 -223.424242)
			(xy 370.682546 -223.373514) (xy 370.694725 -223.3241) (xy 370.714673 -223.27728) (xy 370.741874 -223.234266)
			(xy 370.775622 -223.196172) (xy 370.815044 -223.163985) (xy 370.859118 -223.138539) (xy 370.906704 -223.120492)
			(xy 370.956568 -223.110312) (xy 371.00742 -223.108263) (xy 371.057941 -223.114397) (xy 371.106825 -223.128557)
			(xy 371.152804 -223.150374) (xy 371.194688 -223.179284) (xy 371.231392 -223.214539) (xy 371.261965 -223.255225)
			(xy 371.285616 -223.300288) (xy 371.301732 -223.348562) (xy 371.309896 -223.398796) (xy 371.310408 -223.424242)
			(xy 371.618505 -223.424242) (xy 371.6226 -223.373514) (xy 371.634779 -223.3241) (xy 371.654727 -223.27728)
			(xy 371.681928 -223.234266) (xy 371.715676 -223.196172) (xy 371.755098 -223.163985) (xy 371.799172 -223.138539)
			(xy 371.846758 -223.120492) (xy 371.896622 -223.110312) (xy 371.947474 -223.108263) (xy 371.997995 -223.114397)
			(xy 372.046879 -223.128557) (xy 372.092858 -223.150374) (xy 372.134742 -223.179284) (xy 372.171446 -223.214539)
			(xy 372.202019 -223.255225) (xy 372.22567 -223.300288) (xy 372.241786 -223.348562) (xy 372.24995 -223.398796)
			(xy 372.250462 -223.424242) (xy 372.249959 -223.449231) (xy 372.557276 -223.449231) (xy 372.557276 -223.399253)
			(xy 372.565095 -223.34989) (xy 372.580539 -223.302358) (xy 372.603229 -223.257826) (xy 372.632605 -223.217393)
			(xy 372.667945 -223.182053) (xy 372.708378 -223.152677) (xy 372.75291 -223.129987) (xy 372.800442 -223.114543)
			(xy 372.849805 -223.106724) (xy 372.899783 -223.106724) (xy 372.949146 -223.114543) (xy 372.996678 -223.129987)
			(xy 373.04121 -223.152677) (xy 373.081643 -223.182053) (xy 373.116983 -223.217393) (xy 373.146359 -223.257826)
			(xy 373.169049 -223.302358) (xy 373.184493 -223.34989) (xy 373.192312 -223.399253) (xy 373.192802 -223.424242)
			(xy 373.192312 -223.449231) (xy 374.437384 -223.449231) (xy 374.437384 -223.399253) (xy 374.445203 -223.34989)
			(xy 374.460647 -223.302358) (xy 374.483337 -223.257826) (xy 374.512713 -223.217393) (xy 374.548053 -223.182053)
			(xy 374.588486 -223.152677) (xy 374.633018 -223.129987) (xy 374.68055 -223.114543) (xy 374.729913 -223.106724)
			(xy 374.779891 -223.106724) (xy 374.829254 -223.114543) (xy 374.876786 -223.129987) (xy 374.921318 -223.152677)
			(xy 374.961751 -223.182053) (xy 374.997091 -223.217393) (xy 375.026467 -223.257826) (xy 375.049157 -223.302358)
			(xy 375.064601 -223.34989) (xy 375.07242 -223.399253) (xy 375.07291 -223.424242) (xy 375.07242 -223.449231)
			(xy 375.377184 -223.449231) (xy 375.377184 -223.399253) (xy 375.385003 -223.34989) (xy 375.400447 -223.302358)
			(xy 375.423137 -223.257826) (xy 375.452513 -223.217393) (xy 375.487853 -223.182053) (xy 375.528286 -223.152677)
			(xy 375.572818 -223.129987) (xy 375.62035 -223.114543) (xy 375.669713 -223.106724) (xy 375.719691 -223.106724)
			(xy 375.769054 -223.114543) (xy 375.816586 -223.129987) (xy 375.861118 -223.152677) (xy 375.901551 -223.182053)
			(xy 375.936891 -223.217393) (xy 375.966267 -223.257826) (xy 375.988957 -223.302358) (xy 376.004401 -223.34989)
			(xy 376.01222 -223.399253) (xy 376.01271 -223.424242) (xy 376.01222 -223.449231) (xy 377.257292 -223.449231)
			(xy 377.257292 -223.399253) (xy 377.265111 -223.34989) (xy 377.280555 -223.302358) (xy 377.303245 -223.257826)
			(xy 377.332621 -223.217393) (xy 377.367961 -223.182053) (xy 377.408394 -223.152677) (xy 377.452926 -223.129987)
			(xy 377.500458 -223.114543) (xy 377.549821 -223.106724) (xy 377.599799 -223.106724) (xy 377.649162 -223.114543)
			(xy 377.696694 -223.129987) (xy 377.741226 -223.152677) (xy 377.781659 -223.182053) (xy 377.816999 -223.217393)
			(xy 377.846375 -223.257826) (xy 377.869065 -223.302358) (xy 377.884509 -223.34989) (xy 377.892328 -223.399253)
			(xy 377.892818 -223.424242) (xy 377.892328 -223.449231) (xy 377.884509 -223.498594) (xy 377.869065 -223.546126)
			(xy 377.846375 -223.590658) (xy 377.816999 -223.631091) (xy 377.781659 -223.666431) (xy 377.741226 -223.695807)
			(xy 377.696694 -223.718497) (xy 377.649162 -223.733941) (xy 377.599799 -223.74176) (xy 377.549821 -223.74176)
			(xy 377.500458 -223.733941) (xy 377.452926 -223.718497) (xy 377.408394 -223.695807) (xy 377.367961 -223.666431)
			(xy 377.332621 -223.631091) (xy 377.303245 -223.590658) (xy 377.280555 -223.546126) (xy 377.265111 -223.498594)
			(xy 377.257292 -223.449231) (xy 376.01222 -223.449231) (xy 376.004401 -223.498594) (xy 375.988957 -223.546126)
			(xy 375.966267 -223.590658) (xy 375.936891 -223.631091) (xy 375.901551 -223.666431) (xy 375.861118 -223.695807)
			(xy 375.816586 -223.718497) (xy 375.769054 -223.733941) (xy 375.719691 -223.74176) (xy 375.669713 -223.74176)
			(xy 375.62035 -223.733941) (xy 375.572818 -223.718497) (xy 375.528286 -223.695807) (xy 375.487853 -223.666431)
			(xy 375.452513 -223.631091) (xy 375.423137 -223.590658) (xy 375.400447 -223.546126) (xy 375.385003 -223.498594)
			(xy 375.377184 -223.449231) (xy 375.07242 -223.449231) (xy 375.064601 -223.498594) (xy 375.049157 -223.546126)
			(xy 375.026467 -223.590658) (xy 374.997091 -223.631091) (xy 374.961751 -223.666431) (xy 374.921318 -223.695807)
			(xy 374.876786 -223.718497) (xy 374.829254 -223.733941) (xy 374.779891 -223.74176) (xy 374.729913 -223.74176)
			(xy 374.68055 -223.733941) (xy 374.633018 -223.718497) (xy 374.588486 -223.695807) (xy 374.548053 -223.666431)
			(xy 374.512713 -223.631091) (xy 374.483337 -223.590658) (xy 374.460647 -223.546126) (xy 374.445203 -223.498594)
			(xy 374.437384 -223.449231) (xy 373.192312 -223.449231) (xy 373.184493 -223.498594) (xy 373.169049 -223.546126)
			(xy 373.146359 -223.590658) (xy 373.116983 -223.631091) (xy 373.081643 -223.666431) (xy 373.04121 -223.695807)
			(xy 372.996678 -223.718497) (xy 372.949146 -223.733941) (xy 372.899783 -223.74176) (xy 372.849805 -223.74176)
			(xy 372.800442 -223.733941) (xy 372.75291 -223.718497) (xy 372.708378 -223.695807) (xy 372.667945 -223.666431)
			(xy 372.632605 -223.631091) (xy 372.603229 -223.590658) (xy 372.580539 -223.546126) (xy 372.565095 -223.498594)
			(xy 372.557276 -223.449231) (xy 372.249959 -223.449231) (xy 372.24995 -223.449688) (xy 372.241786 -223.499922)
			(xy 372.22567 -223.548196) (xy 372.202019 -223.593259) (xy 372.171446 -223.633945) (xy 372.134742 -223.6692)
			(xy 372.092858 -223.69811) (xy 372.046879 -223.719927) (xy 371.997995 -223.734087) (xy 371.947474 -223.740221)
			(xy 371.896622 -223.738172) (xy 371.846758 -223.727992) (xy 371.799172 -223.709945) (xy 371.755098 -223.684499)
			(xy 371.715676 -223.652312) (xy 371.681928 -223.614218) (xy 371.654727 -223.571204) (xy 371.634779 -223.524384)
			(xy 371.6226 -223.47497) (xy 371.618505 -223.424242) (xy 371.310408 -223.424242) (xy 371.309896 -223.449688)
			(xy 371.301732 -223.499922) (xy 371.285616 -223.548196) (xy 371.261965 -223.593259) (xy 371.231392 -223.633945)
			(xy 371.194688 -223.6692) (xy 371.152804 -223.69811) (xy 371.106825 -223.719927) (xy 371.057941 -223.734087)
			(xy 371.00742 -223.740221) (xy 370.956568 -223.738172) (xy 370.906704 -223.727992) (xy 370.859118 -223.709945)
			(xy 370.815044 -223.684499) (xy 370.775622 -223.652312) (xy 370.741874 -223.614218) (xy 370.714673 -223.571204)
			(xy 370.694725 -223.524384) (xy 370.682546 -223.47497) (xy 370.678451 -223.424242) (xy 370.372894 -223.424242)
			(xy 370.372404 -223.449231) (xy 370.364585 -223.498594) (xy 370.349141 -223.546126) (xy 370.326451 -223.590658)
			(xy 370.297075 -223.631091) (xy 370.261735 -223.666431) (xy 370.221302 -223.695807) (xy 370.17677 -223.718497)
			(xy 370.129238 -223.733941) (xy 370.079875 -223.74176) (xy 370.029897 -223.74176) (xy 369.980534 -223.733941)
			(xy 369.933002 -223.718497) (xy 369.88847 -223.695807) (xy 369.848037 -223.666431) (xy 369.812697 -223.631091)
			(xy 369.783321 -223.590658) (xy 369.760631 -223.546126) (xy 369.745187 -223.498594) (xy 369.737368 -223.449231)
			(xy 367.552242 -223.449231) (xy 367.544423 -223.498594) (xy 367.528979 -223.546126) (xy 367.506289 -223.590658)
			(xy 367.476913 -223.631091) (xy 367.441573 -223.666431) (xy 367.40114 -223.695807) (xy 367.356608 -223.718497)
			(xy 367.309076 -223.733941) (xy 367.259713 -223.74176) (xy 367.209735 -223.74176) (xy 367.160372 -223.733941)
			(xy 367.11284 -223.718497) (xy 367.068308 -223.695807) (xy 367.027875 -223.666431) (xy 366.992535 -223.631091)
			(xy 366.963159 -223.590658) (xy 366.940469 -223.546126) (xy 366.925025 -223.498594) (xy 366.917206 -223.449231)
			(xy 365.672388 -223.449231) (xy 365.664569 -223.498594) (xy 365.649125 -223.546126) (xy 365.626435 -223.590658)
			(xy 365.597059 -223.631091) (xy 365.561719 -223.666431) (xy 365.521286 -223.695807) (xy 365.476754 -223.718497)
			(xy 365.429222 -223.733941) (xy 365.379859 -223.74176) (xy 365.329881 -223.74176) (xy 365.280518 -223.733941)
			(xy 365.232986 -223.718497) (xy 365.188454 -223.695807) (xy 365.148021 -223.666431) (xy 365.112681 -223.631091)
			(xy 365.083305 -223.590658) (xy 365.060615 -223.546126) (xy 365.045171 -223.498594) (xy 365.037352 -223.449231)
			(xy 364.732334 -223.449231) (xy 364.724515 -223.498594) (xy 364.709071 -223.546126) (xy 364.686381 -223.590658)
			(xy 364.657005 -223.631091) (xy 364.621665 -223.666431) (xy 364.581232 -223.695807) (xy 364.5367 -223.718497)
			(xy 364.489168 -223.733941) (xy 364.439805 -223.74176) (xy 364.389827 -223.74176) (xy 364.340464 -223.733941)
			(xy 364.292932 -223.718497) (xy 364.2484 -223.695807) (xy 364.207967 -223.666431) (xy 364.172627 -223.631091)
			(xy 364.143251 -223.590658) (xy 364.120561 -223.546126) (xy 364.105117 -223.498594) (xy 364.097298 -223.449231)
			(xy 361.912426 -223.449231) (xy 361.904607 -223.498594) (xy 361.889163 -223.546126) (xy 361.866473 -223.590658)
			(xy 361.837097 -223.631091) (xy 361.801757 -223.666431) (xy 361.761324 -223.695807) (xy 361.716792 -223.718497)
			(xy 361.66926 -223.733941) (xy 361.619897 -223.74176) (xy 361.569919 -223.74176) (xy 361.520556 -223.733941)
			(xy 361.473024 -223.718497) (xy 361.428492 -223.695807) (xy 361.388059 -223.666431) (xy 361.352719 -223.631091)
			(xy 361.323343 -223.590658) (xy 361.300653 -223.546126) (xy 361.285209 -223.498594) (xy 361.27739 -223.449231)
			(xy 358.15856 -223.449231) (xy 358.150741 -223.498594) (xy 358.135297 -223.546126) (xy 358.112607 -223.590658)
			(xy 358.083231 -223.631091) (xy 358.047891 -223.666431) (xy 358.007458 -223.695807) (xy 357.962926 -223.718497)
			(xy 357.915394 -223.733941) (xy 357.866031 -223.74176) (xy 357.816053 -223.74176) (xy 357.76669 -223.733941)
			(xy 357.719158 -223.718497) (xy 357.674626 -223.695807) (xy 357.634193 -223.666431) (xy 357.598853 -223.631091)
			(xy 357.569477 -223.590658) (xy 357.546787 -223.546126) (xy 357.531343 -223.498594) (xy 357.523524 -223.449231)
			(xy 357.21876 -223.449231) (xy 357.210941 -223.498594) (xy 357.195497 -223.546126) (xy 357.172807 -223.590658)
			(xy 357.143431 -223.631091) (xy 357.108091 -223.666431) (xy 357.067658 -223.695807) (xy 357.023126 -223.718497)
			(xy 356.975594 -223.733941) (xy 356.926231 -223.74176) (xy 356.876253 -223.74176) (xy 356.82689 -223.733941)
			(xy 356.779358 -223.718497) (xy 356.734826 -223.695807) (xy 356.694393 -223.666431) (xy 356.659053 -223.631091)
			(xy 356.629677 -223.590658) (xy 356.606987 -223.546126) (xy 356.591543 -223.498594) (xy 356.583724 -223.449231)
			(xy 356.27896 -223.449231) (xy 356.271141 -223.498594) (xy 356.255697 -223.546126) (xy 356.233007 -223.590658)
			(xy 356.203631 -223.631091) (xy 356.168291 -223.666431) (xy 356.127858 -223.695807) (xy 356.083326 -223.718497)
			(xy 356.035794 -223.733941) (xy 355.986431 -223.74176) (xy 355.936453 -223.74176) (xy 355.88709 -223.733941)
			(xy 355.839558 -223.718497) (xy 355.795026 -223.695807) (xy 355.754593 -223.666431) (xy 355.719253 -223.631091)
			(xy 355.689877 -223.590658) (xy 355.667187 -223.546126) (xy 355.651743 -223.498594) (xy 355.643924 -223.449231)
			(xy 355.342652 -223.449231) (xy 355.346677 -223.459567) (xy 355.353366 -223.467168) (xy 355.383941 -223.499519)
			(xy 355.440383 -223.568361) (xy 355.491108 -223.641518) (xy 355.535788 -223.718516) (xy 355.574133 -223.798856)
			(xy 355.605895 -223.882019) (xy 355.618796 -223.924622) (xy 355.621985 -223.934175) (xy 355.634564 -223.949884)
			(xy 355.64318 -223.955102) (xy 355.664364 -223.967131) (xy 355.703099 -223.996671) (xy 355.73687 -224.031779)
			(xy 355.764884 -224.071632) (xy 355.786484 -224.115295) (xy 355.801164 -224.161745) (xy 355.80858 -224.209891)
			(xy 355.809042 -224.234248) (xy 355.808575 -224.258589) (xy 355.808475 -224.259237) (xy 356.11357 -224.259237)
			(xy 356.11357 -224.209259) (xy 356.121389 -224.159896) (xy 356.136833 -224.112364) (xy 356.159523 -224.067832)
			(xy 356.188899 -224.027399) (xy 356.224239 -223.992059) (xy 356.264672 -223.962683) (xy 356.309204 -223.939993)
			(xy 356.356736 -223.924549) (xy 356.406099 -223.91673) (xy 356.456077 -223.91673) (xy 356.50544 -223.924549)
			(xy 356.552972 -223.939993) (xy 356.597504 -223.962683) (xy 356.637937 -223.992059) (xy 356.673277 -224.027399)
			(xy 356.702653 -224.067832) (xy 356.725343 -224.112364) (xy 356.740787 -224.159896) (xy 356.748606 -224.209259)
			(xy 356.749096 -224.234248) (xy 356.748606 -224.259237) (xy 357.053624 -224.259237) (xy 357.053624 -224.209259)
			(xy 357.061443 -224.159896) (xy 357.076887 -224.112364) (xy 357.099577 -224.067832) (xy 357.128953 -224.027399)
			(xy 357.164293 -223.992059) (xy 357.204726 -223.962683) (xy 357.249258 -223.939993) (xy 357.29679 -223.924549)
			(xy 357.346153 -223.91673) (xy 357.396131 -223.91673) (xy 357.445494 -223.924549) (xy 357.493026 -223.939993)
			(xy 357.537558 -223.962683) (xy 357.577991 -223.992059) (xy 357.613331 -224.027399) (xy 357.642707 -224.067832)
			(xy 357.665397 -224.112364) (xy 357.680841 -224.159896) (xy 357.68866 -224.209259) (xy 357.68915 -224.234248)
			(xy 357.68866 -224.259237) (xy 357.993678 -224.259237) (xy 357.993678 -224.209259) (xy 358.001497 -224.159896)
			(xy 358.016941 -224.112364) (xy 358.039631 -224.067832) (xy 358.069007 -224.027399) (xy 358.104347 -223.992059)
			(xy 358.14478 -223.962683) (xy 358.189312 -223.939993) (xy 358.236844 -223.924549) (xy 358.286207 -223.91673)
			(xy 358.336185 -223.91673) (xy 358.385548 -223.924549) (xy 358.43308 -223.939993) (xy 358.477612 -223.962683)
			(xy 358.518045 -223.992059) (xy 358.553385 -224.027399) (xy 358.582761 -224.067832) (xy 358.605451 -224.112364)
			(xy 358.620895 -224.159896) (xy 358.628714 -224.209259) (xy 358.629204 -224.234248) (xy 358.628714 -224.259237)
			(xy 360.807236 -224.259237) (xy 360.807236 -224.209259) (xy 360.815055 -224.159896) (xy 360.830499 -224.112364)
			(xy 360.853189 -224.067832) (xy 360.882565 -224.027399) (xy 360.917905 -223.992059) (xy 360.958338 -223.962683)
			(xy 361.00287 -223.939993) (xy 361.050402 -223.924549) (xy 361.099765 -223.91673) (xy 361.149743 -223.91673)
			(xy 361.199106 -223.924549) (xy 361.246638 -223.939993) (xy 361.29117 -223.962683) (xy 361.331603 -223.992059)
			(xy 361.366943 -224.027399) (xy 361.396319 -224.067832) (xy 361.419009 -224.112364) (xy 361.434453 -224.159896)
			(xy 361.442272 -224.209259) (xy 361.442762 -224.234248) (xy 361.442272 -224.259237) (xy 362.687344 -224.259237)
			(xy 362.687344 -224.209259) (xy 362.695163 -224.159896) (xy 362.710607 -224.112364) (xy 362.733297 -224.067832)
			(xy 362.762673 -224.027399) (xy 362.798013 -223.992059) (xy 362.838446 -223.962683) (xy 362.882978 -223.939993)
			(xy 362.93051 -223.924549) (xy 362.979873 -223.91673) (xy 363.029851 -223.91673) (xy 363.079214 -223.924549)
			(xy 363.126746 -223.939993) (xy 363.171278 -223.962683) (xy 363.211711 -223.992059) (xy 363.247051 -224.027399)
			(xy 363.276427 -224.067832) (xy 363.299117 -224.112364) (xy 363.314561 -224.159896) (xy 363.32238 -224.209259)
			(xy 363.32287 -224.234248) (xy 363.32238 -224.259237) (xy 364.567198 -224.259237) (xy 364.567198 -224.209259)
			(xy 364.575017 -224.159896) (xy 364.590461 -224.112364) (xy 364.613151 -224.067832) (xy 364.642527 -224.027399)
			(xy 364.677867 -223.992059) (xy 364.7183 -223.962683) (xy 364.762832 -223.939993) (xy 364.810364 -223.924549)
			(xy 364.859727 -223.91673) (xy 364.909705 -223.91673) (xy 364.959068 -223.924549) (xy 365.0066 -223.939993)
			(xy 365.051132 -223.962683) (xy 365.091565 -223.992059) (xy 365.126905 -224.027399) (xy 365.156281 -224.067832)
			(xy 365.178971 -224.112364) (xy 365.194415 -224.159896) (xy 365.202234 -224.209259) (xy 365.202724 -224.234248)
			(xy 365.202234 -224.259237) (xy 365.507252 -224.259237) (xy 365.507252 -224.209259) (xy 365.515071 -224.159896)
			(xy 365.530515 -224.112364) (xy 365.553205 -224.067832) (xy 365.582581 -224.027399) (xy 365.617921 -223.992059)
			(xy 365.658354 -223.962683) (xy 365.702886 -223.939993) (xy 365.750418 -223.924549) (xy 365.799781 -223.91673)
			(xy 365.849759 -223.91673) (xy 365.899122 -223.924549) (xy 365.946654 -223.939993) (xy 365.991186 -223.962683)
			(xy 366.031619 -223.992059) (xy 366.066959 -224.027399) (xy 366.096335 -224.067832) (xy 366.119025 -224.112364)
			(xy 366.134469 -224.159896) (xy 366.142288 -224.209259) (xy 366.142778 -224.234248) (xy 366.142288 -224.259237)
			(xy 366.447306 -224.259237) (xy 366.447306 -224.209259) (xy 366.455125 -224.159896) (xy 366.470569 -224.112364)
			(xy 366.493259 -224.067832) (xy 366.522635 -224.027399) (xy 366.557975 -223.992059) (xy 366.598408 -223.962683)
			(xy 366.64294 -223.939993) (xy 366.690472 -223.924549) (xy 366.739835 -223.91673) (xy 366.789813 -223.91673)
			(xy 366.839176 -223.924549) (xy 366.886708 -223.939993) (xy 366.93124 -223.962683) (xy 366.971673 -223.992059)
			(xy 367.007013 -224.027399) (xy 367.036389 -224.067832) (xy 367.059079 -224.112364) (xy 367.074523 -224.159896)
			(xy 367.082342 -224.209259) (xy 367.082832 -224.234248) (xy 367.082342 -224.259237) (xy 367.38736 -224.259237)
			(xy 367.38736 -224.209259) (xy 367.395179 -224.159896) (xy 367.410623 -224.112364) (xy 367.433313 -224.067832)
			(xy 367.462689 -224.027399) (xy 367.498029 -223.992059) (xy 367.538462 -223.962683) (xy 367.582994 -223.939993)
			(xy 367.630526 -223.924549) (xy 367.679889 -223.91673) (xy 367.729867 -223.91673) (xy 367.77923 -223.924549)
			(xy 367.826762 -223.939993) (xy 367.871294 -223.962683) (xy 367.911727 -223.992059) (xy 367.947067 -224.027399)
			(xy 367.976443 -224.067832) (xy 367.999133 -224.112364) (xy 368.014577 -224.159896) (xy 368.022396 -224.209259)
			(xy 368.022886 -224.234248) (xy 368.022396 -224.259237) (xy 368.32716 -224.259237) (xy 368.32716 -224.209259)
			(xy 368.334979 -224.159896) (xy 368.350423 -224.112364) (xy 368.373113 -224.067832) (xy 368.402489 -224.027399)
			(xy 368.437829 -223.992059) (xy 368.478262 -223.962683) (xy 368.522794 -223.939993) (xy 368.570326 -223.924549)
			(xy 368.619689 -223.91673) (xy 368.669667 -223.91673) (xy 368.71903 -223.924549) (xy 368.766562 -223.939993)
			(xy 368.811094 -223.962683) (xy 368.851527 -223.992059) (xy 368.886867 -224.027399) (xy 368.916243 -224.067832)
			(xy 368.938933 -224.112364) (xy 368.954377 -224.159896) (xy 368.962196 -224.209259) (xy 368.962686 -224.234248)
			(xy 368.962196 -224.259237) (xy 369.267214 -224.259237) (xy 369.267214 -224.209259) (xy 369.275033 -224.159896)
			(xy 369.290477 -224.112364) (xy 369.313167 -224.067832) (xy 369.342543 -224.027399) (xy 369.377883 -223.992059)
			(xy 369.418316 -223.962683) (xy 369.462848 -223.939993) (xy 369.51038 -223.924549) (xy 369.559743 -223.91673)
			(xy 369.609721 -223.91673) (xy 369.659084 -223.924549) (xy 369.706616 -223.939993) (xy 369.751148 -223.962683)
			(xy 369.791581 -223.992059) (xy 369.826921 -224.027399) (xy 369.856297 -224.067832) (xy 369.878987 -224.112364)
			(xy 369.894431 -224.159896) (xy 369.90225 -224.209259) (xy 369.90274 -224.234248) (xy 369.90225 -224.259237)
			(xy 370.207268 -224.259237) (xy 370.207268 -224.209259) (xy 370.215087 -224.159896) (xy 370.230531 -224.112364)
			(xy 370.253221 -224.067832) (xy 370.282597 -224.027399) (xy 370.317937 -223.992059) (xy 370.35837 -223.962683)
			(xy 370.402902 -223.939993) (xy 370.450434 -223.924549) (xy 370.499797 -223.91673) (xy 370.549775 -223.91673)
			(xy 370.599138 -223.924549) (xy 370.64667 -223.939993) (xy 370.691202 -223.962683) (xy 370.731635 -223.992059)
			(xy 370.766975 -224.027399) (xy 370.796351 -224.067832) (xy 370.819041 -224.112364) (xy 370.834485 -224.159896)
			(xy 370.842304 -224.209259) (xy 370.842794 -224.234248) (xy 370.842304 -224.259237) (xy 371.147322 -224.259237)
			(xy 371.147322 -224.209259) (xy 371.155141 -224.159896) (xy 371.170585 -224.112364) (xy 371.193275 -224.067832)
			(xy 371.222651 -224.027399) (xy 371.257991 -223.992059) (xy 371.298424 -223.962683) (xy 371.342956 -223.939993)
			(xy 371.390488 -223.924549) (xy 371.439851 -223.91673) (xy 371.489829 -223.91673) (xy 371.539192 -223.924549)
			(xy 371.586724 -223.939993) (xy 371.631256 -223.962683) (xy 371.671689 -223.992059) (xy 371.707029 -224.027399)
			(xy 371.736405 -224.067832) (xy 371.759095 -224.112364) (xy 371.774539 -224.159896) (xy 371.782358 -224.209259)
			(xy 371.782848 -224.234248) (xy 371.782358 -224.259237) (xy 372.087376 -224.259237) (xy 372.087376 -224.209259)
			(xy 372.095195 -224.159896) (xy 372.110639 -224.112364) (xy 372.133329 -224.067832) (xy 372.162705 -224.027399)
			(xy 372.198045 -223.992059) (xy 372.238478 -223.962683) (xy 372.28301 -223.939993) (xy 372.330542 -223.924549)
			(xy 372.379905 -223.91673) (xy 372.429883 -223.91673) (xy 372.479246 -223.924549) (xy 372.526778 -223.939993)
			(xy 372.57131 -223.962683) (xy 372.611743 -223.992059) (xy 372.647083 -224.027399) (xy 372.676459 -224.067832)
			(xy 372.699149 -224.112364) (xy 372.714593 -224.159896) (xy 372.722412 -224.209259) (xy 372.722902 -224.234248)
			(xy 372.722412 -224.259237) (xy 373.027176 -224.259237) (xy 373.027176 -224.209259) (xy 373.034995 -224.159896)
			(xy 373.050439 -224.112364) (xy 373.073129 -224.067832) (xy 373.102505 -224.027399) (xy 373.137845 -223.992059)
			(xy 373.178278 -223.962683) (xy 373.22281 -223.939993) (xy 373.270342 -223.924549) (xy 373.319705 -223.91673)
			(xy 373.369683 -223.91673) (xy 373.419046 -223.924549) (xy 373.466578 -223.939993) (xy 373.51111 -223.962683)
			(xy 373.551543 -223.992059) (xy 373.586883 -224.027399) (xy 373.616259 -224.067832) (xy 373.638949 -224.112364)
			(xy 373.654393 -224.159896) (xy 373.662212 -224.209259) (xy 373.662702 -224.234248) (xy 373.662212 -224.259237)
			(xy 373.654393 -224.3086) (xy 373.638949 -224.356132) (xy 373.616259 -224.400664) (xy 373.586883 -224.441097)
			(xy 373.551543 -224.476437) (xy 373.51111 -224.505813) (xy 373.466578 -224.528503) (xy 373.419046 -224.543947)
			(xy 373.369683 -224.551766) (xy 373.319705 -224.551766) (xy 373.270342 -224.543947) (xy 373.22281 -224.528503)
			(xy 373.178278 -224.505813) (xy 373.137845 -224.476437) (xy 373.102505 -224.441097) (xy 373.073129 -224.400664)
			(xy 373.050439 -224.356132) (xy 373.034995 -224.3086) (xy 373.027176 -224.259237) (xy 372.722412 -224.259237)
			(xy 372.714593 -224.3086) (xy 372.699149 -224.356132) (xy 372.676459 -224.400664) (xy 372.647083 -224.441097)
			(xy 372.611743 -224.476437) (xy 372.57131 -224.505813) (xy 372.526778 -224.528503) (xy 372.479246 -224.543947)
			(xy 372.429883 -224.551766) (xy 372.379905 -224.551766) (xy 372.330542 -224.543947) (xy 372.28301 -224.528503)
			(xy 372.238478 -224.505813) (xy 372.198045 -224.476437) (xy 372.162705 -224.441097) (xy 372.133329 -224.400664)
			(xy 372.110639 -224.356132) (xy 372.095195 -224.3086) (xy 372.087376 -224.259237) (xy 371.782358 -224.259237)
			(xy 371.774539 -224.3086) (xy 371.759095 -224.356132) (xy 371.736405 -224.400664) (xy 371.707029 -224.441097)
			(xy 371.671689 -224.476437) (xy 371.631256 -224.505813) (xy 371.586724 -224.528503) (xy 371.539192 -224.543947)
			(xy 371.489829 -224.551766) (xy 371.439851 -224.551766) (xy 371.390488 -224.543947) (xy 371.342956 -224.528503)
			(xy 371.298424 -224.505813) (xy 371.257991 -224.476437) (xy 371.222651 -224.441097) (xy 371.193275 -224.400664)
			(xy 371.170585 -224.356132) (xy 371.155141 -224.3086) (xy 371.147322 -224.259237) (xy 370.842304 -224.259237)
			(xy 370.834485 -224.3086) (xy 370.819041 -224.356132) (xy 370.796351 -224.400664) (xy 370.766975 -224.441097)
			(xy 370.731635 -224.476437) (xy 370.691202 -224.505813) (xy 370.64667 -224.528503) (xy 370.599138 -224.543947)
			(xy 370.549775 -224.551766) (xy 370.499797 -224.551766) (xy 370.450434 -224.543947) (xy 370.402902 -224.528503)
			(xy 370.35837 -224.505813) (xy 370.317937 -224.476437) (xy 370.282597 -224.441097) (xy 370.253221 -224.400664)
			(xy 370.230531 -224.356132) (xy 370.215087 -224.3086) (xy 370.207268 -224.259237) (xy 369.90225 -224.259237)
			(xy 369.894431 -224.3086) (xy 369.878987 -224.356132) (xy 369.856297 -224.400664) (xy 369.826921 -224.441097)
			(xy 369.791581 -224.476437) (xy 369.751148 -224.505813) (xy 369.706616 -224.528503) (xy 369.659084 -224.543947)
			(xy 369.609721 -224.551766) (xy 369.559743 -224.551766) (xy 369.51038 -224.543947) (xy 369.462848 -224.528503)
			(xy 369.418316 -224.505813) (xy 369.377883 -224.476437) (xy 369.342543 -224.441097) (xy 369.313167 -224.400664)
			(xy 369.290477 -224.356132) (xy 369.275033 -224.3086) (xy 369.267214 -224.259237) (xy 368.962196 -224.259237)
			(xy 368.954377 -224.3086) (xy 368.938933 -224.356132) (xy 368.916243 -224.400664) (xy 368.886867 -224.441097)
			(xy 368.851527 -224.476437) (xy 368.811094 -224.505813) (xy 368.766562 -224.528503) (xy 368.71903 -224.543947)
			(xy 368.669667 -224.551766) (xy 368.619689 -224.551766) (xy 368.570326 -224.543947) (xy 368.522794 -224.528503)
			(xy 368.478262 -224.505813) (xy 368.437829 -224.476437) (xy 368.402489 -224.441097) (xy 368.373113 -224.400664)
			(xy 368.350423 -224.356132) (xy 368.334979 -224.3086) (xy 368.32716 -224.259237) (xy 368.022396 -224.259237)
			(xy 368.014577 -224.3086) (xy 367.999133 -224.356132) (xy 367.976443 -224.400664) (xy 367.947067 -224.441097)
			(xy 367.911727 -224.476437) (xy 367.871294 -224.505813) (xy 367.826762 -224.528503) (xy 367.77923 -224.543947)
			(xy 367.729867 -224.551766) (xy 367.679889 -224.551766) (xy 367.630526 -224.543947) (xy 367.582994 -224.528503)
			(xy 367.538462 -224.505813) (xy 367.498029 -224.476437) (xy 367.462689 -224.441097) (xy 367.433313 -224.400664)
			(xy 367.410623 -224.356132) (xy 367.395179 -224.3086) (xy 367.38736 -224.259237) (xy 367.082342 -224.259237)
			(xy 367.074523 -224.3086) (xy 367.059079 -224.356132) (xy 367.036389 -224.400664) (xy 367.007013 -224.441097)
			(xy 366.971673 -224.476437) (xy 366.93124 -224.505813) (xy 366.886708 -224.528503) (xy 366.839176 -224.543947)
			(xy 366.789813 -224.551766) (xy 366.739835 -224.551766) (xy 366.690472 -224.543947) (xy 366.64294 -224.528503)
			(xy 366.598408 -224.505813) (xy 366.557975 -224.476437) (xy 366.522635 -224.441097) (xy 366.493259 -224.400664)
			(xy 366.470569 -224.356132) (xy 366.455125 -224.3086) (xy 366.447306 -224.259237) (xy 366.142288 -224.259237)
			(xy 366.134469 -224.3086) (xy 366.119025 -224.356132) (xy 366.096335 -224.400664) (xy 366.066959 -224.441097)
			(xy 366.031619 -224.476437) (xy 365.991186 -224.505813) (xy 365.946654 -224.528503) (xy 365.899122 -224.543947)
			(xy 365.849759 -224.551766) (xy 365.799781 -224.551766) (xy 365.750418 -224.543947) (xy 365.702886 -224.528503)
			(xy 365.658354 -224.505813) (xy 365.617921 -224.476437) (xy 365.582581 -224.441097) (xy 365.553205 -224.400664)
			(xy 365.530515 -224.356132) (xy 365.515071 -224.3086) (xy 365.507252 -224.259237) (xy 365.202234 -224.259237)
			(xy 365.194415 -224.3086) (xy 365.178971 -224.356132) (xy 365.156281 -224.400664) (xy 365.126905 -224.441097)
			(xy 365.091565 -224.476437) (xy 365.051132 -224.505813) (xy 365.0066 -224.528503) (xy 364.959068 -224.543947)
			(xy 364.909705 -224.551766) (xy 364.859727 -224.551766) (xy 364.810364 -224.543947) (xy 364.762832 -224.528503)
			(xy 364.7183 -224.505813) (xy 364.677867 -224.476437) (xy 364.642527 -224.441097) (xy 364.613151 -224.400664)
			(xy 364.590461 -224.356132) (xy 364.575017 -224.3086) (xy 364.567198 -224.259237) (xy 363.32238 -224.259237)
			(xy 363.314561 -224.3086) (xy 363.299117 -224.356132) (xy 363.276427 -224.400664) (xy 363.247051 -224.441097)
			(xy 363.211711 -224.476437) (xy 363.171278 -224.505813) (xy 363.126746 -224.528503) (xy 363.079214 -224.543947)
			(xy 363.029851 -224.551766) (xy 362.979873 -224.551766) (xy 362.93051 -224.543947) (xy 362.882978 -224.528503)
			(xy 362.838446 -224.505813) (xy 362.798013 -224.476437) (xy 362.762673 -224.441097) (xy 362.733297 -224.400664)
			(xy 362.710607 -224.356132) (xy 362.695163 -224.3086) (xy 362.687344 -224.259237) (xy 361.442272 -224.259237)
			(xy 361.434453 -224.3086) (xy 361.419009 -224.356132) (xy 361.396319 -224.400664) (xy 361.366943 -224.441097)
			(xy 361.331603 -224.476437) (xy 361.29117 -224.505813) (xy 361.246638 -224.528503) (xy 361.199106 -224.543947)
			(xy 361.149743 -224.551766) (xy 361.099765 -224.551766) (xy 361.050402 -224.543947) (xy 361.00287 -224.528503)
			(xy 360.958338 -224.505813) (xy 360.917905 -224.476437) (xy 360.882565 -224.441097) (xy 360.853189 -224.400664)
			(xy 360.830499 -224.356132) (xy 360.815055 -224.3086) (xy 360.807236 -224.259237) (xy 358.628714 -224.259237)
			(xy 358.620895 -224.3086) (xy 358.605451 -224.356132) (xy 358.582761 -224.400664) (xy 358.553385 -224.441097)
			(xy 358.518045 -224.476437) (xy 358.477612 -224.505813) (xy 358.43308 -224.528503) (xy 358.385548 -224.543947)
			(xy 358.336185 -224.551766) (xy 358.286207 -224.551766) (xy 358.236844 -224.543947) (xy 358.189312 -224.528503)
			(xy 358.14478 -224.505813) (xy 358.104347 -224.476437) (xy 358.069007 -224.441097) (xy 358.039631 -224.400664)
			(xy 358.016941 -224.356132) (xy 358.001497 -224.3086) (xy 357.993678 -224.259237) (xy 357.68866 -224.259237)
			(xy 357.680841 -224.3086) (xy 357.665397 -224.356132) (xy 357.642707 -224.400664) (xy 357.613331 -224.441097)
			(xy 357.577991 -224.476437) (xy 357.537558 -224.505813) (xy 357.493026 -224.528503) (xy 357.445494 -224.543947)
			(xy 357.396131 -224.551766) (xy 357.346153 -224.551766) (xy 357.29679 -224.543947) (xy 357.249258 -224.528503)
			(xy 357.204726 -224.505813) (xy 357.164293 -224.476437) (xy 357.128953 -224.441097) (xy 357.099577 -224.400664)
			(xy 357.076887 -224.356132) (xy 357.061443 -224.3086) (xy 357.053624 -224.259237) (xy 356.748606 -224.259237)
			(xy 356.740787 -224.3086) (xy 356.725343 -224.356132) (xy 356.702653 -224.400664) (xy 356.673277 -224.441097)
			(xy 356.637937 -224.476437) (xy 356.597504 -224.505813) (xy 356.552972 -224.528503) (xy 356.50544 -224.543947)
			(xy 356.456077 -224.551766) (xy 356.406099 -224.551766) (xy 356.356736 -224.543947) (xy 356.309204 -224.528503)
			(xy 356.264672 -224.505813) (xy 356.224239 -224.476437) (xy 356.188899 -224.441097) (xy 356.159523 -224.400664)
			(xy 356.136833 -224.356132) (xy 356.121389 -224.3086) (xy 356.11357 -224.259237) (xy 355.808475 -224.259237)
			(xy 355.801151 -224.306702) (xy 355.786484 -224.353123) (xy 355.764915 -224.396767) (xy 355.73695 -224.436615)
			(xy 355.70324 -224.471738) (xy 355.664572 -224.501315) (xy 355.643434 -224.513394) (xy 355.634815 -224.518607)
			(xy 355.622232 -224.534318) (xy 355.61905 -224.543874) (xy 355.606984 -224.584039) (xy 355.577599 -224.662596)
			(xy 355.54237 -224.738711) (xy 355.522276 -224.775522) (xy 355.517082 -224.786198) (xy 355.516028 -224.809889)
			(xy 355.520244 -224.820988) (xy 355.53534 -224.856252) (xy 355.55661 -224.92995) (xy 355.567355 -225.005901)
			(xy 355.567996 -225.044254) (xy 355.567621 -225.069243) (xy 356.583724 -225.069243) (xy 356.583724 -225.019265)
			(xy 356.591543 -224.969902) (xy 356.606987 -224.92237) (xy 356.629677 -224.877838) (xy 356.659053 -224.837405)
			(xy 356.694393 -224.802065) (xy 356.734826 -224.772689) (xy 356.779358 -224.749999) (xy 356.82689 -224.734555)
			(xy 356.876253 -224.726736) (xy 356.926231 -224.726736) (xy 356.975594 -224.734555) (xy 357.023126 -224.749999)
			(xy 357.067658 -224.772689) (xy 357.108091 -224.802065) (xy 357.143431 -224.837405) (xy 357.172807 -224.877838)
			(xy 357.195497 -224.92237) (xy 357.210941 -224.969902) (xy 357.21876 -225.019265) (xy 357.21925 -225.044254)
			(xy 357.21876 -225.069243) (xy 357.523778 -225.069243) (xy 357.523778 -225.019265) (xy 357.531597 -224.969902)
			(xy 357.547041 -224.92237) (xy 357.569731 -224.877838) (xy 357.599107 -224.837405) (xy 357.634447 -224.802065)
			(xy 357.67488 -224.772689) (xy 357.719412 -224.749999) (xy 357.766944 -224.734555) (xy 357.816307 -224.726736)
			(xy 357.866285 -224.726736) (xy 357.915648 -224.734555) (xy 357.96318 -224.749999) (xy 358.007712 -224.772689)
			(xy 358.048145 -224.802065) (xy 358.083485 -224.837405) (xy 358.112861 -224.877838) (xy 358.135551 -224.92237)
			(xy 358.150995 -224.969902) (xy 358.158814 -225.019265) (xy 358.159304 -225.044254) (xy 358.158814 -225.069243)
			(xy 365.037352 -225.069243) (xy 365.037352 -225.019265) (xy 365.045171 -224.969902) (xy 365.060615 -224.92237)
			(xy 365.083305 -224.877838) (xy 365.112681 -224.837405) (xy 365.148021 -224.802065) (xy 365.188454 -224.772689)
			(xy 365.232986 -224.749999) (xy 365.280518 -224.734555) (xy 365.329881 -224.726736) (xy 365.379859 -224.726736)
			(xy 365.429222 -224.734555) (xy 365.476754 -224.749999) (xy 365.521286 -224.772689) (xy 365.561719 -224.802065)
			(xy 365.597059 -224.837405) (xy 365.626435 -224.877838) (xy 365.649125 -224.92237) (xy 365.664569 -224.969902)
			(xy 365.672388 -225.019265) (xy 365.672878 -225.044254) (xy 369.738651 -225.044254) (xy 369.742746 -224.993526)
			(xy 369.754925 -224.944112) (xy 369.774873 -224.897292) (xy 369.802074 -224.854278) (xy 369.835822 -224.816184)
			(xy 369.875244 -224.783997) (xy 369.919318 -224.758551) (xy 369.966904 -224.740504) (xy 370.016768 -224.730324)
			(xy 370.06762 -224.728275) (xy 370.118141 -224.734409) (xy 370.167025 -224.748569) (xy 370.213004 -224.770386)
			(xy 370.254888 -224.799296) (xy 370.291592 -224.834551) (xy 370.322165 -224.875237) (xy 370.345816 -224.9203)
			(xy 370.361932 -224.968574) (xy 370.370096 -225.018808) (xy 370.370608 -225.044254) (xy 370.678451 -225.044254)
			(xy 370.682546 -224.993526) (xy 370.694725 -224.944112) (xy 370.714673 -224.897292) (xy 370.741874 -224.854278)
			(xy 370.775622 -224.816184) (xy 370.815044 -224.783997) (xy 370.859118 -224.758551) (xy 370.906704 -224.740504)
			(xy 370.956568 -224.730324) (xy 371.00742 -224.728275) (xy 371.057941 -224.734409) (xy 371.106825 -224.748569)
			(xy 371.152804 -224.770386) (xy 371.194688 -224.799296) (xy 371.231392 -224.834551) (xy 371.261965 -224.875237)
			(xy 371.285616 -224.9203) (xy 371.301732 -224.968574) (xy 371.309896 -225.018808) (xy 371.310408 -225.044254)
			(xy 371.309905 -225.069243) (xy 372.557276 -225.069243) (xy 372.557276 -225.019265) (xy 372.565095 -224.969902)
			(xy 372.580539 -224.92237) (xy 372.603229 -224.877838) (xy 372.632605 -224.837405) (xy 372.667945 -224.802065)
			(xy 372.708378 -224.772689) (xy 372.75291 -224.749999) (xy 372.800442 -224.734555) (xy 372.849805 -224.726736)
			(xy 372.899783 -224.726736) (xy 372.949146 -224.734555) (xy 372.996678 -224.749999) (xy 373.04121 -224.772689)
			(xy 373.081643 -224.802065) (xy 373.116983 -224.837405) (xy 373.146359 -224.877838) (xy 373.169049 -224.92237)
			(xy 373.184493 -224.969902) (xy 373.192312 -225.019265) (xy 373.192802 -225.044254) (xy 373.192312 -225.069243)
			(xy 373.184493 -225.118606) (xy 373.169049 -225.166138) (xy 373.146359 -225.21067) (xy 373.116983 -225.251103)
			(xy 373.081643 -225.286443) (xy 373.04121 -225.315819) (xy 372.996678 -225.338509) (xy 372.949146 -225.353953)
			(xy 372.899783 -225.361772) (xy 372.849805 -225.361772) (xy 372.800442 -225.353953) (xy 372.75291 -225.338509)
			(xy 372.708378 -225.315819) (xy 372.667945 -225.286443) (xy 372.632605 -225.251103) (xy 372.603229 -225.21067)
			(xy 372.580539 -225.166138) (xy 372.565095 -225.118606) (xy 372.557276 -225.069243) (xy 371.309905 -225.069243)
			(xy 371.309896 -225.0697) (xy 371.301732 -225.119934) (xy 371.285616 -225.168208) (xy 371.261965 -225.213271)
			(xy 371.231392 -225.253957) (xy 371.194688 -225.289212) (xy 371.152804 -225.318122) (xy 371.106825 -225.339939)
			(xy 371.057941 -225.354099) (xy 371.00742 -225.360233) (xy 370.956568 -225.358184) (xy 370.906704 -225.348004)
			(xy 370.859118 -225.329957) (xy 370.815044 -225.304511) (xy 370.775622 -225.272324) (xy 370.741874 -225.23423)
			(xy 370.714673 -225.191216) (xy 370.694725 -225.144396) (xy 370.682546 -225.094982) (xy 370.678451 -225.044254)
			(xy 370.370608 -225.044254) (xy 370.370096 -225.0697) (xy 370.361932 -225.119934) (xy 370.345816 -225.168208)
			(xy 370.322165 -225.213271) (xy 370.291592 -225.253957) (xy 370.254888 -225.289212) (xy 370.213004 -225.318122)
			(xy 370.167025 -225.339939) (xy 370.118141 -225.354099) (xy 370.06762 -225.360233) (xy 370.016768 -225.358184)
			(xy 369.966904 -225.348004) (xy 369.919318 -225.329957) (xy 369.875244 -225.304511) (xy 369.835822 -225.272324)
			(xy 369.802074 -225.23423) (xy 369.774873 -225.191216) (xy 369.754925 -225.144396) (xy 369.742746 -225.094982)
			(xy 369.738651 -225.044254) (xy 365.672878 -225.044254) (xy 365.672388 -225.069243) (xy 365.664569 -225.118606)
			(xy 365.649125 -225.166138) (xy 365.626435 -225.21067) (xy 365.597059 -225.251103) (xy 365.561719 -225.286443)
			(xy 365.521286 -225.315819) (xy 365.476754 -225.338509) (xy 365.429222 -225.353953) (xy 365.379859 -225.361772)
			(xy 365.329881 -225.361772) (xy 365.280518 -225.353953) (xy 365.232986 -225.338509) (xy 365.188454 -225.315819)
			(xy 365.148021 -225.286443) (xy 365.112681 -225.251103) (xy 365.083305 -225.21067) (xy 365.060615 -225.166138)
			(xy 365.045171 -225.118606) (xy 365.037352 -225.069243) (xy 358.158814 -225.069243) (xy 358.150995 -225.118606)
			(xy 358.135551 -225.166138) (xy 358.112861 -225.21067) (xy 358.083485 -225.251103) (xy 358.048145 -225.286443)
			(xy 358.007712 -225.315819) (xy 357.96318 -225.338509) (xy 357.915648 -225.353953) (xy 357.866285 -225.361772)
			(xy 357.816307 -225.361772) (xy 357.766944 -225.353953) (xy 357.719412 -225.338509) (xy 357.67488 -225.315819)
			(xy 357.634447 -225.286443) (xy 357.599107 -225.251103) (xy 357.569731 -225.21067) (xy 357.547041 -225.166138)
			(xy 357.531597 -225.118606) (xy 357.523778 -225.069243) (xy 357.21876 -225.069243) (xy 357.210941 -225.118606)
			(xy 357.195497 -225.166138) (xy 357.172807 -225.21067) (xy 357.143431 -225.251103) (xy 357.108091 -225.286443)
			(xy 357.067658 -225.315819) (xy 357.023126 -225.338509) (xy 356.975594 -225.353953) (xy 356.926231 -225.361772)
			(xy 356.876253 -225.361772) (xy 356.82689 -225.353953) (xy 356.779358 -225.338509) (xy 356.734826 -225.315819)
			(xy 356.694393 -225.286443) (xy 356.659053 -225.251103) (xy 356.629677 -225.21067) (xy 356.606987 -225.166138)
			(xy 356.591543 -225.118606) (xy 356.583724 -225.069243) (xy 355.567621 -225.069243) (xy 355.567501 -225.077265)
			(xy 355.559551 -225.142807) (xy 355.543761 -225.206913) (xy 355.52036 -225.268649) (xy 355.489692 -225.327116)
			(xy 355.452201 -225.381461) (xy 355.408435 -225.430892) (xy 355.359031 -225.47469) (xy 355.304709 -225.512214)
			(xy 355.246262 -225.54292) (xy 355.18454 -225.566359) (xy 355.120444 -225.582189) (xy 355.054907 -225.59018)
			(xy 355.021896 -225.590608) (xy 354.93833 -225.590608) (xy 354.92577 -225.591243) (xy 354.903624 -225.603091)
			(xy 354.896166 -225.613214) (xy 354.849176 -225.683826) (xy 354.842839 -225.694622) (xy 354.84045 -225.719514)
			(xy 354.844604 -225.731324) (xy 354.844604 -225.731578) (xy 354.856091 -225.760939) (xy 354.868511 -225.822741)
			(xy 354.869242 -225.85426) (xy 354.868752 -225.879249) (xy 356.11357 -225.879249) (xy 356.11357 -225.829271)
			(xy 356.121389 -225.779908) (xy 356.136833 -225.732376) (xy 356.159523 -225.687844) (xy 356.188899 -225.647411)
			(xy 356.224239 -225.612071) (xy 356.264672 -225.582695) (xy 356.309204 -225.560005) (xy 356.356736 -225.544561)
			(xy 356.406099 -225.536742) (xy 356.456077 -225.536742) (xy 356.50544 -225.544561) (xy 356.552972 -225.560005)
			(xy 356.597504 -225.582695) (xy 356.637937 -225.612071) (xy 356.673277 -225.647411) (xy 356.702653 -225.687844)
			(xy 356.725343 -225.732376) (xy 356.740787 -225.779908) (xy 356.748606 -225.829271) (xy 356.749096 -225.85426)
			(xy 356.748606 -225.879249) (xy 357.053624 -225.879249) (xy 357.053624 -225.829271) (xy 357.061443 -225.779908)
			(xy 357.076887 -225.732376) (xy 357.099577 -225.687844) (xy 357.128953 -225.647411) (xy 357.164293 -225.612071)
			(xy 357.204726 -225.582695) (xy 357.249258 -225.560005) (xy 357.29679 -225.544561) (xy 357.346153 -225.536742)
			(xy 357.396131 -225.536742) (xy 357.445494 -225.544561) (xy 357.493026 -225.560005) (xy 357.537558 -225.582695)
			(xy 357.577991 -225.612071) (xy 357.613331 -225.647411) (xy 357.642707 -225.687844) (xy 357.665397 -225.732376)
			(xy 357.680841 -225.779908) (xy 357.68866 -225.829271) (xy 357.68915 -225.85426) (xy 357.68866 -225.879249)
			(xy 357.993678 -225.879249) (xy 357.993678 -225.829271) (xy 358.001497 -225.779908) (xy 358.016941 -225.732376)
			(xy 358.039631 -225.687844) (xy 358.069007 -225.647411) (xy 358.104347 -225.612071) (xy 358.14478 -225.582695)
			(xy 358.189312 -225.560005) (xy 358.236844 -225.544561) (xy 358.286207 -225.536742) (xy 358.336185 -225.536742)
			(xy 358.385548 -225.544561) (xy 358.43308 -225.560005) (xy 358.477612 -225.582695) (xy 358.518045 -225.612071)
			(xy 358.553385 -225.647411) (xy 358.582761 -225.687844) (xy 358.605451 -225.732376) (xy 358.620895 -225.779908)
			(xy 358.628714 -225.829271) (xy 358.629204 -225.85426) (xy 358.628714 -225.879249) (xy 360.807236 -225.879249)
			(xy 360.807236 -225.829271) (xy 360.815055 -225.779908) (xy 360.830499 -225.732376) (xy 360.853189 -225.687844)
			(xy 360.882565 -225.647411) (xy 360.917905 -225.612071) (xy 360.958338 -225.582695) (xy 361.00287 -225.560005)
			(xy 361.050402 -225.544561) (xy 361.099765 -225.536742) (xy 361.149743 -225.536742) (xy 361.199106 -225.544561)
			(xy 361.246638 -225.560005) (xy 361.29117 -225.582695) (xy 361.331603 -225.612071) (xy 361.366943 -225.647411)
			(xy 361.396319 -225.687844) (xy 361.419009 -225.732376) (xy 361.434453 -225.779908) (xy 361.442272 -225.829271)
			(xy 361.442762 -225.85426) (xy 361.442272 -225.879249) (xy 361.74729 -225.879249) (xy 361.74729 -225.829271)
			(xy 361.755109 -225.779908) (xy 361.770553 -225.732376) (xy 361.793243 -225.687844) (xy 361.822619 -225.647411)
			(xy 361.857959 -225.612071) (xy 361.898392 -225.582695) (xy 361.942924 -225.560005) (xy 361.990456 -225.544561)
			(xy 362.039819 -225.536742) (xy 362.089797 -225.536742) (xy 362.13916 -225.544561) (xy 362.186692 -225.560005)
			(xy 362.231224 -225.582695) (xy 362.271657 -225.612071) (xy 362.306997 -225.647411) (xy 362.336373 -225.687844)
			(xy 362.359063 -225.732376) (xy 362.374507 -225.779908) (xy 362.382326 -225.829271) (xy 362.382816 -225.85426)
			(xy 362.382326 -225.879249) (xy 362.687344 -225.879249) (xy 362.687344 -225.829271) (xy 362.695163 -225.779908)
			(xy 362.710607 -225.732376) (xy 362.733297 -225.687844) (xy 362.762673 -225.647411) (xy 362.798013 -225.612071)
			(xy 362.838446 -225.582695) (xy 362.882978 -225.560005) (xy 362.93051 -225.544561) (xy 362.979873 -225.536742)
			(xy 363.029851 -225.536742) (xy 363.079214 -225.544561) (xy 363.126746 -225.560005) (xy 363.171278 -225.582695)
			(xy 363.211711 -225.612071) (xy 363.247051 -225.647411) (xy 363.276427 -225.687844) (xy 363.299117 -225.732376)
			(xy 363.314561 -225.779908) (xy 363.32238 -225.829271) (xy 363.32287 -225.85426) (xy 363.32238 -225.879249)
			(xy 364.567198 -225.879249) (xy 364.567198 -225.829271) (xy 364.575017 -225.779908) (xy 364.590461 -225.732376)
			(xy 364.613151 -225.687844) (xy 364.642527 -225.647411) (xy 364.677867 -225.612071) (xy 364.7183 -225.582695)
			(xy 364.762832 -225.560005) (xy 364.810364 -225.544561) (xy 364.859727 -225.536742) (xy 364.909705 -225.536742)
			(xy 364.959068 -225.544561) (xy 365.0066 -225.560005) (xy 365.051132 -225.582695) (xy 365.091565 -225.612071)
			(xy 365.126905 -225.647411) (xy 365.156281 -225.687844) (xy 365.178971 -225.732376) (xy 365.194415 -225.779908)
			(xy 365.202234 -225.829271) (xy 365.202724 -225.85426) (xy 365.202234 -225.879249) (xy 365.507252 -225.879249)
			(xy 365.507252 -225.829271) (xy 365.515071 -225.779908) (xy 365.530515 -225.732376) (xy 365.553205 -225.687844)
			(xy 365.582581 -225.647411) (xy 365.617921 -225.612071) (xy 365.658354 -225.582695) (xy 365.702886 -225.560005)
			(xy 365.750418 -225.544561) (xy 365.799781 -225.536742) (xy 365.849759 -225.536742) (xy 365.899122 -225.544561)
			(xy 365.946654 -225.560005) (xy 365.991186 -225.582695) (xy 366.031619 -225.612071) (xy 366.066959 -225.647411)
			(xy 366.096335 -225.687844) (xy 366.119025 -225.732376) (xy 366.134469 -225.779908) (xy 366.142288 -225.829271)
			(xy 366.142778 -225.85426) (xy 366.142288 -225.879249) (xy 367.38736 -225.879249) (xy 367.38736 -225.829271)
			(xy 367.395179 -225.779908) (xy 367.410623 -225.732376) (xy 367.433313 -225.687844) (xy 367.462689 -225.647411)
			(xy 367.498029 -225.612071) (xy 367.538462 -225.582695) (xy 367.582994 -225.560005) (xy 367.630526 -225.544561)
			(xy 367.679889 -225.536742) (xy 367.729867 -225.536742) (xy 367.77923 -225.544561) (xy 367.826762 -225.560005)
			(xy 367.871294 -225.582695) (xy 367.911727 -225.612071) (xy 367.947067 -225.647411) (xy 367.976443 -225.687844)
			(xy 367.999133 -225.732376) (xy 368.014577 -225.779908) (xy 368.022396 -225.829271) (xy 368.022886 -225.85426)
			(xy 368.022396 -225.879249) (xy 368.327414 -225.879249) (xy 368.327414 -225.829271) (xy 368.335233 -225.779908)
			(xy 368.350677 -225.732376) (xy 368.373367 -225.687844) (xy 368.402743 -225.647411) (xy 368.438083 -225.612071)
			(xy 368.478516 -225.582695) (xy 368.523048 -225.560005) (xy 368.57058 -225.544561) (xy 368.619943 -225.536742)
			(xy 368.669921 -225.536742) (xy 368.719284 -225.544561) (xy 368.766816 -225.560005) (xy 368.811348 -225.582695)
			(xy 368.851781 -225.612071) (xy 368.887121 -225.647411) (xy 368.916497 -225.687844) (xy 368.939187 -225.732376)
			(xy 368.954631 -225.779908) (xy 368.96245 -225.829271) (xy 368.96294 -225.85426) (xy 368.96245 -225.879249)
			(xy 370.207268 -225.879249) (xy 370.207268 -225.829271) (xy 370.215087 -225.779908) (xy 370.230531 -225.732376)
			(xy 370.253221 -225.687844) (xy 370.282597 -225.647411) (xy 370.317937 -225.612071) (xy 370.35837 -225.582695)
			(xy 370.402902 -225.560005) (xy 370.450434 -225.544561) (xy 370.499797 -225.536742) (xy 370.549775 -225.536742)
			(xy 370.599138 -225.544561) (xy 370.64667 -225.560005) (xy 370.691202 -225.582695) (xy 370.731635 -225.612071)
			(xy 370.766975 -225.647411) (xy 370.796351 -225.687844) (xy 370.819041 -225.732376) (xy 370.834485 -225.779908)
			(xy 370.842304 -225.829271) (xy 370.842794 -225.85426) (xy 370.842304 -225.879249) (xy 371.147322 -225.879249)
			(xy 371.147322 -225.829271) (xy 371.155141 -225.779908) (xy 371.170585 -225.732376) (xy 371.193275 -225.687844)
			(xy 371.222651 -225.647411) (xy 371.257991 -225.612071) (xy 371.298424 -225.582695) (xy 371.342956 -225.560005)
			(xy 371.390488 -225.544561) (xy 371.439851 -225.536742) (xy 371.489829 -225.536742) (xy 371.539192 -225.544561)
			(xy 371.586724 -225.560005) (xy 371.631256 -225.582695) (xy 371.671689 -225.612071) (xy 371.707029 -225.647411)
			(xy 371.736405 -225.687844) (xy 371.759095 -225.732376) (xy 371.774539 -225.779908) (xy 371.782358 -225.829271)
			(xy 371.782848 -225.85426) (xy 371.782358 -225.879249) (xy 373.027176 -225.879249) (xy 373.027176 -225.829271)
			(xy 373.034995 -225.779908) (xy 373.050439 -225.732376) (xy 373.073129 -225.687844) (xy 373.102505 -225.647411)
			(xy 373.137845 -225.612071) (xy 373.178278 -225.582695) (xy 373.22281 -225.560005) (xy 373.270342 -225.544561)
			(xy 373.319705 -225.536742) (xy 373.369683 -225.536742) (xy 373.419046 -225.544561) (xy 373.466578 -225.560005)
			(xy 373.51111 -225.582695) (xy 373.551543 -225.612071) (xy 373.586883 -225.647411) (xy 373.616259 -225.687844)
			(xy 373.638949 -225.732376) (xy 373.654393 -225.779908) (xy 373.662212 -225.829271) (xy 373.662702 -225.85426)
			(xy 373.662212 -225.879249) (xy 373.96723 -225.879249) (xy 373.96723 -225.829271) (xy 373.975049 -225.779908)
			(xy 373.990493 -225.732376) (xy 374.013183 -225.687844) (xy 374.042559 -225.647411) (xy 374.077899 -225.612071)
			(xy 374.118332 -225.582695) (xy 374.162864 -225.560005) (xy 374.210396 -225.544561) (xy 374.259759 -225.536742)
			(xy 374.309737 -225.536742) (xy 374.3591 -225.544561) (xy 374.406632 -225.560005) (xy 374.451164 -225.582695)
			(xy 374.491597 -225.612071) (xy 374.526937 -225.647411) (xy 374.556313 -225.687844) (xy 374.579003 -225.732376)
			(xy 374.594447 -225.779908) (xy 374.602266 -225.829271) (xy 374.602756 -225.85426) (xy 374.602266 -225.879249)
			(xy 374.594447 -225.928612) (xy 374.579003 -225.976144) (xy 374.556313 -226.020676) (xy 374.526937 -226.061109)
			(xy 374.491597 -226.096449) (xy 374.451164 -226.125825) (xy 374.406632 -226.148515) (xy 374.3591 -226.163959)
			(xy 374.309737 -226.171778) (xy 374.259759 -226.171778) (xy 374.210396 -226.163959) (xy 374.162864 -226.148515)
			(xy 374.118332 -226.125825) (xy 374.077899 -226.096449) (xy 374.042559 -226.061109) (xy 374.013183 -226.020676)
			(xy 373.990493 -225.976144) (xy 373.975049 -225.928612) (xy 373.96723 -225.879249) (xy 373.662212 -225.879249)
			(xy 373.654393 -225.928612) (xy 373.638949 -225.976144) (xy 373.616259 -226.020676) (xy 373.586883 -226.061109)
			(xy 373.551543 -226.096449) (xy 373.51111 -226.125825) (xy 373.466578 -226.148515) (xy 373.419046 -226.163959)
			(xy 373.369683 -226.171778) (xy 373.319705 -226.171778) (xy 373.270342 -226.163959) (xy 373.22281 -226.148515)
			(xy 373.178278 -226.125825) (xy 373.137845 -226.096449) (xy 373.102505 -226.061109) (xy 373.073129 -226.020676)
			(xy 373.050439 -225.976144) (xy 373.034995 -225.928612) (xy 373.027176 -225.879249) (xy 371.782358 -225.879249)
			(xy 371.774539 -225.928612) (xy 371.759095 -225.976144) (xy 371.736405 -226.020676) (xy 371.707029 -226.061109)
			(xy 371.671689 -226.096449) (xy 371.631256 -226.125825) (xy 371.586724 -226.148515) (xy 371.539192 -226.163959)
			(xy 371.489829 -226.171778) (xy 371.439851 -226.171778) (xy 371.390488 -226.163959) (xy 371.342956 -226.148515)
			(xy 371.298424 -226.125825) (xy 371.257991 -226.096449) (xy 371.222651 -226.061109) (xy 371.193275 -226.020676)
			(xy 371.170585 -225.976144) (xy 371.155141 -225.928612) (xy 371.147322 -225.879249) (xy 370.842304 -225.879249)
			(xy 370.834485 -225.928612) (xy 370.819041 -225.976144) (xy 370.796351 -226.020676) (xy 370.766975 -226.061109)
			(xy 370.731635 -226.096449) (xy 370.691202 -226.125825) (xy 370.64667 -226.148515) (xy 370.599138 -226.163959)
			(xy 370.549775 -226.171778) (xy 370.499797 -226.171778) (xy 370.450434 -226.163959) (xy 370.402902 -226.148515)
			(xy 370.35837 -226.125825) (xy 370.317937 -226.096449) (xy 370.282597 -226.061109) (xy 370.253221 -226.020676)
			(xy 370.230531 -225.976144) (xy 370.215087 -225.928612) (xy 370.207268 -225.879249) (xy 368.96245 -225.879249)
			(xy 368.954631 -225.928612) (xy 368.939187 -225.976144) (xy 368.916497 -226.020676) (xy 368.887121 -226.061109)
			(xy 368.851781 -226.096449) (xy 368.811348 -226.125825) (xy 368.766816 -226.148515) (xy 368.719284 -226.163959)
			(xy 368.669921 -226.171778) (xy 368.619943 -226.171778) (xy 368.57058 -226.163959) (xy 368.523048 -226.148515)
			(xy 368.478516 -226.125825) (xy 368.438083 -226.096449) (xy 368.402743 -226.061109) (xy 368.373367 -226.020676)
			(xy 368.350677 -225.976144) (xy 368.335233 -225.928612) (xy 368.327414 -225.879249) (xy 368.022396 -225.879249)
			(xy 368.014577 -225.928612) (xy 367.999133 -225.976144) (xy 367.976443 -226.020676) (xy 367.947067 -226.061109)
			(xy 367.911727 -226.096449) (xy 367.871294 -226.125825) (xy 367.826762 -226.148515) (xy 367.77923 -226.163959)
			(xy 367.729867 -226.171778) (xy 367.679889 -226.171778) (xy 367.630526 -226.163959) (xy 367.582994 -226.148515)
			(xy 367.538462 -226.125825) (xy 367.498029 -226.096449) (xy 367.462689 -226.061109) (xy 367.433313 -226.020676)
			(xy 367.410623 -225.976144) (xy 367.395179 -225.928612) (xy 367.38736 -225.879249) (xy 366.142288 -225.879249)
			(xy 366.134469 -225.928612) (xy 366.119025 -225.976144) (xy 366.096335 -226.020676) (xy 366.066959 -226.061109)
			(xy 366.031619 -226.096449) (xy 365.991186 -226.125825) (xy 365.946654 -226.148515) (xy 365.899122 -226.163959)
			(xy 365.849759 -226.171778) (xy 365.799781 -226.171778) (xy 365.750418 -226.163959) (xy 365.702886 -226.148515)
			(xy 365.658354 -226.125825) (xy 365.617921 -226.096449) (xy 365.582581 -226.061109) (xy 365.553205 -226.020676)
			(xy 365.530515 -225.976144) (xy 365.515071 -225.928612) (xy 365.507252 -225.879249) (xy 365.202234 -225.879249)
			(xy 365.194415 -225.928612) (xy 365.178971 -225.976144) (xy 365.156281 -226.020676) (xy 365.126905 -226.061109)
			(xy 365.091565 -226.096449) (xy 365.051132 -226.125825) (xy 365.0066 -226.148515) (xy 364.959068 -226.163959)
			(xy 364.909705 -226.171778) (xy 364.859727 -226.171778) (xy 364.810364 -226.163959) (xy 364.762832 -226.148515)
			(xy 364.7183 -226.125825) (xy 364.677867 -226.096449) (xy 364.642527 -226.061109) (xy 364.613151 -226.020676)
			(xy 364.590461 -225.976144) (xy 364.575017 -225.928612) (xy 364.567198 -225.879249) (xy 363.32238 -225.879249)
			(xy 363.314561 -225.928612) (xy 363.299117 -225.976144) (xy 363.276427 -226.020676) (xy 363.247051 -226.061109)
			(xy 363.211711 -226.096449) (xy 363.171278 -226.125825) (xy 363.126746 -226.148515) (xy 363.079214 -226.163959)
			(xy 363.029851 -226.171778) (xy 362.979873 -226.171778) (xy 362.93051 -226.163959) (xy 362.882978 -226.148515)
			(xy 362.838446 -226.125825) (xy 362.798013 -226.096449) (xy 362.762673 -226.061109) (xy 362.733297 -226.020676)
			(xy 362.710607 -225.976144) (xy 362.695163 -225.928612) (xy 362.687344 -225.879249) (xy 362.382326 -225.879249)
			(xy 362.374507 -225.928612) (xy 362.359063 -225.976144) (xy 362.336373 -226.020676) (xy 362.306997 -226.061109)
			(xy 362.271657 -226.096449) (xy 362.231224 -226.125825) (xy 362.186692 -226.148515) (xy 362.13916 -226.163959)
			(xy 362.089797 -226.171778) (xy 362.039819 -226.171778) (xy 361.990456 -226.163959) (xy 361.942924 -226.148515)
			(xy 361.898392 -226.125825) (xy 361.857959 -226.096449) (xy 361.822619 -226.061109) (xy 361.793243 -226.020676)
			(xy 361.770553 -225.976144) (xy 361.755109 -225.928612) (xy 361.74729 -225.879249) (xy 361.442272 -225.879249)
			(xy 361.434453 -225.928612) (xy 361.419009 -225.976144) (xy 361.396319 -226.020676) (xy 361.366943 -226.061109)
			(xy 361.331603 -226.096449) (xy 361.29117 -226.125825) (xy 361.246638 -226.148515) (xy 361.199106 -226.163959)
			(xy 361.149743 -226.171778) (xy 361.099765 -226.171778) (xy 361.050402 -226.163959) (xy 361.00287 -226.148515)
			(xy 360.958338 -226.125825) (xy 360.917905 -226.096449) (xy 360.882565 -226.061109) (xy 360.853189 -226.020676)
			(xy 360.830499 -225.976144) (xy 360.815055 -225.928612) (xy 360.807236 -225.879249) (xy 358.628714 -225.879249)
			(xy 358.620895 -225.928612) (xy 358.605451 -225.976144) (xy 358.582761 -226.020676) (xy 358.553385 -226.061109)
			(xy 358.518045 -226.096449) (xy 358.477612 -226.125825) (xy 358.43308 -226.148515) (xy 358.385548 -226.163959)
			(xy 358.336185 -226.171778) (xy 358.286207 -226.171778) (xy 358.236844 -226.163959) (xy 358.189312 -226.148515)
			(xy 358.14478 -226.125825) (xy 358.104347 -226.096449) (xy 358.069007 -226.061109) (xy 358.039631 -226.020676)
			(xy 358.016941 -225.976144) (xy 358.001497 -225.928612) (xy 357.993678 -225.879249) (xy 357.68866 -225.879249)
			(xy 357.680841 -225.928612) (xy 357.665397 -225.976144) (xy 357.642707 -226.020676) (xy 357.613331 -226.061109)
			(xy 357.577991 -226.096449) (xy 357.537558 -226.125825) (xy 357.493026 -226.148515) (xy 357.445494 -226.163959)
			(xy 357.396131 -226.171778) (xy 357.346153 -226.171778) (xy 357.29679 -226.163959) (xy 357.249258 -226.148515)
			(xy 357.204726 -226.125825) (xy 357.164293 -226.096449) (xy 357.128953 -226.061109) (xy 357.099577 -226.020676)
			(xy 357.076887 -225.976144) (xy 357.061443 -225.928612) (xy 357.053624 -225.879249) (xy 356.748606 -225.879249)
			(xy 356.740787 -225.928612) (xy 356.725343 -225.976144) (xy 356.702653 -226.020676) (xy 356.673277 -226.061109)
			(xy 356.637937 -226.096449) (xy 356.597504 -226.125825) (xy 356.552972 -226.148515) (xy 356.50544 -226.163959)
			(xy 356.456077 -226.171778) (xy 356.406099 -226.171778) (xy 356.356736 -226.163959) (xy 356.309204 -226.148515)
			(xy 356.264672 -226.125825) (xy 356.224239 -226.096449) (xy 356.188899 -226.061109) (xy 356.159523 -226.020676)
			(xy 356.136833 -225.976144) (xy 356.121389 -225.928612) (xy 356.11357 -225.879249) (xy 354.868752 -225.879249)
			(xy 354.860933 -225.928612) (xy 354.845489 -225.976144) (xy 354.822799 -226.020676) (xy 354.793423 -226.061109)
			(xy 354.758083 -226.096449) (xy 354.71765 -226.125825) (xy 354.673118 -226.148515) (xy 354.625586 -226.163959)
			(xy 354.576223 -226.171778) (xy 354.526245 -226.171778) (xy 354.476882 -226.163959) (xy 354.42935 -226.148515)
			(xy 354.384818 -226.125825) (xy 354.344385 -226.096449) (xy 354.309045 -226.061109) (xy 354.279669 -226.020676)
			(xy 354.256979 -225.976144) (xy 354.241535 -225.928612) (xy 354.233716 -225.879249) (xy 354.233226 -225.85426)
			(xy 354.233973 -225.822743) (xy 354.246392 -225.760943) (xy 354.257864 -225.731578) (xy 354.257864 -225.731324)
			(xy 354.262098 -225.719522) (xy 354.259715 -225.694593) (xy 354.253292 -225.683826) (xy 354.206302 -225.613214)
			(xy 354.198782 -225.603158) (xy 354.176675 -225.591311) (xy 354.164138 -225.590608) (xy 354.081334 -225.590608)
			(xy 354.063249 -225.590507) (xy 354.027152 -225.588217) (xy 354.009198 -225.586036) (xy 353.995482 -225.584258)
			(xy 353.970082 -225.594672) (xy 353.900232 -225.687382) (xy 353.897184 -225.71456) (xy 353.902772 -225.72726)
			(xy 353.911133 -225.747332) (xy 353.922903 -225.789191) (xy 353.928843 -225.832265) (xy 353.929188 -225.854006)
			(xy 353.929188 -225.85426) (xy 353.928698 -225.879249) (xy 353.920879 -225.928612) (xy 353.905435 -225.976144)
			(xy 353.882745 -226.020676) (xy 353.853369 -226.061109) (xy 353.818029 -226.096449) (xy 353.777596 -226.125825)
			(xy 353.733064 -226.148515) (xy 353.685532 -226.163959) (xy 353.636169 -226.171778) (xy 353.586191 -226.171778)
			(xy 353.536828 -226.163959) (xy 353.489296 -226.148515) (xy 353.444764 -226.125825) (xy 353.404331 -226.096449)
			(xy 353.368991 -226.061109) (xy 353.339615 -226.020676) (xy 353.316925 -225.976144) (xy 353.301481 -225.928612)
			(xy 353.293662 -225.879249) (xy 353.293172 -225.85426) (xy 353.293681 -225.8284) (xy 353.302054 -225.777362)
			(xy 353.318573 -225.728351) (xy 353.342802 -225.682657) (xy 353.374104 -225.641484) (xy 353.411654 -225.605917)
			(xy 353.454463 -225.576893) (xy 353.501402 -225.555176) (xy 353.551237 -225.541338) (xy 353.57689 -225.53803)
			(xy 353.590352 -225.536506) (xy 353.612704 -225.52025) (xy 353.65309 -225.42627) (xy 353.656313 -225.417885)
			(xy 353.657253 -225.399958) (xy 353.651906 -225.382821) (xy 353.64674 -225.37547) (xy 353.627516 -225.349441)
			(xy 353.594664 -225.293691) (xy 353.568623 -225.234452) (xy 353.54976 -225.172553) (xy 353.538337 -225.10886)
			(xy 353.534514 -225.044263) (xy 353.538345 -224.979667) (xy 353.549777 -224.915975) (xy 353.568649 -224.854079)
			(xy 353.594697 -224.794844) (xy 353.627557 -224.739098) (xy 353.64674 -224.713038) (xy 353.651893 -224.705685)
			(xy 353.657195 -224.688542) (xy 353.656305 -224.670619) (xy 353.65309 -224.662238) (xy 353.612704 -224.568258)
			(xy 353.590352 -224.552002) (xy 353.57689 -224.550478) (xy 353.551231 -224.547191) (xy 353.501382 -224.533372)
			(xy 353.454429 -224.511666) (xy 353.411608 -224.482645) (xy 353.374051 -224.447074) (xy 353.342748 -224.405893)
			(xy 353.318525 -224.360187) (xy 353.302021 -224.311162) (xy 353.293671 -224.260112) (xy 353.293172 -224.234248)
			(xy 353.293911 -224.202729) (xy 353.306315 -224.140923) (xy 353.31781 -224.111566) (xy 353.31781 -224.111312)
			(xy 353.322044 -224.099511) (xy 353.319653 -224.074585) (xy 353.313238 -224.063814) (xy 353.266248 -223.993202)
			(xy 353.258723 -223.983157) (xy 353.236616 -223.971336) (xy 353.224084 -223.970596) (xy 353.14128 -223.970596)
			(xy 353.123195 -223.970497) (xy 353.087097 -223.96821) (xy 353.069144 -223.966024) (xy 353.055428 -223.964246)
			(xy 353.030028 -223.97466) (xy 352.960178 -224.06737) (xy 352.95713 -224.094548) (xy 352.962718 -224.107248)
			(xy 352.971079 -224.12732) (xy 352.982849 -224.169179) (xy 352.98879 -224.212253) (xy 352.989134 -224.233994)
			(xy 352.989134 -224.234248) (xy 352.988644 -224.259237) (xy 352.980825 -224.3086) (xy 352.965381 -224.356132)
			(xy 352.942691 -224.400664) (xy 352.913315 -224.441097) (xy 352.877975 -224.476437) (xy 352.837542 -224.505813)
			(xy 352.79301 -224.528503) (xy 352.745478 -224.543947) (xy 352.696115 -224.551766) (xy 352.646137 -224.551766)
			(xy 352.596774 -224.543947) (xy 352.549242 -224.528503) (xy 352.50471 -224.505813) (xy 352.464277 -224.476437)
			(xy 352.428937 -224.441097) (xy 352.399561 -224.400664) (xy 352.376871 -224.356132) (xy 352.361427 -224.3086)
			(xy 352.353608 -224.259237) (xy 352.353118 -224.234248) (xy 352.353628 -224.208387) (xy 352.362002 -224.157348)
			(xy 352.378521 -224.108335) (xy 352.40275 -224.062639) (xy 352.43405 -224.021463) (xy 352.471599 -223.985892)
			(xy 352.514406 -223.956863) (xy 352.561345 -223.93514) (xy 352.611179 -223.921295) (xy 352.636836 -223.918018)
			(xy 352.650298 -223.916494) (xy 352.67265 -223.900238) (xy 352.713036 -223.806258) (xy 352.716255 -223.797873)
			(xy 352.71719 -223.779948) (xy 352.711844 -223.762813) (xy 352.706686 -223.755458) (xy 352.685379 -223.726561)
			(xy 352.649702 -223.664255) (xy 352.635566 -223.631252) (xy 352.635566 -223.630998) (xy 352.631767 -223.622792)
			(xy 352.619478 -223.609541) (xy 352.603357 -223.601374) (xy 352.594418 -223.60001) (xy 352.50628 -223.589596)
			(xy 352.497237 -223.58886) (xy 352.479607 -223.593094) (xy 352.464586 -223.603247) (xy 352.459036 -223.610424)
			(xy 352.443978 -223.63047) (xy 352.408611 -223.666003) (xy 352.368108 -223.695549) (xy 352.323471 -223.718374)
			(xy 352.275806 -223.733913) (xy 352.226293 -223.741782) (xy 352.201226 -223.74225) (xy 352.17623 -223.741787)
			(xy 352.126853 -223.733971) (xy 352.079308 -223.718525) (xy 352.034763 -223.695832) (xy 351.994318 -223.66645)
			(xy 351.958967 -223.631102) (xy 351.929581 -223.590659) (xy 351.906884 -223.546117) (xy 351.891435 -223.498572)
			(xy 351.883615 -223.449196) (xy 351.883615 -223.399204) (xy 351.891435 -223.349828) (xy 351.906884 -223.302283)
			(xy 351.929581 -223.257741) (xy 351.958967 -223.217298) (xy 351.994318 -223.18195) (xy 352.034763 -223.152568)
			(xy 352.079308 -223.129875) (xy 352.126853 -223.114429) (xy 352.17623 -223.106613) (xy 352.201226 -223.106234)
			(xy 352.226292 -223.106707) (xy 352.275801 -223.114578) (xy 352.323463 -223.13012) (xy 352.368095 -223.152948)
			(xy 352.408592 -223.182498) (xy 352.44395 -223.218036) (xy 352.459036 -223.23806) (xy 352.464638 -223.24518)
			(xy 352.479665 -223.255279) (xy 352.49725 -223.25959) (xy 352.50628 -223.258888) (xy 352.594418 -223.248474)
			(xy 352.603352 -223.247084) (xy 352.619476 -223.238929) (xy 352.631776 -223.225694) (xy 352.635566 -223.217486)
			(xy 352.635566 -223.217232) (xy 352.64217 -223.201484) (xy 352.646455 -223.190398) (xy 352.645379 -223.166687)
			(xy 352.640138 -223.156018) (xy 352.612131 -223.104294) (xy 352.565935 -222.996116) (xy 352.547936 -222.940118)
			(xy 352.544503 -222.93041) (xy 352.53127 -222.914659) (xy 352.522282 -222.909638) (xy 352.499209 -222.897439)
			(xy 352.456888 -222.866899) (xy 352.419883 -222.830096) (xy 352.38911 -222.787944) (xy 352.365332 -222.741485)
			(xy 352.349138 -222.691871) (xy 352.340928 -222.640331) (xy 352.340418 -222.614236) (xy 352.34091 -222.588111)
			(xy 352.349124 -222.53651) (xy 352.365352 -222.486844) (xy 352.389191 -222.440349) (xy 352.420048 -222.398184)
			(xy 352.457153 -222.361397) (xy 352.478086 -222.345758) (xy 352.487465 -222.338145) (xy 352.498455 -222.31667)
			(xy 352.499168 -222.30461) (xy 352.499168 -222.192342) (xy 352.498938 -222.185305) (xy 352.49506 -222.171776)
			(xy 352.491548 -222.165672) (xy 352.475388 -222.138537) (xy 352.448444 -222.081415) (xy 352.427939 -222.021678)
			(xy 352.414122 -221.96005) (xy 352.40716 -221.897277) (xy 352.406712 -221.865698) (xy 352.406712 -221.52102)
			(xy 352.406617 -221.516001) (xy 352.404692 -221.506152) (xy 352.402902 -221.501462) (xy 352.122232 -220.824552)
			(xy 352.118004 -220.815456) (xy 352.103809 -220.801305) (xy 352.085266 -220.793697) (xy 352.075242 -220.79331)
			(xy 351.487994 -220.79331) (xy 351.478241 -220.793817) (xy 351.460202 -220.801256) (xy 351.452942 -220.807788)
			(xy 351.095564 -221.165166) (xy 351.089007 -221.172413) (xy 351.081553 -221.190456) (xy 351.081086 -221.200218)
			(xy 351.081086 -221.427294) (xy 351.080832 -221.429072) (xy 351.080832 -221.432628) (xy 351.080994 -221.438495)
			(xy 351.083683 -221.449916) (xy 351.086166 -221.455234) (xy 351.088706 -221.460568) (xy 351.092516 -221.46514)
			(xy 351.100898 -221.47276) (xy 351.120202 -221.487238) (xy 351.126298 -221.491556) (xy 351.131251 -221.495073)
			(xy 351.142427 -221.499824) (xy 351.148396 -221.500954) (xy 351.159318 -221.502732) (xy 351.170494 -221.49943)
			(xy 351.192654 -221.493259) (xy 351.238173 -221.486633) (xy 351.261172 -221.486222) (xy 351.286164 -221.486685)
			(xy 351.335532 -221.494501) (xy 351.38307 -221.509944) (xy 351.427607 -221.532634) (xy 351.468045 -221.562013)
			(xy 351.503388 -221.597357) (xy 351.532767 -221.637795) (xy 351.555457 -221.682332) (xy 351.5709 -221.72987)
			(xy 351.578715 -221.779238) (xy 351.57918 -221.80423) (xy 351.578705 -221.829004) (xy 351.571017 -221.877953)
			(xy 351.555833 -221.925117) (xy 351.533518 -221.969356) (xy 351.504614 -222.0096) (xy 351.469819 -222.044875)
			(xy 351.429975 -222.074329) (xy 351.386046 -222.097247) (xy 351.339094 -222.113077) (xy 351.290255 -222.121435)
			(xy 351.26549 -222.122238) (xy 351.260918 -222.122238) (xy 351.23098 -222.121524) (xy 351.17217 -222.110263)
			(xy 351.144078 -222.099886) (xy 351.143316 -222.099632) (xy 351.137761 -222.097659) (xy 351.126078 -222.096116)
			(xy 351.120202 -222.096584) (xy 351.107502 -222.097854) (xy 351.062798 -222.128334) (xy 351.02673 -222.152972)
			(xy 351.017855 -222.160463) (xy 351.007557 -222.18125) (xy 351.006918 -222.19285) (xy 351.006918 -222.341186)
			(xy 351.007239 -222.349646) (xy 351.012805 -222.365624) (xy 351.01784 -222.372428) (xy 351.02165 -222.377254)
			(xy 351.023682 -222.379286) (xy 351.041922 -222.398029) (xy 351.072845 -222.440206) (xy 351.096738 -222.486727)
			(xy 351.113004 -222.536431) (xy 351.121238 -222.588076) (xy 351.121234 -222.639225) (xy 351.413554 -222.639225)
			(xy 351.413554 -222.589247) (xy 351.421373 -222.539884) (xy 351.436817 -222.492352) (xy 351.459507 -222.44782)
			(xy 351.488883 -222.407387) (xy 351.524223 -222.372047) (xy 351.564656 -222.342671) (xy 351.609188 -222.319981)
			(xy 351.65672 -222.304537) (xy 351.706083 -222.296718) (xy 351.756061 -222.296718) (xy 351.805424 -222.304537)
			(xy 351.852956 -222.319981) (xy 351.897488 -222.342671) (xy 351.937921 -222.372047) (xy 351.973261 -222.407387)
			(xy 352.002637 -222.44782) (xy 352.025327 -222.492352) (xy 352.040771 -222.539884) (xy 352.04859 -222.589247)
			(xy 352.04908 -222.614236) (xy 352.04859 -222.639225) (xy 352.040771 -222.688588) (xy 352.025327 -222.73612)
			(xy 352.002637 -222.780652) (xy 351.973261 -222.821085) (xy 351.937921 -222.856425) (xy 351.897488 -222.885801)
			(xy 351.852956 -222.908491) (xy 351.805424 -222.923935) (xy 351.756061 -222.931754) (xy 351.706083 -222.931754)
			(xy 351.65672 -222.923935) (xy 351.609188 -222.908491) (xy 351.564656 -222.885801) (xy 351.524223 -222.856425)
			(xy 351.488883 -222.821085) (xy 351.459507 -222.780652) (xy 351.436817 -222.73612) (xy 351.421373 -222.688588)
			(xy 351.413554 -222.639225) (xy 351.121234 -222.639225) (xy 351.121234 -222.640374) (xy 351.112992 -222.692019)
			(xy 351.096718 -222.74172) (xy 351.072818 -222.788237) (xy 351.041889 -222.830409) (xy 351.023682 -222.849186)
			(xy 351.02165 -222.851218) (xy 351.01784 -222.856044) (xy 351.012816 -222.862857) (xy 351.007232 -222.878827)
			(xy 351.006918 -222.887286) (xy 351.006918 -223.970342) (xy 351.007046 -223.975031) (xy 351.008831 -223.984237)
			(xy 351.010474 -223.98863) (xy 351.020634 -224.013522) (xy 351.02673 -224.020126) (xy 351.042148 -224.037772)
			(xy 351.068164 -224.076744) (xy 351.08818 -224.119111) (xy 351.101763 -224.163957) (xy 351.108618 -224.210311)
			(xy 351.109026 -224.23374) (xy 351.109026 -224.234248) (xy 351.108802 -224.253616) (xy 351.108132 -224.259237)
			(xy 351.413554 -224.259237) (xy 351.413554 -224.209259) (xy 351.421373 -224.159896) (xy 351.436817 -224.112364)
			(xy 351.459507 -224.067832) (xy 351.488883 -224.027399) (xy 351.524223 -223.992059) (xy 351.564656 -223.962683)
			(xy 351.609188 -223.939993) (xy 351.65672 -223.924549) (xy 351.706083 -223.91673) (xy 351.756061 -223.91673)
			(xy 351.805424 -223.924549) (xy 351.852956 -223.939993) (xy 351.897488 -223.962683) (xy 351.937921 -223.992059)
			(xy 351.973261 -224.027399) (xy 352.002637 -224.067832) (xy 352.025327 -224.112364) (xy 352.040771 -224.159896)
			(xy 352.04859 -224.209259) (xy 352.04908 -224.234248) (xy 352.04859 -224.259237) (xy 352.040771 -224.3086)
			(xy 352.025327 -224.356132) (xy 352.002637 -224.400664) (xy 351.973261 -224.441097) (xy 351.937921 -224.476437)
			(xy 351.897488 -224.505813) (xy 351.852956 -224.528503) (xy 351.805424 -224.543947) (xy 351.756061 -224.551766)
			(xy 351.706083 -224.551766) (xy 351.65672 -224.543947) (xy 351.609188 -224.528503) (xy 351.564656 -224.505813)
			(xy 351.524223 -224.476437) (xy 351.488883 -224.441097) (xy 351.459507 -224.400664) (xy 351.436817 -224.356132)
			(xy 351.421373 -224.3086) (xy 351.413554 -224.259237) (xy 351.108132 -224.259237) (xy 351.104219 -224.292078)
			(xy 351.099882 -224.310956) (xy 351.093938 -224.333142) (xy 351.076551 -224.375653) (xy 351.053245 -224.41523)
			(xy 351.039176 -224.433384) (xy 351.029524 -224.444814) (xy 351.02673 -224.448116) (xy 351.019872 -224.459038)
			(xy 351.015554 -224.466912) (xy 351.01022 -224.48012) (xy 351.008721 -224.484348) (xy 351.007059 -224.493162)
			(xy 351.006918 -224.497646) (xy 351.006918 -225.138996) (xy 351.006378 -225.148832) (xy 350.998786 -225.166988)
			(xy 350.992186 -225.174302) (xy 350.794574 -225.371914) (xy 350.788763 -225.378222) (xy 350.781409 -225.393703)
			(xy 350.779661 -225.410753) (xy 350.781366 -225.419158) (xy 350.788986 -225.443796) (xy 350.788986 -225.444304)
			(xy 350.808798 -225.507296) (xy 350.811038 -225.513724) (xy 350.818364 -225.525191) (xy 350.823276 -225.529902)
			(xy 350.827594 -225.533966) (xy 350.840548 -225.540062) (xy 350.847914 -225.541332) (xy 350.872029 -225.546178)
			(xy 350.918493 -225.562313) (xy 350.961918 -225.58541) (xy 351.001269 -225.614918) (xy 351.035607 -225.650133)
			(xy 351.064113 -225.690216) (xy 351.086108 -225.73421) (xy 351.101065 -225.781067) (xy 351.10863 -225.829667)
			(xy 351.109026 -225.85426) (xy 351.108565 -225.879249) (xy 351.413554 -225.879249) (xy 351.413554 -225.829271)
			(xy 351.421373 -225.779908) (xy 351.436817 -225.732376) (xy 351.459507 -225.687844) (xy 351.488883 -225.647411)
			(xy 351.524223 -225.612071) (xy 351.564656 -225.582695) (xy 351.609188 -225.560005) (xy 351.65672 -225.544561)
			(xy 351.706083 -225.536742) (xy 351.756061 -225.536742) (xy 351.805424 -225.544561) (xy 351.852956 -225.560005)
			(xy 351.897488 -225.582695) (xy 351.937921 -225.612071) (xy 351.973261 -225.647411) (xy 352.002637 -225.687844)
			(xy 352.025327 -225.732376) (xy 352.040771 -225.779908) (xy 352.04859 -225.829271) (xy 352.04908 -225.85426)
			(xy 352.04859 -225.879249) (xy 352.040771 -225.928612) (xy 352.025327 -225.976144) (xy 352.002637 -226.020676)
			(xy 351.973261 -226.061109) (xy 351.937921 -226.096449) (xy 351.897488 -226.125825) (xy 351.852956 -226.148515)
			(xy 351.805424 -226.163959) (xy 351.756061 -226.171778) (xy 351.706083 -226.171778) (xy 351.65672 -226.163959)
			(xy 351.609188 -226.148515) (xy 351.564656 -226.125825) (xy 351.524223 -226.096449) (xy 351.488883 -226.061109)
			(xy 351.459507 -226.020676) (xy 351.436817 -225.976144) (xy 351.421373 -225.928612) (xy 351.413554 -225.879249)
			(xy 351.108565 -225.879249) (xy 351.108565 -225.879254) (xy 351.100751 -225.928627) (xy 351.085309 -225.976169)
			(xy 351.06262 -226.020711) (xy 351.033242 -226.061155) (xy 350.997899 -226.096504) (xy 350.95746 -226.12589)
			(xy 350.912923 -226.148587) (xy 350.865383 -226.164037) (xy 350.816012 -226.17186) (xy 350.791018 -226.172268)
			(xy 350.766433 -226.171804) (xy 350.717851 -226.164224) (xy 350.671013 -226.149259) (xy 350.627037 -226.127264)
			(xy 350.586969 -226.098763) (xy 350.551765 -226.064436) (xy 350.522262 -226.0251) (xy 350.499165 -225.981692)
			(xy 350.483022 -225.935247) (xy 350.47809 -225.911156) (xy 350.477836 -225.909632) (xy 350.477328 -225.907092)
			(xy 350.475673 -225.901598) (xy 350.470289 -225.89147) (xy 350.46666 -225.887026) (xy 350.46666 -225.886772)
			(xy 350.461954 -225.881671) (xy 350.450356 -225.87406) (xy 350.4438 -225.871786) (xy 350.359218 -225.84537)
			(xy 350.350878 -225.843035) (xy 350.333581 -225.843695) (xy 350.325436 -225.84664) (xy 350.315784 -225.850704)
			(xy 350.18091 -225.985578) (xy 350.177352 -225.988995) (xy 350.169159 -225.994489) (xy 350.164654 -225.9965)
			(xy 350.15424 -226.000818) (xy 350.142048 -226.01174) (xy 350.14154 -226.012502) (xy 350.13773 -226.019106)
			(xy 350.12499 -226.040387) (xy 350.094132 -226.079216) (xy 350.05782 -226.112999) (xy 350.016868 -226.140979)
			(xy 349.972196 -226.162527) (xy 349.924807 -226.17716) (xy 349.875763 -226.184549) (xy 349.850964 -226.184968)
			(xy 349.847916 -226.184968) (xy 349.837248 -226.184714) (xy 349.824914 -226.184116) (xy 349.800377 -226.181322)
			(xy 349.788226 -226.179126) (xy 349.770481 -226.175463) (xy 349.73586 -226.164768) (xy 349.719138 -226.15779)
			(xy 349.71482 -226.155758) (xy 349.693484 -226.150932) (xy 349.680784 -226.15271) (xy 349.677736 -226.153472)
			(xy 349.654876 -226.159314) (xy 349.610008 -226.169838) (xy 349.51902 -226.184532) (xy 349.427147 -226.191889)
			(xy 349.381064 -226.192334) (xy 349.335658 -226.191922) (xy 349.245127 -226.184803) (xy 349.200216 -226.17811)
			(xy 349.165998 -226.172409) (xy 349.098261 -226.157412) (xy 349.064834 -226.148138) (xy 349.053404 -226.144836)
			(xy 349.035116 -226.148392) (xy 349.024702 -226.15144) (xy 349.023686 -226.151694) (xy 349.006101 -226.158057)
			(xy 348.969811 -226.167095) (xy 348.951296 -226.169728) (xy 348.942152 -226.170998) (xy 348.911164 -226.172522)
			(xy 348.885322 -226.172014) (xy 348.834319 -226.163651) (xy 348.785339 -226.14715) (xy 348.739673 -226.122946)
			(xy 348.698521 -226.091676) (xy 348.662967 -226.054163) (xy 348.64802 -226.033076) (xy 348.644464 -226.02825)
			(xy 348.640654 -226.024694) (xy 348.630494 -226.017328) (xy 348.610936 -226.006406) (xy 348.605368 -226.003601)
			(xy 348.593291 -226.000521) (xy 348.58706 -226.00031) (xy 348.469966 -226.00031) (xy 348.460125 -225.999781)
			(xy 348.441954 -225.992204) (xy 348.43466 -225.985578) (xy 348.417134 -225.968052) (xy 348.40917 -225.96082)
			(xy 348.389028 -225.953326) (xy 348.378272 -225.953574) (xy 348.290134 -225.968052) (xy 348.284996 -225.969363)
			(xy 348.275386 -225.973841) (xy 348.271084 -225.976942) (xy 348.266766 -225.97999) (xy 348.259654 -225.988626)
			(xy 348.256606 -225.994468) (xy 348.245002 -226.016987) (xy 348.215748 -226.058342) (xy 348.180305 -226.094534)
			(xy 348.13957 -226.124645) (xy 348.094575 -226.147915) (xy 348.046458 -226.163752) (xy 347.996438 -226.171757)
			(xy 347.97111 -226.172268) (xy 347.946119 -226.171804) (xy 347.896754 -226.163986) (xy 347.849219 -226.148541)
			(xy 347.804686 -226.125849) (xy 347.764251 -226.09647) (xy 347.728911 -226.061126) (xy 347.699535 -226.020689)
			(xy 347.676848 -225.976153) (xy 347.661407 -225.928617) (xy 347.653594 -225.879251) (xy 347.653102 -225.85426)
			(xy 347.653587 -225.82896) (xy 347.661596 -225.778997) (xy 347.677421 -225.730935) (xy 347.700661 -225.685987)
			(xy 347.730731 -225.64529) (xy 347.766869 -225.609872) (xy 347.808164 -225.580629) (xy 347.830648 -225.569018)
			(xy 347.831156 -225.56851) (xy 347.836307 -225.565771) (xy 347.845292 -225.558334) (xy 347.848936 -225.553778)
			(xy 347.852238 -225.549206) (xy 347.856556 -225.538538) (xy 347.871796 -225.447098) (xy 347.87204 -225.436347)
			(xy 347.864525 -225.41622) (xy 347.857318 -225.408236) (xy 347.690186 -225.241104) (xy 347.683471 -225.233867)
			(xy 347.675871 -225.215662) (xy 347.675454 -225.205798) (xy 347.675454 -224.365058) (xy 347.674946 -224.357438)
			(xy 347.673168 -224.347786) (xy 347.671136 -224.340166) (xy 347.667834 -224.33026) (xy 347.667834 -224.330006)
			(xy 347.665802 -224.323656) (xy 347.665294 -224.321624) (xy 347.66504 -224.320862) (xy 347.664786 -224.320354)
			(xy 347.664786 -224.319846) (xy 347.65742 -224.287588) (xy 347.656404 -224.280984) (xy 347.655896 -224.279968)
			(xy 347.641672 -224.250758) (xy 347.63583 -224.244916) (xy 347.624146 -224.233232) (xy 347.604888 -224.213626)
			(xy 347.568044 -224.17284) (xy 347.550486 -224.151698) (xy 347.549978 -224.150936) (xy 347.52407 -224.119186)
			(xy 347.517974 -224.111312) (xy 347.501882 -224.090008) (xy 347.471767 -224.045913) (xy 347.457776 -224.023174)
			(xy 347.454982 -224.018602) (xy 347.441266 -224.00387) (xy 347.43644 -224.000314) (xy 347.425518 -223.997774)
			(xy 347.422724 -223.997266) (xy 347.420184 -223.996758) (xy 347.40746 -223.994904) (xy 347.382177 -223.990205)
			(xy 347.369638 -223.98736) (xy 347.353382 -223.983296) (xy 347.349572 -223.98228) (xy 347.347794 -223.982026)
			(xy 347.334586 -223.981772) (xy 347.31706 -223.987106) (xy 347.312903 -223.989375) (xy 347.305478 -223.995253)
			(xy 347.302328 -223.99879) (xy 347.298264 -224.003362) (xy 347.292676 -224.014792) (xy 347.291406 -224.020888)
			(xy 347.290241 -224.027153) (xy 347.290756 -224.039883) (xy 347.292422 -224.046034) (xy 347.293184 -224.048574)
			(xy 347.295724 -224.055178) (xy 347.299534 -224.062798) (xy 347.300804 -224.065084) (xy 347.301312 -224.065846)
			(xy 347.312637 -224.084841) (xy 347.330506 -224.125293) (xy 347.342607 -224.167828) (xy 347.348706 -224.211628)
			(xy 347.349064 -224.23374) (xy 347.349064 -224.240852) (xy 347.348091 -224.2655) (xy 347.33947 -224.314068)
			(xy 347.323452 -224.360721) (xy 347.30042 -224.40434) (xy 347.270928 -224.443879) (xy 347.235684 -224.478389)
			(xy 347.195533 -224.507042) (xy 347.151438 -224.529149) (xy 347.104458 -224.544182) (xy 347.055719 -224.551778)
			(xy 347.031056 -224.552256) (xy 347.006068 -224.551762) (xy 346.956707 -224.543939) (xy 346.909178 -224.528491)
			(xy 346.864649 -224.5058) (xy 346.824218 -224.476424) (xy 346.788879 -224.441085) (xy 346.759502 -224.400654)
			(xy 346.73681 -224.356126) (xy 346.721362 -224.308597) (xy 346.713538 -224.259236) (xy 346.713048 -224.234248)
			(xy 346.713488 -224.20984) (xy 346.720938 -224.161597) (xy 346.735668 -224.115057) (xy 346.757335 -224.071314)
			(xy 346.785429 -224.031393) (xy 346.819291 -223.996232) (xy 346.858127 -223.966656) (xy 346.901024 -223.943359)
			(xy 346.946977 -223.926888) (xy 346.970858 -223.921828) (xy 346.97162 -223.921828) (xy 346.972128 -223.921574)
			(xy 346.978312 -223.920115) (xy 346.989751 -223.914594) (xy 346.994734 -223.910652) (xy 346.998798 -223.90735)
			(xy 347.002354 -223.902524) (xy 347.008196 -223.891856) (xy 347.024198 -223.851978) (xy 347.039692 -223.813116)
			(xy 347.04195 -223.807034) (xy 347.043626 -223.794173) (xy 347.042994 -223.787716) (xy 347.04147 -223.775524)
			(xy 347.033342 -223.764348) (xy 347.021404 -223.74733) (xy 347.015562 -223.737932) (xy 347.015054 -223.737424)
			(xy 346.999052 -223.711262) (xy 346.990416 -223.695768) (xy 346.990416 -223.695514) (xy 346.985082 -223.6851)
			(xy 346.985082 -223.684846) (xy 346.980002 -223.674686) (xy 346.979494 -223.673924) (xy 346.979494 -223.67367)
			(xy 346.974668 -223.66351) (xy 346.970858 -223.655128) (xy 346.969334 -223.651826) (xy 346.966737 -223.647181)
			(xy 346.959955 -223.638983) (xy 346.955872 -223.63557) (xy 346.951046 -223.632014) (xy 346.945458 -223.629474)
			(xy 346.932758 -223.625918) (xy 346.890848 -223.619568) (xy 346.89034 -223.619568) (xy 346.84843 -223.613472)
			(xy 346.841064 -223.612964) (xy 346.803472 -223.630236) (xy 346.796868 -223.637856) (xy 346.778629 -223.657171)
			(xy 346.736901 -223.690044) (xy 346.690294 -223.715531) (xy 346.640101 -223.732923) (xy 346.587717 -223.741738)
			(xy 346.561156 -223.74225) (xy 346.536166 -223.741756) (xy 346.486802 -223.733931) (xy 346.439269 -223.718481)
			(xy 346.394738 -223.695786) (xy 346.354305 -223.666405) (xy 346.318966 -223.631061) (xy 346.289591 -223.590624)
			(xy 346.266902 -223.54609) (xy 346.251458 -223.498556) (xy 346.24364 -223.44919) (xy 346.24364 -223.39921)
			(xy 346.251458 -223.349844) (xy 346.266902 -223.30231) (xy 346.289591 -223.257776) (xy 346.318966 -223.217339)
			(xy 346.354305 -223.181995) (xy 346.394738 -223.152614) (xy 346.439269 -223.129919) (xy 346.486802 -223.114469)
			(xy 346.536166 -223.106644) (xy 346.561156 -223.106234) (xy 346.588487 -223.106805) (xy 346.642344 -223.116153)
			(xy 346.693813 -223.134566) (xy 346.741378 -223.1615) (xy 346.783643 -223.196165) (xy 346.801948 -223.21647)
			(xy 346.803218 -223.217994) (xy 346.803726 -223.218502) (xy 346.807282 -223.22282) (xy 346.817696 -223.230186)
			(xy 346.823284 -223.232472) (xy 346.829159 -223.234483) (xy 346.841491 -223.235899) (xy 346.847668 -223.235266)
			(xy 346.890594 -223.228916) (xy 346.932504 -223.222566) (xy 346.941394 -223.220534) (xy 346.944904 -223.219254)
			(xy 346.951532 -223.215806) (xy 346.954602 -223.213676) (xy 346.955872 -223.21266) (xy 346.965778 -223.20504)
			(xy 346.968826 -223.19869) (xy 346.97035 -223.195388) (xy 346.971112 -223.193102) (xy 346.984964 -223.162551)
			(xy 347.018714 -223.104579) (xy 347.058943 -223.050899) (xy 347.105111 -223.002232) (xy 347.156597 -222.959231)
			(xy 347.212711 -222.922473) (xy 347.2727 -222.892453) (xy 347.335759 -222.869572) (xy 347.401041 -222.854137)
			(xy 347.467669 -222.846357) (xy 347.50121 -222.845884) (xy 347.804486 -222.845884) (xy 347.832743 -222.846259)
			(xy 347.888979 -222.851853) (xy 347.916754 -222.85706) (xy 347.9546 -222.86595) (xy 347.957902 -222.866712)
			(xy 347.964506 -222.867474) (xy 347.977714 -222.867474) (xy 347.984318 -222.866712) (xy 347.986096 -222.866204)
			(xy 347.988382 -222.865696) (xy 347.989144 -222.865442) (xy 348.00286 -222.861886) (xy 348.009464 -222.860362)
			(xy 348.01048 -222.860108) (xy 348.018354 -222.85833) (xy 348.023688 -222.855536) (xy 348.034102 -222.847662)
			(xy 348.168722 -222.713042) (xy 348.171618 -222.709979) (xy 348.17647 -222.703087) (xy 348.178374 -222.699326)
			(xy 348.179136 -222.697294) (xy 348.181145 -222.692455) (xy 348.183333 -222.682211) (xy 348.183454 -222.676974)
			(xy 348.183454 -221.601538) (xy 348.182946 -221.595696) (xy 348.180914 -221.582488) (xy 348.179644 -221.578678)
			(xy 348.167706 -221.535498) (xy 348.159913 -221.501098) (xy 348.151514 -221.431065) (xy 348.150942 -221.395798)
			(xy 348.150942 -221.289372) (xy 348.15018 -221.280736) (xy 348.147132 -221.270068) (xy 348.143322 -221.261178)
			(xy 348.070932 -221.188788) (xy 348.063686 -221.182229) (xy 348.045642 -221.174771) (xy 348.03588 -221.17431)
			(xy 338.44357 -221.17431) (xy 338.433707 -221.174729) (xy 338.415486 -221.182291) (xy 338.401547 -221.196251)
			(xy 338.394014 -221.214484) (xy 338.393532 -221.224348) (xy 338.393532 -221.66453) (xy 338.39404 -221.67215)
			(xy 338.396326 -221.683326) (xy 338.398358 -221.690438) (xy 338.39912 -221.69247) (xy 338.408191 -221.718416)
			(xy 338.418283 -221.772441) (xy 338.419186 -221.799912) (xy 338.419186 -221.803468) (xy 338.418646 -221.829219)
			(xy 345.303584 -221.829219) (xy 345.303584 -221.779241) (xy 345.311403 -221.729878) (xy 345.326847 -221.682346)
			(xy 345.349537 -221.637814) (xy 345.378913 -221.597381) (xy 345.414253 -221.562041) (xy 345.454686 -221.532665)
			(xy 345.499218 -221.509975) (xy 345.54675 -221.494531) (xy 345.596113 -221.486712) (xy 345.646091 -221.486712)
			(xy 345.695454 -221.494531) (xy 345.742986 -221.509975) (xy 345.787518 -221.532665) (xy 345.827951 -221.562041)
			(xy 345.863291 -221.597381) (xy 345.892667 -221.637814) (xy 345.915357 -221.682346) (xy 345.930801 -221.729878)
			(xy 345.93862 -221.779241) (xy 345.93911 -221.80423) (xy 345.93862 -221.829219) (xy 345.930801 -221.878582)
			(xy 345.915357 -221.926114) (xy 345.892667 -221.970646) (xy 345.863291 -222.011079) (xy 345.827951 -222.046419)
			(xy 345.787518 -222.075795) (xy 345.742986 -222.098485) (xy 345.695454 -222.113929) (xy 345.646091 -222.121748)
			(xy 345.596113 -222.121748) (xy 345.54675 -222.113929) (xy 345.499218 -222.098485) (xy 345.454686 -222.075795)
			(xy 345.414253 -222.046419) (xy 345.378913 -222.011079) (xy 345.349537 -221.970646) (xy 345.326847 -221.926114)
			(xy 345.311403 -221.878582) (xy 345.303584 -221.829219) (xy 338.418646 -221.829219) (xy 338.418556 -221.833522)
			(xy 338.407426 -221.892589) (xy 338.397088 -221.920816) (xy 338.393532 -221.92996) (xy 338.393532 -222.203518)
			(xy 338.394097 -222.214228) (xy 338.403053 -222.233695) (xy 338.410804 -222.24111) (xy 338.426552 -222.254064)
			(xy 338.427314 -222.254826) (xy 338.472018 -222.29191) (xy 338.476213 -222.294999) (xy 338.485556 -222.299603)
			(xy 338.49056 -222.301054) (xy 338.500466 -222.303594) (xy 338.51215 -222.301562) (xy 338.52675 -222.299034)
			(xy 338.556262 -222.296366) (xy 338.571078 -222.296228) (xy 338.596067 -222.296691) (xy 338.645432 -222.304507)
			(xy 338.692965 -222.319948) (xy 338.737498 -222.342636) (xy 338.777933 -222.372011) (xy 338.813274 -222.40735)
			(xy 338.842652 -222.447783) (xy 338.865343 -222.492314) (xy 338.880788 -222.539847) (xy 338.888607 -222.589211)
			(xy 338.888607 -222.639189) (xy 338.888601 -222.639225) (xy 339.193614 -222.639225) (xy 339.193614 -222.589247)
			(xy 339.201433 -222.539884) (xy 339.216877 -222.492352) (xy 339.239567 -222.44782) (xy 339.268943 -222.407387)
			(xy 339.304283 -222.372047) (xy 339.344716 -222.342671) (xy 339.389248 -222.319981) (xy 339.43678 -222.304537)
			(xy 339.486143 -222.296718) (xy 339.536121 -222.296718) (xy 339.585484 -222.304537) (xy 339.633016 -222.319981)
			(xy 339.677548 -222.342671) (xy 339.717981 -222.372047) (xy 339.753321 -222.407387) (xy 339.782697 -222.44782)
			(xy 339.805387 -222.492352) (xy 339.820831 -222.539884) (xy 339.82865 -222.589247) (xy 339.82914 -222.614236)
			(xy 339.82865 -222.639225) (xy 340.133668 -222.639225) (xy 340.133668 -222.589247) (xy 340.141487 -222.539884)
			(xy 340.156931 -222.492352) (xy 340.179621 -222.44782) (xy 340.208997 -222.407387) (xy 340.244337 -222.372047)
			(xy 340.28477 -222.342671) (xy 340.329302 -222.319981) (xy 340.376834 -222.304537) (xy 340.426197 -222.296718)
			(xy 340.476175 -222.296718) (xy 340.525538 -222.304537) (xy 340.57307 -222.319981) (xy 340.617602 -222.342671)
			(xy 340.658035 -222.372047) (xy 340.693375 -222.407387) (xy 340.722751 -222.44782) (xy 340.745441 -222.492352)
			(xy 340.760885 -222.539884) (xy 340.768704 -222.589247) (xy 340.769194 -222.614236) (xy 340.768704 -222.639225)
			(xy 342.953576 -222.639225) (xy 342.953576 -222.589247) (xy 342.961395 -222.539884) (xy 342.976839 -222.492352)
			(xy 342.999529 -222.44782) (xy 343.028905 -222.407387) (xy 343.064245 -222.372047) (xy 343.104678 -222.342671)
			(xy 343.14921 -222.319981) (xy 343.196742 -222.304537) (xy 343.246105 -222.296718) (xy 343.296083 -222.296718)
			(xy 343.345446 -222.304537) (xy 343.392978 -222.319981) (xy 343.43751 -222.342671) (xy 343.477943 -222.372047)
			(xy 343.513283 -222.407387) (xy 343.542659 -222.44782) (xy 343.565349 -222.492352) (xy 343.580793 -222.539884)
			(xy 343.588612 -222.589247) (xy 343.589102 -222.614236) (xy 343.588612 -222.639225) (xy 345.773484 -222.639225)
			(xy 345.773484 -222.589247) (xy 345.781303 -222.539884) (xy 345.796747 -222.492352) (xy 345.819437 -222.44782)
			(xy 345.848813 -222.407387) (xy 345.884153 -222.372047) (xy 345.924586 -222.342671) (xy 345.969118 -222.319981)
			(xy 346.01665 -222.304537) (xy 346.066013 -222.296718) (xy 346.115991 -222.296718) (xy 346.165354 -222.304537)
			(xy 346.212886 -222.319981) (xy 346.257418 -222.342671) (xy 346.297851 -222.372047) (xy 346.333191 -222.407387)
			(xy 346.362567 -222.44782) (xy 346.385257 -222.492352) (xy 346.400701 -222.539884) (xy 346.40852 -222.589247)
			(xy 346.40901 -222.614236) (xy 346.40852 -222.639225) (xy 346.400701 -222.688588) (xy 346.385257 -222.73612)
			(xy 346.362567 -222.780652) (xy 346.333191 -222.821085) (xy 346.297851 -222.856425) (xy 346.257418 -222.885801)
			(xy 346.212886 -222.908491) (xy 346.165354 -222.923935) (xy 346.115991 -222.931754) (xy 346.066013 -222.931754)
			(xy 346.01665 -222.923935) (xy 345.969118 -222.908491) (xy 345.924586 -222.885801) (xy 345.884153 -222.856425)
			(xy 345.848813 -222.821085) (xy 345.819437 -222.780652) (xy 345.796747 -222.73612) (xy 345.781303 -222.688588)
			(xy 345.773484 -222.639225) (xy 343.588612 -222.639225) (xy 343.580793 -222.688588) (xy 343.565349 -222.73612)
			(xy 343.542659 -222.780652) (xy 343.513283 -222.821085) (xy 343.477943 -222.856425) (xy 343.43751 -222.885801)
			(xy 343.392978 -222.908491) (xy 343.345446 -222.923935) (xy 343.296083 -222.931754) (xy 343.246105 -222.931754)
			(xy 343.196742 -222.923935) (xy 343.14921 -222.908491) (xy 343.104678 -222.885801) (xy 343.064245 -222.856425)
			(xy 343.028905 -222.821085) (xy 342.999529 -222.780652) (xy 342.976839 -222.73612) (xy 342.961395 -222.688588)
			(xy 342.953576 -222.639225) (xy 340.768704 -222.639225) (xy 340.760885 -222.688588) (xy 340.745441 -222.73612)
			(xy 340.722751 -222.780652) (xy 340.693375 -222.821085) (xy 340.658035 -222.856425) (xy 340.617602 -222.885801)
			(xy 340.57307 -222.908491) (xy 340.525538 -222.923935) (xy 340.476175 -222.931754) (xy 340.426197 -222.931754)
			(xy 340.376834 -222.923935) (xy 340.329302 -222.908491) (xy 340.28477 -222.885801) (xy 340.244337 -222.856425)
			(xy 340.208997 -222.821085) (xy 340.179621 -222.780652) (xy 340.156931 -222.73612) (xy 340.141487 -222.688588)
			(xy 340.133668 -222.639225) (xy 339.82865 -222.639225) (xy 339.820831 -222.688588) (xy 339.805387 -222.73612)
			(xy 339.782697 -222.780652) (xy 339.753321 -222.821085) (xy 339.717981 -222.856425) (xy 339.677548 -222.885801)
			(xy 339.633016 -222.908491) (xy 339.585484 -222.923935) (xy 339.536121 -222.931754) (xy 339.486143 -222.931754)
			(xy 339.43678 -222.923935) (xy 339.389248 -222.908491) (xy 339.344716 -222.885801) (xy 339.304283 -222.856425)
			(xy 339.268943 -222.821085) (xy 339.239567 -222.780652) (xy 339.216877 -222.73612) (xy 339.201433 -222.688588)
			(xy 339.193614 -222.639225) (xy 338.888601 -222.639225) (xy 338.880788 -222.688553) (xy 338.865343 -222.736086)
			(xy 338.842652 -222.780617) (xy 338.813274 -222.82105) (xy 338.777933 -222.856389) (xy 338.737498 -222.885764)
			(xy 338.692965 -222.908452) (xy 338.645432 -222.923893) (xy 338.596067 -222.931709) (xy 338.571078 -222.932244)
			(xy 338.556261 -222.932121) (xy 338.526749 -222.929448) (xy 338.51215 -222.92691) (xy 338.500466 -222.924878)
			(xy 338.49056 -222.927418) (xy 338.485543 -222.928836) (xy 338.476192 -222.933439) (xy 338.472018 -222.936562)
			(xy 338.427314 -222.973646) (xy 338.426552 -222.974408) (xy 338.410804 -222.987362) (xy 338.403037 -222.994761)
			(xy 338.394106 -223.014241) (xy 338.393532 -223.024954) (xy 338.393532 -223.284542) (xy 338.39404 -223.292162)
			(xy 338.396326 -223.303338) (xy 338.398358 -223.31045) (xy 338.39912 -223.312482) (xy 338.40819 -223.338428)
			(xy 338.41828 -223.392453) (xy 338.419186 -223.419924) (xy 338.419186 -223.42348) (xy 338.418645 -223.449231)
			(xy 338.72346 -223.449231) (xy 338.72346 -223.399253) (xy 338.731279 -223.34989) (xy 338.746723 -223.302358)
			(xy 338.769413 -223.257826) (xy 338.798789 -223.217393) (xy 338.834129 -223.182053) (xy 338.874562 -223.152677)
			(xy 338.919094 -223.129987) (xy 338.966626 -223.114543) (xy 339.015989 -223.106724) (xy 339.065967 -223.106724)
			(xy 339.11533 -223.114543) (xy 339.162862 -223.129987) (xy 339.207394 -223.152677) (xy 339.247827 -223.182053)
			(xy 339.283167 -223.217393) (xy 339.312543 -223.257826) (xy 339.335233 -223.302358) (xy 339.350677 -223.34989)
			(xy 339.358496 -223.399253) (xy 339.358986 -223.424242) (xy 339.358496 -223.449231) (xy 341.543622 -223.449231)
			(xy 341.543622 -223.399253) (xy 341.551441 -223.34989) (xy 341.566885 -223.302358) (xy 341.589575 -223.257826)
			(xy 341.618951 -223.217393) (xy 341.654291 -223.182053) (xy 341.694724 -223.152677) (xy 341.739256 -223.129987)
			(xy 341.786788 -223.114543) (xy 341.836151 -223.106724) (xy 341.886129 -223.106724) (xy 341.935492 -223.114543)
			(xy 341.983024 -223.129987) (xy 342.027556 -223.152677) (xy 342.067989 -223.182053) (xy 342.103329 -223.217393)
			(xy 342.132705 -223.257826) (xy 342.155395 -223.302358) (xy 342.170839 -223.34989) (xy 342.178658 -223.399253)
			(xy 342.179148 -223.424242) (xy 342.178658 -223.449231) (xy 342.483676 -223.449231) (xy 342.483676 -223.399253)
			(xy 342.491495 -223.34989) (xy 342.506939 -223.302358) (xy 342.529629 -223.257826) (xy 342.559005 -223.217393)
			(xy 342.594345 -223.182053) (xy 342.634778 -223.152677) (xy 342.67931 -223.129987) (xy 342.726842 -223.114543)
			(xy 342.776205 -223.106724) (xy 342.826183 -223.106724) (xy 342.875546 -223.114543) (xy 342.923078 -223.129987)
			(xy 342.96761 -223.152677) (xy 343.008043 -223.182053) (xy 343.043383 -223.217393) (xy 343.072759 -223.257826)
			(xy 343.095449 -223.302358) (xy 343.110893 -223.34989) (xy 343.118712 -223.399253) (xy 343.119202 -223.424242)
			(xy 343.118712 -223.449231) (xy 343.423476 -223.449231) (xy 343.423476 -223.399253) (xy 343.431295 -223.34989)
			(xy 343.446739 -223.302358) (xy 343.469429 -223.257826) (xy 343.498805 -223.217393) (xy 343.534145 -223.182053)
			(xy 343.574578 -223.152677) (xy 343.61911 -223.129987) (xy 343.666642 -223.114543) (xy 343.716005 -223.106724)
			(xy 343.765983 -223.106724) (xy 343.815346 -223.114543) (xy 343.862878 -223.129987) (xy 343.90741 -223.152677)
			(xy 343.947843 -223.182053) (xy 343.983183 -223.217393) (xy 344.012559 -223.257826) (xy 344.035249 -223.302358)
			(xy 344.050693 -223.34989) (xy 344.058512 -223.399253) (xy 344.059002 -223.424242) (xy 344.058512 -223.449231)
			(xy 344.050693 -223.498594) (xy 344.035249 -223.546126) (xy 344.012559 -223.590658) (xy 343.983183 -223.631091)
			(xy 343.947843 -223.666431) (xy 343.90741 -223.695807) (xy 343.862878 -223.718497) (xy 343.815346 -223.733941)
			(xy 343.765983 -223.74176) (xy 343.716005 -223.74176) (xy 343.666642 -223.733941) (xy 343.61911 -223.718497)
			(xy 343.574578 -223.695807) (xy 343.534145 -223.666431) (xy 343.498805 -223.631091) (xy 343.469429 -223.590658)
			(xy 343.446739 -223.546126) (xy 343.431295 -223.498594) (xy 343.423476 -223.449231) (xy 343.118712 -223.449231)
			(xy 343.110893 -223.498594) (xy 343.095449 -223.546126) (xy 343.072759 -223.590658) (xy 343.043383 -223.631091)
			(xy 343.008043 -223.666431) (xy 342.96761 -223.695807) (xy 342.923078 -223.718497) (xy 342.875546 -223.733941)
			(xy 342.826183 -223.74176) (xy 342.776205 -223.74176) (xy 342.726842 -223.733941) (xy 342.67931 -223.718497)
			(xy 342.634778 -223.695807) (xy 342.594345 -223.666431) (xy 342.559005 -223.631091) (xy 342.529629 -223.590658)
			(xy 342.506939 -223.546126) (xy 342.491495 -223.498594) (xy 342.483676 -223.449231) (xy 342.178658 -223.449231)
			(xy 342.170839 -223.498594) (xy 342.155395 -223.546126) (xy 342.132705 -223.590658) (xy 342.103329 -223.631091)
			(xy 342.067989 -223.666431) (xy 342.027556 -223.695807) (xy 341.983024 -223.718497) (xy 341.935492 -223.733941)
			(xy 341.886129 -223.74176) (xy 341.836151 -223.74176) (xy 341.786788 -223.733941) (xy 341.739256 -223.718497)
			(xy 341.694724 -223.695807) (xy 341.654291 -223.666431) (xy 341.618951 -223.631091) (xy 341.589575 -223.590658)
			(xy 341.566885 -223.546126) (xy 341.551441 -223.498594) (xy 341.543622 -223.449231) (xy 339.358496 -223.449231)
			(xy 339.350677 -223.498594) (xy 339.335233 -223.546126) (xy 339.312543 -223.590658) (xy 339.283167 -223.631091)
			(xy 339.247827 -223.666431) (xy 339.207394 -223.695807) (xy 339.162862 -223.718497) (xy 339.11533 -223.733941)
			(xy 339.065967 -223.74176) (xy 339.015989 -223.74176) (xy 338.966626 -223.733941) (xy 338.919094 -223.718497)
			(xy 338.874562 -223.695807) (xy 338.834129 -223.666431) (xy 338.798789 -223.631091) (xy 338.769413 -223.590658)
			(xy 338.746723 -223.546126) (xy 338.731279 -223.498594) (xy 338.72346 -223.449231) (xy 338.418645 -223.449231)
			(xy 338.418555 -223.453534) (xy 338.407423 -223.5126) (xy 338.397088 -223.540828) (xy 338.393532 -223.549972)
			(xy 338.393532 -223.82353) (xy 338.3941 -223.834239) (xy 338.403059 -223.853702) (xy 338.410804 -223.861122)
			(xy 338.426552 -223.874076) (xy 338.427314 -223.874838) (xy 338.472018 -223.911922) (xy 338.476213 -223.915011)
			(xy 338.485557 -223.919614) (xy 338.49056 -223.921066) (xy 338.500466 -223.923606) (xy 338.51215 -223.921574)
			(xy 338.52675 -223.919046) (xy 338.556262 -223.916377) (xy 338.571078 -223.91624) (xy 338.596067 -223.916703)
			(xy 338.645429 -223.924518) (xy 338.692961 -223.939959) (xy 338.737492 -223.962646) (xy 338.777925 -223.99202)
			(xy 338.813265 -224.027358) (xy 338.842642 -224.06779) (xy 338.865332 -224.112319) (xy 338.880777 -224.15985)
			(xy 338.888595 -224.209211) (xy 338.888595 -224.259189) (xy 338.888587 -224.259237) (xy 339.193614 -224.259237)
			(xy 339.193614 -224.209259) (xy 339.201433 -224.159896) (xy 339.216877 -224.112364) (xy 339.239567 -224.067832)
			(xy 339.268943 -224.027399) (xy 339.304283 -223.992059) (xy 339.344716 -223.962683) (xy 339.389248 -223.939993)
			(xy 339.43678 -223.924549) (xy 339.486143 -223.91673) (xy 339.536121 -223.91673) (xy 339.585484 -223.924549)
			(xy 339.633016 -223.939993) (xy 339.677548 -223.962683) (xy 339.717981 -223.992059) (xy 339.753321 -224.027399)
			(xy 339.782697 -224.067832) (xy 339.805387 -224.112364) (xy 339.820831 -224.159896) (xy 339.82865 -224.209259)
			(xy 339.82914 -224.234248) (xy 339.82865 -224.259237) (xy 341.073468 -224.259237) (xy 341.073468 -224.209259)
			(xy 341.081287 -224.159896) (xy 341.096731 -224.112364) (xy 341.119421 -224.067832) (xy 341.148797 -224.027399)
			(xy 341.184137 -223.992059) (xy 341.22457 -223.962683) (xy 341.269102 -223.939993) (xy 341.316634 -223.924549)
			(xy 341.365997 -223.91673) (xy 341.415975 -223.91673) (xy 341.465338 -223.924549) (xy 341.51287 -223.939993)
			(xy 341.557402 -223.962683) (xy 341.597835 -223.992059) (xy 341.633175 -224.027399) (xy 341.662551 -224.067832)
			(xy 341.685241 -224.112364) (xy 341.700685 -224.159896) (xy 341.708504 -224.209259) (xy 341.708994 -224.234248)
			(xy 341.708504 -224.259237) (xy 343.89363 -224.259237) (xy 343.89363 -224.209259) (xy 343.901449 -224.159896)
			(xy 343.916893 -224.112364) (xy 343.939583 -224.067832) (xy 343.968959 -224.027399) (xy 344.004299 -223.992059)
			(xy 344.044732 -223.962683) (xy 344.089264 -223.939993) (xy 344.136796 -223.924549) (xy 344.186159 -223.91673)
			(xy 344.236137 -223.91673) (xy 344.2855 -223.924549) (xy 344.333032 -223.939993) (xy 344.377564 -223.962683)
			(xy 344.417997 -223.992059) (xy 344.453337 -224.027399) (xy 344.482713 -224.067832) (xy 344.505403 -224.112364)
			(xy 344.520847 -224.159896) (xy 344.528666 -224.209259) (xy 344.529156 -224.234248) (xy 344.528666 -224.259237)
			(xy 344.833684 -224.259237) (xy 344.833684 -224.209259) (xy 344.841503 -224.159896) (xy 344.856947 -224.112364)
			(xy 344.879637 -224.067832) (xy 344.909013 -224.027399) (xy 344.944353 -223.992059) (xy 344.984786 -223.962683)
			(xy 345.029318 -223.939993) (xy 345.07685 -223.924549) (xy 345.126213 -223.91673) (xy 345.176191 -223.91673)
			(xy 345.225554 -223.924549) (xy 345.273086 -223.939993) (xy 345.317618 -223.962683) (xy 345.358051 -223.992059)
			(xy 345.393391 -224.027399) (xy 345.422767 -224.067832) (xy 345.445457 -224.112364) (xy 345.460901 -224.159896)
			(xy 345.46872 -224.209259) (xy 345.46921 -224.234248) (xy 345.46872 -224.259237) (xy 345.773484 -224.259237)
			(xy 345.773484 -224.209259) (xy 345.781303 -224.159896) (xy 345.796747 -224.112364) (xy 345.819437 -224.067832)
			(xy 345.848813 -224.027399) (xy 345.884153 -223.992059) (xy 345.924586 -223.962683) (xy 345.969118 -223.939993)
			(xy 346.01665 -223.924549) (xy 346.066013 -223.91673) (xy 346.115991 -223.91673) (xy 346.165354 -223.924549)
			(xy 346.212886 -223.939993) (xy 346.257418 -223.962683) (xy 346.297851 -223.992059) (xy 346.333191 -224.027399)
			(xy 346.362567 -224.067832) (xy 346.385257 -224.112364) (xy 346.400701 -224.159896) (xy 346.40852 -224.209259)
			(xy 346.40901 -224.234248) (xy 346.40852 -224.259237) (xy 346.400701 -224.3086) (xy 346.385257 -224.356132)
			(xy 346.362567 -224.400664) (xy 346.333191 -224.441097) (xy 346.297851 -224.476437) (xy 346.257418 -224.505813)
			(xy 346.212886 -224.528503) (xy 346.165354 -224.543947) (xy 346.115991 -224.551766) (xy 346.066013 -224.551766)
			(xy 346.01665 -224.543947) (xy 345.969118 -224.528503) (xy 345.924586 -224.505813) (xy 345.884153 -224.476437)
			(xy 345.848813 -224.441097) (xy 345.819437 -224.400664) (xy 345.796747 -224.356132) (xy 345.781303 -224.3086)
			(xy 345.773484 -224.259237) (xy 345.46872 -224.259237) (xy 345.460901 -224.3086) (xy 345.445457 -224.356132)
			(xy 345.422767 -224.400664) (xy 345.393391 -224.441097) (xy 345.358051 -224.476437) (xy 345.317618 -224.505813)
			(xy 345.273086 -224.528503) (xy 345.225554 -224.543947) (xy 345.176191 -224.551766) (xy 345.126213 -224.551766)
			(xy 345.07685 -224.543947) (xy 345.029318 -224.528503) (xy 344.984786 -224.505813) (xy 344.944353 -224.476437)
			(xy 344.909013 -224.441097) (xy 344.879637 -224.400664) (xy 344.856947 -224.356132) (xy 344.841503 -224.3086)
			(xy 344.833684 -224.259237) (xy 344.528666 -224.259237) (xy 344.520847 -224.3086) (xy 344.505403 -224.356132)
			(xy 344.482713 -224.400664) (xy 344.453337 -224.441097) (xy 344.417997 -224.476437) (xy 344.377564 -224.505813)
			(xy 344.333032 -224.528503) (xy 344.2855 -224.543947) (xy 344.236137 -224.551766) (xy 344.186159 -224.551766)
			(xy 344.136796 -224.543947) (xy 344.089264 -224.528503) (xy 344.044732 -224.505813) (xy 344.004299 -224.476437)
			(xy 343.968959 -224.441097) (xy 343.939583 -224.400664) (xy 343.916893 -224.356132) (xy 343.901449 -224.3086)
			(xy 343.89363 -224.259237) (xy 341.708504 -224.259237) (xy 341.700685 -224.3086) (xy 341.685241 -224.356132)
			(xy 341.662551 -224.400664) (xy 341.633175 -224.441097) (xy 341.597835 -224.476437) (xy 341.557402 -224.505813)
			(xy 341.51287 -224.528503) (xy 341.465338 -224.543947) (xy 341.415975 -224.551766) (xy 341.365997 -224.551766)
			(xy 341.316634 -224.543947) (xy 341.269102 -224.528503) (xy 341.22457 -224.505813) (xy 341.184137 -224.476437)
			(xy 341.148797 -224.441097) (xy 341.119421 -224.400664) (xy 341.096731 -224.356132) (xy 341.081287 -224.3086)
			(xy 341.073468 -224.259237) (xy 339.82865 -224.259237) (xy 339.820831 -224.3086) (xy 339.805387 -224.356132)
			(xy 339.782697 -224.400664) (xy 339.753321 -224.441097) (xy 339.717981 -224.476437) (xy 339.677548 -224.505813)
			(xy 339.633016 -224.528503) (xy 339.585484 -224.543947) (xy 339.536121 -224.551766) (xy 339.486143 -224.551766)
			(xy 339.43678 -224.543947) (xy 339.389248 -224.528503) (xy 339.344716 -224.505813) (xy 339.304283 -224.476437)
			(xy 339.268943 -224.441097) (xy 339.239567 -224.400664) (xy 339.216877 -224.356132) (xy 339.201433 -224.3086)
			(xy 339.193614 -224.259237) (xy 338.888587 -224.259237) (xy 338.880777 -224.30855) (xy 338.865332 -224.356081)
			(xy 338.842642 -224.40061) (xy 338.813265 -224.441042) (xy 338.777925 -224.47638) (xy 338.737492 -224.505754)
			(xy 338.692961 -224.528441) (xy 338.645429 -224.543882) (xy 338.596067 -224.551697) (xy 338.571078 -224.552256)
			(xy 338.556261 -224.552133) (xy 338.526749 -224.54946) (xy 338.51215 -224.546922) (xy 338.500466 -224.54489)
			(xy 338.49056 -224.54743) (xy 338.485544 -224.548848) (xy 338.476193 -224.553452) (xy 338.472018 -224.556574)
			(xy 338.427314 -224.593658) (xy 338.426552 -224.59442) (xy 338.410804 -224.607374) (xy 338.403023 -224.614767)
			(xy 338.394057 -224.634247) (xy 338.393532 -224.644966) (xy 338.393532 -224.904554) (xy 338.39404 -224.912174)
			(xy 338.396326 -224.92335) (xy 338.398358 -224.930462) (xy 338.39912 -224.932494) (xy 338.408189 -224.95844)
			(xy 338.418277 -225.012465) (xy 338.419186 -225.039936) (xy 338.419186 -225.043492) (xy 338.41917 -225.044254)
			(xy 338.724743 -225.044254) (xy 338.728838 -224.993526) (xy 338.741017 -224.944112) (xy 338.760965 -224.897292)
			(xy 338.788166 -224.854278) (xy 338.821914 -224.816184) (xy 338.861336 -224.783997) (xy 338.90541 -224.758551)
			(xy 338.952996 -224.740504) (xy 339.00286 -224.730324) (xy 339.053712 -224.728275) (xy 339.104233 -224.734409)
			(xy 339.153117 -224.748569) (xy 339.199096 -224.770386) (xy 339.24098 -224.799296) (xy 339.277684 -224.834551)
			(xy 339.308257 -224.875237) (xy 339.331908 -224.9203) (xy 339.348024 -224.968574) (xy 339.356188 -225.018808)
			(xy 339.3567 -225.044254) (xy 339.356197 -225.069243) (xy 339.663514 -225.069243) (xy 339.663514 -225.019265)
			(xy 339.671333 -224.969902) (xy 339.686777 -224.92237) (xy 339.709467 -224.877838) (xy 339.738843 -224.837405)
			(xy 339.774183 -224.802065) (xy 339.814616 -224.772689) (xy 339.859148 -224.749999) (xy 339.90668 -224.734555)
			(xy 339.956043 -224.726736) (xy 340.006021 -224.726736) (xy 340.055384 -224.734555) (xy 340.102916 -224.749999)
			(xy 340.147448 -224.772689) (xy 340.187881 -224.802065) (xy 340.223221 -224.837405) (xy 340.252597 -224.877838)
			(xy 340.275287 -224.92237) (xy 340.290731 -224.969902) (xy 340.29855 -225.019265) (xy 340.29904 -225.044254)
			(xy 340.29855 -225.069243) (xy 340.603568 -225.069243) (xy 340.603568 -225.019265) (xy 340.611387 -224.969902)
			(xy 340.626831 -224.92237) (xy 340.649521 -224.877838) (xy 340.678897 -224.837405) (xy 340.714237 -224.802065)
			(xy 340.75467 -224.772689) (xy 340.799202 -224.749999) (xy 340.846734 -224.734555) (xy 340.896097 -224.726736)
			(xy 340.946075 -224.726736) (xy 340.995438 -224.734555) (xy 341.04297 -224.749999) (xy 341.087502 -224.772689)
			(xy 341.127935 -224.802065) (xy 341.163275 -224.837405) (xy 341.192651 -224.877838) (xy 341.215341 -224.92237)
			(xy 341.230785 -224.969902) (xy 341.238604 -225.019265) (xy 341.239094 -225.044254) (xy 341.544905 -225.044254)
			(xy 341.549 -224.993526) (xy 341.561179 -224.944112) (xy 341.581127 -224.897292) (xy 341.608328 -224.854278)
			(xy 341.642076 -224.816184) (xy 341.681498 -224.783997) (xy 341.725572 -224.758551) (xy 341.773158 -224.740504)
			(xy 341.823022 -224.730324) (xy 341.873874 -224.728275) (xy 341.924395 -224.734409) (xy 341.973279 -224.748569)
			(xy 342.019258 -224.770386) (xy 342.061142 -224.799296) (xy 342.097846 -224.834551) (xy 342.128419 -224.875237)
			(xy 342.15207 -224.9203) (xy 342.168186 -224.968574) (xy 342.17635 -225.018808) (xy 342.176862 -225.044254)
			(xy 342.176359 -225.069243) (xy 342.483676 -225.069243) (xy 342.483676 -225.019265) (xy 342.491495 -224.969902)
			(xy 342.506939 -224.92237) (xy 342.529629 -224.877838) (xy 342.559005 -224.837405) (xy 342.594345 -224.802065)
			(xy 342.634778 -224.772689) (xy 342.67931 -224.749999) (xy 342.726842 -224.734555) (xy 342.776205 -224.726736)
			(xy 342.826183 -224.726736) (xy 342.875546 -224.734555) (xy 342.923078 -224.749999) (xy 342.96761 -224.772689)
			(xy 343.008043 -224.802065) (xy 343.043383 -224.837405) (xy 343.072759 -224.877838) (xy 343.095449 -224.92237)
			(xy 343.110893 -224.969902) (xy 343.118712 -225.019265) (xy 343.119202 -225.044254) (xy 343.118712 -225.069243)
			(xy 343.423476 -225.069243) (xy 343.423476 -225.019265) (xy 343.431295 -224.969902) (xy 343.446739 -224.92237)
			(xy 343.469429 -224.877838) (xy 343.498805 -224.837405) (xy 343.534145 -224.802065) (xy 343.574578 -224.772689)
			(xy 343.61911 -224.749999) (xy 343.666642 -224.734555) (xy 343.716005 -224.726736) (xy 343.765983 -224.726736)
			(xy 343.815346 -224.734555) (xy 343.862878 -224.749999) (xy 343.90741 -224.772689) (xy 343.947843 -224.802065)
			(xy 343.983183 -224.837405) (xy 344.012559 -224.877838) (xy 344.035249 -224.92237) (xy 344.050693 -224.969902)
			(xy 344.058512 -225.019265) (xy 344.059002 -225.044254) (xy 344.058512 -225.069243) (xy 345.303584 -225.069243)
			(xy 345.303584 -225.019265) (xy 345.311403 -224.969902) (xy 345.326847 -224.92237) (xy 345.349537 -224.877838)
			(xy 345.378913 -224.837405) (xy 345.414253 -224.802065) (xy 345.454686 -224.772689) (xy 345.499218 -224.749999)
			(xy 345.54675 -224.734555) (xy 345.596113 -224.726736) (xy 345.646091 -224.726736) (xy 345.695454 -224.734555)
			(xy 345.742986 -224.749999) (xy 345.787518 -224.772689) (xy 345.827951 -224.802065) (xy 345.863291 -224.837405)
			(xy 345.892667 -224.877838) (xy 345.915357 -224.92237) (xy 345.930801 -224.969902) (xy 345.93862 -225.019265)
			(xy 345.93911 -225.044254) (xy 345.93862 -225.069243) (xy 346.243638 -225.069243) (xy 346.243638 -225.019265)
			(xy 346.251457 -224.969902) (xy 346.266901 -224.92237) (xy 346.289591 -224.877838) (xy 346.318967 -224.837405)
			(xy 346.354307 -224.802065) (xy 346.39474 -224.772689) (xy 346.439272 -224.749999) (xy 346.486804 -224.734555)
			(xy 346.536167 -224.726736) (xy 346.586145 -224.726736) (xy 346.635508 -224.734555) (xy 346.68304 -224.749999)
			(xy 346.727572 -224.772689) (xy 346.768005 -224.802065) (xy 346.803345 -224.837405) (xy 346.832721 -224.877838)
			(xy 346.855411 -224.92237) (xy 346.870855 -224.969902) (xy 346.878674 -225.019265) (xy 346.879164 -225.044254)
			(xy 346.878674 -225.069243) (xy 346.870855 -225.118606) (xy 346.855411 -225.166138) (xy 346.832721 -225.21067)
			(xy 346.803345 -225.251103) (xy 346.768005 -225.286443) (xy 346.727572 -225.315819) (xy 346.68304 -225.338509)
			(xy 346.635508 -225.353953) (xy 346.586145 -225.361772) (xy 346.536167 -225.361772) (xy 346.486804 -225.353953)
			(xy 346.439272 -225.338509) (xy 346.39474 -225.315819) (xy 346.354307 -225.286443) (xy 346.318967 -225.251103)
			(xy 346.289591 -225.21067) (xy 346.266901 -225.166138) (xy 346.251457 -225.118606) (xy 346.243638 -225.069243)
			(xy 345.93862 -225.069243) (xy 345.930801 -225.118606) (xy 345.915357 -225.166138) (xy 345.892667 -225.21067)
			(xy 345.863291 -225.251103) (xy 345.827951 -225.286443) (xy 345.787518 -225.315819) (xy 345.742986 -225.338509)
			(xy 345.695454 -225.353953) (xy 345.646091 -225.361772) (xy 345.596113 -225.361772) (xy 345.54675 -225.353953)
			(xy 345.499218 -225.338509) (xy 345.454686 -225.315819) (xy 345.414253 -225.286443) (xy 345.378913 -225.251103)
			(xy 345.349537 -225.21067) (xy 345.326847 -225.166138) (xy 345.311403 -225.118606) (xy 345.303584 -225.069243)
			(xy 344.058512 -225.069243) (xy 344.050693 -225.118606) (xy 344.035249 -225.166138) (xy 344.012559 -225.21067)
			(xy 343.983183 -225.251103) (xy 343.947843 -225.286443) (xy 343.90741 -225.315819) (xy 343.862878 -225.338509)
			(xy 343.815346 -225.353953) (xy 343.765983 -225.361772) (xy 343.716005 -225.361772) (xy 343.666642 -225.353953)
			(xy 343.61911 -225.338509) (xy 343.574578 -225.315819) (xy 343.534145 -225.286443) (xy 343.498805 -225.251103)
			(xy 343.469429 -225.21067) (xy 343.446739 -225.166138) (xy 343.431295 -225.118606) (xy 343.423476 -225.069243)
			(xy 343.118712 -225.069243) (xy 343.110893 -225.118606) (xy 343.095449 -225.166138) (xy 343.072759 -225.21067)
			(xy 343.043383 -225.251103) (xy 343.008043 -225.286443) (xy 342.96761 -225.315819) (xy 342.923078 -225.338509)
			(xy 342.875546 -225.353953) (xy 342.826183 -225.361772) (xy 342.776205 -225.361772) (xy 342.726842 -225.353953)
			(xy 342.67931 -225.338509) (xy 342.634778 -225.315819) (xy 342.594345 -225.286443) (xy 342.559005 -225.251103)
			(xy 342.529629 -225.21067) (xy 342.506939 -225.166138) (xy 342.491495 -225.118606) (xy 342.483676 -225.069243)
			(xy 342.176359 -225.069243) (xy 342.17635 -225.0697) (xy 342.168186 -225.119934) (xy 342.15207 -225.168208)
			(xy 342.128419 -225.213271) (xy 342.097846 -225.253957) (xy 342.061142 -225.289212) (xy 342.019258 -225.318122)
			(xy 341.973279 -225.339939) (xy 341.924395 -225.354099) (xy 341.873874 -225.360233) (xy 341.823022 -225.358184)
			(xy 341.773158 -225.348004) (xy 341.725572 -225.329957) (xy 341.681498 -225.304511) (xy 341.642076 -225.272324)
			(xy 341.608328 -225.23423) (xy 341.581127 -225.191216) (xy 341.561179 -225.144396) (xy 341.549 -225.094982)
			(xy 341.544905 -225.044254) (xy 341.239094 -225.044254) (xy 341.238604 -225.069243) (xy 341.230785 -225.118606)
			(xy 341.215341 -225.166138) (xy 341.192651 -225.21067) (xy 341.163275 -225.251103) (xy 341.127935 -225.286443)
			(xy 341.087502 -225.315819) (xy 341.04297 -225.338509) (xy 340.995438 -225.353953) (xy 340.946075 -225.361772)
			(xy 340.896097 -225.361772) (xy 340.846734 -225.353953) (xy 340.799202 -225.338509) (xy 340.75467 -225.315819)
			(xy 340.714237 -225.286443) (xy 340.678897 -225.251103) (xy 340.649521 -225.21067) (xy 340.626831 -225.166138)
			(xy 340.611387 -225.118606) (xy 340.603568 -225.069243) (xy 340.29855 -225.069243) (xy 340.290731 -225.118606)
			(xy 340.275287 -225.166138) (xy 340.252597 -225.21067) (xy 340.223221 -225.251103) (xy 340.187881 -225.286443)
			(xy 340.147448 -225.315819) (xy 340.102916 -225.338509) (xy 340.055384 -225.353953) (xy 340.006021 -225.361772)
			(xy 339.956043 -225.361772) (xy 339.90668 -225.353953) (xy 339.859148 -225.338509) (xy 339.814616 -225.315819)
			(xy 339.774183 -225.286443) (xy 339.738843 -225.251103) (xy 339.709467 -225.21067) (xy 339.686777 -225.166138)
			(xy 339.671333 -225.118606) (xy 339.663514 -225.069243) (xy 339.356197 -225.069243) (xy 339.356188 -225.0697)
			(xy 339.348024 -225.119934) (xy 339.331908 -225.168208) (xy 339.308257 -225.213271) (xy 339.277684 -225.253957)
			(xy 339.24098 -225.289212) (xy 339.199096 -225.318122) (xy 339.153117 -225.339939) (xy 339.104233 -225.354099)
			(xy 339.053712 -225.360233) (xy 339.00286 -225.358184) (xy 338.952996 -225.348004) (xy 338.90541 -225.329957)
			(xy 338.861336 -225.304511) (xy 338.821914 -225.272324) (xy 338.788166 -225.23423) (xy 338.760965 -225.191216)
			(xy 338.741017 -225.144396) (xy 338.728838 -225.094982) (xy 338.724743 -225.044254) (xy 338.41917 -225.044254)
			(xy 338.418563 -225.073548) (xy 338.407447 -225.132619) (xy 338.397088 -225.16084) (xy 338.393532 -225.169984)
			(xy 338.393532 -225.443542) (xy 338.394082 -225.45426) (xy 338.40302 -225.473749) (xy 338.410804 -225.481134)
			(xy 338.426552 -225.494088) (xy 338.427314 -225.49485) (xy 338.46389 -225.525076) (xy 338.468147 -225.528135)
			(xy 338.47762 -225.532619) (xy 338.482686 -225.533966) (xy 338.4931 -225.536506) (xy 338.504276 -225.53422)
			(xy 338.520664 -225.531027) (xy 338.553876 -225.527591) (xy 338.57057 -225.527362) (xy 338.571078 -225.527362)
			(xy 338.596772 -225.527838) (xy 338.647528 -225.535874) (xy 338.696402 -225.551751) (xy 338.74219 -225.575078)
			(xy 338.783766 -225.605282) (xy 338.820104 -225.641618) (xy 338.85031 -225.683191) (xy 338.873641 -225.728978)
			(xy 338.889521 -225.77785) (xy 338.89756 -225.828606) (xy 338.89756 -225.879249) (xy 339.193614 -225.879249)
			(xy 339.193614 -225.829271) (xy 339.201433 -225.779908) (xy 339.216877 -225.732376) (xy 339.239567 -225.687844)
			(xy 339.268943 -225.647411) (xy 339.304283 -225.612071) (xy 339.344716 -225.582695) (xy 339.389248 -225.560005)
			(xy 339.43678 -225.544561) (xy 339.486143 -225.536742) (xy 339.536121 -225.536742) (xy 339.585484 -225.544561)
			(xy 339.633016 -225.560005) (xy 339.677548 -225.582695) (xy 339.717981 -225.612071) (xy 339.753321 -225.647411)
			(xy 339.782697 -225.687844) (xy 339.805387 -225.732376) (xy 339.820831 -225.779908) (xy 339.82865 -225.829271)
			(xy 339.82914 -225.85426) (xy 340.134951 -225.85426) (xy 340.139046 -225.803532) (xy 340.151225 -225.754118)
			(xy 340.171173 -225.707298) (xy 340.198374 -225.664284) (xy 340.232122 -225.62619) (xy 340.271544 -225.594003)
			(xy 340.315618 -225.568557) (xy 340.363204 -225.55051) (xy 340.413068 -225.54033) (xy 340.46392 -225.538281)
			(xy 340.514441 -225.544415) (xy 340.563325 -225.558575) (xy 340.609304 -225.580392) (xy 340.651188 -225.609302)
			(xy 340.687892 -225.644557) (xy 340.718465 -225.685243) (xy 340.742116 -225.730306) (xy 340.758232 -225.77858)
			(xy 340.766396 -225.828814) (xy 340.766908 -225.85426) (xy 340.766405 -225.879249) (xy 341.073468 -225.879249)
			(xy 341.073468 -225.829271) (xy 341.081287 -225.779908) (xy 341.096731 -225.732376) (xy 341.119421 -225.687844)
			(xy 341.148797 -225.647411) (xy 341.184137 -225.612071) (xy 341.22457 -225.582695) (xy 341.269102 -225.560005)
			(xy 341.316634 -225.544561) (xy 341.365997 -225.536742) (xy 341.415975 -225.536742) (xy 341.465338 -225.544561)
			(xy 341.51287 -225.560005) (xy 341.557402 -225.582695) (xy 341.597835 -225.612071) (xy 341.633175 -225.647411)
			(xy 341.662551 -225.687844) (xy 341.685241 -225.732376) (xy 341.700685 -225.779908) (xy 341.708504 -225.829271)
			(xy 341.708994 -225.85426) (xy 342.014805 -225.85426) (xy 342.0189 -225.803532) (xy 342.031079 -225.754118)
			(xy 342.051027 -225.707298) (xy 342.078228 -225.664284) (xy 342.111976 -225.62619) (xy 342.151398 -225.594003)
			(xy 342.195472 -225.568557) (xy 342.243058 -225.55051) (xy 342.292922 -225.54033) (xy 342.343774 -225.538281)
			(xy 342.394295 -225.544415) (xy 342.443179 -225.558575) (xy 342.489158 -225.580392) (xy 342.531042 -225.609302)
			(xy 342.567746 -225.644557) (xy 342.598319 -225.685243) (xy 342.62197 -225.730306) (xy 342.638086 -225.77858)
			(xy 342.64625 -225.828814) (xy 342.646762 -225.85426) (xy 342.954859 -225.85426) (xy 342.958954 -225.803532)
			(xy 342.971133 -225.754118) (xy 342.991081 -225.707298) (xy 343.018282 -225.664284) (xy 343.05203 -225.62619)
			(xy 343.091452 -225.594003) (xy 343.135526 -225.568557) (xy 343.183112 -225.55051) (xy 343.232976 -225.54033)
			(xy 343.283828 -225.538281) (xy 343.334349 -225.544415) (xy 343.383233 -225.558575) (xy 343.429212 -225.580392)
			(xy 343.471096 -225.609302) (xy 343.5078 -225.644557) (xy 343.538373 -225.685243) (xy 343.562024 -225.730306)
			(xy 343.57814 -225.77858) (xy 343.586304 -225.828814) (xy 343.586816 -225.85426) (xy 343.586313 -225.879249)
			(xy 344.833684 -225.879249) (xy 344.833684 -225.829271) (xy 344.841503 -225.779908) (xy 344.856947 -225.732376)
			(xy 344.879637 -225.687844) (xy 344.909013 -225.647411) (xy 344.944353 -225.612071) (xy 344.984786 -225.582695)
			(xy 345.029318 -225.560005) (xy 345.07685 -225.544561) (xy 345.126213 -225.536742) (xy 345.176191 -225.536742)
			(xy 345.225554 -225.544561) (xy 345.273086 -225.560005) (xy 345.317618 -225.582695) (xy 345.358051 -225.612071)
			(xy 345.393391 -225.647411) (xy 345.422767 -225.687844) (xy 345.445457 -225.732376) (xy 345.460901 -225.779908)
			(xy 345.46872 -225.829271) (xy 345.46921 -225.85426) (xy 345.46872 -225.879249) (xy 345.773484 -225.879249)
			(xy 345.773484 -225.829271) (xy 345.781303 -225.779908) (xy 345.796747 -225.732376) (xy 345.819437 -225.687844)
			(xy 345.848813 -225.647411) (xy 345.884153 -225.612071) (xy 345.924586 -225.582695) (xy 345.969118 -225.560005)
			(xy 346.01665 -225.544561) (xy 346.066013 -225.536742) (xy 346.115991 -225.536742) (xy 346.165354 -225.544561)
			(xy 346.212886 -225.560005) (xy 346.257418 -225.582695) (xy 346.297851 -225.612071) (xy 346.333191 -225.647411)
			(xy 346.362567 -225.687844) (xy 346.385257 -225.732376) (xy 346.400701 -225.779908) (xy 346.40852 -225.829271)
			(xy 346.40901 -225.85426) (xy 346.40852 -225.879249) (xy 346.400701 -225.928612) (xy 346.385257 -225.976144)
			(xy 346.362567 -226.020676) (xy 346.333191 -226.061109) (xy 346.297851 -226.096449) (xy 346.257418 -226.125825)
			(xy 346.212886 -226.148515) (xy 346.165354 -226.163959) (xy 346.115991 -226.171778) (xy 346.066013 -226.171778)
			(xy 346.01665 -226.163959) (xy 345.969118 -226.148515) (xy 345.924586 -226.125825) (xy 345.884153 -226.096449)
			(xy 345.848813 -226.061109) (xy 345.819437 -226.020676) (xy 345.796747 -225.976144) (xy 345.781303 -225.928612)
			(xy 345.773484 -225.879249) (xy 345.46872 -225.879249) (xy 345.460901 -225.928612) (xy 345.445457 -225.976144)
			(xy 345.422767 -226.020676) (xy 345.393391 -226.061109) (xy 345.358051 -226.096449) (xy 345.317618 -226.125825)
			(xy 345.273086 -226.148515) (xy 345.225554 -226.163959) (xy 345.176191 -226.171778) (xy 345.126213 -226.171778)
			(xy 345.07685 -226.163959) (xy 345.029318 -226.148515) (xy 344.984786 -226.125825) (xy 344.944353 -226.096449)
			(xy 344.909013 -226.061109) (xy 344.879637 -226.020676) (xy 344.856947 -225.976144) (xy 344.841503 -225.928612)
			(xy 344.833684 -225.879249) (xy 343.586313 -225.879249) (xy 343.586304 -225.879706) (xy 343.57814 -225.92994)
			(xy 343.562024 -225.978214) (xy 343.538373 -226.023277) (xy 343.5078 -226.063963) (xy 343.471096 -226.099218)
			(xy 343.429212 -226.128128) (xy 343.383233 -226.149945) (xy 343.334349 -226.164105) (xy 343.283828 -226.170239)
			(xy 343.232976 -226.16819) (xy 343.183112 -226.15801) (xy 343.135526 -226.139963) (xy 343.091452 -226.114517)
			(xy 343.05203 -226.08233) (xy 343.018282 -226.044236) (xy 342.991081 -226.001222) (xy 342.971133 -225.954402)
			(xy 342.958954 -225.904988) (xy 342.954859 -225.85426) (xy 342.646762 -225.85426) (xy 342.64625 -225.879706)
			(xy 342.638086 -225.92994) (xy 342.62197 -225.978214) (xy 342.598319 -226.023277) (xy 342.567746 -226.063963)
			(xy 342.531042 -226.099218) (xy 342.489158 -226.128128) (xy 342.443179 -226.149945) (xy 342.394295 -226.164105)
			(xy 342.343774 -226.170239) (xy 342.292922 -226.16819) (xy 342.243058 -226.15801) (xy 342.195472 -226.139963)
			(xy 342.151398 -226.114517) (xy 342.111976 -226.08233) (xy 342.078228 -226.044236) (xy 342.051027 -226.001222)
			(xy 342.031079 -225.954402) (xy 342.0189 -225.904988) (xy 342.014805 -225.85426) (xy 341.708994 -225.85426)
			(xy 341.708504 -225.879249) (xy 341.700685 -225.928612) (xy 341.685241 -225.976144) (xy 341.662551 -226.020676)
			(xy 341.633175 -226.061109) (xy 341.597835 -226.096449) (xy 341.557402 -226.125825) (xy 341.51287 -226.148515)
			(xy 341.465338 -226.163959) (xy 341.415975 -226.171778) (xy 341.365997 -226.171778) (xy 341.316634 -226.163959)
			(xy 341.269102 -226.148515) (xy 341.22457 -226.125825) (xy 341.184137 -226.096449) (xy 341.148797 -226.061109)
			(xy 341.119421 -226.020676) (xy 341.096731 -225.976144) (xy 341.081287 -225.928612) (xy 341.073468 -225.879249)
			(xy 340.766405 -225.879249) (xy 340.766396 -225.879706) (xy 340.758232 -225.92994) (xy 340.742116 -225.978214)
			(xy 340.718465 -226.023277) (xy 340.687892 -226.063963) (xy 340.651188 -226.099218) (xy 340.609304 -226.128128)
			(xy 340.563325 -226.149945) (xy 340.514441 -226.164105) (xy 340.46392 -226.170239) (xy 340.413068 -226.16819)
			(xy 340.363204 -226.15801) (xy 340.315618 -226.139963) (xy 340.271544 -226.114517) (xy 340.232122 -226.08233)
			(xy 340.198374 -226.044236) (xy 340.171173 -226.001222) (xy 340.151225 -225.954402) (xy 340.139046 -225.904988)
			(xy 340.134951 -225.85426) (xy 339.82914 -225.85426) (xy 339.82865 -225.879249) (xy 339.820831 -225.928612)
			(xy 339.805387 -225.976144) (xy 339.782697 -226.020676) (xy 339.753321 -226.061109) (xy 339.717981 -226.096449)
			(xy 339.677548 -226.125825) (xy 339.633016 -226.148515) (xy 339.585484 -226.163959) (xy 339.536121 -226.171778)
			(xy 339.486143 -226.171778) (xy 339.43678 -226.163959) (xy 339.389248 -226.148515) (xy 339.344716 -226.125825)
			(xy 339.304283 -226.096449) (xy 339.268943 -226.061109) (xy 339.239567 -226.020676) (xy 339.216877 -225.976144)
			(xy 339.201433 -225.928612) (xy 339.193614 -225.879249) (xy 338.89756 -225.879249) (xy 338.89756 -225.879994)
			(xy 338.889521 -225.93075) (xy 338.873641 -225.979622) (xy 338.85031 -226.025409) (xy 338.820104 -226.066982)
			(xy 338.783766 -226.103318) (xy 338.74219 -226.133522) (xy 338.696402 -226.156849) (xy 338.647528 -226.172726)
			(xy 338.596772 -226.180762) (xy 338.571078 -226.181158) (xy 338.57057 -226.181158) (xy 338.553875 -226.180934)
			(xy 338.520664 -226.177495) (xy 338.504276 -226.1743) (xy 338.4931 -226.172014) (xy 338.482686 -226.174554)
			(xy 338.477624 -226.175911) (xy 338.468154 -226.180396) (xy 338.46389 -226.183444) (xy 338.427314 -226.21367)
			(xy 338.426552 -226.214432) (xy 338.410804 -226.227386) (xy 338.403025 -226.23478) (xy 338.394064 -226.254259)
			(xy 338.393532 -226.264978) (xy 338.393532 -226.524566) (xy 338.39404 -226.532186) (xy 338.396326 -226.543362)
			(xy 338.398358 -226.550474) (xy 338.39912 -226.552506) (xy 338.405471 -226.570279) (xy 338.414386 -226.606953)
			(xy 338.4169 -226.625658) (xy 338.418932 -226.641914) (xy 338.419186 -226.647502) (xy 338.419186 -226.664266)
			(xy 338.724743 -226.664266) (xy 338.728838 -226.613538) (xy 338.741017 -226.564124) (xy 338.760965 -226.517304)
			(xy 338.788166 -226.47429) (xy 338.821914 -226.436196) (xy 338.861336 -226.404009) (xy 338.90541 -226.378563)
			(xy 338.952996 -226.360516) (xy 339.00286 -226.350336) (xy 339.053712 -226.348287) (xy 339.104233 -226.354421)
			(xy 339.153117 -226.368581) (xy 339.199096 -226.390398) (xy 339.24098 -226.419308) (xy 339.277684 -226.454563)
			(xy 339.308257 -226.495249) (xy 339.331908 -226.540312) (xy 339.348024 -226.588586) (xy 339.356188 -226.63882)
			(xy 339.3567 -226.664266) (xy 339.664797 -226.664266) (xy 339.668892 -226.613538) (xy 339.681071 -226.564124)
			(xy 339.701019 -226.517304) (xy 339.72822 -226.47429) (xy 339.761968 -226.436196) (xy 339.80139 -226.404009)
			(xy 339.845464 -226.378563) (xy 339.89305 -226.360516) (xy 339.942914 -226.350336) (xy 339.993766 -226.348287)
			(xy 340.044287 -226.354421) (xy 340.093171 -226.368581) (xy 340.13915 -226.390398) (xy 340.181034 -226.419308)
			(xy 340.217738 -226.454563) (xy 340.248311 -226.495249) (xy 340.271962 -226.540312) (xy 340.288078 -226.588586)
			(xy 340.296242 -226.63882) (xy 340.296754 -226.664266) (xy 340.296251 -226.689255) (xy 340.603568 -226.689255)
			(xy 340.603568 -226.639277) (xy 340.611387 -226.589914) (xy 340.626831 -226.542382) (xy 340.649521 -226.49785)
			(xy 340.678897 -226.457417) (xy 340.714237 -226.422077) (xy 340.75467 -226.392701) (xy 340.799202 -226.370011)
			(xy 340.846734 -226.354567) (xy 340.896097 -226.346748) (xy 340.946075 -226.346748) (xy 340.995438 -226.354567)
			(xy 341.04297 -226.370011) (xy 341.087502 -226.392701) (xy 341.127935 -226.422077) (xy 341.163275 -226.457417)
			(xy 341.192651 -226.49785) (xy 341.215341 -226.542382) (xy 341.230785 -226.589914) (xy 341.238604 -226.639277)
			(xy 341.239094 -226.664266) (xy 341.544905 -226.664266) (xy 341.549 -226.613538) (xy 341.561179 -226.564124)
			(xy 341.581127 -226.517304) (xy 341.608328 -226.47429) (xy 341.642076 -226.436196) (xy 341.681498 -226.404009)
			(xy 341.725572 -226.378563) (xy 341.773158 -226.360516) (xy 341.823022 -226.350336) (xy 341.873874 -226.348287)
			(xy 341.924395 -226.354421) (xy 341.973279 -226.368581) (xy 342.019258 -226.390398) (xy 342.061142 -226.419308)
			(xy 342.097846 -226.454563) (xy 342.128419 -226.495249) (xy 342.15207 -226.540312) (xy 342.168186 -226.588586)
			(xy 342.17635 -226.63882) (xy 342.176862 -226.664266) (xy 342.176359 -226.689255) (xy 342.483676 -226.689255)
			(xy 342.483676 -226.639277) (xy 342.491495 -226.589914) (xy 342.506939 -226.542382) (xy 342.529629 -226.49785)
			(xy 342.559005 -226.457417) (xy 342.594345 -226.422077) (xy 342.634778 -226.392701) (xy 342.67931 -226.370011)
			(xy 342.726842 -226.354567) (xy 342.776205 -226.346748) (xy 342.826183 -226.346748) (xy 342.875546 -226.354567)
			(xy 342.923078 -226.370011) (xy 342.96761 -226.392701) (xy 343.008043 -226.422077) (xy 343.043383 -226.457417)
			(xy 343.072759 -226.49785) (xy 343.095449 -226.542382) (xy 343.110893 -226.589914) (xy 343.118712 -226.639277)
			(xy 343.119202 -226.664266) (xy 343.424759 -226.664266) (xy 343.428854 -226.613538) (xy 343.441033 -226.564124)
			(xy 343.460981 -226.517304) (xy 343.488182 -226.47429) (xy 343.52193 -226.436196) (xy 343.561352 -226.404009)
			(xy 343.605426 -226.378563) (xy 343.653012 -226.360516) (xy 343.702876 -226.350336) (xy 343.753728 -226.348287)
			(xy 343.804249 -226.354421) (xy 343.853133 -226.368581) (xy 343.899112 -226.390398) (xy 343.940996 -226.419308)
			(xy 343.9777 -226.454563) (xy 344.008273 -226.495249) (xy 344.031924 -226.540312) (xy 344.04804 -226.588586)
			(xy 344.056204 -226.63882) (xy 344.056716 -226.664266) (xy 344.056213 -226.689255) (xy 344.36353 -226.689255)
			(xy 344.36353 -226.639277) (xy 344.371349 -226.589914) (xy 344.386793 -226.542382) (xy 344.409483 -226.49785)
			(xy 344.438859 -226.457417) (xy 344.474199 -226.422077) (xy 344.514632 -226.392701) (xy 344.559164 -226.370011)
			(xy 344.606696 -226.354567) (xy 344.656059 -226.346748) (xy 344.706037 -226.346748) (xy 344.7554 -226.354567)
			(xy 344.802932 -226.370011) (xy 344.847464 -226.392701) (xy 344.887897 -226.422077) (xy 344.923237 -226.457417)
			(xy 344.952613 -226.49785) (xy 344.975303 -226.542382) (xy 344.990747 -226.589914) (xy 344.998566 -226.639277)
			(xy 344.999056 -226.664266) (xy 345.304867 -226.664266) (xy 345.308962 -226.613538) (xy 345.321141 -226.564124)
			(xy 345.341089 -226.517304) (xy 345.36829 -226.47429) (xy 345.402038 -226.436196) (xy 345.44146 -226.404009)
			(xy 345.485534 -226.378563) (xy 345.53312 -226.360516) (xy 345.582984 -226.350336) (xy 345.633836 -226.348287)
			(xy 345.684357 -226.354421) (xy 345.733241 -226.368581) (xy 345.77922 -226.390398) (xy 345.821104 -226.419308)
			(xy 345.857808 -226.454563) (xy 345.888381 -226.495249) (xy 345.912032 -226.540312) (xy 345.928148 -226.588586)
			(xy 345.936312 -226.63882) (xy 345.936824 -226.664266) (xy 346.244921 -226.664266) (xy 346.249016 -226.613538)
			(xy 346.261195 -226.564124) (xy 346.281143 -226.517304) (xy 346.308344 -226.47429) (xy 346.342092 -226.436196)
			(xy 346.381514 -226.404009) (xy 346.425588 -226.378563) (xy 346.473174 -226.360516) (xy 346.523038 -226.350336)
			(xy 346.57389 -226.348287) (xy 346.624411 -226.354421) (xy 346.673295 -226.368581) (xy 346.719274 -226.390398)
			(xy 346.761158 -226.419308) (xy 346.797862 -226.454563) (xy 346.828435 -226.495249) (xy 346.852086 -226.540312)
			(xy 346.868202 -226.588586) (xy 346.876366 -226.63882) (xy 346.876878 -226.664266) (xy 346.876375 -226.689255)
			(xy 347.183692 -226.689255) (xy 347.183692 -226.639277) (xy 347.191511 -226.589914) (xy 347.206955 -226.542382)
			(xy 347.229645 -226.49785) (xy 347.259021 -226.457417) (xy 347.294361 -226.422077) (xy 347.334794 -226.392701)
			(xy 347.379326 -226.370011) (xy 347.426858 -226.354567) (xy 347.476221 -226.346748) (xy 347.526199 -226.346748)
			(xy 347.575562 -226.354567) (xy 347.623094 -226.370011) (xy 347.667626 -226.392701) (xy 347.708059 -226.422077)
			(xy 347.743399 -226.457417) (xy 347.772775 -226.49785) (xy 347.795465 -226.542382) (xy 347.810909 -226.589914)
			(xy 347.818728 -226.639277) (xy 347.819218 -226.664266) (xy 348.124775 -226.664266) (xy 348.12887 -226.613538)
			(xy 348.141049 -226.564124) (xy 348.160997 -226.517304) (xy 348.188198 -226.47429) (xy 348.221946 -226.436196)
			(xy 348.261368 -226.404009) (xy 348.305442 -226.378563) (xy 348.353028 -226.360516) (xy 348.402892 -226.350336)
			(xy 348.453744 -226.348287) (xy 348.504265 -226.354421) (xy 348.553149 -226.368581) (xy 348.599128 -226.390398)
			(xy 348.641012 -226.419308) (xy 348.677716 -226.454563) (xy 348.708289 -226.495249) (xy 348.73194 -226.540312)
			(xy 348.748056 -226.588586) (xy 348.75622 -226.63882) (xy 348.756732 -226.664266) (xy 349.064829 -226.664266)
			(xy 349.068924 -226.613538) (xy 349.081103 -226.564124) (xy 349.101051 -226.517304) (xy 349.128252 -226.47429)
			(xy 349.162 -226.436196) (xy 349.201422 -226.404009) (xy 349.245496 -226.378563) (xy 349.293082 -226.360516)
			(xy 349.342946 -226.350336) (xy 349.393798 -226.348287) (xy 349.444319 -226.354421) (xy 349.493203 -226.368581)
			(xy 349.539182 -226.390398) (xy 349.581066 -226.419308) (xy 349.61777 -226.454563) (xy 349.648343 -226.495249)
			(xy 349.671994 -226.540312) (xy 349.68811 -226.588586) (xy 349.696274 -226.63882) (xy 349.696786 -226.664266)
			(xy 349.696283 -226.689255) (xy 350.0036 -226.689255) (xy 350.0036 -226.639277) (xy 350.011419 -226.589914)
			(xy 350.026863 -226.542382) (xy 350.049553 -226.49785) (xy 350.078929 -226.457417) (xy 350.114269 -226.422077)
			(xy 350.154702 -226.392701) (xy 350.199234 -226.370011) (xy 350.246766 -226.354567) (xy 350.296129 -226.346748)
			(xy 350.346107 -226.346748) (xy 350.39547 -226.354567) (xy 350.443002 -226.370011) (xy 350.487534 -226.392701)
			(xy 350.527967 -226.422077) (xy 350.563307 -226.457417) (xy 350.592683 -226.49785) (xy 350.615373 -226.542382)
			(xy 350.630817 -226.589914) (xy 350.638636 -226.639277) (xy 350.639126 -226.664266) (xy 350.944937 -226.664266)
			(xy 350.949032 -226.613538) (xy 350.961211 -226.564124) (xy 350.981159 -226.517304) (xy 351.00836 -226.47429)
			(xy 351.042108 -226.436196) (xy 351.08153 -226.404009) (xy 351.125604 -226.378563) (xy 351.17319 -226.360516)
			(xy 351.223054 -226.350336) (xy 351.273906 -226.348287) (xy 351.324427 -226.354421) (xy 351.373311 -226.368581)
			(xy 351.41929 -226.390398) (xy 351.461174 -226.419308) (xy 351.497878 -226.454563) (xy 351.528451 -226.495249)
			(xy 351.552102 -226.540312) (xy 351.568218 -226.588586) (xy 351.576382 -226.63882) (xy 351.576894 -226.664266)
			(xy 351.884991 -226.664266) (xy 351.889086 -226.613538) (xy 351.901265 -226.564124) (xy 351.921213 -226.517304)
			(xy 351.948414 -226.47429) (xy 351.982162 -226.436196) (xy 352.021584 -226.404009) (xy 352.065658 -226.378563)
			(xy 352.113244 -226.360516) (xy 352.163108 -226.350336) (xy 352.21396 -226.348287) (xy 352.264481 -226.354421)
			(xy 352.313365 -226.368581) (xy 352.359344 -226.390398) (xy 352.401228 -226.419308) (xy 352.437932 -226.454563)
			(xy 352.468505 -226.495249) (xy 352.492156 -226.540312) (xy 352.508272 -226.588586) (xy 352.516436 -226.63882)
			(xy 352.516948 -226.664266) (xy 352.516445 -226.689255) (xy 352.823508 -226.689255) (xy 352.823508 -226.639277)
			(xy 352.831327 -226.589914) (xy 352.846771 -226.542382) (xy 352.869461 -226.49785) (xy 352.898837 -226.457417)
			(xy 352.934177 -226.422077) (xy 352.97461 -226.392701) (xy 353.019142 -226.370011) (xy 353.066674 -226.354567)
			(xy 353.116037 -226.346748) (xy 353.166015 -226.346748) (xy 353.215378 -226.354567) (xy 353.26291 -226.370011)
			(xy 353.307442 -226.392701) (xy 353.347875 -226.422077) (xy 353.383215 -226.457417) (xy 353.412591 -226.49785)
			(xy 353.435281 -226.542382) (xy 353.450725 -226.589914) (xy 353.458544 -226.639277) (xy 353.459034 -226.664266)
			(xy 353.764845 -226.664266) (xy 353.76894 -226.613538) (xy 353.781119 -226.564124) (xy 353.801067 -226.517304)
			(xy 353.828268 -226.47429) (xy 353.862016 -226.436196) (xy 353.901438 -226.404009) (xy 353.945512 -226.378563)
			(xy 353.993098 -226.360516) (xy 354.042962 -226.350336) (xy 354.093814 -226.348287) (xy 354.144335 -226.354421)
			(xy 354.193219 -226.368581) (xy 354.239198 -226.390398) (xy 354.281082 -226.419308) (xy 354.317786 -226.454563)
			(xy 354.348359 -226.495249) (xy 354.37201 -226.540312) (xy 354.388126 -226.588586) (xy 354.39629 -226.63882)
			(xy 354.396802 -226.664266) (xy 354.704899 -226.664266) (xy 354.708994 -226.613538) (xy 354.721173 -226.564124)
			(xy 354.741121 -226.517304) (xy 354.768322 -226.47429) (xy 354.80207 -226.436196) (xy 354.841492 -226.404009)
			(xy 354.885566 -226.378563) (xy 354.933152 -226.360516) (xy 354.983016 -226.350336) (xy 355.033868 -226.348287)
			(xy 355.084389 -226.354421) (xy 355.133273 -226.368581) (xy 355.179252 -226.390398) (xy 355.221136 -226.419308)
			(xy 355.25784 -226.454563) (xy 355.288413 -226.495249) (xy 355.312064 -226.540312) (xy 355.32818 -226.588586)
			(xy 355.336344 -226.63882) (xy 355.336856 -226.664266) (xy 355.336353 -226.689255) (xy 355.64367 -226.689255)
			(xy 355.64367 -226.639277) (xy 355.651489 -226.589914) (xy 355.666933 -226.542382) (xy 355.689623 -226.49785)
			(xy 355.718999 -226.457417) (xy 355.754339 -226.422077) (xy 355.794772 -226.392701) (xy 355.839304 -226.370011)
			(xy 355.886836 -226.354567) (xy 355.936199 -226.346748) (xy 355.986177 -226.346748) (xy 356.03554 -226.354567)
			(xy 356.083072 -226.370011) (xy 356.127604 -226.392701) (xy 356.168037 -226.422077) (xy 356.203377 -226.457417)
			(xy 356.232753 -226.49785) (xy 356.255443 -226.542382) (xy 356.270887 -226.589914) (xy 356.278706 -226.639277)
			(xy 356.279196 -226.664266) (xy 356.278706 -226.689255) (xy 363.157244 -226.689255) (xy 363.157244 -226.639277)
			(xy 363.165063 -226.589914) (xy 363.180507 -226.542382) (xy 363.203197 -226.49785) (xy 363.232573 -226.457417)
			(xy 363.267913 -226.422077) (xy 363.308346 -226.392701) (xy 363.352878 -226.370011) (xy 363.40041 -226.354567)
			(xy 363.449773 -226.346748) (xy 363.499751 -226.346748) (xy 363.549114 -226.354567) (xy 363.596646 -226.370011)
			(xy 363.641178 -226.392701) (xy 363.681611 -226.422077) (xy 363.716951 -226.457417) (xy 363.746327 -226.49785)
			(xy 363.769017 -226.542382) (xy 363.784461 -226.589914) (xy 363.79228 -226.639277) (xy 363.79277 -226.664266)
			(xy 364.098581 -226.664266) (xy 364.102676 -226.613538) (xy 364.114855 -226.564124) (xy 364.134803 -226.517304)
			(xy 364.162004 -226.47429) (xy 364.195752 -226.436196) (xy 364.235174 -226.404009) (xy 364.279248 -226.378563)
			(xy 364.326834 -226.360516) (xy 364.376698 -226.350336) (xy 364.42755 -226.348287) (xy 364.478071 -226.354421)
			(xy 364.526955 -226.368581) (xy 364.572934 -226.390398) (xy 364.614818 -226.419308) (xy 364.651522 -226.454563)
			(xy 364.682095 -226.495249) (xy 364.705746 -226.540312) (xy 364.721862 -226.588586) (xy 364.730026 -226.63882)
			(xy 364.730538 -226.664266) (xy 365.038635 -226.664266) (xy 365.04273 -226.613538) (xy 365.054909 -226.564124)
			(xy 365.074857 -226.517304) (xy 365.102058 -226.47429) (xy 365.135806 -226.436196) (xy 365.175228 -226.404009)
			(xy 365.219302 -226.378563) (xy 365.266888 -226.360516) (xy 365.316752 -226.350336) (xy 365.367604 -226.348287)
			(xy 365.418125 -226.354421) (xy 365.467009 -226.368581) (xy 365.512988 -226.390398) (xy 365.554872 -226.419308)
			(xy 365.591576 -226.454563) (xy 365.622149 -226.495249) (xy 365.6458 -226.540312) (xy 365.661916 -226.588586)
			(xy 365.67008 -226.63882) (xy 365.670592 -226.664266) (xy 365.670089 -226.689255) (xy 365.977406 -226.689255)
			(xy 365.977406 -226.639277) (xy 365.985225 -226.589914) (xy 366.000669 -226.542382) (xy 366.023359 -226.49785)
			(xy 366.052735 -226.457417) (xy 366.088075 -226.422077) (xy 366.128508 -226.392701) (xy 366.17304 -226.370011)
			(xy 366.220572 -226.354567) (xy 366.269935 -226.346748) (xy 366.319913 -226.346748) (xy 366.369276 -226.354567)
			(xy 366.416808 -226.370011) (xy 366.46134 -226.392701) (xy 366.501773 -226.422077) (xy 366.537113 -226.457417)
			(xy 366.566489 -226.49785) (xy 366.589179 -226.542382) (xy 366.604623 -226.589914) (xy 366.612442 -226.639277)
			(xy 366.612932 -226.664266) (xy 366.918489 -226.664266) (xy 366.922584 -226.613538) (xy 366.934763 -226.564124)
			(xy 366.954711 -226.517304) (xy 366.981912 -226.47429) (xy 367.01566 -226.436196) (xy 367.055082 -226.404009)
			(xy 367.099156 -226.378563) (xy 367.146742 -226.360516) (xy 367.196606 -226.350336) (xy 367.247458 -226.348287)
			(xy 367.297979 -226.354421) (xy 367.346863 -226.368581) (xy 367.392842 -226.390398) (xy 367.434726 -226.419308)
			(xy 367.47143 -226.454563) (xy 367.502003 -226.495249) (xy 367.525654 -226.540312) (xy 367.54177 -226.588586)
			(xy 367.549934 -226.63882) (xy 367.550446 -226.664266) (xy 367.858543 -226.664266) (xy 367.862638 -226.613538)
			(xy 367.874817 -226.564124) (xy 367.894765 -226.517304) (xy 367.921966 -226.47429) (xy 367.955714 -226.436196)
			(xy 367.995136 -226.404009) (xy 368.03921 -226.378563) (xy 368.086796 -226.360516) (xy 368.13666 -226.350336)
			(xy 368.187512 -226.348287) (xy 368.238033 -226.354421) (xy 368.286917 -226.368581) (xy 368.332896 -226.390398)
			(xy 368.37478 -226.419308) (xy 368.411484 -226.454563) (xy 368.442057 -226.495249) (xy 368.465708 -226.540312)
			(xy 368.481824 -226.588586) (xy 368.489988 -226.63882) (xy 368.4905 -226.664266) (xy 368.489997 -226.689255)
			(xy 368.797314 -226.689255) (xy 368.797314 -226.639277) (xy 368.805133 -226.589914) (xy 368.820577 -226.542382)
			(xy 368.843267 -226.49785) (xy 368.872643 -226.457417) (xy 368.907983 -226.422077) (xy 368.948416 -226.392701)
			(xy 368.992948 -226.370011) (xy 369.04048 -226.354567) (xy 369.089843 -226.346748) (xy 369.139821 -226.346748)
			(xy 369.189184 -226.354567) (xy 369.236716 -226.370011) (xy 369.281248 -226.392701) (xy 369.321681 -226.422077)
			(xy 369.357021 -226.457417) (xy 369.386397 -226.49785) (xy 369.409087 -226.542382) (xy 369.424531 -226.589914)
			(xy 369.43235 -226.639277) (xy 369.43284 -226.664266) (xy 369.738651 -226.664266) (xy 369.742746 -226.613538)
			(xy 369.754925 -226.564124) (xy 369.774873 -226.517304) (xy 369.802074 -226.47429) (xy 369.835822 -226.436196)
			(xy 369.875244 -226.404009) (xy 369.919318 -226.378563) (xy 369.966904 -226.360516) (xy 370.016768 -226.350336)
			(xy 370.06762 -226.348287) (xy 370.118141 -226.354421) (xy 370.167025 -226.368581) (xy 370.213004 -226.390398)
			(xy 370.254888 -226.419308) (xy 370.291592 -226.454563) (xy 370.322165 -226.495249) (xy 370.345816 -226.540312)
			(xy 370.361932 -226.588586) (xy 370.370096 -226.63882) (xy 370.370608 -226.664266) (xy 370.678451 -226.664266)
			(xy 370.682546 -226.613538) (xy 370.694725 -226.564124) (xy 370.714673 -226.517304) (xy 370.741874 -226.47429)
			(xy 370.775622 -226.436196) (xy 370.815044 -226.404009) (xy 370.859118 -226.378563) (xy 370.906704 -226.360516)
			(xy 370.956568 -226.350336) (xy 371.00742 -226.348287) (xy 371.057941 -226.354421) (xy 371.106825 -226.368581)
			(xy 371.152804 -226.390398) (xy 371.194688 -226.419308) (xy 371.231392 -226.454563) (xy 371.261965 -226.495249)
			(xy 371.285616 -226.540312) (xy 371.301732 -226.588586) (xy 371.309896 -226.63882) (xy 371.310408 -226.664266)
			(xy 371.309905 -226.689255) (xy 371.617222 -226.689255) (xy 371.617222 -226.639277) (xy 371.625041 -226.589914)
			(xy 371.640485 -226.542382) (xy 371.663175 -226.49785) (xy 371.692551 -226.457417) (xy 371.727891 -226.422077)
			(xy 371.768324 -226.392701) (xy 371.812856 -226.370011) (xy 371.860388 -226.354567) (xy 371.909751 -226.346748)
			(xy 371.959729 -226.346748) (xy 372.009092 -226.354567) (xy 372.056624 -226.370011) (xy 372.101156 -226.392701)
			(xy 372.141589 -226.422077) (xy 372.176929 -226.457417) (xy 372.206305 -226.49785) (xy 372.228995 -226.542382)
			(xy 372.244439 -226.589914) (xy 372.252258 -226.639277) (xy 372.252748 -226.664266) (xy 372.558559 -226.664266)
			(xy 372.562654 -226.613538) (xy 372.574833 -226.564124) (xy 372.594781 -226.517304) (xy 372.621982 -226.47429)
			(xy 372.65573 -226.436196) (xy 372.695152 -226.404009) (xy 372.739226 -226.378563) (xy 372.786812 -226.360516)
			(xy 372.836676 -226.350336) (xy 372.887528 -226.348287) (xy 372.938049 -226.354421) (xy 372.986933 -226.368581)
			(xy 373.032912 -226.390398) (xy 373.074796 -226.419308) (xy 373.1115 -226.454563) (xy 373.142073 -226.495249)
			(xy 373.165724 -226.540312) (xy 373.18184 -226.588586) (xy 373.190004 -226.63882) (xy 373.190516 -226.664266)
			(xy 373.498613 -226.664266) (xy 373.502708 -226.613538) (xy 373.514887 -226.564124) (xy 373.534835 -226.517304)
			(xy 373.562036 -226.47429) (xy 373.595784 -226.436196) (xy 373.635206 -226.404009) (xy 373.67928 -226.378563)
			(xy 373.726866 -226.360516) (xy 373.77673 -226.350336) (xy 373.827582 -226.348287) (xy 373.878103 -226.354421)
			(xy 373.926987 -226.368581) (xy 373.972966 -226.390398) (xy 374.01485 -226.419308) (xy 374.051554 -226.454563)
			(xy 374.082127 -226.495249) (xy 374.105778 -226.540312) (xy 374.121894 -226.588586) (xy 374.130058 -226.63882)
			(xy 374.13057 -226.664266) (xy 374.130067 -226.689255) (xy 374.437384 -226.689255) (xy 374.437384 -226.639277)
			(xy 374.445203 -226.589914) (xy 374.460647 -226.542382) (xy 374.483337 -226.49785) (xy 374.512713 -226.457417)
			(xy 374.548053 -226.422077) (xy 374.588486 -226.392701) (xy 374.633018 -226.370011) (xy 374.68055 -226.354567)
			(xy 374.729913 -226.346748) (xy 374.779891 -226.346748) (xy 374.829254 -226.354567) (xy 374.876786 -226.370011)
			(xy 374.921318 -226.392701) (xy 374.961751 -226.422077) (xy 374.997091 -226.457417) (xy 375.026467 -226.49785)
			(xy 375.049157 -226.542382) (xy 375.064601 -226.589914) (xy 375.07242 -226.639277) (xy 375.07291 -226.664266)
			(xy 375.07242 -226.689255) (xy 375.064601 -226.738618) (xy 375.049157 -226.78615) (xy 375.026467 -226.830682)
			(xy 374.997091 -226.871115) (xy 374.961751 -226.906455) (xy 374.921318 -226.935831) (xy 374.876786 -226.958521)
			(xy 374.829254 -226.973965) (xy 374.779891 -226.981784) (xy 374.729913 -226.981784) (xy 374.68055 -226.973965)
			(xy 374.633018 -226.958521) (xy 374.588486 -226.935831) (xy 374.548053 -226.906455) (xy 374.512713 -226.871115)
			(xy 374.483337 -226.830682) (xy 374.460647 -226.78615) (xy 374.445203 -226.738618) (xy 374.437384 -226.689255)
			(xy 374.130067 -226.689255) (xy 374.130058 -226.689712) (xy 374.121894 -226.739946) (xy 374.105778 -226.78822)
			(xy 374.082127 -226.833283) (xy 374.051554 -226.873969) (xy 374.01485 -226.909224) (xy 373.972966 -226.938134)
			(xy 373.926987 -226.959951) (xy 373.878103 -226.974111) (xy 373.827582 -226.980245) (xy 373.77673 -226.978196)
			(xy 373.726866 -226.968016) (xy 373.67928 -226.949969) (xy 373.635206 -226.924523) (xy 373.595784 -226.892336)
			(xy 373.562036 -226.854242) (xy 373.534835 -226.811228) (xy 373.514887 -226.764408) (xy 373.502708 -226.714994)
			(xy 373.498613 -226.664266) (xy 373.190516 -226.664266) (xy 373.190004 -226.689712) (xy 373.18184 -226.739946)
			(xy 373.165724 -226.78822) (xy 373.142073 -226.833283) (xy 373.1115 -226.873969) (xy 373.074796 -226.909224)
			(xy 373.032912 -226.938134) (xy 372.986933 -226.959951) (xy 372.938049 -226.974111) (xy 372.887528 -226.980245)
			(xy 372.836676 -226.978196) (xy 372.786812 -226.968016) (xy 372.739226 -226.949969) (xy 372.695152 -226.924523)
			(xy 372.65573 -226.892336) (xy 372.621982 -226.854242) (xy 372.594781 -226.811228) (xy 372.574833 -226.764408)
			(xy 372.562654 -226.714994) (xy 372.558559 -226.664266) (xy 372.252748 -226.664266) (xy 372.252258 -226.689255)
			(xy 372.244439 -226.738618) (xy 372.228995 -226.78615) (xy 372.206305 -226.830682) (xy 372.176929 -226.871115)
			(xy 372.141589 -226.906455) (xy 372.101156 -226.935831) (xy 372.056624 -226.958521) (xy 372.009092 -226.973965)
			(xy 371.959729 -226.981784) (xy 371.909751 -226.981784) (xy 371.860388 -226.973965) (xy 371.812856 -226.958521)
			(xy 371.768324 -226.935831) (xy 371.727891 -226.906455) (xy 371.692551 -226.871115) (xy 371.663175 -226.830682)
			(xy 371.640485 -226.78615) (xy 371.625041 -226.738618) (xy 371.617222 -226.689255) (xy 371.309905 -226.689255)
			(xy 371.309896 -226.689712) (xy 371.301732 -226.739946) (xy 371.285616 -226.78822) (xy 371.261965 -226.833283)
			(xy 371.231392 -226.873969) (xy 371.194688 -226.909224) (xy 371.152804 -226.938134) (xy 371.106825 -226.959951)
			(xy 371.057941 -226.974111) (xy 371.00742 -226.980245) (xy 370.956568 -226.978196) (xy 370.906704 -226.968016)
			(xy 370.859118 -226.949969) (xy 370.815044 -226.924523) (xy 370.775622 -226.892336) (xy 370.741874 -226.854242)
			(xy 370.714673 -226.811228) (xy 370.694725 -226.764408) (xy 370.682546 -226.714994) (xy 370.678451 -226.664266)
			(xy 370.370608 -226.664266) (xy 370.370096 -226.689712) (xy 370.361932 -226.739946) (xy 370.345816 -226.78822)
			(xy 370.322165 -226.833283) (xy 370.291592 -226.873969) (xy 370.254888 -226.909224) (xy 370.213004 -226.938134)
			(xy 370.167025 -226.959951) (xy 370.118141 -226.974111) (xy 370.06762 -226.980245) (xy 370.016768 -226.978196)
			(xy 369.966904 -226.968016) (xy 369.919318 -226.949969) (xy 369.875244 -226.924523) (xy 369.835822 -226.892336)
			(xy 369.802074 -226.854242) (xy 369.774873 -226.811228) (xy 369.754925 -226.764408) (xy 369.742746 -226.714994)
			(xy 369.738651 -226.664266) (xy 369.43284 -226.664266) (xy 369.43235 -226.689255) (xy 369.424531 -226.738618)
			(xy 369.409087 -226.78615) (xy 369.386397 -226.830682) (xy 369.357021 -226.871115) (xy 369.321681 -226.906455)
			(xy 369.281248 -226.935831) (xy 369.236716 -226.958521) (xy 369.189184 -226.973965) (xy 369.139821 -226.981784)
			(xy 369.089843 -226.981784) (xy 369.04048 -226.973965) (xy 368.992948 -226.958521) (xy 368.948416 -226.935831)
			(xy 368.907983 -226.906455) (xy 368.872643 -226.871115) (xy 368.843267 -226.830682) (xy 368.820577 -226.78615)
			(xy 368.805133 -226.738618) (xy 368.797314 -226.689255) (xy 368.489997 -226.689255) (xy 368.489988 -226.689712)
			(xy 368.481824 -226.739946) (xy 368.465708 -226.78822) (xy 368.442057 -226.833283) (xy 368.411484 -226.873969)
			(xy 368.37478 -226.909224) (xy 368.332896 -226.938134) (xy 368.286917 -226.959951) (xy 368.238033 -226.974111)
			(xy 368.187512 -226.980245) (xy 368.13666 -226.978196) (xy 368.086796 -226.968016) (xy 368.03921 -226.949969)
			(xy 367.995136 -226.924523) (xy 367.955714 -226.892336) (xy 367.921966 -226.854242) (xy 367.894765 -226.811228)
			(xy 367.874817 -226.764408) (xy 367.862638 -226.714994) (xy 367.858543 -226.664266) (xy 367.550446 -226.664266)
			(xy 367.549934 -226.689712) (xy 367.54177 -226.739946) (xy 367.525654 -226.78822) (xy 367.502003 -226.833283)
			(xy 367.47143 -226.873969) (xy 367.434726 -226.909224) (xy 367.392842 -226.938134) (xy 367.346863 -226.959951)
			(xy 367.297979 -226.974111) (xy 367.247458 -226.980245) (xy 367.196606 -226.978196) (xy 367.146742 -226.968016)
			(xy 367.099156 -226.949969) (xy 367.055082 -226.924523) (xy 367.01566 -226.892336) (xy 366.981912 -226.854242)
			(xy 366.954711 -226.811228) (xy 366.934763 -226.764408) (xy 366.922584 -226.714994) (xy 366.918489 -226.664266)
			(xy 366.612932 -226.664266) (xy 366.612442 -226.689255) (xy 366.604623 -226.738618) (xy 366.589179 -226.78615)
			(xy 366.566489 -226.830682) (xy 366.537113 -226.871115) (xy 366.501773 -226.906455) (xy 366.46134 -226.935831)
			(xy 366.416808 -226.958521) (xy 366.369276 -226.973965) (xy 366.319913 -226.981784) (xy 366.269935 -226.981784)
			(xy 366.220572 -226.973965) (xy 366.17304 -226.958521) (xy 366.128508 -226.935831) (xy 366.088075 -226.906455)
			(xy 366.052735 -226.871115) (xy 366.023359 -226.830682) (xy 366.000669 -226.78615) (xy 365.985225 -226.738618)
			(xy 365.977406 -226.689255) (xy 365.670089 -226.689255) (xy 365.67008 -226.689712) (xy 365.661916 -226.739946)
			(xy 365.6458 -226.78822) (xy 365.622149 -226.833283) (xy 365.591576 -226.873969) (xy 365.554872 -226.909224)
			(xy 365.512988 -226.938134) (xy 365.467009 -226.959951) (xy 365.418125 -226.974111) (xy 365.367604 -226.980245)
			(xy 365.316752 -226.978196) (xy 365.266888 -226.968016) (xy 365.219302 -226.949969) (xy 365.175228 -226.924523)
			(xy 365.135806 -226.892336) (xy 365.102058 -226.854242) (xy 365.074857 -226.811228) (xy 365.054909 -226.764408)
			(xy 365.04273 -226.714994) (xy 365.038635 -226.664266) (xy 364.730538 -226.664266) (xy 364.730026 -226.689712)
			(xy 364.721862 -226.739946) (xy 364.705746 -226.78822) (xy 364.682095 -226.833283) (xy 364.651522 -226.873969)
			(xy 364.614818 -226.909224) (xy 364.572934 -226.938134) (xy 364.526955 -226.959951) (xy 364.478071 -226.974111)
			(xy 364.42755 -226.980245) (xy 364.376698 -226.978196) (xy 364.326834 -226.968016) (xy 364.279248 -226.949969)
			(xy 364.235174 -226.924523) (xy 364.195752 -226.892336) (xy 364.162004 -226.854242) (xy 364.134803 -226.811228)
			(xy 364.114855 -226.764408) (xy 364.102676 -226.714994) (xy 364.098581 -226.664266) (xy 363.79277 -226.664266)
			(xy 363.79228 -226.689255) (xy 363.784461 -226.738618) (xy 363.769017 -226.78615) (xy 363.746327 -226.830682)
			(xy 363.716951 -226.871115) (xy 363.681611 -226.906455) (xy 363.641178 -226.935831) (xy 363.596646 -226.958521)
			(xy 363.549114 -226.973965) (xy 363.499751 -226.981784) (xy 363.449773 -226.981784) (xy 363.40041 -226.973965)
			(xy 363.352878 -226.958521) (xy 363.308346 -226.935831) (xy 363.267913 -226.906455) (xy 363.232573 -226.871115)
			(xy 363.203197 -226.830682) (xy 363.180507 -226.78615) (xy 363.165063 -226.738618) (xy 363.157244 -226.689255)
			(xy 356.278706 -226.689255) (xy 356.270887 -226.738618) (xy 356.255443 -226.78615) (xy 356.232753 -226.830682)
			(xy 356.203377 -226.871115) (xy 356.168037 -226.906455) (xy 356.127604 -226.935831) (xy 356.083072 -226.958521)
			(xy 356.03554 -226.973965) (xy 355.986177 -226.981784) (xy 355.936199 -226.981784) (xy 355.886836 -226.973965)
			(xy 355.839304 -226.958521) (xy 355.794772 -226.935831) (xy 355.754339 -226.906455) (xy 355.718999 -226.871115)
			(xy 355.689623 -226.830682) (xy 355.666933 -226.78615) (xy 355.651489 -226.738618) (xy 355.64367 -226.689255)
			(xy 355.336353 -226.689255) (xy 355.336344 -226.689712) (xy 355.32818 -226.739946) (xy 355.312064 -226.78822)
			(xy 355.288413 -226.833283) (xy 355.25784 -226.873969) (xy 355.221136 -226.909224) (xy 355.179252 -226.938134)
			(xy 355.133273 -226.959951) (xy 355.084389 -226.974111) (xy 355.033868 -226.980245) (xy 354.983016 -226.978196)
			(xy 354.933152 -226.968016) (xy 354.885566 -226.949969) (xy 354.841492 -226.924523) (xy 354.80207 -226.892336)
			(xy 354.768322 -226.854242) (xy 354.741121 -226.811228) (xy 354.721173 -226.764408) (xy 354.708994 -226.714994)
			(xy 354.704899 -226.664266) (xy 354.396802 -226.664266) (xy 354.39629 -226.689712) (xy 354.388126 -226.739946)
			(xy 354.37201 -226.78822) (xy 354.348359 -226.833283) (xy 354.317786 -226.873969) (xy 354.281082 -226.909224)
			(xy 354.239198 -226.938134) (xy 354.193219 -226.959951) (xy 354.144335 -226.974111) (xy 354.093814 -226.980245)
			(xy 354.042962 -226.978196) (xy 353.993098 -226.968016) (xy 353.945512 -226.949969) (xy 353.901438 -226.924523)
			(xy 353.862016 -226.892336) (xy 353.828268 -226.854242) (xy 353.801067 -226.811228) (xy 353.781119 -226.764408)
			(xy 353.76894 -226.714994) (xy 353.764845 -226.664266) (xy 353.459034 -226.664266) (xy 353.458544 -226.689255)
			(xy 353.450725 -226.738618) (xy 353.435281 -226.78615) (xy 353.412591 -226.830682) (xy 353.383215 -226.871115)
			(xy 353.347875 -226.906455) (xy 353.307442 -226.935831) (xy 353.26291 -226.958521) (xy 353.215378 -226.973965)
			(xy 353.166015 -226.981784) (xy 353.116037 -226.981784) (xy 353.066674 -226.973965) (xy 353.019142 -226.958521)
			(xy 352.97461 -226.935831) (xy 352.934177 -226.906455) (xy 352.898837 -226.871115) (xy 352.869461 -226.830682)
			(xy 352.846771 -226.78615) (xy 352.831327 -226.738618) (xy 352.823508 -226.689255) (xy 352.516445 -226.689255)
			(xy 352.516436 -226.689712) (xy 352.508272 -226.739946) (xy 352.492156 -226.78822) (xy 352.468505 -226.833283)
			(xy 352.437932 -226.873969) (xy 352.401228 -226.909224) (xy 352.359344 -226.938134) (xy 352.313365 -226.959951)
			(xy 352.264481 -226.974111) (xy 352.21396 -226.980245) (xy 352.163108 -226.978196) (xy 352.113244 -226.968016)
			(xy 352.065658 -226.949969) (xy 352.021584 -226.924523) (xy 351.982162 -226.892336) (xy 351.948414 -226.854242)
			(xy 351.921213 -226.811228) (xy 351.901265 -226.764408) (xy 351.889086 -226.714994) (xy 351.884991 -226.664266)
			(xy 351.576894 -226.664266) (xy 351.576382 -226.689712) (xy 351.568218 -226.739946) (xy 351.552102 -226.78822)
			(xy 351.528451 -226.833283) (xy 351.497878 -226.873969) (xy 351.461174 -226.909224) (xy 351.41929 -226.938134)
			(xy 351.373311 -226.959951) (xy 351.324427 -226.974111) (xy 351.273906 -226.980245) (xy 351.223054 -226.978196)
			(xy 351.17319 -226.968016) (xy 351.125604 -226.949969) (xy 351.08153 -226.924523) (xy 351.042108 -226.892336)
			(xy 351.00836 -226.854242) (xy 350.981159 -226.811228) (xy 350.961211 -226.764408) (xy 350.949032 -226.714994)
			(xy 350.944937 -226.664266) (xy 350.639126 -226.664266) (xy 350.638636 -226.689255) (xy 350.630817 -226.738618)
			(xy 350.615373 -226.78615) (xy 350.592683 -226.830682) (xy 350.563307 -226.871115) (xy 350.527967 -226.906455)
			(xy 350.487534 -226.935831) (xy 350.443002 -226.958521) (xy 350.39547 -226.973965) (xy 350.346107 -226.981784)
			(xy 350.296129 -226.981784) (xy 350.246766 -226.973965) (xy 350.199234 -226.958521) (xy 350.154702 -226.935831)
			(xy 350.114269 -226.906455) (xy 350.078929 -226.871115) (xy 350.049553 -226.830682) (xy 350.026863 -226.78615)
			(xy 350.011419 -226.738618) (xy 350.0036 -226.689255) (xy 349.696283 -226.689255) (xy 349.696274 -226.689712)
			(xy 349.68811 -226.739946) (xy 349.671994 -226.78822) (xy 349.648343 -226.833283) (xy 349.61777 -226.873969)
			(xy 349.581066 -226.909224) (xy 349.539182 -226.938134) (xy 349.493203 -226.959951) (xy 349.444319 -226.974111)
			(xy 349.393798 -226.980245) (xy 349.342946 -226.978196) (xy 349.293082 -226.968016) (xy 349.245496 -226.949969)
			(xy 349.201422 -226.924523) (xy 349.162 -226.892336) (xy 349.128252 -226.854242) (xy 349.101051 -226.811228)
			(xy 349.081103 -226.764408) (xy 349.068924 -226.714994) (xy 349.064829 -226.664266) (xy 348.756732 -226.664266)
			(xy 348.75622 -226.689712) (xy 348.748056 -226.739946) (xy 348.73194 -226.78822) (xy 348.708289 -226.833283)
			(xy 348.677716 -226.873969) (xy 348.641012 -226.909224) (xy 348.599128 -226.938134) (xy 348.553149 -226.959951)
			(xy 348.504265 -226.974111) (xy 348.453744 -226.980245) (xy 348.402892 -226.978196) (xy 348.353028 -226.968016)
			(xy 348.305442 -226.949969) (xy 348.261368 -226.924523) (xy 348.221946 -226.892336) (xy 348.188198 -226.854242)
			(xy 348.160997 -226.811228) (xy 348.141049 -226.764408) (xy 348.12887 -226.714994) (xy 348.124775 -226.664266)
			(xy 347.819218 -226.664266) (xy 347.818728 -226.689255) (xy 347.810909 -226.738618) (xy 347.795465 -226.78615)
			(xy 347.772775 -226.830682) (xy 347.743399 -226.871115) (xy 347.708059 -226.906455) (xy 347.667626 -226.935831)
			(xy 347.623094 -226.958521) (xy 347.575562 -226.973965) (xy 347.526199 -226.981784) (xy 347.476221 -226.981784)
			(xy 347.426858 -226.973965) (xy 347.379326 -226.958521) (xy 347.334794 -226.935831) (xy 347.294361 -226.906455)
			(xy 347.259021 -226.871115) (xy 347.229645 -226.830682) (xy 347.206955 -226.78615) (xy 347.191511 -226.738618)
			(xy 347.183692 -226.689255) (xy 346.876375 -226.689255) (xy 346.876366 -226.689712) (xy 346.868202 -226.739946)
			(xy 346.852086 -226.78822) (xy 346.828435 -226.833283) (xy 346.797862 -226.873969) (xy 346.761158 -226.909224)
			(xy 346.719274 -226.938134) (xy 346.673295 -226.959951) (xy 346.624411 -226.974111) (xy 346.57389 -226.980245)
			(xy 346.523038 -226.978196) (xy 346.473174 -226.968016) (xy 346.425588 -226.949969) (xy 346.381514 -226.924523)
			(xy 346.342092 -226.892336) (xy 346.308344 -226.854242) (xy 346.281143 -226.811228) (xy 346.261195 -226.764408)
			(xy 346.249016 -226.714994) (xy 346.244921 -226.664266) (xy 345.936824 -226.664266) (xy 345.936312 -226.689712)
			(xy 345.928148 -226.739946) (xy 345.912032 -226.78822) (xy 345.888381 -226.833283) (xy 345.857808 -226.873969)
			(xy 345.821104 -226.909224) (xy 345.77922 -226.938134) (xy 345.733241 -226.959951) (xy 345.684357 -226.974111)
			(xy 345.633836 -226.980245) (xy 345.582984 -226.978196) (xy 345.53312 -226.968016) (xy 345.485534 -226.949969)
			(xy 345.44146 -226.924523) (xy 345.402038 -226.892336) (xy 345.36829 -226.854242) (xy 345.341089 -226.811228)
			(xy 345.321141 -226.764408) (xy 345.308962 -226.714994) (xy 345.304867 -226.664266) (xy 344.999056 -226.664266)
			(xy 344.998566 -226.689255) (xy 344.990747 -226.738618) (xy 344.975303 -226.78615) (xy 344.952613 -226.830682)
			(xy 344.923237 -226.871115) (xy 344.887897 -226.906455) (xy 344.847464 -226.935831) (xy 344.802932 -226.958521)
			(xy 344.7554 -226.973965) (xy 344.706037 -226.981784) (xy 344.656059 -226.981784) (xy 344.606696 -226.973965)
			(xy 344.559164 -226.958521) (xy 344.514632 -226.935831) (xy 344.474199 -226.906455) (xy 344.438859 -226.871115)
			(xy 344.409483 -226.830682) (xy 344.386793 -226.78615) (xy 344.371349 -226.738618) (xy 344.36353 -226.689255)
			(xy 344.056213 -226.689255) (xy 344.056204 -226.689712) (xy 344.04804 -226.739946) (xy 344.031924 -226.78822)
			(xy 344.008273 -226.833283) (xy 343.9777 -226.873969) (xy 343.940996 -226.909224) (xy 343.899112 -226.938134)
			(xy 343.853133 -226.959951) (xy 343.804249 -226.974111) (xy 343.753728 -226.980245) (xy 343.702876 -226.978196)
			(xy 343.653012 -226.968016) (xy 343.605426 -226.949969) (xy 343.561352 -226.924523) (xy 343.52193 -226.892336)
			(xy 343.488182 -226.854242) (xy 343.460981 -226.811228) (xy 343.441033 -226.764408) (xy 343.428854 -226.714994)
			(xy 343.424759 -226.664266) (xy 343.119202 -226.664266) (xy 343.118712 -226.689255) (xy 343.110893 -226.738618)
			(xy 343.095449 -226.78615) (xy 343.072759 -226.830682) (xy 343.043383 -226.871115) (xy 343.008043 -226.906455)
			(xy 342.96761 -226.935831) (xy 342.923078 -226.958521) (xy 342.875546 -226.973965) (xy 342.826183 -226.981784)
			(xy 342.776205 -226.981784) (xy 342.726842 -226.973965) (xy 342.67931 -226.958521) (xy 342.634778 -226.935831)
			(xy 342.594345 -226.906455) (xy 342.559005 -226.871115) (xy 342.529629 -226.830682) (xy 342.506939 -226.78615)
			(xy 342.491495 -226.738618) (xy 342.483676 -226.689255) (xy 342.176359 -226.689255) (xy 342.17635 -226.689712)
			(xy 342.168186 -226.739946) (xy 342.15207 -226.78822) (xy 342.128419 -226.833283) (xy 342.097846 -226.873969)
			(xy 342.061142 -226.909224) (xy 342.019258 -226.938134) (xy 341.973279 -226.959951) (xy 341.924395 -226.974111)
			(xy 341.873874 -226.980245) (xy 341.823022 -226.978196) (xy 341.773158 -226.968016) (xy 341.725572 -226.949969)
			(xy 341.681498 -226.924523) (xy 341.642076 -226.892336) (xy 341.608328 -226.854242) (xy 341.581127 -226.811228)
			(xy 341.561179 -226.764408) (xy 341.549 -226.714994) (xy 341.544905 -226.664266) (xy 341.239094 -226.664266)
			(xy 341.238604 -226.689255) (xy 341.230785 -226.738618) (xy 341.215341 -226.78615) (xy 341.192651 -226.830682)
			(xy 341.163275 -226.871115) (xy 341.127935 -226.906455) (xy 341.087502 -226.935831) (xy 341.04297 -226.958521)
			(xy 340.995438 -226.973965) (xy 340.946075 -226.981784) (xy 340.896097 -226.981784) (xy 340.846734 -226.973965)
			(xy 340.799202 -226.958521) (xy 340.75467 -226.935831) (xy 340.714237 -226.906455) (xy 340.678897 -226.871115)
			(xy 340.649521 -226.830682) (xy 340.626831 -226.78615) (xy 340.611387 -226.738618) (xy 340.603568 -226.689255)
			(xy 340.296251 -226.689255) (xy 340.296242 -226.689712) (xy 340.288078 -226.739946) (xy 340.271962 -226.78822)
			(xy 340.248311 -226.833283) (xy 340.217738 -226.873969) (xy 340.181034 -226.909224) (xy 340.13915 -226.938134)
			(xy 340.093171 -226.959951) (xy 340.044287 -226.974111) (xy 339.993766 -226.980245) (xy 339.942914 -226.978196)
			(xy 339.89305 -226.968016) (xy 339.845464 -226.949969) (xy 339.80139 -226.924523) (xy 339.761968 -226.892336)
			(xy 339.72822 -226.854242) (xy 339.701019 -226.811228) (xy 339.681071 -226.764408) (xy 339.668892 -226.714994)
			(xy 339.664797 -226.664266) (xy 339.3567 -226.664266) (xy 339.356188 -226.689712) (xy 339.348024 -226.739946)
			(xy 339.331908 -226.78822) (xy 339.308257 -226.833283) (xy 339.277684 -226.873969) (xy 339.24098 -226.909224)
			(xy 339.199096 -226.938134) (xy 339.153117 -226.959951) (xy 339.104233 -226.974111) (xy 339.053712 -226.980245)
			(xy 339.00286 -226.978196) (xy 338.952996 -226.968016) (xy 338.90541 -226.949969) (xy 338.861336 -226.924523)
			(xy 338.821914 -226.892336) (xy 338.788166 -226.854242) (xy 338.760965 -226.811228) (xy 338.741017 -226.764408)
			(xy 338.728838 -226.714994) (xy 338.724743 -226.664266) (xy 338.419186 -226.664266) (xy 338.418902 -226.682791)
			(xy 338.414578 -226.719588) (xy 338.41055 -226.737672) (xy 338.40928 -226.74326) (xy 338.40928 -226.757738)
			(xy 338.409415 -226.762629) (xy 338.41133 -226.772223) (xy 338.41309 -226.776788) (xy 338.4169 -226.785678)
			(xy 338.7598 -227.128578) (xy 338.762866 -227.131469) (xy 338.769763 -227.136312) (xy 338.773516 -227.13823)
			(xy 338.775548 -227.138992) (xy 338.780388 -227.140995) (xy 338.790632 -227.143172) (xy 338.795868 -227.14331)
			(xy 344.595958 -227.14331) (xy 344.605796 -227.143844) (xy 344.623959 -227.151429) (xy 344.631264 -227.158042)
			(xy 344.972483 -227.499261) (xy 346.713538 -227.499261) (xy 346.713538 -227.449283) (xy 346.721357 -227.39992)
			(xy 346.736801 -227.352388) (xy 346.759491 -227.307856) (xy 346.788867 -227.267423) (xy 346.824207 -227.232083)
			(xy 346.86464 -227.202707) (xy 346.909172 -227.180017) (xy 346.956704 -227.164573) (xy 347.006067 -227.156754)
			(xy 347.056045 -227.156754) (xy 347.105408 -227.164573) (xy 347.15294 -227.180017) (xy 347.197472 -227.202707)
			(xy 347.237905 -227.232083) (xy 347.273245 -227.267423) (xy 347.302621 -227.307856) (xy 347.325311 -227.352388)
			(xy 347.340755 -227.39992) (xy 347.348574 -227.449283) (xy 347.349064 -227.474272) (xy 347.348574 -227.499261)
			(xy 349.5337 -227.499261) (xy 349.5337 -227.449283) (xy 349.541519 -227.39992) (xy 349.556963 -227.352388)
			(xy 349.579653 -227.307856) (xy 349.609029 -227.267423) (xy 349.644369 -227.232083) (xy 349.684802 -227.202707)
			(xy 349.729334 -227.180017) (xy 349.776866 -227.164573) (xy 349.826229 -227.156754) (xy 349.876207 -227.156754)
			(xy 349.92557 -227.164573) (xy 349.973102 -227.180017) (xy 350.017634 -227.202707) (xy 350.058067 -227.232083)
			(xy 350.093407 -227.267423) (xy 350.122783 -227.307856) (xy 350.145473 -227.352388) (xy 350.160917 -227.39992)
			(xy 350.168736 -227.449283) (xy 350.169226 -227.474272) (xy 350.168736 -227.499261) (xy 352.353608 -227.499261)
			(xy 352.353608 -227.449283) (xy 352.361427 -227.39992) (xy 352.376871 -227.352388) (xy 352.399561 -227.307856)
			(xy 352.428937 -227.267423) (xy 352.464277 -227.232083) (xy 352.50471 -227.202707) (xy 352.549242 -227.180017)
			(xy 352.596774 -227.164573) (xy 352.646137 -227.156754) (xy 352.696115 -227.156754) (xy 352.745478 -227.164573)
			(xy 352.79301 -227.180017) (xy 352.837542 -227.202707) (xy 352.877975 -227.232083) (xy 352.913315 -227.267423)
			(xy 352.942691 -227.307856) (xy 352.965381 -227.352388) (xy 352.980825 -227.39992) (xy 352.988644 -227.449283)
			(xy 352.989134 -227.474272) (xy 352.988644 -227.499261) (xy 355.173516 -227.499261) (xy 355.173516 -227.449283)
			(xy 355.181335 -227.39992) (xy 355.196779 -227.352388) (xy 355.219469 -227.307856) (xy 355.248845 -227.267423)
			(xy 355.284185 -227.232083) (xy 355.324618 -227.202707) (xy 355.36915 -227.180017) (xy 355.416682 -227.164573)
			(xy 355.466045 -227.156754) (xy 355.516023 -227.156754) (xy 355.565386 -227.164573) (xy 355.612918 -227.180017)
			(xy 355.65745 -227.202707) (xy 355.697883 -227.232083) (xy 355.733223 -227.267423) (xy 355.762599 -227.307856)
			(xy 355.785289 -227.352388) (xy 355.800733 -227.39992) (xy 355.808552 -227.449283) (xy 355.809042 -227.474272)
			(xy 356.114853 -227.474272) (xy 356.118948 -227.423544) (xy 356.131127 -227.37413) (xy 356.151075 -227.32731)
			(xy 356.178276 -227.284296) (xy 356.212024 -227.246202) (xy 356.251446 -227.214015) (xy 356.29552 -227.188569)
			(xy 356.343106 -227.170522) (xy 356.39297 -227.160342) (xy 356.443822 -227.158293) (xy 356.494343 -227.164427)
			(xy 356.543227 -227.178587) (xy 356.589206 -227.200404) (xy 356.63109 -227.229314) (xy 356.667794 -227.264569)
			(xy 356.698367 -227.305255) (xy 356.722018 -227.350318) (xy 356.738134 -227.398592) (xy 356.746298 -227.448826)
			(xy 356.74681 -227.474272) (xy 357.054907 -227.474272) (xy 357.059002 -227.423544) (xy 357.071181 -227.37413)
			(xy 357.091129 -227.32731) (xy 357.11833 -227.284296) (xy 357.152078 -227.246202) (xy 357.1915 -227.214015)
			(xy 357.235574 -227.188569) (xy 357.28316 -227.170522) (xy 357.333024 -227.160342) (xy 357.383876 -227.158293)
			(xy 357.434397 -227.164427) (xy 357.483281 -227.178587) (xy 357.52926 -227.200404) (xy 357.571144 -227.229314)
			(xy 357.607848 -227.264569) (xy 357.638421 -227.305255) (xy 357.662072 -227.350318) (xy 357.678188 -227.398592)
			(xy 357.686352 -227.448826) (xy 357.686864 -227.474272) (xy 357.686361 -227.499261) (xy 357.993678 -227.499261)
			(xy 357.993678 -227.449283) (xy 358.001497 -227.39992) (xy 358.016941 -227.352388) (xy 358.039631 -227.307856)
			(xy 358.069007 -227.267423) (xy 358.104347 -227.232083) (xy 358.14478 -227.202707) (xy 358.189312 -227.180017)
			(xy 358.236844 -227.164573) (xy 358.286207 -227.156754) (xy 358.336185 -227.156754) (xy 358.385548 -227.164573)
			(xy 358.43308 -227.180017) (xy 358.477612 -227.202707) (xy 358.518045 -227.232083) (xy 358.553385 -227.267423)
			(xy 358.582761 -227.307856) (xy 358.605451 -227.352388) (xy 358.620895 -227.39992) (xy 358.628714 -227.449283)
			(xy 358.629204 -227.474272) (xy 358.628714 -227.499261) (xy 360.807236 -227.499261) (xy 360.807236 -227.449283)
			(xy 360.815055 -227.39992) (xy 360.830499 -227.352388) (xy 360.853189 -227.307856) (xy 360.882565 -227.267423)
			(xy 360.917905 -227.232083) (xy 360.958338 -227.202707) (xy 361.00287 -227.180017) (xy 361.050402 -227.164573)
			(xy 361.099765 -227.156754) (xy 361.149743 -227.156754) (xy 361.199106 -227.164573) (xy 361.246638 -227.180017)
			(xy 361.29117 -227.202707) (xy 361.331603 -227.232083) (xy 361.366943 -227.267423) (xy 361.396319 -227.307856)
			(xy 361.419009 -227.352388) (xy 361.434453 -227.39992) (xy 361.442272 -227.449283) (xy 361.442762 -227.474272)
			(xy 361.748573 -227.474272) (xy 361.752668 -227.423544) (xy 361.764847 -227.37413) (xy 361.784795 -227.32731)
			(xy 361.811996 -227.284296) (xy 361.845744 -227.246202) (xy 361.885166 -227.214015) (xy 361.92924 -227.188569)
			(xy 361.976826 -227.170522) (xy 362.02669 -227.160342) (xy 362.077542 -227.158293) (xy 362.128063 -227.164427)
			(xy 362.176947 -227.178587) (xy 362.222926 -227.200404) (xy 362.26481 -227.229314) (xy 362.301514 -227.264569)
			(xy 362.332087 -227.305255) (xy 362.355738 -227.350318) (xy 362.371854 -227.398592) (xy 362.380018 -227.448826)
			(xy 362.38053 -227.474272) (xy 362.688627 -227.474272) (xy 362.692722 -227.423544) (xy 362.704901 -227.37413)
			(xy 362.724849 -227.32731) (xy 362.75205 -227.284296) (xy 362.785798 -227.246202) (xy 362.82522 -227.214015)
			(xy 362.869294 -227.188569) (xy 362.91688 -227.170522) (xy 362.966744 -227.160342) (xy 363.017596 -227.158293)
			(xy 363.068117 -227.164427) (xy 363.117001 -227.178587) (xy 363.16298 -227.200404) (xy 363.204864 -227.229314)
			(xy 363.241568 -227.264569) (xy 363.272141 -227.305255) (xy 363.295792 -227.350318) (xy 363.311908 -227.398592)
			(xy 363.320072 -227.448826) (xy 363.320584 -227.474272) (xy 363.320081 -227.499261) (xy 363.627398 -227.499261)
			(xy 363.627398 -227.449283) (xy 363.635217 -227.39992) (xy 363.650661 -227.352388) (xy 363.673351 -227.307856)
			(xy 363.702727 -227.267423) (xy 363.738067 -227.232083) (xy 363.7785 -227.202707) (xy 363.823032 -227.180017)
			(xy 363.870564 -227.164573) (xy 363.919927 -227.156754) (xy 363.969905 -227.156754) (xy 364.019268 -227.164573)
			(xy 364.0668 -227.180017) (xy 364.111332 -227.202707) (xy 364.151765 -227.232083) (xy 364.187105 -227.267423)
			(xy 364.216481 -227.307856) (xy 364.239171 -227.352388) (xy 364.254615 -227.39992) (xy 364.262434 -227.449283)
			(xy 364.262924 -227.474272) (xy 364.262434 -227.499261) (xy 366.447306 -227.499261) (xy 366.447306 -227.449283)
			(xy 366.455125 -227.39992) (xy 366.470569 -227.352388) (xy 366.493259 -227.307856) (xy 366.522635 -227.267423)
			(xy 366.557975 -227.232083) (xy 366.598408 -227.202707) (xy 366.64294 -227.180017) (xy 366.690472 -227.164573)
			(xy 366.739835 -227.156754) (xy 366.789813 -227.156754) (xy 366.839176 -227.164573) (xy 366.886708 -227.180017)
			(xy 366.93124 -227.202707) (xy 366.971673 -227.232083) (xy 367.007013 -227.267423) (xy 367.036389 -227.307856)
			(xy 367.059079 -227.352388) (xy 367.074523 -227.39992) (xy 367.082342 -227.449283) (xy 367.082832 -227.474272)
			(xy 367.082342 -227.499261) (xy 369.267214 -227.499261) (xy 369.267214 -227.449283) (xy 369.275033 -227.39992)
			(xy 369.290477 -227.352388) (xy 369.313167 -227.307856) (xy 369.342543 -227.267423) (xy 369.377883 -227.232083)
			(xy 369.418316 -227.202707) (xy 369.462848 -227.180017) (xy 369.51038 -227.164573) (xy 369.559743 -227.156754)
			(xy 369.609721 -227.156754) (xy 369.659084 -227.164573) (xy 369.706616 -227.180017) (xy 369.751148 -227.202707)
			(xy 369.791581 -227.232083) (xy 369.826921 -227.267423) (xy 369.856297 -227.307856) (xy 369.878987 -227.352388)
			(xy 369.894431 -227.39992) (xy 369.90225 -227.449283) (xy 369.90274 -227.474272) (xy 369.90225 -227.499261)
			(xy 372.087376 -227.499261) (xy 372.087376 -227.449283) (xy 372.095195 -227.39992) (xy 372.110639 -227.352388)
			(xy 372.133329 -227.307856) (xy 372.162705 -227.267423) (xy 372.198045 -227.232083) (xy 372.238478 -227.202707)
			(xy 372.28301 -227.180017) (xy 372.330542 -227.164573) (xy 372.379905 -227.156754) (xy 372.429883 -227.156754)
			(xy 372.479246 -227.164573) (xy 372.526778 -227.180017) (xy 372.57131 -227.202707) (xy 372.611743 -227.232083)
			(xy 372.647083 -227.267423) (xy 372.676459 -227.307856) (xy 372.699149 -227.352388) (xy 372.714593 -227.39992)
			(xy 372.722412 -227.449283) (xy 372.722902 -227.474272) (xy 372.722412 -227.499261) (xy 372.714593 -227.548624)
			(xy 372.699149 -227.596156) (xy 372.676459 -227.640688) (xy 372.647083 -227.681121) (xy 372.611743 -227.716461)
			(xy 372.57131 -227.745837) (xy 372.526778 -227.768527) (xy 372.479246 -227.783971) (xy 372.429883 -227.79179)
			(xy 372.379905 -227.79179) (xy 372.330542 -227.783971) (xy 372.28301 -227.768527) (xy 372.238478 -227.745837)
			(xy 372.198045 -227.716461) (xy 372.162705 -227.681121) (xy 372.133329 -227.640688) (xy 372.110639 -227.596156)
			(xy 372.095195 -227.548624) (xy 372.087376 -227.499261) (xy 369.90225 -227.499261) (xy 369.894431 -227.548624)
			(xy 369.878987 -227.596156) (xy 369.856297 -227.640688) (xy 369.826921 -227.681121) (xy 369.791581 -227.716461)
			(xy 369.751148 -227.745837) (xy 369.706616 -227.768527) (xy 369.659084 -227.783971) (xy 369.609721 -227.79179)
			(xy 369.559743 -227.79179) (xy 369.51038 -227.783971) (xy 369.462848 -227.768527) (xy 369.418316 -227.745837)
			(xy 369.377883 -227.716461) (xy 369.342543 -227.681121) (xy 369.313167 -227.640688) (xy 369.290477 -227.596156)
			(xy 369.275033 -227.548624) (xy 369.267214 -227.499261) (xy 367.082342 -227.499261) (xy 367.074523 -227.548624)
			(xy 367.059079 -227.596156) (xy 367.036389 -227.640688) (xy 367.007013 -227.681121) (xy 366.971673 -227.716461)
			(xy 366.93124 -227.745837) (xy 366.886708 -227.768527) (xy 366.839176 -227.783971) (xy 366.789813 -227.79179)
			(xy 366.739835 -227.79179) (xy 366.690472 -227.783971) (xy 366.64294 -227.768527) (xy 366.598408 -227.745837)
			(xy 366.557975 -227.716461) (xy 366.522635 -227.681121) (xy 366.493259 -227.640688) (xy 366.470569 -227.596156)
			(xy 366.455125 -227.548624) (xy 366.447306 -227.499261) (xy 364.262434 -227.499261) (xy 364.254615 -227.548624)
			(xy 364.239171 -227.596156) (xy 364.216481 -227.640688) (xy 364.187105 -227.681121) (xy 364.151765 -227.716461)
			(xy 364.111332 -227.745837) (xy 364.0668 -227.768527) (xy 364.019268 -227.783971) (xy 363.969905 -227.79179)
			(xy 363.919927 -227.79179) (xy 363.870564 -227.783971) (xy 363.823032 -227.768527) (xy 363.7785 -227.745837)
			(xy 363.738067 -227.716461) (xy 363.702727 -227.681121) (xy 363.673351 -227.640688) (xy 363.650661 -227.596156)
			(xy 363.635217 -227.548624) (xy 363.627398 -227.499261) (xy 363.320081 -227.499261) (xy 363.320072 -227.499718)
			(xy 363.311908 -227.549952) (xy 363.295792 -227.598226) (xy 363.272141 -227.643289) (xy 363.241568 -227.683975)
			(xy 363.204864 -227.71923) (xy 363.16298 -227.74814) (xy 363.117001 -227.769957) (xy 363.068117 -227.784117)
			(xy 363.017596 -227.790251) (xy 362.966744 -227.788202) (xy 362.91688 -227.778022) (xy 362.869294 -227.759975)
			(xy 362.82522 -227.734529) (xy 362.785798 -227.702342) (xy 362.75205 -227.664248) (xy 362.724849 -227.621234)
			(xy 362.704901 -227.574414) (xy 362.692722 -227.525) (xy 362.688627 -227.474272) (xy 362.38053 -227.474272)
			(xy 362.380018 -227.499718) (xy 362.371854 -227.549952) (xy 362.355738 -227.598226) (xy 362.332087 -227.643289)
			(xy 362.301514 -227.683975) (xy 362.26481 -227.71923) (xy 362.222926 -227.74814) (xy 362.176947 -227.769957)
			(xy 362.128063 -227.784117) (xy 362.077542 -227.790251) (xy 362.02669 -227.788202) (xy 361.976826 -227.778022)
			(xy 361.92924 -227.759975) (xy 361.885166 -227.734529) (xy 361.845744 -227.702342) (xy 361.811996 -227.664248)
			(xy 361.784795 -227.621234) (xy 361.764847 -227.574414) (xy 361.752668 -227.525) (xy 361.748573 -227.474272)
			(xy 361.442762 -227.474272) (xy 361.442272 -227.499261) (xy 361.434453 -227.548624) (xy 361.419009 -227.596156)
			(xy 361.396319 -227.640688) (xy 361.366943 -227.681121) (xy 361.331603 -227.716461) (xy 361.29117 -227.745837)
			(xy 361.246638 -227.768527) (xy 361.199106 -227.783971) (xy 361.149743 -227.79179) (xy 361.099765 -227.79179)
			(xy 361.050402 -227.783971) (xy 361.00287 -227.768527) (xy 360.958338 -227.745837) (xy 360.917905 -227.716461)
			(xy 360.882565 -227.681121) (xy 360.853189 -227.640688) (xy 360.830499 -227.596156) (xy 360.815055 -227.548624)
			(xy 360.807236 -227.499261) (xy 358.628714 -227.499261) (xy 358.620895 -227.548624) (xy 358.605451 -227.596156)
			(xy 358.582761 -227.640688) (xy 358.553385 -227.681121) (xy 358.518045 -227.716461) (xy 358.477612 -227.745837)
			(xy 358.43308 -227.768527) (xy 358.385548 -227.783971) (xy 358.336185 -227.79179) (xy 358.286207 -227.79179)
			(xy 358.236844 -227.783971) (xy 358.189312 -227.768527) (xy 358.14478 -227.745837) (xy 358.104347 -227.716461)
			(xy 358.069007 -227.681121) (xy 358.039631 -227.640688) (xy 358.016941 -227.596156) (xy 358.001497 -227.548624)
			(xy 357.993678 -227.499261) (xy 357.686361 -227.499261) (xy 357.686352 -227.499718) (xy 357.678188 -227.549952)
			(xy 357.662072 -227.598226) (xy 357.638421 -227.643289) (xy 357.607848 -227.683975) (xy 357.571144 -227.71923)
			(xy 357.52926 -227.74814) (xy 357.483281 -227.769957) (xy 357.434397 -227.784117) (xy 357.383876 -227.790251)
			(xy 357.333024 -227.788202) (xy 357.28316 -227.778022) (xy 357.235574 -227.759975) (xy 357.1915 -227.734529)
			(xy 357.152078 -227.702342) (xy 357.11833 -227.664248) (xy 357.091129 -227.621234) (xy 357.071181 -227.574414)
			(xy 357.059002 -227.525) (xy 357.054907 -227.474272) (xy 356.74681 -227.474272) (xy 356.746298 -227.499718)
			(xy 356.738134 -227.549952) (xy 356.722018 -227.598226) (xy 356.698367 -227.643289) (xy 356.667794 -227.683975)
			(xy 356.63109 -227.71923) (xy 356.589206 -227.74814) (xy 356.543227 -227.769957) (xy 356.494343 -227.784117)
			(xy 356.443822 -227.790251) (xy 356.39297 -227.788202) (xy 356.343106 -227.778022) (xy 356.29552 -227.759975)
			(xy 356.251446 -227.734529) (xy 356.212024 -227.702342) (xy 356.178276 -227.664248) (xy 356.151075 -227.621234)
			(xy 356.131127 -227.574414) (xy 356.118948 -227.525) (xy 356.114853 -227.474272) (xy 355.809042 -227.474272)
			(xy 355.808552 -227.499261) (xy 355.800733 -227.548624) (xy 355.785289 -227.596156) (xy 355.762599 -227.640688)
			(xy 355.733223 -227.681121) (xy 355.697883 -227.716461) (xy 355.65745 -227.745837) (xy 355.612918 -227.768527)
			(xy 355.565386 -227.783971) (xy 355.516023 -227.79179) (xy 355.466045 -227.79179) (xy 355.416682 -227.783971)
			(xy 355.36915 -227.768527) (xy 355.324618 -227.745837) (xy 355.284185 -227.716461) (xy 355.248845 -227.681121)
			(xy 355.219469 -227.640688) (xy 355.196779 -227.596156) (xy 355.181335 -227.548624) (xy 355.173516 -227.499261)
			(xy 352.988644 -227.499261) (xy 352.980825 -227.548624) (xy 352.965381 -227.596156) (xy 352.942691 -227.640688)
			(xy 352.913315 -227.681121) (xy 352.877975 -227.716461) (xy 352.837542 -227.745837) (xy 352.79301 -227.768527)
			(xy 352.745478 -227.783971) (xy 352.696115 -227.79179) (xy 352.646137 -227.79179) (xy 352.596774 -227.783971)
			(xy 352.549242 -227.768527) (xy 352.50471 -227.745837) (xy 352.464277 -227.716461) (xy 352.428937 -227.681121)
			(xy 352.399561 -227.640688) (xy 352.376871 -227.596156) (xy 352.361427 -227.548624) (xy 352.353608 -227.499261)
			(xy 350.168736 -227.499261) (xy 350.160917 -227.548624) (xy 350.145473 -227.596156) (xy 350.122783 -227.640688)
			(xy 350.093407 -227.681121) (xy 350.058067 -227.716461) (xy 350.017634 -227.745837) (xy 349.973102 -227.768527)
			(xy 349.92557 -227.783971) (xy 349.876207 -227.79179) (xy 349.826229 -227.79179) (xy 349.776866 -227.783971)
			(xy 349.729334 -227.768527) (xy 349.684802 -227.745837) (xy 349.644369 -227.716461) (xy 349.609029 -227.681121)
			(xy 349.579653 -227.640688) (xy 349.556963 -227.596156) (xy 349.541519 -227.548624) (xy 349.5337 -227.499261)
			(xy 347.348574 -227.499261) (xy 347.340755 -227.548624) (xy 347.325311 -227.596156) (xy 347.302621 -227.640688)
			(xy 347.273245 -227.681121) (xy 347.237905 -227.716461) (xy 347.197472 -227.745837) (xy 347.15294 -227.768527)
			(xy 347.105408 -227.783971) (xy 347.056045 -227.79179) (xy 347.006067 -227.79179) (xy 346.956704 -227.783971)
			(xy 346.909172 -227.768527) (xy 346.86464 -227.745837) (xy 346.824207 -227.716461) (xy 346.788867 -227.681121)
			(xy 346.759491 -227.640688) (xy 346.736801 -227.596156) (xy 346.721357 -227.548624) (xy 346.713538 -227.499261)
			(xy 344.972483 -227.499261) (xy 344.9828 -227.509578) (xy 344.98952 -227.516814) (xy 344.997128 -227.535019)
			(xy 344.997532 -227.544884) (xy 344.997532 -228.250242) (xy 344.997786 -228.254814) (xy 344.999056 -228.284024)
			(xy 344.999056 -228.284278) (xy 345.304867 -228.284278) (xy 345.308962 -228.23355) (xy 345.321141 -228.184136)
			(xy 345.341089 -228.137316) (xy 345.36829 -228.094302) (xy 345.402038 -228.056208) (xy 345.44146 -228.024021)
			(xy 345.485534 -227.998575) (xy 345.53312 -227.980528) (xy 345.582984 -227.970348) (xy 345.633836 -227.968299)
			(xy 345.684357 -227.974433) (xy 345.733241 -227.988593) (xy 345.77922 -228.01041) (xy 345.821104 -228.03932)
			(xy 345.857808 -228.074575) (xy 345.888381 -228.115261) (xy 345.912032 -228.160324) (xy 345.928148 -228.208598)
			(xy 345.936312 -228.258832) (xy 345.936824 -228.284278) (xy 346.244921 -228.284278) (xy 346.249016 -228.23355)
			(xy 346.261195 -228.184136) (xy 346.281143 -228.137316) (xy 346.308344 -228.094302) (xy 346.342092 -228.056208)
			(xy 346.381514 -228.024021) (xy 346.425588 -227.998575) (xy 346.473174 -227.980528) (xy 346.523038 -227.970348)
			(xy 346.57389 -227.968299) (xy 346.624411 -227.974433) (xy 346.673295 -227.988593) (xy 346.719274 -228.01041)
			(xy 346.761158 -228.03932) (xy 346.797862 -228.074575) (xy 346.828435 -228.115261) (xy 346.852086 -228.160324)
			(xy 346.868202 -228.208598) (xy 346.876366 -228.258832) (xy 346.876878 -228.284278) (xy 346.876375 -228.309267)
			(xy 347.183692 -228.309267) (xy 347.183692 -228.259289) (xy 347.191511 -228.209926) (xy 347.206955 -228.162394)
			(xy 347.229645 -228.117862) (xy 347.259021 -228.077429) (xy 347.294361 -228.042089) (xy 347.334794 -228.012713)
			(xy 347.379326 -227.990023) (xy 347.426858 -227.974579) (xy 347.476221 -227.96676) (xy 347.526199 -227.96676)
			(xy 347.575562 -227.974579) (xy 347.623094 -227.990023) (xy 347.667626 -228.012713) (xy 347.708059 -228.042089)
			(xy 347.743399 -228.077429) (xy 347.772775 -228.117862) (xy 347.795465 -228.162394) (xy 347.810909 -228.209926)
			(xy 347.818728 -228.259289) (xy 347.819218 -228.284278) (xy 348.124775 -228.284278) (xy 348.12887 -228.23355)
			(xy 348.141049 -228.184136) (xy 348.160997 -228.137316) (xy 348.188198 -228.094302) (xy 348.221946 -228.056208)
			(xy 348.261368 -228.024021) (xy 348.305442 -227.998575) (xy 348.353028 -227.980528) (xy 348.402892 -227.970348)
			(xy 348.453744 -227.968299) (xy 348.504265 -227.974433) (xy 348.553149 -227.988593) (xy 348.599128 -228.01041)
			(xy 348.641012 -228.03932) (xy 348.677716 -228.074575) (xy 348.708289 -228.115261) (xy 348.73194 -228.160324)
			(xy 348.748056 -228.208598) (xy 348.75622 -228.258832) (xy 348.756732 -228.284278) (xy 349.064829 -228.284278)
			(xy 349.068924 -228.23355) (xy 349.081103 -228.184136) (xy 349.101051 -228.137316) (xy 349.128252 -228.094302)
			(xy 349.162 -228.056208) (xy 349.201422 -228.024021) (xy 349.245496 -227.998575) (xy 349.293082 -227.980528)
			(xy 349.342946 -227.970348) (xy 349.393798 -227.968299) (xy 349.444319 -227.974433) (xy 349.493203 -227.988593)
			(xy 349.539182 -228.01041) (xy 349.581066 -228.03932) (xy 349.61777 -228.074575) (xy 349.648343 -228.115261)
			(xy 349.671994 -228.160324) (xy 349.68811 -228.208598) (xy 349.696274 -228.258832) (xy 349.696786 -228.284278)
			(xy 349.696283 -228.309267) (xy 350.0036 -228.309267) (xy 350.0036 -228.259289) (xy 350.011419 -228.209926)
			(xy 350.026863 -228.162394) (xy 350.049553 -228.117862) (xy 350.078929 -228.077429) (xy 350.114269 -228.042089)
			(xy 350.154702 -228.012713) (xy 350.199234 -227.990023) (xy 350.246766 -227.974579) (xy 350.296129 -227.96676)
			(xy 350.346107 -227.96676) (xy 350.39547 -227.974579) (xy 350.443002 -227.990023) (xy 350.487534 -228.012713)
			(xy 350.527967 -228.042089) (xy 350.563307 -228.077429) (xy 350.592683 -228.117862) (xy 350.615373 -228.162394)
			(xy 350.630817 -228.209926) (xy 350.638636 -228.259289) (xy 350.639126 -228.284278) (xy 350.944937 -228.284278)
			(xy 350.949032 -228.23355) (xy 350.961211 -228.184136) (xy 350.981159 -228.137316) (xy 351.00836 -228.094302)
			(xy 351.042108 -228.056208) (xy 351.08153 -228.024021) (xy 351.125604 -227.998575) (xy 351.17319 -227.980528)
			(xy 351.223054 -227.970348) (xy 351.273906 -227.968299) (xy 351.324427 -227.974433) (xy 351.373311 -227.988593)
			(xy 351.41929 -228.01041) (xy 351.461174 -228.03932) (xy 351.497878 -228.074575) (xy 351.528451 -228.115261)
			(xy 351.552102 -228.160324) (xy 351.568218 -228.208598) (xy 351.576382 -228.258832) (xy 351.576894 -228.284278)
			(xy 351.884991 -228.284278) (xy 351.889086 -228.23355) (xy 351.901265 -228.184136) (xy 351.921213 -228.137316)
			(xy 351.948414 -228.094302) (xy 351.982162 -228.056208) (xy 352.021584 -228.024021) (xy 352.065658 -227.998575)
			(xy 352.113244 -227.980528) (xy 352.163108 -227.970348) (xy 352.21396 -227.968299) (xy 352.264481 -227.974433)
			(xy 352.313365 -227.988593) (xy 352.359344 -228.01041) (xy 352.401228 -228.03932) (xy 352.437932 -228.074575)
			(xy 352.468505 -228.115261) (xy 352.492156 -228.160324) (xy 352.508272 -228.208598) (xy 352.516436 -228.258832)
			(xy 352.516948 -228.284278) (xy 352.516445 -228.309267) (xy 352.823508 -228.309267) (xy 352.823508 -228.259289)
			(xy 352.831327 -228.209926) (xy 352.846771 -228.162394) (xy 352.869461 -228.117862) (xy 352.898837 -228.077429)
			(xy 352.934177 -228.042089) (xy 352.97461 -228.012713) (xy 353.019142 -227.990023) (xy 353.066674 -227.974579)
			(xy 353.116037 -227.96676) (xy 353.166015 -227.96676) (xy 353.215378 -227.974579) (xy 353.26291 -227.990023)
			(xy 353.307442 -228.012713) (xy 353.347875 -228.042089) (xy 353.383215 -228.077429) (xy 353.412591 -228.117862)
			(xy 353.435281 -228.162394) (xy 353.450725 -228.209926) (xy 353.458544 -228.259289) (xy 353.459034 -228.284278)
			(xy 353.764845 -228.284278) (xy 353.76894 -228.23355) (xy 353.781119 -228.184136) (xy 353.801067 -228.137316)
			(xy 353.828268 -228.094302) (xy 353.862016 -228.056208) (xy 353.901438 -228.024021) (xy 353.945512 -227.998575)
			(xy 353.993098 -227.980528) (xy 354.042962 -227.970348) (xy 354.093814 -227.968299) (xy 354.144335 -227.974433)
			(xy 354.193219 -227.988593) (xy 354.239198 -228.01041) (xy 354.281082 -228.03932) (xy 354.317786 -228.074575)
			(xy 354.348359 -228.115261) (xy 354.37201 -228.160324) (xy 354.388126 -228.208598) (xy 354.39629 -228.258832)
			(xy 354.396802 -228.284278) (xy 354.704899 -228.284278) (xy 354.708994 -228.23355) (xy 354.721173 -228.184136)
			(xy 354.741121 -228.137316) (xy 354.768322 -228.094302) (xy 354.80207 -228.056208) (xy 354.841492 -228.024021)
			(xy 354.885566 -227.998575) (xy 354.933152 -227.980528) (xy 354.983016 -227.970348) (xy 355.033868 -227.968299)
			(xy 355.084389 -227.974433) (xy 355.133273 -227.988593) (xy 355.179252 -228.01041) (xy 355.221136 -228.03932)
			(xy 355.25784 -228.074575) (xy 355.288413 -228.115261) (xy 355.312064 -228.160324) (xy 355.32818 -228.208598)
			(xy 355.336344 -228.258832) (xy 355.336856 -228.284278) (xy 355.336353 -228.309267) (xy 355.64367 -228.309267)
			(xy 355.64367 -228.259289) (xy 355.651489 -228.209926) (xy 355.666933 -228.162394) (xy 355.689623 -228.117862)
			(xy 355.718999 -228.077429) (xy 355.754339 -228.042089) (xy 355.794772 -228.012713) (xy 355.839304 -227.990023)
			(xy 355.886836 -227.974579) (xy 355.936199 -227.96676) (xy 355.986177 -227.96676) (xy 356.03554 -227.974579)
			(xy 356.083072 -227.990023) (xy 356.127604 -228.012713) (xy 356.168037 -228.042089) (xy 356.203377 -228.077429)
			(xy 356.232753 -228.117862) (xy 356.255443 -228.162394) (xy 356.270887 -228.209926) (xy 356.278706 -228.259289)
			(xy 356.279196 -228.284278) (xy 356.278706 -228.309267) (xy 363.157244 -228.309267) (xy 363.157244 -228.259289)
			(xy 363.165063 -228.209926) (xy 363.180507 -228.162394) (xy 363.203197 -228.117862) (xy 363.232573 -228.077429)
			(xy 363.267913 -228.042089) (xy 363.308346 -228.012713) (xy 363.352878 -227.990023) (xy 363.40041 -227.974579)
			(xy 363.449773 -227.96676) (xy 363.499751 -227.96676) (xy 363.549114 -227.974579) (xy 363.596646 -227.990023)
			(xy 363.641178 -228.012713) (xy 363.681611 -228.042089) (xy 363.716951 -228.077429) (xy 363.746327 -228.117862)
			(xy 363.769017 -228.162394) (xy 363.784461 -228.209926) (xy 363.79228 -228.259289) (xy 363.79277 -228.284278)
			(xy 364.098581 -228.284278) (xy 364.102676 -228.23355) (xy 364.114855 -228.184136) (xy 364.134803 -228.137316)
			(xy 364.162004 -228.094302) (xy 364.195752 -228.056208) (xy 364.235174 -228.024021) (xy 364.279248 -227.998575)
			(xy 364.326834 -227.980528) (xy 364.376698 -227.970348) (xy 364.42755 -227.968299) (xy 364.478071 -227.974433)
			(xy 364.526955 -227.988593) (xy 364.572934 -228.01041) (xy 364.614818 -228.03932) (xy 364.651522 -228.074575)
			(xy 364.682095 -228.115261) (xy 364.705746 -228.160324) (xy 364.721862 -228.208598) (xy 364.730026 -228.258832)
			(xy 364.730538 -228.284278) (xy 365.038635 -228.284278) (xy 365.04273 -228.23355) (xy 365.054909 -228.184136)
			(xy 365.074857 -228.137316) (xy 365.102058 -228.094302) (xy 365.135806 -228.056208) (xy 365.175228 -228.024021)
			(xy 365.219302 -227.998575) (xy 365.266888 -227.980528) (xy 365.316752 -227.970348) (xy 365.367604 -227.968299)
			(xy 365.418125 -227.974433) (xy 365.467009 -227.988593) (xy 365.512988 -228.01041) (xy 365.554872 -228.03932)
			(xy 365.591576 -228.074575) (xy 365.622149 -228.115261) (xy 365.6458 -228.160324) (xy 365.661916 -228.208598)
			(xy 365.67008 -228.258832) (xy 365.670592 -228.284278) (xy 365.670089 -228.309267) (xy 365.977406 -228.309267)
			(xy 365.977406 -228.259289) (xy 365.985225 -228.209926) (xy 366.000669 -228.162394) (xy 366.023359 -228.117862)
			(xy 366.052735 -228.077429) (xy 366.088075 -228.042089) (xy 366.128508 -228.012713) (xy 366.17304 -227.990023)
			(xy 366.220572 -227.974579) (xy 366.269935 -227.96676) (xy 366.319913 -227.96676) (xy 366.369276 -227.974579)
			(xy 366.416808 -227.990023) (xy 366.46134 -228.012713) (xy 366.501773 -228.042089) (xy 366.537113 -228.077429)
			(xy 366.566489 -228.117862) (xy 366.589179 -228.162394) (xy 366.604623 -228.209926) (xy 366.612442 -228.259289)
			(xy 366.612932 -228.284278) (xy 366.918489 -228.284278) (xy 366.922584 -228.23355) (xy 366.934763 -228.184136)
			(xy 366.954711 -228.137316) (xy 366.981912 -228.094302) (xy 367.01566 -228.056208) (xy 367.055082 -228.024021)
			(xy 367.099156 -227.998575) (xy 367.146742 -227.980528) (xy 367.196606 -227.970348) (xy 367.247458 -227.968299)
			(xy 367.297979 -227.974433) (xy 367.346863 -227.988593) (xy 367.392842 -228.01041) (xy 367.434726 -228.03932)
			(xy 367.47143 -228.074575) (xy 367.502003 -228.115261) (xy 367.525654 -228.160324) (xy 367.54177 -228.208598)
			(xy 367.549934 -228.258832) (xy 367.550446 -228.284278) (xy 367.858543 -228.284278) (xy 367.862638 -228.23355)
			(xy 367.874817 -228.184136) (xy 367.894765 -228.137316) (xy 367.921966 -228.094302) (xy 367.955714 -228.056208)
			(xy 367.995136 -228.024021) (xy 368.03921 -227.998575) (xy 368.086796 -227.980528) (xy 368.13666 -227.970348)
			(xy 368.187512 -227.968299) (xy 368.238033 -227.974433) (xy 368.286917 -227.988593) (xy 368.332896 -228.01041)
			(xy 368.37478 -228.03932) (xy 368.411484 -228.074575) (xy 368.442057 -228.115261) (xy 368.465708 -228.160324)
			(xy 368.481824 -228.208598) (xy 368.489988 -228.258832) (xy 368.4905 -228.284278) (xy 368.489997 -228.309267)
			(xy 368.797314 -228.309267) (xy 368.797314 -228.259289) (xy 368.805133 -228.209926) (xy 368.820577 -228.162394)
			(xy 368.843267 -228.117862) (xy 368.872643 -228.077429) (xy 368.907983 -228.042089) (xy 368.948416 -228.012713)
			(xy 368.992948 -227.990023) (xy 369.04048 -227.974579) (xy 369.089843 -227.96676) (xy 369.139821 -227.96676)
			(xy 369.189184 -227.974579) (xy 369.236716 -227.990023) (xy 369.281248 -228.012713) (xy 369.321681 -228.042089)
			(xy 369.357021 -228.077429) (xy 369.386397 -228.117862) (xy 369.409087 -228.162394) (xy 369.424531 -228.209926)
			(xy 369.43235 -228.259289) (xy 369.43284 -228.284278) (xy 369.738651 -228.284278) (xy 369.742746 -228.23355)
			(xy 369.754925 -228.184136) (xy 369.774873 -228.137316) (xy 369.802074 -228.094302) (xy 369.835822 -228.056208)
			(xy 369.875244 -228.024021) (xy 369.919318 -227.998575) (xy 369.966904 -227.980528) (xy 370.016768 -227.970348)
			(xy 370.06762 -227.968299) (xy 370.118141 -227.974433) (xy 370.167025 -227.988593) (xy 370.213004 -228.01041)
			(xy 370.254888 -228.03932) (xy 370.291592 -228.074575) (xy 370.322165 -228.115261) (xy 370.345816 -228.160324)
			(xy 370.361932 -228.208598) (xy 370.370096 -228.258832) (xy 370.370608 -228.284278) (xy 370.678451 -228.284278)
			(xy 370.682546 -228.23355) (xy 370.694725 -228.184136) (xy 370.714673 -228.137316) (xy 370.741874 -228.094302)
			(xy 370.775622 -228.056208) (xy 370.815044 -228.024021) (xy 370.859118 -227.998575) (xy 370.906704 -227.980528)
			(xy 370.956568 -227.970348) (xy 371.00742 -227.968299) (xy 371.057941 -227.974433) (xy 371.106825 -227.988593)
			(xy 371.152804 -228.01041) (xy 371.194688 -228.03932) (xy 371.231392 -228.074575) (xy 371.261965 -228.115261)
			(xy 371.285616 -228.160324) (xy 371.301732 -228.208598) (xy 371.309896 -228.258832) (xy 371.310408 -228.284278)
			(xy 371.309905 -228.309267) (xy 371.617222 -228.309267) (xy 371.617222 -228.259289) (xy 371.625041 -228.209926)
			(xy 371.640485 -228.162394) (xy 371.663175 -228.117862) (xy 371.692551 -228.077429) (xy 371.727891 -228.042089)
			(xy 371.768324 -228.012713) (xy 371.812856 -227.990023) (xy 371.860388 -227.974579) (xy 371.909751 -227.96676)
			(xy 371.959729 -227.96676) (xy 372.009092 -227.974579) (xy 372.056624 -227.990023) (xy 372.101156 -228.012713)
			(xy 372.141589 -228.042089) (xy 372.176929 -228.077429) (xy 372.206305 -228.117862) (xy 372.228995 -228.162394)
			(xy 372.244439 -228.209926) (xy 372.252258 -228.259289) (xy 372.252748 -228.284278) (xy 372.558559 -228.284278)
			(xy 372.562654 -228.23355) (xy 372.574833 -228.184136) (xy 372.594781 -228.137316) (xy 372.621982 -228.094302)
			(xy 372.65573 -228.056208) (xy 372.695152 -228.024021) (xy 372.739226 -227.998575) (xy 372.786812 -227.980528)
			(xy 372.836676 -227.970348) (xy 372.887528 -227.968299) (xy 372.938049 -227.974433) (xy 372.986933 -227.988593)
			(xy 373.032912 -228.01041) (xy 373.074796 -228.03932) (xy 373.1115 -228.074575) (xy 373.142073 -228.115261)
			(xy 373.165724 -228.160324) (xy 373.18184 -228.208598) (xy 373.190004 -228.258832) (xy 373.190516 -228.284278)
			(xy 373.498613 -228.284278) (xy 373.502708 -228.23355) (xy 373.514887 -228.184136) (xy 373.534835 -228.137316)
			(xy 373.562036 -228.094302) (xy 373.595784 -228.056208) (xy 373.635206 -228.024021) (xy 373.67928 -227.998575)
			(xy 373.726866 -227.980528) (xy 373.77673 -227.970348) (xy 373.827582 -227.968299) (xy 373.878103 -227.974433)
			(xy 373.926987 -227.988593) (xy 373.972966 -228.01041) (xy 374.01485 -228.03932) (xy 374.051554 -228.074575)
			(xy 374.082127 -228.115261) (xy 374.105778 -228.160324) (xy 374.121894 -228.208598) (xy 374.130058 -228.258832)
			(xy 374.13057 -228.284278) (xy 374.130058 -228.309724) (xy 374.121894 -228.359958) (xy 374.105778 -228.408232)
			(xy 374.082127 -228.453295) (xy 374.051554 -228.493981) (xy 374.01485 -228.529236) (xy 373.972966 -228.558146)
			(xy 373.926987 -228.579963) (xy 373.878103 -228.594123) (xy 373.827582 -228.600257) (xy 373.77673 -228.598208)
			(xy 373.726866 -228.588028) (xy 373.67928 -228.569981) (xy 373.635206 -228.544535) (xy 373.595784 -228.512348)
			(xy 373.562036 -228.474254) (xy 373.534835 -228.43124) (xy 373.514887 -228.38442) (xy 373.502708 -228.335006)
			(xy 373.498613 -228.284278) (xy 373.190516 -228.284278) (xy 373.190004 -228.309724) (xy 373.18184 -228.359958)
			(xy 373.165724 -228.408232) (xy 373.142073 -228.453295) (xy 373.1115 -228.493981) (xy 373.074796 -228.529236)
			(xy 373.032912 -228.558146) (xy 372.986933 -228.579963) (xy 372.938049 -228.594123) (xy 372.887528 -228.600257)
			(xy 372.836676 -228.598208) (xy 372.786812 -228.588028) (xy 372.739226 -228.569981) (xy 372.695152 -228.544535)
			(xy 372.65573 -228.512348) (xy 372.621982 -228.474254) (xy 372.594781 -228.43124) (xy 372.574833 -228.38442)
			(xy 372.562654 -228.335006) (xy 372.558559 -228.284278) (xy 372.252748 -228.284278) (xy 372.252258 -228.309267)
			(xy 372.244439 -228.35863) (xy 372.228995 -228.406162) (xy 372.206305 -228.450694) (xy 372.176929 -228.491127)
			(xy 372.141589 -228.526467) (xy 372.101156 -228.555843) (xy 372.056624 -228.578533) (xy 372.009092 -228.593977)
			(xy 371.959729 -228.601796) (xy 371.909751 -228.601796) (xy 371.860388 -228.593977) (xy 371.812856 -228.578533)
			(xy 371.768324 -228.555843) (xy 371.727891 -228.526467) (xy 371.692551 -228.491127) (xy 371.663175 -228.450694)
			(xy 371.640485 -228.406162) (xy 371.625041 -228.35863) (xy 371.617222 -228.309267) (xy 371.309905 -228.309267)
			(xy 371.309896 -228.309724) (xy 371.301732 -228.359958) (xy 371.285616 -228.408232) (xy 371.261965 -228.453295)
			(xy 371.231392 -228.493981) (xy 371.194688 -228.529236) (xy 371.152804 -228.558146) (xy 371.106825 -228.579963)
			(xy 371.057941 -228.594123) (xy 371.00742 -228.600257) (xy 370.956568 -228.598208) (xy 370.906704 -228.588028)
			(xy 370.859118 -228.569981) (xy 370.815044 -228.544535) (xy 370.775622 -228.512348) (xy 370.741874 -228.474254)
			(xy 370.714673 -228.43124) (xy 370.694725 -228.38442) (xy 370.682546 -228.335006) (xy 370.678451 -228.284278)
			(xy 370.370608 -228.284278) (xy 370.370096 -228.309724) (xy 370.361932 -228.359958) (xy 370.345816 -228.408232)
			(xy 370.322165 -228.453295) (xy 370.291592 -228.493981) (xy 370.254888 -228.529236) (xy 370.213004 -228.558146)
			(xy 370.167025 -228.579963) (xy 370.118141 -228.594123) (xy 370.06762 -228.600257) (xy 370.016768 -228.598208)
			(xy 369.966904 -228.588028) (xy 369.919318 -228.569981) (xy 369.875244 -228.544535) (xy 369.835822 -228.512348)
			(xy 369.802074 -228.474254) (xy 369.774873 -228.43124) (xy 369.754925 -228.38442) (xy 369.742746 -228.335006)
			(xy 369.738651 -228.284278) (xy 369.43284 -228.284278) (xy 369.43235 -228.309267) (xy 369.424531 -228.35863)
			(xy 369.409087 -228.406162) (xy 369.386397 -228.450694) (xy 369.357021 -228.491127) (xy 369.321681 -228.526467)
			(xy 369.281248 -228.555843) (xy 369.236716 -228.578533) (xy 369.189184 -228.593977) (xy 369.139821 -228.601796)
			(xy 369.089843 -228.601796) (xy 369.04048 -228.593977) (xy 368.992948 -228.578533) (xy 368.948416 -228.555843)
			(xy 368.907983 -228.526467) (xy 368.872643 -228.491127) (xy 368.843267 -228.450694) (xy 368.820577 -228.406162)
			(xy 368.805133 -228.35863) (xy 368.797314 -228.309267) (xy 368.489997 -228.309267) (xy 368.489988 -228.309724)
			(xy 368.481824 -228.359958) (xy 368.465708 -228.408232) (xy 368.442057 -228.453295) (xy 368.411484 -228.493981)
			(xy 368.37478 -228.529236) (xy 368.332896 -228.558146) (xy 368.286917 -228.579963) (xy 368.238033 -228.594123)
			(xy 368.187512 -228.600257) (xy 368.13666 -228.598208) (xy 368.086796 -228.588028) (xy 368.03921 -228.569981)
			(xy 367.995136 -228.544535) (xy 367.955714 -228.512348) (xy 367.921966 -228.474254) (xy 367.894765 -228.43124)
			(xy 367.874817 -228.38442) (xy 367.862638 -228.335006) (xy 367.858543 -228.284278) (xy 367.550446 -228.284278)
			(xy 367.549934 -228.309724) (xy 367.54177 -228.359958) (xy 367.525654 -228.408232) (xy 367.502003 -228.453295)
			(xy 367.47143 -228.493981) (xy 367.434726 -228.529236) (xy 367.392842 -228.558146) (xy 367.346863 -228.579963)
			(xy 367.297979 -228.594123) (xy 367.247458 -228.600257) (xy 367.196606 -228.598208) (xy 367.146742 -228.588028)
			(xy 367.099156 -228.569981) (xy 367.055082 -228.544535) (xy 367.01566 -228.512348) (xy 366.981912 -228.474254)
			(xy 366.954711 -228.43124) (xy 366.934763 -228.38442) (xy 366.922584 -228.335006) (xy 366.918489 -228.284278)
			(xy 366.612932 -228.284278) (xy 366.612442 -228.309267) (xy 366.604623 -228.35863) (xy 366.589179 -228.406162)
			(xy 366.566489 -228.450694) (xy 366.537113 -228.491127) (xy 366.501773 -228.526467) (xy 366.46134 -228.555843)
			(xy 366.416808 -228.578533) (xy 366.369276 -228.593977) (xy 366.319913 -228.601796) (xy 366.269935 -228.601796)
			(xy 366.220572 -228.593977) (xy 366.17304 -228.578533) (xy 366.128508 -228.555843) (xy 366.088075 -228.526467)
			(xy 366.052735 -228.491127) (xy 366.023359 -228.450694) (xy 366.000669 -228.406162) (xy 365.985225 -228.35863)
			(xy 365.977406 -228.309267) (xy 365.670089 -228.309267) (xy 365.67008 -228.309724) (xy 365.661916 -228.359958)
			(xy 365.6458 -228.408232) (xy 365.622149 -228.453295) (xy 365.591576 -228.493981) (xy 365.554872 -228.529236)
			(xy 365.512988 -228.558146) (xy 365.467009 -228.579963) (xy 365.418125 -228.594123) (xy 365.367604 -228.600257)
			(xy 365.316752 -228.598208) (xy 365.266888 -228.588028) (xy 365.219302 -228.569981) (xy 365.175228 -228.544535)
			(xy 365.135806 -228.512348) (xy 365.102058 -228.474254) (xy 365.074857 -228.43124) (xy 365.054909 -228.38442)
			(xy 365.04273 -228.335006) (xy 365.038635 -228.284278) (xy 364.730538 -228.284278) (xy 364.730026 -228.309724)
			(xy 364.721862 -228.359958) (xy 364.705746 -228.408232) (xy 364.682095 -228.453295) (xy 364.651522 -228.493981)
			(xy 364.614818 -228.529236) (xy 364.572934 -228.558146) (xy 364.526955 -228.579963) (xy 364.478071 -228.594123)
			(xy 364.42755 -228.600257) (xy 364.376698 -228.598208) (xy 364.326834 -228.588028) (xy 364.279248 -228.569981)
			(xy 364.235174 -228.544535) (xy 364.195752 -228.512348) (xy 364.162004 -228.474254) (xy 364.134803 -228.43124)
			(xy 364.114855 -228.38442) (xy 364.102676 -228.335006) (xy 364.098581 -228.284278) (xy 363.79277 -228.284278)
			(xy 363.79228 -228.309267) (xy 363.784461 -228.35863) (xy 363.769017 -228.406162) (xy 363.746327 -228.450694)
			(xy 363.716951 -228.491127) (xy 363.681611 -228.526467) (xy 363.641178 -228.555843) (xy 363.596646 -228.578533)
			(xy 363.549114 -228.593977) (xy 363.499751 -228.601796) (xy 363.449773 -228.601796) (xy 363.40041 -228.593977)
			(xy 363.352878 -228.578533) (xy 363.308346 -228.555843) (xy 363.267913 -228.526467) (xy 363.232573 -228.491127)
			(xy 363.203197 -228.450694) (xy 363.180507 -228.406162) (xy 363.165063 -228.35863) (xy 363.157244 -228.309267)
			(xy 356.278706 -228.309267) (xy 356.270887 -228.35863) (xy 356.255443 -228.406162) (xy 356.232753 -228.450694)
			(xy 356.203377 -228.491127) (xy 356.168037 -228.526467) (xy 356.127604 -228.555843) (xy 356.083072 -228.578533)
			(xy 356.03554 -228.593977) (xy 355.986177 -228.601796) (xy 355.936199 -228.601796) (xy 355.886836 -228.593977)
			(xy 355.839304 -228.578533) (xy 355.794772 -228.555843) (xy 355.754339 -228.526467) (xy 355.718999 -228.491127)
			(xy 355.689623 -228.450694) (xy 355.666933 -228.406162) (xy 355.651489 -228.35863) (xy 355.64367 -228.309267)
			(xy 355.336353 -228.309267) (xy 355.336344 -228.309724) (xy 355.32818 -228.359958) (xy 355.312064 -228.408232)
			(xy 355.288413 -228.453295) (xy 355.25784 -228.493981) (xy 355.221136 -228.529236) (xy 355.179252 -228.558146)
			(xy 355.133273 -228.579963) (xy 355.084389 -228.594123) (xy 355.033868 -228.600257) (xy 354.983016 -228.598208)
			(xy 354.933152 -228.588028) (xy 354.885566 -228.569981) (xy 354.841492 -228.544535) (xy 354.80207 -228.512348)
			(xy 354.768322 -228.474254) (xy 354.741121 -228.43124) (xy 354.721173 -228.38442) (xy 354.708994 -228.335006)
			(xy 354.704899 -228.284278) (xy 354.396802 -228.284278) (xy 354.39629 -228.309724) (xy 354.388126 -228.359958)
			(xy 354.37201 -228.408232) (xy 354.348359 -228.453295) (xy 354.317786 -228.493981) (xy 354.281082 -228.529236)
			(xy 354.239198 -228.558146) (xy 354.193219 -228.579963) (xy 354.144335 -228.594123) (xy 354.093814 -228.600257)
			(xy 354.042962 -228.598208) (xy 353.993098 -228.588028) (xy 353.945512 -228.569981) (xy 353.901438 -228.544535)
			(xy 353.862016 -228.512348) (xy 353.828268 -228.474254) (xy 353.801067 -228.43124) (xy 353.781119 -228.38442)
			(xy 353.76894 -228.335006) (xy 353.764845 -228.284278) (xy 353.459034 -228.284278) (xy 353.458544 -228.309267)
			(xy 353.450725 -228.35863) (xy 353.435281 -228.406162) (xy 353.412591 -228.450694) (xy 353.383215 -228.491127)
			(xy 353.347875 -228.526467) (xy 353.307442 -228.555843) (xy 353.26291 -228.578533) (xy 353.215378 -228.593977)
			(xy 353.166015 -228.601796) (xy 353.116037 -228.601796) (xy 353.066674 -228.593977) (xy 353.019142 -228.578533)
			(xy 352.97461 -228.555843) (xy 352.934177 -228.526467) (xy 352.898837 -228.491127) (xy 352.869461 -228.450694)
			(xy 352.846771 -228.406162) (xy 352.831327 -228.35863) (xy 352.823508 -228.309267) (xy 352.516445 -228.309267)
			(xy 352.516436 -228.309724) (xy 352.508272 -228.359958) (xy 352.492156 -228.408232) (xy 352.468505 -228.453295)
			(xy 352.437932 -228.493981) (xy 352.401228 -228.529236) (xy 352.359344 -228.558146) (xy 352.313365 -228.579963)
			(xy 352.264481 -228.594123) (xy 352.21396 -228.600257) (xy 352.163108 -228.598208) (xy 352.113244 -228.588028)
			(xy 352.065658 -228.569981) (xy 352.021584 -228.544535) (xy 351.982162 -228.512348) (xy 351.948414 -228.474254)
			(xy 351.921213 -228.43124) (xy 351.901265 -228.38442) (xy 351.889086 -228.335006) (xy 351.884991 -228.284278)
			(xy 351.576894 -228.284278) (xy 351.576382 -228.309724) (xy 351.568218 -228.359958) (xy 351.552102 -228.408232)
			(xy 351.528451 -228.453295) (xy 351.497878 -228.493981) (xy 351.461174 -228.529236) (xy 351.41929 -228.558146)
			(xy 351.373311 -228.579963) (xy 351.324427 -228.594123) (xy 351.273906 -228.600257) (xy 351.223054 -228.598208)
			(xy 351.17319 -228.588028) (xy 351.125604 -228.569981) (xy 351.08153 -228.544535) (xy 351.042108 -228.512348)
			(xy 351.00836 -228.474254) (xy 350.981159 -228.43124) (xy 350.961211 -228.38442) (xy 350.949032 -228.335006)
			(xy 350.944937 -228.284278) (xy 350.639126 -228.284278) (xy 350.638636 -228.309267) (xy 350.630817 -228.35863)
			(xy 350.615373 -228.406162) (xy 350.592683 -228.450694) (xy 350.563307 -228.491127) (xy 350.527967 -228.526467)
			(xy 350.487534 -228.555843) (xy 350.443002 -228.578533) (xy 350.39547 -228.593977) (xy 350.346107 -228.601796)
			(xy 350.296129 -228.601796) (xy 350.246766 -228.593977) (xy 350.199234 -228.578533) (xy 350.154702 -228.555843)
			(xy 350.114269 -228.526467) (xy 350.078929 -228.491127) (xy 350.049553 -228.450694) (xy 350.026863 -228.406162)
			(xy 350.011419 -228.35863) (xy 350.0036 -228.309267) (xy 349.696283 -228.309267) (xy 349.696274 -228.309724)
			(xy 349.68811 -228.359958) (xy 349.671994 -228.408232) (xy 349.648343 -228.453295) (xy 349.61777 -228.493981)
			(xy 349.581066 -228.529236) (xy 349.539182 -228.558146) (xy 349.493203 -228.579963) (xy 349.444319 -228.594123)
			(xy 349.393798 -228.600257) (xy 349.342946 -228.598208) (xy 349.293082 -228.588028) (xy 349.245496 -228.569981)
			(xy 349.201422 -228.544535) (xy 349.162 -228.512348) (xy 349.128252 -228.474254) (xy 349.101051 -228.43124)
			(xy 349.081103 -228.38442) (xy 349.068924 -228.335006) (xy 349.064829 -228.284278) (xy 348.756732 -228.284278)
			(xy 348.75622 -228.309724) (xy 348.748056 -228.359958) (xy 348.73194 -228.408232) (xy 348.708289 -228.453295)
			(xy 348.677716 -228.493981) (xy 348.641012 -228.529236) (xy 348.599128 -228.558146) (xy 348.553149 -228.579963)
			(xy 348.504265 -228.594123) (xy 348.453744 -228.600257) (xy 348.402892 -228.598208) (xy 348.353028 -228.588028)
			(xy 348.305442 -228.569981) (xy 348.261368 -228.544535) (xy 348.221946 -228.512348) (xy 348.188198 -228.474254)
			(xy 348.160997 -228.43124) (xy 348.141049 -228.38442) (xy 348.12887 -228.335006) (xy 348.124775 -228.284278)
			(xy 347.819218 -228.284278) (xy 347.818728 -228.309267) (xy 347.810909 -228.35863) (xy 347.795465 -228.406162)
			(xy 347.772775 -228.450694) (xy 347.743399 -228.491127) (xy 347.708059 -228.526467) (xy 347.667626 -228.555843)
			(xy 347.623094 -228.578533) (xy 347.575562 -228.593977) (xy 347.526199 -228.601796) (xy 347.476221 -228.601796)
			(xy 347.426858 -228.593977) (xy 347.379326 -228.578533) (xy 347.334794 -228.555843) (xy 347.294361 -228.526467)
			(xy 347.259021 -228.491127) (xy 347.229645 -228.450694) (xy 347.206955 -228.406162) (xy 347.191511 -228.35863)
			(xy 347.183692 -228.309267) (xy 346.876375 -228.309267) (xy 346.876366 -228.309724) (xy 346.868202 -228.359958)
			(xy 346.852086 -228.408232) (xy 346.828435 -228.453295) (xy 346.797862 -228.493981) (xy 346.761158 -228.529236)
			(xy 346.719274 -228.558146) (xy 346.673295 -228.579963) (xy 346.624411 -228.594123) (xy 346.57389 -228.600257)
			(xy 346.523038 -228.598208) (xy 346.473174 -228.588028) (xy 346.425588 -228.569981) (xy 346.381514 -228.544535)
			(xy 346.342092 -228.512348) (xy 346.308344 -228.474254) (xy 346.281143 -228.43124) (xy 346.261195 -228.38442)
			(xy 346.249016 -228.335006) (xy 346.244921 -228.284278) (xy 345.936824 -228.284278) (xy 345.936312 -228.309724)
			(xy 345.928148 -228.359958) (xy 345.912032 -228.408232) (xy 345.888381 -228.453295) (xy 345.857808 -228.493981)
			(xy 345.821104 -228.529236) (xy 345.77922 -228.558146) (xy 345.733241 -228.579963) (xy 345.684357 -228.594123)
			(xy 345.633836 -228.600257) (xy 345.582984 -228.598208) (xy 345.53312 -228.588028) (xy 345.485534 -228.569981)
			(xy 345.44146 -228.544535) (xy 345.402038 -228.512348) (xy 345.36829 -228.474254) (xy 345.341089 -228.43124)
			(xy 345.321141 -228.38442) (xy 345.308962 -228.335006) (xy 345.304867 -228.284278) (xy 344.999056 -228.284278)
			(xy 344.999056 -228.284532) (xy 344.997786 -228.313742) (xy 344.997532 -228.318314) (xy 344.997532 -228.679756)
			(xy 344.998045 -228.689507) (xy 345.005489 -228.707541) (xy 345.01201 -228.714808) (xy 345.072462 -228.767894)
			(xy 345.079274 -228.772921) (xy 345.095244 -228.778507) (xy 345.103704 -228.778816) (xy 345.110562 -228.778816)
			(xy 345.113356 -228.778562) (xy 345.122781 -228.777494) (xy 345.141717 -228.776353) (xy 345.151202 -228.776276)
			(xy 345.176192 -228.776767) (xy 345.225558 -228.784586) (xy 345.273092 -228.800031) (xy 345.317625 -228.822722)
			(xy 345.35806 -228.8521) (xy 345.393402 -228.887441) (xy 345.422779 -228.927877) (xy 345.44547 -228.97241)
			(xy 345.460915 -229.019944) (xy 345.468734 -229.06931) (xy 345.468734 -229.119273) (xy 345.773484 -229.119273)
			(xy 345.773484 -229.069295) (xy 345.781303 -229.019932) (xy 345.796747 -228.9724) (xy 345.819437 -228.927868)
			(xy 345.848813 -228.887435) (xy 345.884153 -228.852095) (xy 345.924586 -228.822719) (xy 345.969118 -228.800029)
			(xy 346.01665 -228.784585) (xy 346.066013 -228.776766) (xy 346.115991 -228.776766) (xy 346.165354 -228.784585)
			(xy 346.212886 -228.800029) (xy 346.257418 -228.822719) (xy 346.297851 -228.852095) (xy 346.333191 -228.887435)
			(xy 346.362567 -228.927868) (xy 346.385257 -228.9724) (xy 346.400701 -229.019932) (xy 346.40852 -229.069295)
			(xy 346.40901 -229.094284) (xy 346.40852 -229.119273) (xy 346.713538 -229.119273) (xy 346.713538 -229.069295)
			(xy 346.721357 -229.019932) (xy 346.736801 -228.9724) (xy 346.759491 -228.927868) (xy 346.788867 -228.887435)
			(xy 346.824207 -228.852095) (xy 346.86464 -228.822719) (xy 346.909172 -228.800029) (xy 346.956704 -228.784585)
			(xy 347.006067 -228.776766) (xy 347.056045 -228.776766) (xy 347.105408 -228.784585) (xy 347.15294 -228.800029)
			(xy 347.197472 -228.822719) (xy 347.237905 -228.852095) (xy 347.273245 -228.887435) (xy 347.302621 -228.927868)
			(xy 347.325311 -228.9724) (xy 347.340755 -229.019932) (xy 347.348574 -229.069295) (xy 347.349064 -229.094284)
			(xy 347.348574 -229.119273) (xy 347.653592 -229.119273) (xy 347.653592 -229.069295) (xy 347.661411 -229.019932)
			(xy 347.676855 -228.9724) (xy 347.699545 -228.927868) (xy 347.728921 -228.887435) (xy 347.764261 -228.852095)
			(xy 347.804694 -228.822719) (xy 347.849226 -228.800029) (xy 347.896758 -228.784585) (xy 347.946121 -228.776766)
			(xy 347.996099 -228.776766) (xy 348.045462 -228.784585) (xy 348.092994 -228.800029) (xy 348.137526 -228.822719)
			(xy 348.177959 -228.852095) (xy 348.213299 -228.887435) (xy 348.242675 -228.927868) (xy 348.265365 -228.9724)
			(xy 348.280809 -229.019932) (xy 348.288628 -229.069295) (xy 348.289118 -229.094284) (xy 348.288628 -229.119273)
			(xy 348.593646 -229.119273) (xy 348.593646 -229.069295) (xy 348.601465 -229.019932) (xy 348.616909 -228.9724)
			(xy 348.639599 -228.927868) (xy 348.668975 -228.887435) (xy 348.704315 -228.852095) (xy 348.744748 -228.822719)
			(xy 348.78928 -228.800029) (xy 348.836812 -228.784585) (xy 348.886175 -228.776766) (xy 348.936153 -228.776766)
			(xy 348.985516 -228.784585) (xy 349.033048 -228.800029) (xy 349.07758 -228.822719) (xy 349.118013 -228.852095)
			(xy 349.153353 -228.887435) (xy 349.182729 -228.927868) (xy 349.205419 -228.9724) (xy 349.220863 -229.019932)
			(xy 349.228682 -229.069295) (xy 349.229172 -229.094284) (xy 349.228682 -229.119273) (xy 349.5337 -229.119273)
			(xy 349.5337 -229.069295) (xy 349.541519 -229.019932) (xy 349.556963 -228.9724) (xy 349.579653 -228.927868)
			(xy 349.609029 -228.887435) (xy 349.644369 -228.852095) (xy 349.684802 -228.822719) (xy 349.729334 -228.800029)
			(xy 349.776866 -228.784585) (xy 349.826229 -228.776766) (xy 349.876207 -228.776766) (xy 349.92557 -228.784585)
			(xy 349.973102 -228.800029) (xy 350.017634 -228.822719) (xy 350.058067 -228.852095) (xy 350.093407 -228.887435)
			(xy 350.122783 -228.927868) (xy 350.145473 -228.9724) (xy 350.160917 -229.019932) (xy 350.168736 -229.069295)
			(xy 350.169226 -229.094284) (xy 350.168736 -229.119273) (xy 350.4735 -229.119273) (xy 350.4735 -229.069295)
			(xy 350.481319 -229.019932) (xy 350.496763 -228.9724) (xy 350.519453 -228.927868) (xy 350.548829 -228.887435)
			(xy 350.584169 -228.852095) (xy 350.624602 -228.822719) (xy 350.669134 -228.800029) (xy 350.716666 -228.784585)
			(xy 350.766029 -228.776766) (xy 350.816007 -228.776766) (xy 350.86537 -228.784585) (xy 350.912902 -228.800029)
			(xy 350.957434 -228.822719) (xy 350.997867 -228.852095) (xy 351.033207 -228.887435) (xy 351.062583 -228.927868)
			(xy 351.085273 -228.9724) (xy 351.100717 -229.019932) (xy 351.108536 -229.069295) (xy 351.109026 -229.094284)
			(xy 351.108536 -229.119273) (xy 351.413554 -229.119273) (xy 351.413554 -229.069295) (xy 351.421373 -229.019932)
			(xy 351.436817 -228.9724) (xy 351.459507 -228.927868) (xy 351.488883 -228.887435) (xy 351.524223 -228.852095)
			(xy 351.564656 -228.822719) (xy 351.609188 -228.800029) (xy 351.65672 -228.784585) (xy 351.706083 -228.776766)
			(xy 351.756061 -228.776766) (xy 351.805424 -228.784585) (xy 351.852956 -228.800029) (xy 351.897488 -228.822719)
			(xy 351.937921 -228.852095) (xy 351.973261 -228.887435) (xy 352.002637 -228.927868) (xy 352.025327 -228.9724)
			(xy 352.040771 -229.019932) (xy 352.04859 -229.069295) (xy 352.04908 -229.094284) (xy 352.04859 -229.119273)
			(xy 352.353608 -229.119273) (xy 352.353608 -229.069295) (xy 352.361427 -229.019932) (xy 352.376871 -228.9724)
			(xy 352.399561 -228.927868) (xy 352.428937 -228.887435) (xy 352.464277 -228.852095) (xy 352.50471 -228.822719)
			(xy 352.549242 -228.800029) (xy 352.596774 -228.784585) (xy 352.646137 -228.776766) (xy 352.696115 -228.776766)
			(xy 352.745478 -228.784585) (xy 352.79301 -228.800029) (xy 352.837542 -228.822719) (xy 352.877975 -228.852095)
			(xy 352.913315 -228.887435) (xy 352.942691 -228.927868) (xy 352.965381 -228.9724) (xy 352.980825 -229.019932)
			(xy 352.988644 -229.069295) (xy 352.989134 -229.094284) (xy 352.988644 -229.119273) (xy 353.293662 -229.119273)
			(xy 353.293662 -229.069295) (xy 353.301481 -229.019932) (xy 353.316925 -228.9724) (xy 353.339615 -228.927868)
			(xy 353.368991 -228.887435) (xy 353.404331 -228.852095) (xy 353.444764 -228.822719) (xy 353.489296 -228.800029)
			(xy 353.536828 -228.784585) (xy 353.586191 -228.776766) (xy 353.636169 -228.776766) (xy 353.685532 -228.784585)
			(xy 353.733064 -228.800029) (xy 353.777596 -228.822719) (xy 353.818029 -228.852095) (xy 353.853369 -228.887435)
			(xy 353.882745 -228.927868) (xy 353.905435 -228.9724) (xy 353.920879 -229.019932) (xy 353.928698 -229.069295)
			(xy 353.929188 -229.094284) (xy 353.928698 -229.119273) (xy 354.233716 -229.119273) (xy 354.233716 -229.069295)
			(xy 354.241535 -229.019932) (xy 354.256979 -228.9724) (xy 354.279669 -228.927868) (xy 354.309045 -228.887435)
			(xy 354.344385 -228.852095) (xy 354.384818 -228.822719) (xy 354.42935 -228.800029) (xy 354.476882 -228.784585)
			(xy 354.526245 -228.776766) (xy 354.576223 -228.776766) (xy 354.625586 -228.784585) (xy 354.673118 -228.800029)
			(xy 354.71765 -228.822719) (xy 354.758083 -228.852095) (xy 354.793423 -228.887435) (xy 354.822799 -228.927868)
			(xy 354.845489 -228.9724) (xy 354.860933 -229.019932) (xy 354.868752 -229.069295) (xy 354.869242 -229.094284)
			(xy 354.868752 -229.119273) (xy 355.173516 -229.119273) (xy 355.173516 -229.069295) (xy 355.181335 -229.019932)
			(xy 355.196779 -228.9724) (xy 355.219469 -228.927868) (xy 355.248845 -228.887435) (xy 355.284185 -228.852095)
			(xy 355.324618 -228.822719) (xy 355.36915 -228.800029) (xy 355.416682 -228.784585) (xy 355.466045 -228.776766)
			(xy 355.516023 -228.776766) (xy 355.565386 -228.784585) (xy 355.612918 -228.800029) (xy 355.65745 -228.822719)
			(xy 355.697883 -228.852095) (xy 355.733223 -228.887435) (xy 355.762599 -228.927868) (xy 355.785289 -228.9724)
			(xy 355.800733 -229.019932) (xy 355.808552 -229.069295) (xy 355.809042 -229.094284) (xy 356.114853 -229.094284)
			(xy 356.118948 -229.043556) (xy 356.131127 -228.994142) (xy 356.151075 -228.947322) (xy 356.178276 -228.904308)
			(xy 356.212024 -228.866214) (xy 356.251446 -228.834027) (xy 356.29552 -228.808581) (xy 356.343106 -228.790534)
			(xy 356.39297 -228.780354) (xy 356.443822 -228.778305) (xy 356.494343 -228.784439) (xy 356.543227 -228.798599)
			(xy 356.589206 -228.820416) (xy 356.63109 -228.849326) (xy 356.667794 -228.884581) (xy 356.698367 -228.925267)
			(xy 356.722018 -228.97033) (xy 356.738134 -229.018604) (xy 356.746298 -229.068838) (xy 356.74681 -229.094284)
			(xy 357.054907 -229.094284) (xy 357.059002 -229.043556) (xy 357.071181 -228.994142) (xy 357.091129 -228.947322)
			(xy 357.11833 -228.904308) (xy 357.152078 -228.866214) (xy 357.1915 -228.834027) (xy 357.235574 -228.808581)
			(xy 357.28316 -228.790534) (xy 357.333024 -228.780354) (xy 357.383876 -228.778305) (xy 357.434397 -228.784439)
			(xy 357.483281 -228.798599) (xy 357.52926 -228.820416) (xy 357.571144 -228.849326) (xy 357.607848 -228.884581)
			(xy 357.638421 -228.925267) (xy 357.662072 -228.97033) (xy 357.678188 -229.018604) (xy 357.686352 -229.068838)
			(xy 357.686864 -229.094284) (xy 357.686361 -229.119273) (xy 357.993678 -229.119273) (xy 357.993678 -229.069295)
			(xy 358.001497 -229.019932) (xy 358.016941 -228.9724) (xy 358.039631 -228.927868) (xy 358.069007 -228.887435)
			(xy 358.104347 -228.852095) (xy 358.14478 -228.822719) (xy 358.189312 -228.800029) (xy 358.236844 -228.784585)
			(xy 358.286207 -228.776766) (xy 358.336185 -228.776766) (xy 358.385548 -228.784585) (xy 358.43308 -228.800029)
			(xy 358.477612 -228.822719) (xy 358.518045 -228.852095) (xy 358.553385 -228.887435) (xy 358.582761 -228.927868)
			(xy 358.605451 -228.9724) (xy 358.620895 -229.019932) (xy 358.628714 -229.069295) (xy 358.629204 -229.094284)
			(xy 358.628714 -229.119273) (xy 360.807236 -229.119273) (xy 360.807236 -229.069295) (xy 360.815055 -229.019932)
			(xy 360.830499 -228.9724) (xy 360.853189 -228.927868) (xy 360.882565 -228.887435) (xy 360.917905 -228.852095)
			(xy 360.958338 -228.822719) (xy 361.00287 -228.800029) (xy 361.050402 -228.784585) (xy 361.099765 -228.776766)
			(xy 361.149743 -228.776766) (xy 361.199106 -228.784585) (xy 361.246638 -228.800029) (xy 361.29117 -228.822719)
			(xy 361.331603 -228.852095) (xy 361.366943 -228.887435) (xy 361.396319 -228.927868) (xy 361.419009 -228.9724)
			(xy 361.434453 -229.019932) (xy 361.442272 -229.069295) (xy 361.442762 -229.094284) (xy 361.748573 -229.094284)
			(xy 361.752668 -229.043556) (xy 361.764847 -228.994142) (xy 361.784795 -228.947322) (xy 361.811996 -228.904308)
			(xy 361.845744 -228.866214) (xy 361.885166 -228.834027) (xy 361.92924 -228.808581) (xy 361.976826 -228.790534)
			(xy 362.02669 -228.780354) (xy 362.077542 -228.778305) (xy 362.128063 -228.784439) (xy 362.176947 -228.798599)
			(xy 362.222926 -228.820416) (xy 362.26481 -228.849326) (xy 362.301514 -228.884581) (xy 362.332087 -228.925267)
			(xy 362.355738 -228.97033) (xy 362.371854 -229.018604) (xy 362.380018 -229.068838) (xy 362.38053 -229.094284)
			(xy 362.688627 -229.094284) (xy 362.692722 -229.043556) (xy 362.704901 -228.994142) (xy 362.724849 -228.947322)
			(xy 362.75205 -228.904308) (xy 362.785798 -228.866214) (xy 362.82522 -228.834027) (xy 362.869294 -228.808581)
			(xy 362.91688 -228.790534) (xy 362.966744 -228.780354) (xy 363.017596 -228.778305) (xy 363.068117 -228.784439)
			(xy 363.117001 -228.798599) (xy 363.16298 -228.820416) (xy 363.204864 -228.849326) (xy 363.241568 -228.884581)
			(xy 363.272141 -228.925267) (xy 363.295792 -228.97033) (xy 363.311908 -229.018604) (xy 363.320072 -229.068838)
			(xy 363.320584 -229.094284) (xy 363.320081 -229.119273) (xy 363.627398 -229.119273) (xy 363.627398 -229.069295)
			(xy 363.635217 -229.019932) (xy 363.650661 -228.9724) (xy 363.673351 -228.927868) (xy 363.702727 -228.887435)
			(xy 363.738067 -228.852095) (xy 363.7785 -228.822719) (xy 363.823032 -228.800029) (xy 363.870564 -228.784585)
			(xy 363.919927 -228.776766) (xy 363.969905 -228.776766) (xy 364.019268 -228.784585) (xy 364.0668 -228.800029)
			(xy 364.111332 -228.822719) (xy 364.151765 -228.852095) (xy 364.187105 -228.887435) (xy 364.216481 -228.927868)
			(xy 364.239171 -228.9724) (xy 364.254615 -229.019932) (xy 364.262434 -229.069295) (xy 364.262924 -229.094284)
			(xy 364.262434 -229.119273) (xy 364.567198 -229.119273) (xy 364.567198 -229.069295) (xy 364.575017 -229.019932)
			(xy 364.590461 -228.9724) (xy 364.613151 -228.927868) (xy 364.642527 -228.887435) (xy 364.677867 -228.852095)
			(xy 364.7183 -228.822719) (xy 364.762832 -228.800029) (xy 364.810364 -228.784585) (xy 364.859727 -228.776766)
			(xy 364.909705 -228.776766) (xy 364.959068 -228.784585) (xy 365.0066 -228.800029) (xy 365.051132 -228.822719)
			(xy 365.091565 -228.852095) (xy 365.126905 -228.887435) (xy 365.156281 -228.927868) (xy 365.178971 -228.9724)
			(xy 365.194415 -229.019932) (xy 365.202234 -229.069295) (xy 365.202724 -229.094284) (xy 365.202234 -229.119273)
			(xy 365.507252 -229.119273) (xy 365.507252 -229.069295) (xy 365.515071 -229.019932) (xy 365.530515 -228.9724)
			(xy 365.553205 -228.927868) (xy 365.582581 -228.887435) (xy 365.617921 -228.852095) (xy 365.658354 -228.822719)
			(xy 365.702886 -228.800029) (xy 365.750418 -228.784585) (xy 365.799781 -228.776766) (xy 365.849759 -228.776766)
			(xy 365.899122 -228.784585) (xy 365.946654 -228.800029) (xy 365.991186 -228.822719) (xy 366.031619 -228.852095)
			(xy 366.066959 -228.887435) (xy 366.096335 -228.927868) (xy 366.119025 -228.9724) (xy 366.134469 -229.019932)
			(xy 366.142288 -229.069295) (xy 366.142778 -229.094284) (xy 366.142288 -229.119273) (xy 366.447306 -229.119273)
			(xy 366.447306 -229.069295) (xy 366.455125 -229.019932) (xy 366.470569 -228.9724) (xy 366.493259 -228.927868)
			(xy 366.522635 -228.887435) (xy 366.557975 -228.852095) (xy 366.598408 -228.822719) (xy 366.64294 -228.800029)
			(xy 366.690472 -228.784585) (xy 366.739835 -228.776766) (xy 366.789813 -228.776766) (xy 366.839176 -228.784585)
			(xy 366.886708 -228.800029) (xy 366.93124 -228.822719) (xy 366.971673 -228.852095) (xy 367.007013 -228.887435)
			(xy 367.036389 -228.927868) (xy 367.059079 -228.9724) (xy 367.074523 -229.019932) (xy 367.082342 -229.069295)
			(xy 367.082832 -229.094284) (xy 367.082342 -229.119273) (xy 367.38736 -229.119273) (xy 367.38736 -229.069295)
			(xy 367.395179 -229.019932) (xy 367.410623 -228.9724) (xy 367.433313 -228.927868) (xy 367.462689 -228.887435)
			(xy 367.498029 -228.852095) (xy 367.538462 -228.822719) (xy 367.582994 -228.800029) (xy 367.630526 -228.784585)
			(xy 367.679889 -228.776766) (xy 367.729867 -228.776766) (xy 367.77923 -228.784585) (xy 367.826762 -228.800029)
			(xy 367.871294 -228.822719) (xy 367.911727 -228.852095) (xy 367.947067 -228.887435) (xy 367.976443 -228.927868)
			(xy 367.999133 -228.9724) (xy 368.014577 -229.019932) (xy 368.022396 -229.069295) (xy 368.022886 -229.094284)
			(xy 368.022396 -229.119273) (xy 368.327414 -229.119273) (xy 368.327414 -229.069295) (xy 368.335233 -229.019932)
			(xy 368.350677 -228.9724) (xy 368.373367 -228.927868) (xy 368.402743 -228.887435) (xy 368.438083 -228.852095)
			(xy 368.478516 -228.822719) (xy 368.523048 -228.800029) (xy 368.57058 -228.784585) (xy 368.619943 -228.776766)
			(xy 368.669921 -228.776766) (xy 368.719284 -228.784585) (xy 368.766816 -228.800029) (xy 368.811348 -228.822719)
			(xy 368.851781 -228.852095) (xy 368.887121 -228.887435) (xy 368.916497 -228.927868) (xy 368.939187 -228.9724)
			(xy 368.954631 -229.019932) (xy 368.96245 -229.069295) (xy 368.96294 -229.094284) (xy 368.96245 -229.119273)
			(xy 369.267214 -229.119273) (xy 369.267214 -229.069295) (xy 369.275033 -229.019932) (xy 369.290477 -228.9724)
			(xy 369.313167 -228.927868) (xy 369.342543 -228.887435) (xy 369.377883 -228.852095) (xy 369.418316 -228.822719)
			(xy 369.462848 -228.800029) (xy 369.51038 -228.784585) (xy 369.559743 -228.776766) (xy 369.609721 -228.776766)
			(xy 369.659084 -228.784585) (xy 369.706616 -228.800029) (xy 369.751148 -228.822719) (xy 369.791581 -228.852095)
			(xy 369.826921 -228.887435) (xy 369.856297 -228.927868) (xy 369.878987 -228.9724) (xy 369.894431 -229.019932)
			(xy 369.90225 -229.069295) (xy 369.90274 -229.094284) (xy 369.90225 -229.119273) (xy 370.207268 -229.119273)
			(xy 370.207268 -229.069295) (xy 370.215087 -229.019932) (xy 370.230531 -228.9724) (xy 370.253221 -228.927868)
			(xy 370.282597 -228.887435) (xy 370.317937 -228.852095) (xy 370.35837 -228.822719) (xy 370.402902 -228.800029)
			(xy 370.450434 -228.784585) (xy 370.499797 -228.776766) (xy 370.549775 -228.776766) (xy 370.599138 -228.784585)
			(xy 370.64667 -228.800029) (xy 370.691202 -228.822719) (xy 370.731635 -228.852095) (xy 370.766975 -228.887435)
			(xy 370.796351 -228.927868) (xy 370.819041 -228.9724) (xy 370.834485 -229.019932) (xy 370.842304 -229.069295)
			(xy 370.842794 -229.094284) (xy 370.842304 -229.119273) (xy 371.147322 -229.119273) (xy 371.147322 -229.069295)
			(xy 371.155141 -229.019932) (xy 371.170585 -228.9724) (xy 371.193275 -228.927868) (xy 371.222651 -228.887435)
			(xy 371.257991 -228.852095) (xy 371.298424 -228.822719) (xy 371.342956 -228.800029) (xy 371.390488 -228.784585)
			(xy 371.439851 -228.776766) (xy 371.489829 -228.776766) (xy 371.539192 -228.784585) (xy 371.586724 -228.800029)
			(xy 371.631256 -228.822719) (xy 371.671689 -228.852095) (xy 371.707029 -228.887435) (xy 371.736405 -228.927868)
			(xy 371.759095 -228.9724) (xy 371.774539 -229.019932) (xy 371.782358 -229.069295) (xy 371.782848 -229.094284)
			(xy 371.782358 -229.119273) (xy 372.087376 -229.119273) (xy 372.087376 -229.069295) (xy 372.095195 -229.019932)
			(xy 372.110639 -228.9724) (xy 372.133329 -228.927868) (xy 372.162705 -228.887435) (xy 372.198045 -228.852095)
			(xy 372.238478 -228.822719) (xy 372.28301 -228.800029) (xy 372.330542 -228.784585) (xy 372.379905 -228.776766)
			(xy 372.429883 -228.776766) (xy 372.479246 -228.784585) (xy 372.526778 -228.800029) (xy 372.57131 -228.822719)
			(xy 372.611743 -228.852095) (xy 372.647083 -228.887435) (xy 372.676459 -228.927868) (xy 372.699149 -228.9724)
			(xy 372.714593 -229.019932) (xy 372.722412 -229.069295) (xy 372.722902 -229.094284) (xy 372.722412 -229.119273)
			(xy 373.027176 -229.119273) (xy 373.027176 -229.069295) (xy 373.034995 -229.019932) (xy 373.050439 -228.9724)
			(xy 373.073129 -228.927868) (xy 373.102505 -228.887435) (xy 373.137845 -228.852095) (xy 373.178278 -228.822719)
			(xy 373.22281 -228.800029) (xy 373.270342 -228.784585) (xy 373.319705 -228.776766) (xy 373.369683 -228.776766)
			(xy 373.419046 -228.784585) (xy 373.466578 -228.800029) (xy 373.51111 -228.822719) (xy 373.551543 -228.852095)
			(xy 373.586883 -228.887435) (xy 373.616259 -228.927868) (xy 373.638949 -228.9724) (xy 373.654393 -229.019932)
			(xy 373.662212 -229.069295) (xy 373.662702 -229.094284) (xy 373.662212 -229.119273) (xy 373.654393 -229.168636)
			(xy 373.638949 -229.216168) (xy 373.616259 -229.2607) (xy 373.586883 -229.301133) (xy 373.551543 -229.336473)
			(xy 373.51111 -229.365849) (xy 373.466578 -229.388539) (xy 373.419046 -229.403983) (xy 373.369683 -229.411802)
			(xy 373.319705 -229.411802) (xy 373.270342 -229.403983) (xy 373.22281 -229.388539) (xy 373.178278 -229.365849)
			(xy 373.137845 -229.336473) (xy 373.102505 -229.301133) (xy 373.073129 -229.2607) (xy 373.050439 -229.216168)
			(xy 373.034995 -229.168636) (xy 373.027176 -229.119273) (xy 372.722412 -229.119273) (xy 372.714593 -229.168636)
			(xy 372.699149 -229.216168) (xy 372.676459 -229.2607) (xy 372.647083 -229.301133) (xy 372.611743 -229.336473)
			(xy 372.57131 -229.365849) (xy 372.526778 -229.388539) (xy 372.479246 -229.403983) (xy 372.429883 -229.411802)
			(xy 372.379905 -229.411802) (xy 372.330542 -229.403983) (xy 372.28301 -229.388539) (xy 372.238478 -229.365849)
			(xy 372.198045 -229.336473) (xy 372.162705 -229.301133) (xy 372.133329 -229.2607) (xy 372.110639 -229.216168)
			(xy 372.095195 -229.168636) (xy 372.087376 -229.119273) (xy 371.782358 -229.119273) (xy 371.774539 -229.168636)
			(xy 371.759095 -229.216168) (xy 371.736405 -229.2607) (xy 371.707029 -229.301133) (xy 371.671689 -229.336473)
			(xy 371.631256 -229.365849) (xy 371.586724 -229.388539) (xy 371.539192 -229.403983) (xy 371.489829 -229.411802)
			(xy 371.439851 -229.411802) (xy 371.390488 -229.403983) (xy 371.342956 -229.388539) (xy 371.298424 -229.365849)
			(xy 371.257991 -229.336473) (xy 371.222651 -229.301133) (xy 371.193275 -229.2607) (xy 371.170585 -229.216168)
			(xy 371.155141 -229.168636) (xy 371.147322 -229.119273) (xy 370.842304 -229.119273) (xy 370.834485 -229.168636)
			(xy 370.819041 -229.216168) (xy 370.796351 -229.2607) (xy 370.766975 -229.301133) (xy 370.731635 -229.336473)
			(xy 370.691202 -229.365849) (xy 370.64667 -229.388539) (xy 370.599138 -229.403983) (xy 370.549775 -229.411802)
			(xy 370.499797 -229.411802) (xy 370.450434 -229.403983) (xy 370.402902 -229.388539) (xy 370.35837 -229.365849)
			(xy 370.317937 -229.336473) (xy 370.282597 -229.301133) (xy 370.253221 -229.2607) (xy 370.230531 -229.216168)
			(xy 370.215087 -229.168636) (xy 370.207268 -229.119273) (xy 369.90225 -229.119273) (xy 369.894431 -229.168636)
			(xy 369.878987 -229.216168) (xy 369.856297 -229.2607) (xy 369.826921 -229.301133) (xy 369.791581 -229.336473)
			(xy 369.751148 -229.365849) (xy 369.706616 -229.388539) (xy 369.659084 -229.403983) (xy 369.609721 -229.411802)
			(xy 369.559743 -229.411802) (xy 369.51038 -229.403983) (xy 369.462848 -229.388539) (xy 369.418316 -229.365849)
			(xy 369.377883 -229.336473) (xy 369.342543 -229.301133) (xy 369.313167 -229.2607) (xy 369.290477 -229.216168)
			(xy 369.275033 -229.168636) (xy 369.267214 -229.119273) (xy 368.96245 -229.119273) (xy 368.954631 -229.168636)
			(xy 368.939187 -229.216168) (xy 368.916497 -229.2607) (xy 368.887121 -229.301133) (xy 368.851781 -229.336473)
			(xy 368.811348 -229.365849) (xy 368.766816 -229.388539) (xy 368.719284 -229.403983) (xy 368.669921 -229.411802)
			(xy 368.619943 -229.411802) (xy 368.57058 -229.403983) (xy 368.523048 -229.388539) (xy 368.478516 -229.365849)
			(xy 368.438083 -229.336473) (xy 368.402743 -229.301133) (xy 368.373367 -229.2607) (xy 368.350677 -229.216168)
			(xy 368.335233 -229.168636) (xy 368.327414 -229.119273) (xy 368.022396 -229.119273) (xy 368.014577 -229.168636)
			(xy 367.999133 -229.216168) (xy 367.976443 -229.2607) (xy 367.947067 -229.301133) (xy 367.911727 -229.336473)
			(xy 367.871294 -229.365849) (xy 367.826762 -229.388539) (xy 367.77923 -229.403983) (xy 367.729867 -229.411802)
			(xy 367.679889 -229.411802) (xy 367.630526 -229.403983) (xy 367.582994 -229.388539) (xy 367.538462 -229.365849)
			(xy 367.498029 -229.336473) (xy 367.462689 -229.301133) (xy 367.433313 -229.2607) (xy 367.410623 -229.216168)
			(xy 367.395179 -229.168636) (xy 367.38736 -229.119273) (xy 367.082342 -229.119273) (xy 367.074523 -229.168636)
			(xy 367.059079 -229.216168) (xy 367.036389 -229.2607) (xy 367.007013 -229.301133) (xy 366.971673 -229.336473)
			(xy 366.93124 -229.365849) (xy 366.886708 -229.388539) (xy 366.839176 -229.403983) (xy 366.789813 -229.411802)
			(xy 366.739835 -229.411802) (xy 366.690472 -229.403983) (xy 366.64294 -229.388539) (xy 366.598408 -229.365849)
			(xy 366.557975 -229.336473) (xy 366.522635 -229.301133) (xy 366.493259 -229.2607) (xy 366.470569 -229.216168)
			(xy 366.455125 -229.168636) (xy 366.447306 -229.119273) (xy 366.142288 -229.119273) (xy 366.134469 -229.168636)
			(xy 366.119025 -229.216168) (xy 366.096335 -229.2607) (xy 366.066959 -229.301133) (xy 366.031619 -229.336473)
			(xy 365.991186 -229.365849) (xy 365.946654 -229.388539) (xy 365.899122 -229.403983) (xy 365.849759 -229.411802)
			(xy 365.799781 -229.411802) (xy 365.750418 -229.403983) (xy 365.702886 -229.388539) (xy 365.658354 -229.365849)
			(xy 365.617921 -229.336473) (xy 365.582581 -229.301133) (xy 365.553205 -229.2607) (xy 365.530515 -229.216168)
			(xy 365.515071 -229.168636) (xy 365.507252 -229.119273) (xy 365.202234 -229.119273) (xy 365.194415 -229.168636)
			(xy 365.178971 -229.216168) (xy 365.156281 -229.2607) (xy 365.126905 -229.301133) (xy 365.091565 -229.336473)
			(xy 365.051132 -229.365849) (xy 365.0066 -229.388539) (xy 364.959068 -229.403983) (xy 364.909705 -229.411802)
			(xy 364.859727 -229.411802) (xy 364.810364 -229.403983) (xy 364.762832 -229.388539) (xy 364.7183 -229.365849)
			(xy 364.677867 -229.336473) (xy 364.642527 -229.301133) (xy 364.613151 -229.2607) (xy 364.590461 -229.216168)
			(xy 364.575017 -229.168636) (xy 364.567198 -229.119273) (xy 364.262434 -229.119273) (xy 364.254615 -229.168636)
			(xy 364.239171 -229.216168) (xy 364.216481 -229.2607) (xy 364.187105 -229.301133) (xy 364.151765 -229.336473)
			(xy 364.111332 -229.365849) (xy 364.0668 -229.388539) (xy 364.019268 -229.403983) (xy 363.969905 -229.411802)
			(xy 363.919927 -229.411802) (xy 363.870564 -229.403983) (xy 363.823032 -229.388539) (xy 363.7785 -229.365849)
			(xy 363.738067 -229.336473) (xy 363.702727 -229.301133) (xy 363.673351 -229.2607) (xy 363.650661 -229.216168)
			(xy 363.635217 -229.168636) (xy 363.627398 -229.119273) (xy 363.320081 -229.119273) (xy 363.320072 -229.11973)
			(xy 363.311908 -229.169964) (xy 363.295792 -229.218238) (xy 363.272141 -229.263301) (xy 363.241568 -229.303987)
			(xy 363.204864 -229.339242) (xy 363.16298 -229.368152) (xy 363.117001 -229.389969) (xy 363.068117 -229.404129)
			(xy 363.017596 -229.410263) (xy 362.966744 -229.408214) (xy 362.91688 -229.398034) (xy 362.869294 -229.379987)
			(xy 362.82522 -229.354541) (xy 362.785798 -229.322354) (xy 362.75205 -229.28426) (xy 362.724849 -229.241246)
			(xy 362.704901 -229.194426) (xy 362.692722 -229.145012) (xy 362.688627 -229.094284) (xy 362.38053 -229.094284)
			(xy 362.380018 -229.11973) (xy 362.371854 -229.169964) (xy 362.355738 -229.218238) (xy 362.332087 -229.263301)
			(xy 362.301514 -229.303987) (xy 362.26481 -229.339242) (xy 362.222926 -229.368152) (xy 362.176947 -229.389969)
			(xy 362.128063 -229.404129) (xy 362.077542 -229.410263) (xy 362.02669 -229.408214) (xy 361.976826 -229.398034)
			(xy 361.92924 -229.379987) (xy 361.885166 -229.354541) (xy 361.845744 -229.322354) (xy 361.811996 -229.28426)
			(xy 361.784795 -229.241246) (xy 361.764847 -229.194426) (xy 361.752668 -229.145012) (xy 361.748573 -229.094284)
			(xy 361.442762 -229.094284) (xy 361.442272 -229.119273) (xy 361.434453 -229.168636) (xy 361.419009 -229.216168)
			(xy 361.396319 -229.2607) (xy 361.366943 -229.301133) (xy 361.331603 -229.336473) (xy 361.29117 -229.365849)
			(xy 361.246638 -229.388539) (xy 361.199106 -229.403983) (xy 361.149743 -229.411802) (xy 361.099765 -229.411802)
			(xy 361.050402 -229.403983) (xy 361.00287 -229.388539) (xy 360.958338 -229.365849) (xy 360.917905 -229.336473)
			(xy 360.882565 -229.301133) (xy 360.853189 -229.2607) (xy 360.830499 -229.216168) (xy 360.815055 -229.168636)
			(xy 360.807236 -229.119273) (xy 358.628714 -229.119273) (xy 358.620895 -229.168636) (xy 358.605451 -229.216168)
			(xy 358.582761 -229.2607) (xy 358.553385 -229.301133) (xy 358.518045 -229.336473) (xy 358.477612 -229.365849)
			(xy 358.43308 -229.388539) (xy 358.385548 -229.403983) (xy 358.336185 -229.411802) (xy 358.286207 -229.411802)
			(xy 358.236844 -229.403983) (xy 358.189312 -229.388539) (xy 358.14478 -229.365849) (xy 358.104347 -229.336473)
			(xy 358.069007 -229.301133) (xy 358.039631 -229.2607) (xy 358.016941 -229.216168) (xy 358.001497 -229.168636)
			(xy 357.993678 -229.119273) (xy 357.686361 -229.119273) (xy 357.686352 -229.11973) (xy 357.678188 -229.169964)
			(xy 357.662072 -229.218238) (xy 357.638421 -229.263301) (xy 357.607848 -229.303987) (xy 357.571144 -229.339242)
			(xy 357.52926 -229.368152) (xy 357.483281 -229.389969) (xy 357.434397 -229.404129) (xy 357.383876 -229.410263)
			(xy 357.333024 -229.408214) (xy 357.28316 -229.398034) (xy 357.235574 -229.379987) (xy 357.1915 -229.354541)
			(xy 357.152078 -229.322354) (xy 357.11833 -229.28426) (xy 357.091129 -229.241246) (xy 357.071181 -229.194426)
			(xy 357.059002 -229.145012) (xy 357.054907 -229.094284) (xy 356.74681 -229.094284) (xy 356.746298 -229.11973)
			(xy 356.738134 -229.169964) (xy 356.722018 -229.218238) (xy 356.698367 -229.263301) (xy 356.667794 -229.303987)
			(xy 356.63109 -229.339242) (xy 356.589206 -229.368152) (xy 356.543227 -229.389969) (xy 356.494343 -229.404129)
			(xy 356.443822 -229.410263) (xy 356.39297 -229.408214) (xy 356.343106 -229.398034) (xy 356.29552 -229.379987)
			(xy 356.251446 -229.354541) (xy 356.212024 -229.322354) (xy 356.178276 -229.28426) (xy 356.151075 -229.241246)
			(xy 356.131127 -229.194426) (xy 356.118948 -229.145012) (xy 356.114853 -229.094284) (xy 355.809042 -229.094284)
			(xy 355.808552 -229.119273) (xy 355.800733 -229.168636) (xy 355.785289 -229.216168) (xy 355.762599 -229.2607)
			(xy 355.733223 -229.301133) (xy 355.697883 -229.336473) (xy 355.65745 -229.365849) (xy 355.612918 -229.388539)
			(xy 355.565386 -229.403983) (xy 355.516023 -229.411802) (xy 355.466045 -229.411802) (xy 355.416682 -229.403983)
			(xy 355.36915 -229.388539) (xy 355.324618 -229.365849) (xy 355.284185 -229.336473) (xy 355.248845 -229.301133)
			(xy 355.219469 -229.2607) (xy 355.196779 -229.216168) (xy 355.181335 -229.168636) (xy 355.173516 -229.119273)
			(xy 354.868752 -229.119273) (xy 354.860933 -229.168636) (xy 354.845489 -229.216168) (xy 354.822799 -229.2607)
			(xy 354.793423 -229.301133) (xy 354.758083 -229.336473) (xy 354.71765 -229.365849) (xy 354.673118 -229.388539)
			(xy 354.625586 -229.403983) (xy 354.576223 -229.411802) (xy 354.526245 -229.411802) (xy 354.476882 -229.403983)
			(xy 354.42935 -229.388539) (xy 354.384818 -229.365849) (xy 354.344385 -229.336473) (xy 354.309045 -229.301133)
			(xy 354.279669 -229.2607) (xy 354.256979 -229.216168) (xy 354.241535 -229.168636) (xy 354.233716 -229.119273)
			(xy 353.928698 -229.119273) (xy 353.920879 -229.168636) (xy 353.905435 -229.216168) (xy 353.882745 -229.2607)
			(xy 353.853369 -229.301133) (xy 353.818029 -229.336473) (xy 353.777596 -229.365849) (xy 353.733064 -229.388539)
			(xy 353.685532 -229.403983) (xy 353.636169 -229.411802) (xy 353.586191 -229.411802) (xy 353.536828 -229.403983)
			(xy 353.489296 -229.388539) (xy 353.444764 -229.365849) (xy 353.404331 -229.336473) (xy 353.368991 -229.301133)
			(xy 353.339615 -229.2607) (xy 353.316925 -229.216168) (xy 353.301481 -229.168636) (xy 353.293662 -229.119273)
			(xy 352.988644 -229.119273) (xy 352.980825 -229.168636) (xy 352.965381 -229.216168) (xy 352.942691 -229.2607)
			(xy 352.913315 -229.301133) (xy 352.877975 -229.336473) (xy 352.837542 -229.365849) (xy 352.79301 -229.388539)
			(xy 352.745478 -229.403983) (xy 352.696115 -229.411802) (xy 352.646137 -229.411802) (xy 352.596774 -229.403983)
			(xy 352.549242 -229.388539) (xy 352.50471 -229.365849) (xy 352.464277 -229.336473) (xy 352.428937 -229.301133)
			(xy 352.399561 -229.2607) (xy 352.376871 -229.216168) (xy 352.361427 -229.168636) (xy 352.353608 -229.119273)
			(xy 352.04859 -229.119273) (xy 352.040771 -229.168636) (xy 352.025327 -229.216168) (xy 352.002637 -229.2607)
			(xy 351.973261 -229.301133) (xy 351.937921 -229.336473) (xy 351.897488 -229.365849) (xy 351.852956 -229.388539)
			(xy 351.805424 -229.403983) (xy 351.756061 -229.411802) (xy 351.706083 -229.411802) (xy 351.65672 -229.403983)
			(xy 351.609188 -229.388539) (xy 351.564656 -229.365849) (xy 351.524223 -229.336473) (xy 351.488883 -229.301133)
			(xy 351.459507 -229.2607) (xy 351.436817 -229.216168) (xy 351.421373 -229.168636) (xy 351.413554 -229.119273)
			(xy 351.108536 -229.119273) (xy 351.100717 -229.168636) (xy 351.085273 -229.216168) (xy 351.062583 -229.2607)
			(xy 351.033207 -229.301133) (xy 350.997867 -229.336473) (xy 350.957434 -229.365849) (xy 350.912902 -229.388539)
			(xy 350.86537 -229.403983) (xy 350.816007 -229.411802) (xy 350.766029 -229.411802) (xy 350.716666 -229.403983)
			(xy 350.669134 -229.388539) (xy 350.624602 -229.365849) (xy 350.584169 -229.336473) (xy 350.548829 -229.301133)
			(xy 350.519453 -229.2607) (xy 350.496763 -229.216168) (xy 350.481319 -229.168636) (xy 350.4735 -229.119273)
			(xy 350.168736 -229.119273) (xy 350.160917 -229.168636) (xy 350.145473 -229.216168) (xy 350.122783 -229.2607)
			(xy 350.093407 -229.301133) (xy 350.058067 -229.336473) (xy 350.017634 -229.365849) (xy 349.973102 -229.388539)
			(xy 349.92557 -229.403983) (xy 349.876207 -229.411802) (xy 349.826229 -229.411802) (xy 349.776866 -229.403983)
			(xy 349.729334 -229.388539) (xy 349.684802 -229.365849) (xy 349.644369 -229.336473) (xy 349.609029 -229.301133)
			(xy 349.579653 -229.2607) (xy 349.556963 -229.216168) (xy 349.541519 -229.168636) (xy 349.5337 -229.119273)
			(xy 349.228682 -229.119273) (xy 349.220863 -229.168636) (xy 349.205419 -229.216168) (xy 349.182729 -229.2607)
			(xy 349.153353 -229.301133) (xy 349.118013 -229.336473) (xy 349.07758 -229.365849) (xy 349.033048 -229.388539)
			(xy 348.985516 -229.403983) (xy 348.936153 -229.411802) (xy 348.886175 -229.411802) (xy 348.836812 -229.403983)
			(xy 348.78928 -229.388539) (xy 348.744748 -229.365849) (xy 348.704315 -229.336473) (xy 348.668975 -229.301133)
			(xy 348.639599 -229.2607) (xy 348.616909 -229.216168) (xy 348.601465 -229.168636) (xy 348.593646 -229.119273)
			(xy 348.288628 -229.119273) (xy 348.280809 -229.168636) (xy 348.265365 -229.216168) (xy 348.242675 -229.2607)
			(xy 348.213299 -229.301133) (xy 348.177959 -229.336473) (xy 348.137526 -229.365849) (xy 348.092994 -229.388539)
			(xy 348.045462 -229.403983) (xy 347.996099 -229.411802) (xy 347.946121 -229.411802) (xy 347.896758 -229.403983)
			(xy 347.849226 -229.388539) (xy 347.804694 -229.365849) (xy 347.764261 -229.336473) (xy 347.728921 -229.301133)
			(xy 347.699545 -229.2607) (xy 347.676855 -229.216168) (xy 347.661411 -229.168636) (xy 347.653592 -229.119273)
			(xy 347.348574 -229.119273) (xy 347.340755 -229.168636) (xy 347.325311 -229.216168) (xy 347.302621 -229.2607)
			(xy 347.273245 -229.301133) (xy 347.237905 -229.336473) (xy 347.197472 -229.365849) (xy 347.15294 -229.388539)
			(xy 347.105408 -229.403983) (xy 347.056045 -229.411802) (xy 347.006067 -229.411802) (xy 346.956704 -229.403983)
			(xy 346.909172 -229.388539) (xy 346.86464 -229.365849) (xy 346.824207 -229.336473) (xy 346.788867 -229.301133)
			(xy 346.759491 -229.2607) (xy 346.736801 -229.216168) (xy 346.721357 -229.168636) (xy 346.713538 -229.119273)
			(xy 346.40852 -229.119273) (xy 346.400701 -229.168636) (xy 346.385257 -229.216168) (xy 346.362567 -229.2607)
			(xy 346.333191 -229.301133) (xy 346.297851 -229.336473) (xy 346.257418 -229.365849) (xy 346.212886 -229.388539)
			(xy 346.165354 -229.403983) (xy 346.115991 -229.411802) (xy 346.066013 -229.411802) (xy 346.01665 -229.403983)
			(xy 345.969118 -229.388539) (xy 345.924586 -229.365849) (xy 345.884153 -229.336473) (xy 345.848813 -229.301133)
			(xy 345.819437 -229.2607) (xy 345.796747 -229.216168) (xy 345.781303 -229.168636) (xy 345.773484 -229.119273)
			(xy 345.468734 -229.119273) (xy 345.468734 -229.11929) (xy 345.460915 -229.168656) (xy 345.44547 -229.21619)
			(xy 345.422779 -229.260723) (xy 345.393402 -229.301159) (xy 345.35806 -229.3365) (xy 345.317625 -229.365878)
			(xy 345.273092 -229.388569) (xy 345.225558 -229.404014) (xy 345.176192 -229.411833) (xy 345.151202 -229.412292)
			(xy 345.141014 -229.412227) (xy 345.120678 -229.410957) (xy 345.110562 -229.409752) (xy 345.09964 -229.408482)
			(xy 345.089988 -229.411276) (xy 345.084905 -229.412988) (xy 345.075558 -229.418245) (xy 345.071446 -229.42169)
			(xy 345.051888 -229.438708) (xy 345.01201 -229.47376) (xy 345.005458 -229.481009) (xy 344.99801 -229.499052)
			(xy 344.997532 -229.508812) (xy 344.997532 -229.87) (xy 344.997786 -229.874572) (xy 344.999056 -229.903782)
			(xy 344.999056 -229.904036) (xy 345.304867 -229.904036) (xy 345.308962 -229.853308) (xy 345.321141 -229.803894)
			(xy 345.341089 -229.757074) (xy 345.36829 -229.71406) (xy 345.402038 -229.675966) (xy 345.44146 -229.643779)
			(xy 345.485534 -229.618333) (xy 345.53312 -229.600286) (xy 345.582984 -229.590106) (xy 345.633836 -229.588057)
			(xy 345.684357 -229.594191) (xy 345.733241 -229.608351) (xy 345.77922 -229.630168) (xy 345.821104 -229.659078)
			(xy 345.857808 -229.694333) (xy 345.888381 -229.735019) (xy 345.912032 -229.780082) (xy 345.928148 -229.828356)
			(xy 345.936312 -229.87859) (xy 345.936824 -229.904036) (xy 346.244921 -229.904036) (xy 346.249016 -229.853308)
			(xy 346.261195 -229.803894) (xy 346.281143 -229.757074) (xy 346.308344 -229.71406) (xy 346.342092 -229.675966)
			(xy 346.381514 -229.643779) (xy 346.425588 -229.618333) (xy 346.473174 -229.600286) (xy 346.523038 -229.590106)
			(xy 346.57389 -229.588057) (xy 346.624411 -229.594191) (xy 346.673295 -229.608351) (xy 346.719274 -229.630168)
			(xy 346.761158 -229.659078) (xy 346.797862 -229.694333) (xy 346.828435 -229.735019) (xy 346.852086 -229.780082)
			(xy 346.868202 -229.828356) (xy 346.876366 -229.87859) (xy 346.876878 -229.904036) (xy 346.876375 -229.929025)
			(xy 347.183692 -229.929025) (xy 347.183692 -229.879047) (xy 347.191511 -229.829684) (xy 347.206955 -229.782152)
			(xy 347.229645 -229.73762) (xy 347.259021 -229.697187) (xy 347.294361 -229.661847) (xy 347.334794 -229.632471)
			(xy 347.379326 -229.609781) (xy 347.426858 -229.594337) (xy 347.476221 -229.586518) (xy 347.526199 -229.586518)
			(xy 347.575562 -229.594337) (xy 347.623094 -229.609781) (xy 347.667626 -229.632471) (xy 347.708059 -229.661847)
			(xy 347.743399 -229.697187) (xy 347.772775 -229.73762) (xy 347.795465 -229.782152) (xy 347.810909 -229.829684)
			(xy 347.818728 -229.879047) (xy 347.819218 -229.904036) (xy 348.124775 -229.904036) (xy 348.12887 -229.853308)
			(xy 348.141049 -229.803894) (xy 348.160997 -229.757074) (xy 348.188198 -229.71406) (xy 348.221946 -229.675966)
			(xy 348.261368 -229.643779) (xy 348.305442 -229.618333) (xy 348.353028 -229.600286) (xy 348.402892 -229.590106)
			(xy 348.453744 -229.588057) (xy 348.504265 -229.594191) (xy 348.553149 -229.608351) (xy 348.599128 -229.630168)
			(xy 348.641012 -229.659078) (xy 348.677716 -229.694333) (xy 348.708289 -229.735019) (xy 348.73194 -229.780082)
			(xy 348.748056 -229.828356) (xy 348.75622 -229.87859) (xy 348.756732 -229.904036) (xy 349.064829 -229.904036)
			(xy 349.068924 -229.853308) (xy 349.081103 -229.803894) (xy 349.101051 -229.757074) (xy 349.128252 -229.71406)
			(xy 349.162 -229.675966) (xy 349.201422 -229.643779) (xy 349.245496 -229.618333) (xy 349.293082 -229.600286)
			(xy 349.342946 -229.590106) (xy 349.393798 -229.588057) (xy 349.444319 -229.594191) (xy 349.493203 -229.608351)
			(xy 349.539182 -229.630168) (xy 349.581066 -229.659078) (xy 349.61777 -229.694333) (xy 349.648343 -229.735019)
			(xy 349.671994 -229.780082) (xy 349.68811 -229.828356) (xy 349.696274 -229.87859) (xy 349.696786 -229.904036)
			(xy 349.696283 -229.929025) (xy 350.0036 -229.929025) (xy 350.0036 -229.879047) (xy 350.011419 -229.829684)
			(xy 350.026863 -229.782152) (xy 350.049553 -229.73762) (xy 350.078929 -229.697187) (xy 350.114269 -229.661847)
			(xy 350.154702 -229.632471) (xy 350.199234 -229.609781) (xy 350.246766 -229.594337) (xy 350.296129 -229.586518)
			(xy 350.346107 -229.586518) (xy 350.39547 -229.594337) (xy 350.443002 -229.609781) (xy 350.487534 -229.632471)
			(xy 350.527967 -229.661847) (xy 350.563307 -229.697187) (xy 350.592683 -229.73762) (xy 350.615373 -229.782152)
			(xy 350.630817 -229.829684) (xy 350.638636 -229.879047) (xy 350.639126 -229.904036) (xy 350.944937 -229.904036)
			(xy 350.949032 -229.853308) (xy 350.961211 -229.803894) (xy 350.981159 -229.757074) (xy 351.00836 -229.71406)
			(xy 351.042108 -229.675966) (xy 351.08153 -229.643779) (xy 351.125604 -229.618333) (xy 351.17319 -229.600286)
			(xy 351.223054 -229.590106) (xy 351.273906 -229.588057) (xy 351.324427 -229.594191) (xy 351.373311 -229.608351)
			(xy 351.41929 -229.630168) (xy 351.461174 -229.659078) (xy 351.497878 -229.694333) (xy 351.528451 -229.735019)
			(xy 351.552102 -229.780082) (xy 351.568218 -229.828356) (xy 351.576382 -229.87859) (xy 351.576894 -229.904036)
			(xy 351.884991 -229.904036) (xy 351.889086 -229.853308) (xy 351.901265 -229.803894) (xy 351.921213 -229.757074)
			(xy 351.948414 -229.71406) (xy 351.982162 -229.675966) (xy 352.021584 -229.643779) (xy 352.065658 -229.618333)
			(xy 352.113244 -229.600286) (xy 352.163108 -229.590106) (xy 352.21396 -229.588057) (xy 352.264481 -229.594191)
			(xy 352.313365 -229.608351) (xy 352.359344 -229.630168) (xy 352.401228 -229.659078) (xy 352.437932 -229.694333)
			(xy 352.468505 -229.735019) (xy 352.492156 -229.780082) (xy 352.508272 -229.828356) (xy 352.516436 -229.87859)
			(xy 352.516948 -229.904036) (xy 352.516445 -229.929025) (xy 352.823508 -229.929025) (xy 352.823508 -229.879047)
			(xy 352.831327 -229.829684) (xy 352.846771 -229.782152) (xy 352.869461 -229.73762) (xy 352.898837 -229.697187)
			(xy 352.934177 -229.661847) (xy 352.97461 -229.632471) (xy 353.019142 -229.609781) (xy 353.066674 -229.594337)
			(xy 353.116037 -229.586518) (xy 353.166015 -229.586518) (xy 353.215378 -229.594337) (xy 353.26291 -229.609781)
			(xy 353.307442 -229.632471) (xy 353.347875 -229.661847) (xy 353.383215 -229.697187) (xy 353.412591 -229.73762)
			(xy 353.435281 -229.782152) (xy 353.450725 -229.829684) (xy 353.458544 -229.879047) (xy 353.459034 -229.904036)
			(xy 353.764845 -229.904036) (xy 353.76894 -229.853308) (xy 353.781119 -229.803894) (xy 353.801067 -229.757074)
			(xy 353.828268 -229.71406) (xy 353.862016 -229.675966) (xy 353.901438 -229.643779) (xy 353.945512 -229.618333)
			(xy 353.993098 -229.600286) (xy 354.042962 -229.590106) (xy 354.093814 -229.588057) (xy 354.144335 -229.594191)
			(xy 354.193219 -229.608351) (xy 354.239198 -229.630168) (xy 354.281082 -229.659078) (xy 354.317786 -229.694333)
			(xy 354.348359 -229.735019) (xy 354.37201 -229.780082) (xy 354.388126 -229.828356) (xy 354.39629 -229.87859)
			(xy 354.396802 -229.904036) (xy 354.704899 -229.904036) (xy 354.708994 -229.853308) (xy 354.721173 -229.803894)
			(xy 354.741121 -229.757074) (xy 354.768322 -229.71406) (xy 354.80207 -229.675966) (xy 354.841492 -229.643779)
			(xy 354.885566 -229.618333) (xy 354.933152 -229.600286) (xy 354.983016 -229.590106) (xy 355.033868 -229.588057)
			(xy 355.084389 -229.594191) (xy 355.133273 -229.608351) (xy 355.179252 -229.630168) (xy 355.221136 -229.659078)
			(xy 355.25784 -229.694333) (xy 355.288413 -229.735019) (xy 355.312064 -229.780082) (xy 355.32818 -229.828356)
			(xy 355.336344 -229.87859) (xy 355.336856 -229.904036) (xy 355.336353 -229.929025) (xy 355.64367 -229.929025)
			(xy 355.64367 -229.879047) (xy 355.651489 -229.829684) (xy 355.666933 -229.782152) (xy 355.689623 -229.73762)
			(xy 355.718999 -229.697187) (xy 355.754339 -229.661847) (xy 355.794772 -229.632471) (xy 355.839304 -229.609781)
			(xy 355.886836 -229.594337) (xy 355.936199 -229.586518) (xy 355.986177 -229.586518) (xy 356.03554 -229.594337)
			(xy 356.083072 -229.609781) (xy 356.127604 -229.632471) (xy 356.168037 -229.661847) (xy 356.203377 -229.697187)
			(xy 356.232753 -229.73762) (xy 356.255443 -229.782152) (xy 356.270887 -229.829684) (xy 356.278706 -229.879047)
			(xy 356.279196 -229.904036) (xy 356.278706 -229.929025) (xy 356.583724 -229.929025) (xy 356.583724 -229.879047)
			(xy 356.591543 -229.829684) (xy 356.606987 -229.782152) (xy 356.629677 -229.73762) (xy 356.659053 -229.697187)
			(xy 356.694393 -229.661847) (xy 356.734826 -229.632471) (xy 356.779358 -229.609781) (xy 356.82689 -229.594337)
			(xy 356.876253 -229.586518) (xy 356.926231 -229.586518) (xy 356.975594 -229.594337) (xy 357.023126 -229.609781)
			(xy 357.067658 -229.632471) (xy 357.108091 -229.661847) (xy 357.143431 -229.697187) (xy 357.172807 -229.73762)
			(xy 357.195497 -229.782152) (xy 357.210941 -229.829684) (xy 357.21876 -229.879047) (xy 357.21925 -229.904036)
			(xy 357.21876 -229.929025) (xy 357.523524 -229.929025) (xy 357.523524 -229.879047) (xy 357.531343 -229.829684)
			(xy 357.546787 -229.782152) (xy 357.569477 -229.73762) (xy 357.598853 -229.697187) (xy 357.634193 -229.661847)
			(xy 357.674626 -229.632471) (xy 357.719158 -229.609781) (xy 357.76669 -229.594337) (xy 357.816053 -229.586518)
			(xy 357.866031 -229.586518) (xy 357.915394 -229.594337) (xy 357.962926 -229.609781) (xy 358.007458 -229.632471)
			(xy 358.047891 -229.661847) (xy 358.083231 -229.697187) (xy 358.112607 -229.73762) (xy 358.135297 -229.782152)
			(xy 358.150741 -229.829684) (xy 358.15856 -229.879047) (xy 358.15905 -229.904036) (xy 358.15856 -229.929025)
			(xy 361.27739 -229.929025) (xy 361.27739 -229.879047) (xy 361.285209 -229.829684) (xy 361.300653 -229.782152)
			(xy 361.323343 -229.73762) (xy 361.352719 -229.697187) (xy 361.388059 -229.661847) (xy 361.428492 -229.632471)
			(xy 361.473024 -229.609781) (xy 361.520556 -229.594337) (xy 361.569919 -229.586518) (xy 361.619897 -229.586518)
			(xy 361.66926 -229.594337) (xy 361.716792 -229.609781) (xy 361.761324 -229.632471) (xy 361.801757 -229.661847)
			(xy 361.837097 -229.697187) (xy 361.866473 -229.73762) (xy 361.889163 -229.782152) (xy 361.904607 -229.829684)
			(xy 361.912426 -229.879047) (xy 361.912916 -229.904036) (xy 361.912426 -229.929025) (xy 362.21719 -229.929025)
			(xy 362.21719 -229.879047) (xy 362.225009 -229.829684) (xy 362.240453 -229.782152) (xy 362.263143 -229.73762)
			(xy 362.292519 -229.697187) (xy 362.327859 -229.661847) (xy 362.368292 -229.632471) (xy 362.412824 -229.609781)
			(xy 362.460356 -229.594337) (xy 362.509719 -229.586518) (xy 362.559697 -229.586518) (xy 362.60906 -229.594337)
			(xy 362.656592 -229.609781) (xy 362.701124 -229.632471) (xy 362.741557 -229.661847) (xy 362.776897 -229.697187)
			(xy 362.806273 -229.73762) (xy 362.828963 -229.782152) (xy 362.844407 -229.829684) (xy 362.852226 -229.879047)
			(xy 362.852716 -229.904036) (xy 362.852226 -229.929025) (xy 363.157244 -229.929025) (xy 363.157244 -229.879047)
			(xy 363.165063 -229.829684) (xy 363.180507 -229.782152) (xy 363.203197 -229.73762) (xy 363.232573 -229.697187)
			(xy 363.267913 -229.661847) (xy 363.308346 -229.632471) (xy 363.352878 -229.609781) (xy 363.40041 -229.594337)
			(xy 363.449773 -229.586518) (xy 363.499751 -229.586518) (xy 363.549114 -229.594337) (xy 363.596646 -229.609781)
			(xy 363.641178 -229.632471) (xy 363.681611 -229.661847) (xy 363.716951 -229.697187) (xy 363.746327 -229.73762)
			(xy 363.769017 -229.782152) (xy 363.784461 -229.829684) (xy 363.79228 -229.879047) (xy 363.79277 -229.904036)
			(xy 364.098581 -229.904036) (xy 364.102676 -229.853308) (xy 364.114855 -229.803894) (xy 364.134803 -229.757074)
			(xy 364.162004 -229.71406) (xy 364.195752 -229.675966) (xy 364.235174 -229.643779) (xy 364.279248 -229.618333)
			(xy 364.326834 -229.600286) (xy 364.376698 -229.590106) (xy 364.42755 -229.588057) (xy 364.478071 -229.594191)
			(xy 364.526955 -229.608351) (xy 364.572934 -229.630168) (xy 364.614818 -229.659078) (xy 364.651522 -229.694333)
			(xy 364.682095 -229.735019) (xy 364.705746 -229.780082) (xy 364.721862 -229.828356) (xy 364.730026 -229.87859)
			(xy 364.730538 -229.904036) (xy 365.038635 -229.904036) (xy 365.04273 -229.853308) (xy 365.054909 -229.803894)
			(xy 365.074857 -229.757074) (xy 365.102058 -229.71406) (xy 365.135806 -229.675966) (xy 365.175228 -229.643779)
			(xy 365.219302 -229.618333) (xy 365.266888 -229.600286) (xy 365.316752 -229.590106) (xy 365.367604 -229.588057)
			(xy 365.418125 -229.594191) (xy 365.467009 -229.608351) (xy 365.512988 -229.630168) (xy 365.554872 -229.659078)
			(xy 365.591576 -229.694333) (xy 365.622149 -229.735019) (xy 365.6458 -229.780082) (xy 365.661916 -229.828356)
			(xy 365.67008 -229.87859) (xy 365.670592 -229.904036) (xy 365.670089 -229.929025) (xy 365.977406 -229.929025)
			(xy 365.977406 -229.879047) (xy 365.985225 -229.829684) (xy 366.000669 -229.782152) (xy 366.023359 -229.73762)
			(xy 366.052735 -229.697187) (xy 366.088075 -229.661847) (xy 366.128508 -229.632471) (xy 366.17304 -229.609781)
			(xy 366.220572 -229.594337) (xy 366.269935 -229.586518) (xy 366.319913 -229.586518) (xy 366.369276 -229.594337)
			(xy 366.416808 -229.609781) (xy 366.46134 -229.632471) (xy 366.501773 -229.661847) (xy 366.537113 -229.697187)
			(xy 366.566489 -229.73762) (xy 366.589179 -229.782152) (xy 366.604623 -229.829684) (xy 366.612442 -229.879047)
			(xy 366.612932 -229.904036) (xy 366.918489 -229.904036) (xy 366.922584 -229.853308) (xy 366.934763 -229.803894)
			(xy 366.954711 -229.757074) (xy 366.981912 -229.71406) (xy 367.01566 -229.675966) (xy 367.055082 -229.643779)
			(xy 367.099156 -229.618333) (xy 367.146742 -229.600286) (xy 367.196606 -229.590106) (xy 367.247458 -229.588057)
			(xy 367.297979 -229.594191) (xy 367.346863 -229.608351) (xy 367.392842 -229.630168) (xy 367.434726 -229.659078)
			(xy 367.47143 -229.694333) (xy 367.502003 -229.735019) (xy 367.525654 -229.780082) (xy 367.54177 -229.828356)
			(xy 367.549934 -229.87859) (xy 367.550446 -229.904036) (xy 367.858543 -229.904036) (xy 367.862638 -229.853308)
			(xy 367.874817 -229.803894) (xy 367.894765 -229.757074) (xy 367.921966 -229.71406) (xy 367.955714 -229.675966)
			(xy 367.995136 -229.643779) (xy 368.03921 -229.618333) (xy 368.086796 -229.600286) (xy 368.13666 -229.590106)
			(xy 368.187512 -229.588057) (xy 368.238033 -229.594191) (xy 368.286917 -229.608351) (xy 368.332896 -229.630168)
			(xy 368.37478 -229.659078) (xy 368.411484 -229.694333) (xy 368.442057 -229.735019) (xy 368.465708 -229.780082)
			(xy 368.481824 -229.828356) (xy 368.489988 -229.87859) (xy 368.4905 -229.904036) (xy 368.489997 -229.929025)
			(xy 368.797314 -229.929025) (xy 368.797314 -229.879047) (xy 368.805133 -229.829684) (xy 368.820577 -229.782152)
			(xy 368.843267 -229.73762) (xy 368.872643 -229.697187) (xy 368.907983 -229.661847) (xy 368.948416 -229.632471)
			(xy 368.992948 -229.609781) (xy 369.04048 -229.594337) (xy 369.089843 -229.586518) (xy 369.139821 -229.586518)
			(xy 369.189184 -229.594337) (xy 369.236716 -229.609781) (xy 369.281248 -229.632471) (xy 369.321681 -229.661847)
			(xy 369.357021 -229.697187) (xy 369.386397 -229.73762) (xy 369.409087 -229.782152) (xy 369.424531 -229.829684)
			(xy 369.43235 -229.879047) (xy 369.43284 -229.904036) (xy 369.738651 -229.904036) (xy 369.742746 -229.853308)
			(xy 369.754925 -229.803894) (xy 369.774873 -229.757074) (xy 369.802074 -229.71406) (xy 369.835822 -229.675966)
			(xy 369.875244 -229.643779) (xy 369.919318 -229.618333) (xy 369.966904 -229.600286) (xy 370.016768 -229.590106)
			(xy 370.06762 -229.588057) (xy 370.118141 -229.594191) (xy 370.167025 -229.608351) (xy 370.213004 -229.630168)
			(xy 370.254888 -229.659078) (xy 370.291592 -229.694333) (xy 370.322165 -229.735019) (xy 370.345816 -229.780082)
			(xy 370.361932 -229.828356) (xy 370.370096 -229.87859) (xy 370.370608 -229.904036) (xy 370.678451 -229.904036)
			(xy 370.682546 -229.853308) (xy 370.694725 -229.803894) (xy 370.714673 -229.757074) (xy 370.741874 -229.71406)
			(xy 370.775622 -229.675966) (xy 370.815044 -229.643779) (xy 370.859118 -229.618333) (xy 370.906704 -229.600286)
			(xy 370.956568 -229.590106) (xy 371.00742 -229.588057) (xy 371.057941 -229.594191) (xy 371.106825 -229.608351)
			(xy 371.152804 -229.630168) (xy 371.194688 -229.659078) (xy 371.231392 -229.694333) (xy 371.261965 -229.735019)
			(xy 371.285616 -229.780082) (xy 371.301732 -229.828356) (xy 371.309896 -229.87859) (xy 371.310408 -229.904036)
			(xy 371.309905 -229.929025) (xy 371.617222 -229.929025) (xy 371.617222 -229.879047) (xy 371.625041 -229.829684)
			(xy 371.640485 -229.782152) (xy 371.663175 -229.73762) (xy 371.692551 -229.697187) (xy 371.727891 -229.661847)
			(xy 371.768324 -229.632471) (xy 371.812856 -229.609781) (xy 371.860388 -229.594337) (xy 371.909751 -229.586518)
			(xy 371.959729 -229.586518) (xy 372.009092 -229.594337) (xy 372.056624 -229.609781) (xy 372.101156 -229.632471)
			(xy 372.141589 -229.661847) (xy 372.176929 -229.697187) (xy 372.206305 -229.73762) (xy 372.228995 -229.782152)
			(xy 372.244439 -229.829684) (xy 372.252258 -229.879047) (xy 372.252748 -229.904036) (xy 372.558559 -229.904036)
			(xy 372.562654 -229.853308) (xy 372.574833 -229.803894) (xy 372.594781 -229.757074) (xy 372.621982 -229.71406)
			(xy 372.65573 -229.675966) (xy 372.695152 -229.643779) (xy 372.739226 -229.618333) (xy 372.786812 -229.600286)
			(xy 372.836676 -229.590106) (xy 372.887528 -229.588057) (xy 372.938049 -229.594191) (xy 372.986933 -229.608351)
			(xy 373.032912 -229.630168) (xy 373.074796 -229.659078) (xy 373.1115 -229.694333) (xy 373.142073 -229.735019)
			(xy 373.165724 -229.780082) (xy 373.18184 -229.828356) (xy 373.190004 -229.87859) (xy 373.190516 -229.904036)
			(xy 373.498613 -229.904036) (xy 373.502708 -229.853308) (xy 373.514887 -229.803894) (xy 373.534835 -229.757074)
			(xy 373.562036 -229.71406) (xy 373.595784 -229.675966) (xy 373.635206 -229.643779) (xy 373.67928 -229.618333)
			(xy 373.726866 -229.600286) (xy 373.77673 -229.590106) (xy 373.827582 -229.588057) (xy 373.878103 -229.594191)
			(xy 373.926987 -229.608351) (xy 373.972966 -229.630168) (xy 374.01485 -229.659078) (xy 374.051554 -229.694333)
			(xy 374.082127 -229.735019) (xy 374.105778 -229.780082) (xy 374.121894 -229.828356) (xy 374.130058 -229.87859)
			(xy 374.13057 -229.904036) (xy 374.130058 -229.929482) (xy 374.121894 -229.979716) (xy 374.105778 -230.02799)
			(xy 374.082127 -230.073053) (xy 374.051554 -230.113739) (xy 374.01485 -230.148994) (xy 373.972966 -230.177904)
			(xy 373.926987 -230.199721) (xy 373.878103 -230.213881) (xy 373.827582 -230.220015) (xy 373.77673 -230.217966)
			(xy 373.726866 -230.207786) (xy 373.67928 -230.189739) (xy 373.635206 -230.164293) (xy 373.595784 -230.132106)
			(xy 373.562036 -230.094012) (xy 373.534835 -230.050998) (xy 373.514887 -230.004178) (xy 373.502708 -229.954764)
			(xy 373.498613 -229.904036) (xy 373.190516 -229.904036) (xy 373.190004 -229.929482) (xy 373.18184 -229.979716)
			(xy 373.165724 -230.02799) (xy 373.142073 -230.073053) (xy 373.1115 -230.113739) (xy 373.074796 -230.148994)
			(xy 373.032912 -230.177904) (xy 372.986933 -230.199721) (xy 372.938049 -230.213881) (xy 372.887528 -230.220015)
			(xy 372.836676 -230.217966) (xy 372.786812 -230.207786) (xy 372.739226 -230.189739) (xy 372.695152 -230.164293)
			(xy 372.65573 -230.132106) (xy 372.621982 -230.094012) (xy 372.594781 -230.050998) (xy 372.574833 -230.004178)
			(xy 372.562654 -229.954764) (xy 372.558559 -229.904036) (xy 372.252748 -229.904036) (xy 372.252258 -229.929025)
			(xy 372.244439 -229.978388) (xy 372.228995 -230.02592) (xy 372.206305 -230.070452) (xy 372.176929 -230.110885)
			(xy 372.141589 -230.146225) (xy 372.101156 -230.175601) (xy 372.056624 -230.198291) (xy 372.009092 -230.213735)
			(xy 371.959729 -230.221554) (xy 371.909751 -230.221554) (xy 371.860388 -230.213735) (xy 371.812856 -230.198291)
			(xy 371.768324 -230.175601) (xy 371.727891 -230.146225) (xy 371.692551 -230.110885) (xy 371.663175 -230.070452)
			(xy 371.640485 -230.02592) (xy 371.625041 -229.978388) (xy 371.617222 -229.929025) (xy 371.309905 -229.929025)
			(xy 371.309896 -229.929482) (xy 371.301732 -229.979716) (xy 371.285616 -230.02799) (xy 371.261965 -230.073053)
			(xy 371.231392 -230.113739) (xy 371.194688 -230.148994) (xy 371.152804 -230.177904) (xy 371.106825 -230.199721)
			(xy 371.057941 -230.213881) (xy 371.00742 -230.220015) (xy 370.956568 -230.217966) (xy 370.906704 -230.207786)
			(xy 370.859118 -230.189739) (xy 370.815044 -230.164293) (xy 370.775622 -230.132106) (xy 370.741874 -230.094012)
			(xy 370.714673 -230.050998) (xy 370.694725 -230.004178) (xy 370.682546 -229.954764) (xy 370.678451 -229.904036)
			(xy 370.370608 -229.904036) (xy 370.370096 -229.929482) (xy 370.361932 -229.979716) (xy 370.345816 -230.02799)
			(xy 370.322165 -230.073053) (xy 370.291592 -230.113739) (xy 370.254888 -230.148994) (xy 370.213004 -230.177904)
			(xy 370.167025 -230.199721) (xy 370.118141 -230.213881) (xy 370.06762 -230.220015) (xy 370.016768 -230.217966)
			(xy 369.966904 -230.207786) (xy 369.919318 -230.189739) (xy 369.875244 -230.164293) (xy 369.835822 -230.132106)
			(xy 369.802074 -230.094012) (xy 369.774873 -230.050998) (xy 369.754925 -230.004178) (xy 369.742746 -229.954764)
			(xy 369.738651 -229.904036) (xy 369.43284 -229.904036) (xy 369.43235 -229.929025) (xy 369.424531 -229.978388)
			(xy 369.409087 -230.02592) (xy 369.386397 -230.070452) (xy 369.357021 -230.110885) (xy 369.321681 -230.146225)
			(xy 369.281248 -230.175601) (xy 369.236716 -230.198291) (xy 369.189184 -230.213735) (xy 369.139821 -230.221554)
			(xy 369.089843 -230.221554) (xy 369.04048 -230.213735) (xy 368.992948 -230.198291) (xy 368.948416 -230.175601)
			(xy 368.907983 -230.146225) (xy 368.872643 -230.110885) (xy 368.843267 -230.070452) (xy 368.820577 -230.02592)
			(xy 368.805133 -229.978388) (xy 368.797314 -229.929025) (xy 368.489997 -229.929025) (xy 368.489988 -229.929482)
			(xy 368.481824 -229.979716) (xy 368.465708 -230.02799) (xy 368.442057 -230.073053) (xy 368.411484 -230.113739)
			(xy 368.37478 -230.148994) (xy 368.332896 -230.177904) (xy 368.286917 -230.199721) (xy 368.238033 -230.213881)
			(xy 368.187512 -230.220015) (xy 368.13666 -230.217966) (xy 368.086796 -230.207786) (xy 368.03921 -230.189739)
			(xy 367.995136 -230.164293) (xy 367.955714 -230.132106) (xy 367.921966 -230.094012) (xy 367.894765 -230.050998)
			(xy 367.874817 -230.004178) (xy 367.862638 -229.954764) (xy 367.858543 -229.904036) (xy 367.550446 -229.904036)
			(xy 367.549934 -229.929482) (xy 367.54177 -229.979716) (xy 367.525654 -230.02799) (xy 367.502003 -230.073053)
			(xy 367.47143 -230.113739) (xy 367.434726 -230.148994) (xy 367.392842 -230.177904) (xy 367.346863 -230.199721)
			(xy 367.297979 -230.213881) (xy 367.247458 -230.220015) (xy 367.196606 -230.217966) (xy 367.146742 -230.207786)
			(xy 367.099156 -230.189739) (xy 367.055082 -230.164293) (xy 367.01566 -230.132106) (xy 366.981912 -230.094012)
			(xy 366.954711 -230.050998) (xy 366.934763 -230.004178) (xy 366.922584 -229.954764) (xy 366.918489 -229.904036)
			(xy 366.612932 -229.904036) (xy 366.612442 -229.929025) (xy 366.604623 -229.978388) (xy 366.589179 -230.02592)
			(xy 366.566489 -230.070452) (xy 366.537113 -230.110885) (xy 366.501773 -230.146225) (xy 366.46134 -230.175601)
			(xy 366.416808 -230.198291) (xy 366.369276 -230.213735) (xy 366.319913 -230.221554) (xy 366.269935 -230.221554)
			(xy 366.220572 -230.213735) (xy 366.17304 -230.198291) (xy 366.128508 -230.175601) (xy 366.088075 -230.146225)
			(xy 366.052735 -230.110885) (xy 366.023359 -230.070452) (xy 366.000669 -230.02592) (xy 365.985225 -229.978388)
			(xy 365.977406 -229.929025) (xy 365.670089 -229.929025) (xy 365.67008 -229.929482) (xy 365.661916 -229.979716)
			(xy 365.6458 -230.02799) (xy 365.622149 -230.073053) (xy 365.591576 -230.113739) (xy 365.554872 -230.148994)
			(xy 365.512988 -230.177904) (xy 365.467009 -230.199721) (xy 365.418125 -230.213881) (xy 365.367604 -230.220015)
			(xy 365.316752 -230.217966) (xy 365.266888 -230.207786) (xy 365.219302 -230.189739) (xy 365.175228 -230.164293)
			(xy 365.135806 -230.132106) (xy 365.102058 -230.094012) (xy 365.074857 -230.050998) (xy 365.054909 -230.004178)
			(xy 365.04273 -229.954764) (xy 365.038635 -229.904036) (xy 364.730538 -229.904036) (xy 364.730026 -229.929482)
			(xy 364.721862 -229.979716) (xy 364.705746 -230.02799) (xy 364.682095 -230.073053) (xy 364.651522 -230.113739)
			(xy 364.614818 -230.148994) (xy 364.572934 -230.177904) (xy 364.526955 -230.199721) (xy 364.478071 -230.213881)
			(xy 364.42755 -230.220015) (xy 364.376698 -230.217966) (xy 364.326834 -230.207786) (xy 364.279248 -230.189739)
			(xy 364.235174 -230.164293) (xy 364.195752 -230.132106) (xy 364.162004 -230.094012) (xy 364.134803 -230.050998)
			(xy 364.114855 -230.004178) (xy 364.102676 -229.954764) (xy 364.098581 -229.904036) (xy 363.79277 -229.904036)
			(xy 363.79228 -229.929025) (xy 363.784461 -229.978388) (xy 363.769017 -230.02592) (xy 363.746327 -230.070452)
			(xy 363.716951 -230.110885) (xy 363.681611 -230.146225) (xy 363.641178 -230.175601) (xy 363.596646 -230.198291)
			(xy 363.549114 -230.213735) (xy 363.499751 -230.221554) (xy 363.449773 -230.221554) (xy 363.40041 -230.213735)
			(xy 363.352878 -230.198291) (xy 363.308346 -230.175601) (xy 363.267913 -230.146225) (xy 363.232573 -230.110885)
			(xy 363.203197 -230.070452) (xy 363.180507 -230.02592) (xy 363.165063 -229.978388) (xy 363.157244 -229.929025)
			(xy 362.852226 -229.929025) (xy 362.844407 -229.978388) (xy 362.828963 -230.02592) (xy 362.806273 -230.070452)
			(xy 362.776897 -230.110885) (xy 362.741557 -230.146225) (xy 362.701124 -230.175601) (xy 362.656592 -230.198291)
			(xy 362.60906 -230.213735) (xy 362.559697 -230.221554) (xy 362.509719 -230.221554) (xy 362.460356 -230.213735)
			(xy 362.412824 -230.198291) (xy 362.368292 -230.175601) (xy 362.327859 -230.146225) (xy 362.292519 -230.110885)
			(xy 362.263143 -230.070452) (xy 362.240453 -230.02592) (xy 362.225009 -229.978388) (xy 362.21719 -229.929025)
			(xy 361.912426 -229.929025) (xy 361.904607 -229.978388) (xy 361.889163 -230.02592) (xy 361.866473 -230.070452)
			(xy 361.837097 -230.110885) (xy 361.801757 -230.146225) (xy 361.761324 -230.175601) (xy 361.716792 -230.198291)
			(xy 361.66926 -230.213735) (xy 361.619897 -230.221554) (xy 361.569919 -230.221554) (xy 361.520556 -230.213735)
			(xy 361.473024 -230.198291) (xy 361.428492 -230.175601) (xy 361.388059 -230.146225) (xy 361.352719 -230.110885)
			(xy 361.323343 -230.070452) (xy 361.300653 -230.02592) (xy 361.285209 -229.978388) (xy 361.27739 -229.929025)
			(xy 358.15856 -229.929025) (xy 358.150741 -229.978388) (xy 358.135297 -230.02592) (xy 358.112607 -230.070452)
			(xy 358.083231 -230.110885) (xy 358.047891 -230.146225) (xy 358.007458 -230.175601) (xy 357.962926 -230.198291)
			(xy 357.915394 -230.213735) (xy 357.866031 -230.221554) (xy 357.816053 -230.221554) (xy 357.76669 -230.213735)
			(xy 357.719158 -230.198291) (xy 357.674626 -230.175601) (xy 357.634193 -230.146225) (xy 357.598853 -230.110885)
			(xy 357.569477 -230.070452) (xy 357.546787 -230.02592) (xy 357.531343 -229.978388) (xy 357.523524 -229.929025)
			(xy 357.21876 -229.929025) (xy 357.210941 -229.978388) (xy 357.195497 -230.02592) (xy 357.172807 -230.070452)
			(xy 357.143431 -230.110885) (xy 357.108091 -230.146225) (xy 357.067658 -230.175601) (xy 357.023126 -230.198291)
			(xy 356.975594 -230.213735) (xy 356.926231 -230.221554) (xy 356.876253 -230.221554) (xy 356.82689 -230.213735)
			(xy 356.779358 -230.198291) (xy 356.734826 -230.175601) (xy 356.694393 -230.146225) (xy 356.659053 -230.110885)
			(xy 356.629677 -230.070452) (xy 356.606987 -230.02592) (xy 356.591543 -229.978388) (xy 356.583724 -229.929025)
			(xy 356.278706 -229.929025) (xy 356.270887 -229.978388) (xy 356.255443 -230.02592) (xy 356.232753 -230.070452)
			(xy 356.203377 -230.110885) (xy 356.168037 -230.146225) (xy 356.127604 -230.175601) (xy 356.083072 -230.198291)
			(xy 356.03554 -230.213735) (xy 355.986177 -230.221554) (xy 355.936199 -230.221554) (xy 355.886836 -230.213735)
			(xy 355.839304 -230.198291) (xy 355.794772 -230.175601) (xy 355.754339 -230.146225) (xy 355.718999 -230.110885)
			(xy 355.689623 -230.070452) (xy 355.666933 -230.02592) (xy 355.651489 -229.978388) (xy 355.64367 -229.929025)
			(xy 355.336353 -229.929025) (xy 355.336344 -229.929482) (xy 355.32818 -229.979716) (xy 355.312064 -230.02799)
			(xy 355.288413 -230.073053) (xy 355.25784 -230.113739) (xy 355.221136 -230.148994) (xy 355.179252 -230.177904)
			(xy 355.133273 -230.199721) (xy 355.084389 -230.213881) (xy 355.033868 -230.220015) (xy 354.983016 -230.217966)
			(xy 354.933152 -230.207786) (xy 354.885566 -230.189739) (xy 354.841492 -230.164293) (xy 354.80207 -230.132106)
			(xy 354.768322 -230.094012) (xy 354.741121 -230.050998) (xy 354.721173 -230.004178) (xy 354.708994 -229.954764)
			(xy 354.704899 -229.904036) (xy 354.396802 -229.904036) (xy 354.39629 -229.929482) (xy 354.388126 -229.979716)
			(xy 354.37201 -230.02799) (xy 354.348359 -230.073053) (xy 354.317786 -230.113739) (xy 354.281082 -230.148994)
			(xy 354.239198 -230.177904) (xy 354.193219 -230.199721) (xy 354.144335 -230.213881) (xy 354.093814 -230.220015)
			(xy 354.042962 -230.217966) (xy 353.993098 -230.207786) (xy 353.945512 -230.189739) (xy 353.901438 -230.164293)
			(xy 353.862016 -230.132106) (xy 353.828268 -230.094012) (xy 353.801067 -230.050998) (xy 353.781119 -230.004178)
			(xy 353.76894 -229.954764) (xy 353.764845 -229.904036) (xy 353.459034 -229.904036) (xy 353.458544 -229.929025)
			(xy 353.450725 -229.978388) (xy 353.435281 -230.02592) (xy 353.412591 -230.070452) (xy 353.383215 -230.110885)
			(xy 353.347875 -230.146225) (xy 353.307442 -230.175601) (xy 353.26291 -230.198291) (xy 353.215378 -230.213735)
			(xy 353.166015 -230.221554) (xy 353.116037 -230.221554) (xy 353.066674 -230.213735) (xy 353.019142 -230.198291)
			(xy 352.97461 -230.175601) (xy 352.934177 -230.146225) (xy 352.898837 -230.110885) (xy 352.869461 -230.070452)
			(xy 352.846771 -230.02592) (xy 352.831327 -229.978388) (xy 352.823508 -229.929025) (xy 352.516445 -229.929025)
			(xy 352.516436 -229.929482) (xy 352.508272 -229.979716) (xy 352.492156 -230.02799) (xy 352.468505 -230.073053)
			(xy 352.437932 -230.113739) (xy 352.401228 -230.148994) (xy 352.359344 -230.177904) (xy 352.313365 -230.199721)
			(xy 352.264481 -230.213881) (xy 352.21396 -230.220015) (xy 352.163108 -230.217966) (xy 352.113244 -230.207786)
			(xy 352.065658 -230.189739) (xy 352.021584 -230.164293) (xy 351.982162 -230.132106) (xy 351.948414 -230.094012)
			(xy 351.921213 -230.050998) (xy 351.901265 -230.004178) (xy 351.889086 -229.954764) (xy 351.884991 -229.904036)
			(xy 351.576894 -229.904036) (xy 351.576382 -229.929482) (xy 351.568218 -229.979716) (xy 351.552102 -230.02799)
			(xy 351.528451 -230.073053) (xy 351.497878 -230.113739) (xy 351.461174 -230.148994) (xy 351.41929 -230.177904)
			(xy 351.373311 -230.199721) (xy 351.324427 -230.213881) (xy 351.273906 -230.220015) (xy 351.223054 -230.217966)
			(xy 351.17319 -230.207786) (xy 351.125604 -230.189739) (xy 351.08153 -230.164293) (xy 351.042108 -230.132106)
			(xy 351.00836 -230.094012) (xy 350.981159 -230.050998) (xy 350.961211 -230.004178) (xy 350.949032 -229.954764)
			(xy 350.944937 -229.904036) (xy 350.639126 -229.904036) (xy 350.638636 -229.929025) (xy 350.630817 -229.978388)
			(xy 350.615373 -230.02592) (xy 350.592683 -230.070452) (xy 350.563307 -230.110885) (xy 350.527967 -230.146225)
			(xy 350.487534 -230.175601) (xy 350.443002 -230.198291) (xy 350.39547 -230.213735) (xy 350.346107 -230.221554)
			(xy 350.296129 -230.221554) (xy 350.246766 -230.213735) (xy 350.199234 -230.198291) (xy 350.154702 -230.175601)
			(xy 350.114269 -230.146225) (xy 350.078929 -230.110885) (xy 350.049553 -230.070452) (xy 350.026863 -230.02592)
			(xy 350.011419 -229.978388) (xy 350.0036 -229.929025) (xy 349.696283 -229.929025) (xy 349.696274 -229.929482)
			(xy 349.68811 -229.979716) (xy 349.671994 -230.02799) (xy 349.648343 -230.073053) (xy 349.61777 -230.113739)
			(xy 349.581066 -230.148994) (xy 349.539182 -230.177904) (xy 349.493203 -230.199721) (xy 349.444319 -230.213881)
			(xy 349.393798 -230.220015) (xy 349.342946 -230.217966) (xy 349.293082 -230.207786) (xy 349.245496 -230.189739)
			(xy 349.201422 -230.164293) (xy 349.162 -230.132106) (xy 349.128252 -230.094012) (xy 349.101051 -230.050998)
			(xy 349.081103 -230.004178) (xy 349.068924 -229.954764) (xy 349.064829 -229.904036) (xy 348.756732 -229.904036)
			(xy 348.75622 -229.929482) (xy 348.748056 -229.979716) (xy 348.73194 -230.02799) (xy 348.708289 -230.073053)
			(xy 348.677716 -230.113739) (xy 348.641012 -230.148994) (xy 348.599128 -230.177904) (xy 348.553149 -230.199721)
			(xy 348.504265 -230.213881) (xy 348.453744 -230.220015) (xy 348.402892 -230.217966) (xy 348.353028 -230.207786)
			(xy 348.305442 -230.189739) (xy 348.261368 -230.164293) (xy 348.221946 -230.132106) (xy 348.188198 -230.094012)
			(xy 348.160997 -230.050998) (xy 348.141049 -230.004178) (xy 348.12887 -229.954764) (xy 348.124775 -229.904036)
			(xy 347.819218 -229.904036) (xy 347.818728 -229.929025) (xy 347.810909 -229.978388) (xy 347.795465 -230.02592)
			(xy 347.772775 -230.070452) (xy 347.743399 -230.110885) (xy 347.708059 -230.146225) (xy 347.667626 -230.175601)
			(xy 347.623094 -230.198291) (xy 347.575562 -230.213735) (xy 347.526199 -230.221554) (xy 347.476221 -230.221554)
			(xy 347.426858 -230.213735) (xy 347.379326 -230.198291) (xy 347.334794 -230.175601) (xy 347.294361 -230.146225)
			(xy 347.259021 -230.110885) (xy 347.229645 -230.070452) (xy 347.206955 -230.02592) (xy 347.191511 -229.978388)
			(xy 347.183692 -229.929025) (xy 346.876375 -229.929025) (xy 346.876366 -229.929482) (xy 346.868202 -229.979716)
			(xy 346.852086 -230.02799) (xy 346.828435 -230.073053) (xy 346.797862 -230.113739) (xy 346.761158 -230.148994)
			(xy 346.719274 -230.177904) (xy 346.673295 -230.199721) (xy 346.624411 -230.213881) (xy 346.57389 -230.220015)
			(xy 346.523038 -230.217966) (xy 346.473174 -230.207786) (xy 346.425588 -230.189739) (xy 346.381514 -230.164293)
			(xy 346.342092 -230.132106) (xy 346.308344 -230.094012) (xy 346.281143 -230.050998) (xy 346.261195 -230.004178)
			(xy 346.249016 -229.954764) (xy 346.244921 -229.904036) (xy 345.936824 -229.904036) (xy 345.936312 -229.929482)
			(xy 345.928148 -229.979716) (xy 345.912032 -230.02799) (xy 345.888381 -230.073053) (xy 345.857808 -230.113739)
			(xy 345.821104 -230.148994) (xy 345.77922 -230.177904) (xy 345.733241 -230.199721) (xy 345.684357 -230.213881)
			(xy 345.633836 -230.220015) (xy 345.582984 -230.217966) (xy 345.53312 -230.207786) (xy 345.485534 -230.189739)
			(xy 345.44146 -230.164293) (xy 345.402038 -230.132106) (xy 345.36829 -230.094012) (xy 345.341089 -230.050998)
			(xy 345.321141 -230.004178) (xy 345.308962 -229.954764) (xy 345.304867 -229.904036) (xy 344.999056 -229.904036)
			(xy 344.999056 -229.90429) (xy 344.997786 -229.9335) (xy 344.997532 -229.938072) (xy 344.997532 -230.739285)
			(xy 346.713538 -230.739285) (xy 346.713538 -230.689307) (xy 346.721357 -230.639944) (xy 346.736801 -230.592412)
			(xy 346.759491 -230.54788) (xy 346.788867 -230.507447) (xy 346.824207 -230.472107) (xy 346.86464 -230.442731)
			(xy 346.909172 -230.420041) (xy 346.956704 -230.404597) (xy 347.006067 -230.396778) (xy 347.056045 -230.396778)
			(xy 347.105408 -230.404597) (xy 347.15294 -230.420041) (xy 347.197472 -230.442731) (xy 347.237905 -230.472107)
			(xy 347.273245 -230.507447) (xy 347.302621 -230.54788) (xy 347.325311 -230.592412) (xy 347.340755 -230.639944)
			(xy 347.348574 -230.689307) (xy 347.349064 -230.714296) (xy 347.348574 -230.739285) (xy 349.5337 -230.739285)
			(xy 349.5337 -230.689307) (xy 349.541519 -230.639944) (xy 349.556963 -230.592412) (xy 349.579653 -230.54788)
			(xy 349.609029 -230.507447) (xy 349.644369 -230.472107) (xy 349.684802 -230.442731) (xy 349.729334 -230.420041)
			(xy 349.776866 -230.404597) (xy 349.826229 -230.396778) (xy 349.876207 -230.396778) (xy 349.92557 -230.404597)
			(xy 349.973102 -230.420041) (xy 350.017634 -230.442731) (xy 350.058067 -230.472107) (xy 350.093407 -230.507447)
			(xy 350.122783 -230.54788) (xy 350.145473 -230.592412) (xy 350.160917 -230.639944) (xy 350.168736 -230.689307)
			(xy 350.169226 -230.714296) (xy 350.168736 -230.739285) (xy 352.353608 -230.739285) (xy 352.353608 -230.689307)
			(xy 352.361427 -230.639944) (xy 352.376871 -230.592412) (xy 352.399561 -230.54788) (xy 352.428937 -230.507447)
			(xy 352.464277 -230.472107) (xy 352.50471 -230.442731) (xy 352.549242 -230.420041) (xy 352.596774 -230.404597)
			(xy 352.646137 -230.396778) (xy 352.696115 -230.396778) (xy 352.745478 -230.404597) (xy 352.79301 -230.420041)
			(xy 352.837542 -230.442731) (xy 352.877975 -230.472107) (xy 352.913315 -230.507447) (xy 352.942691 -230.54788)
			(xy 352.965381 -230.592412) (xy 352.980825 -230.639944) (xy 352.988644 -230.689307) (xy 352.989134 -230.714296)
			(xy 352.988649 -230.739031) (xy 355.173516 -230.739031) (xy 355.173516 -230.689053) (xy 355.181335 -230.63969)
			(xy 355.196779 -230.592158) (xy 355.219469 -230.547626) (xy 355.248845 -230.507193) (xy 355.284185 -230.471853)
			(xy 355.324618 -230.442477) (xy 355.36915 -230.419787) (xy 355.416682 -230.404343) (xy 355.466045 -230.396524)
			(xy 355.516023 -230.396524) (xy 355.565386 -230.404343) (xy 355.612918 -230.419787) (xy 355.65745 -230.442477)
			(xy 355.697883 -230.471853) (xy 355.733223 -230.507193) (xy 355.762599 -230.547626) (xy 355.785289 -230.592158)
			(xy 355.800733 -230.63969) (xy 355.808552 -230.689053) (xy 355.809042 -230.714042) (xy 355.809037 -230.714296)
			(xy 356.114853 -230.714296) (xy 356.118948 -230.663568) (xy 356.131127 -230.614154) (xy 356.151075 -230.567334)
			(xy 356.178276 -230.52432) (xy 356.212024 -230.486226) (xy 356.251446 -230.454039) (xy 356.29552 -230.428593)
			(xy 356.343106 -230.410546) (xy 356.39297 -230.400366) (xy 356.443822 -230.398317) (xy 356.494343 -230.404451)
			(xy 356.543227 -230.418611) (xy 356.589206 -230.440428) (xy 356.63109 -230.469338) (xy 356.667794 -230.504593)
			(xy 356.698367 -230.545279) (xy 356.722018 -230.590342) (xy 356.738134 -230.638616) (xy 356.746298 -230.68885)
			(xy 356.74681 -230.714296) (xy 357.054907 -230.714296) (xy 357.059002 -230.663568) (xy 357.071181 -230.614154)
			(xy 357.091129 -230.567334) (xy 357.11833 -230.52432) (xy 357.152078 -230.486226) (xy 357.1915 -230.454039)
			(xy 357.235574 -230.428593) (xy 357.28316 -230.410546) (xy 357.333024 -230.400366) (xy 357.383876 -230.398317)
			(xy 357.434397 -230.404451) (xy 357.483281 -230.418611) (xy 357.52926 -230.440428) (xy 357.571144 -230.469338)
			(xy 357.607848 -230.504593) (xy 357.638421 -230.545279) (xy 357.662072 -230.590342) (xy 357.678188 -230.638616)
			(xy 357.686352 -230.68885) (xy 357.686864 -230.714296) (xy 357.686361 -230.739285) (xy 357.993678 -230.739285)
			(xy 357.993678 -230.689307) (xy 358.001497 -230.639944) (xy 358.016941 -230.592412) (xy 358.039631 -230.54788)
			(xy 358.069007 -230.507447) (xy 358.104347 -230.472107) (xy 358.14478 -230.442731) (xy 358.189312 -230.420041)
			(xy 358.236844 -230.404597) (xy 358.286207 -230.396778) (xy 358.336185 -230.396778) (xy 358.385548 -230.404597)
			(xy 358.43308 -230.420041) (xy 358.477612 -230.442731) (xy 358.518045 -230.472107) (xy 358.553385 -230.507447)
			(xy 358.582761 -230.54788) (xy 358.605451 -230.592412) (xy 358.620895 -230.639944) (xy 358.628714 -230.689307)
			(xy 358.629204 -230.714296) (xy 358.628714 -230.739285) (xy 360.807236 -230.739285) (xy 360.807236 -230.689307)
			(xy 360.815055 -230.639944) (xy 360.830499 -230.592412) (xy 360.853189 -230.54788) (xy 360.882565 -230.507447)
			(xy 360.917905 -230.472107) (xy 360.958338 -230.442731) (xy 361.00287 -230.420041) (xy 361.050402 -230.404597)
			(xy 361.099765 -230.396778) (xy 361.149743 -230.396778) (xy 361.199106 -230.404597) (xy 361.246638 -230.420041)
			(xy 361.29117 -230.442731) (xy 361.331603 -230.472107) (xy 361.366943 -230.507447) (xy 361.396319 -230.54788)
			(xy 361.419009 -230.592412) (xy 361.434453 -230.639944) (xy 361.442272 -230.689307) (xy 361.442762 -230.714296)
			(xy 361.748573 -230.714296) (xy 361.752668 -230.663568) (xy 361.764847 -230.614154) (xy 361.784795 -230.567334)
			(xy 361.811996 -230.52432) (xy 361.845744 -230.486226) (xy 361.885166 -230.454039) (xy 361.92924 -230.428593)
			(xy 361.976826 -230.410546) (xy 362.02669 -230.400366) (xy 362.077542 -230.398317) (xy 362.128063 -230.404451)
			(xy 362.176947 -230.418611) (xy 362.222926 -230.440428) (xy 362.26481 -230.469338) (xy 362.301514 -230.504593)
			(xy 362.332087 -230.545279) (xy 362.355738 -230.590342) (xy 362.371854 -230.638616) (xy 362.380018 -230.68885)
			(xy 362.38053 -230.714296) (xy 362.688627 -230.714296) (xy 362.692722 -230.663568) (xy 362.704901 -230.614154)
			(xy 362.724849 -230.567334) (xy 362.75205 -230.52432) (xy 362.785798 -230.486226) (xy 362.82522 -230.454039)
			(xy 362.869294 -230.428593) (xy 362.91688 -230.410546) (xy 362.966744 -230.400366) (xy 363.017596 -230.398317)
			(xy 363.068117 -230.404451) (xy 363.117001 -230.418611) (xy 363.16298 -230.440428) (xy 363.204864 -230.469338)
			(xy 363.241568 -230.504593) (xy 363.272141 -230.545279) (xy 363.295792 -230.590342) (xy 363.311908 -230.638616)
			(xy 363.320072 -230.68885) (xy 363.320584 -230.714296) (xy 363.320086 -230.739031) (xy 363.627398 -230.739031)
			(xy 363.627398 -230.689053) (xy 363.635217 -230.63969) (xy 363.650661 -230.592158) (xy 363.673351 -230.547626)
			(xy 363.702727 -230.507193) (xy 363.738067 -230.471853) (xy 363.7785 -230.442477) (xy 363.823032 -230.419787)
			(xy 363.870564 -230.404343) (xy 363.919927 -230.396524) (xy 363.969905 -230.396524) (xy 364.019268 -230.404343)
			(xy 364.0668 -230.419787) (xy 364.111332 -230.442477) (xy 364.151765 -230.471853) (xy 364.187105 -230.507193)
			(xy 364.216481 -230.547626) (xy 364.239171 -230.592158) (xy 364.254615 -230.63969) (xy 364.262434 -230.689053)
			(xy 364.262924 -230.714042) (xy 364.262434 -230.739031) (xy 364.262394 -230.739285) (xy 366.447306 -230.739285)
			(xy 366.447306 -230.689307) (xy 366.455125 -230.639944) (xy 366.470569 -230.592412) (xy 366.493259 -230.54788)
			(xy 366.522635 -230.507447) (xy 366.557975 -230.472107) (xy 366.598408 -230.442731) (xy 366.64294 -230.420041)
			(xy 366.690472 -230.404597) (xy 366.739835 -230.396778) (xy 366.789813 -230.396778) (xy 366.839176 -230.404597)
			(xy 366.886708 -230.420041) (xy 366.93124 -230.442731) (xy 366.971673 -230.472107) (xy 367.007013 -230.507447)
			(xy 367.036389 -230.54788) (xy 367.059079 -230.592412) (xy 367.074523 -230.639944) (xy 367.082342 -230.689307)
			(xy 367.082832 -230.714296) (xy 367.082342 -230.739285) (xy 369.267214 -230.739285) (xy 369.267214 -230.689307)
			(xy 369.275033 -230.639944) (xy 369.290477 -230.592412) (xy 369.313167 -230.54788) (xy 369.342543 -230.507447)
			(xy 369.377883 -230.472107) (xy 369.418316 -230.442731) (xy 369.462848 -230.420041) (xy 369.51038 -230.404597)
			(xy 369.559743 -230.396778) (xy 369.609721 -230.396778) (xy 369.659084 -230.404597) (xy 369.706616 -230.420041)
			(xy 369.751148 -230.442731) (xy 369.791581 -230.472107) (xy 369.826921 -230.507447) (xy 369.856297 -230.54788)
			(xy 369.878987 -230.592412) (xy 369.894431 -230.639944) (xy 369.90225 -230.689307) (xy 369.90274 -230.714296)
			(xy 369.902255 -230.739031) (xy 372.087376 -230.739031) (xy 372.087376 -230.689053) (xy 372.095195 -230.63969)
			(xy 372.110639 -230.592158) (xy 372.133329 -230.547626) (xy 372.162705 -230.507193) (xy 372.198045 -230.471853)
			(xy 372.238478 -230.442477) (xy 372.28301 -230.419787) (xy 372.330542 -230.404343) (xy 372.379905 -230.396524)
			(xy 372.429883 -230.396524) (xy 372.479246 -230.404343) (xy 372.526778 -230.419787) (xy 372.57131 -230.442477)
			(xy 372.611743 -230.471853) (xy 372.647083 -230.507193) (xy 372.676459 -230.547626) (xy 372.699149 -230.592158)
			(xy 372.714593 -230.63969) (xy 372.722412 -230.689053) (xy 372.722902 -230.714042) (xy 372.722412 -230.739031)
			(xy 372.714593 -230.788394) (xy 372.699149 -230.835926) (xy 372.676459 -230.880458) (xy 372.647083 -230.920891)
			(xy 372.611743 -230.956231) (xy 372.57131 -230.985607) (xy 372.526778 -231.008297) (xy 372.479246 -231.023741)
			(xy 372.429883 -231.03156) (xy 372.379905 -231.03156) (xy 372.330542 -231.023741) (xy 372.28301 -231.008297)
			(xy 372.238478 -230.985607) (xy 372.198045 -230.956231) (xy 372.162705 -230.920891) (xy 372.133329 -230.880458)
			(xy 372.110639 -230.835926) (xy 372.095195 -230.788394) (xy 372.087376 -230.739031) (xy 369.902255 -230.739031)
			(xy 369.90225 -230.739285) (xy 369.894431 -230.788648) (xy 369.878987 -230.83618) (xy 369.856297 -230.880712)
			(xy 369.826921 -230.921145) (xy 369.791581 -230.956485) (xy 369.751148 -230.985861) (xy 369.706616 -231.008551)
			(xy 369.659084 -231.023995) (xy 369.609721 -231.031814) (xy 369.559743 -231.031814) (xy 369.51038 -231.023995)
			(xy 369.462848 -231.008551) (xy 369.418316 -230.985861) (xy 369.377883 -230.956485) (xy 369.342543 -230.921145)
			(xy 369.313167 -230.880712) (xy 369.290477 -230.83618) (xy 369.275033 -230.788648) (xy 369.267214 -230.739285)
			(xy 367.082342 -230.739285) (xy 367.074523 -230.788648) (xy 367.059079 -230.83618) (xy 367.036389 -230.880712)
			(xy 367.007013 -230.921145) (xy 366.971673 -230.956485) (xy 366.93124 -230.985861) (xy 366.886708 -231.008551)
			(xy 366.839176 -231.023995) (xy 366.789813 -231.031814) (xy 366.739835 -231.031814) (xy 366.690472 -231.023995)
			(xy 366.64294 -231.008551) (xy 366.598408 -230.985861) (xy 366.557975 -230.956485) (xy 366.522635 -230.921145)
			(xy 366.493259 -230.880712) (xy 366.470569 -230.83618) (xy 366.455125 -230.788648) (xy 366.447306 -230.739285)
			(xy 364.262394 -230.739285) (xy 364.254615 -230.788394) (xy 364.239171 -230.835926) (xy 364.216481 -230.880458)
			(xy 364.187105 -230.920891) (xy 364.151765 -230.956231) (xy 364.111332 -230.985607) (xy 364.0668 -231.008297)
			(xy 364.019268 -231.023741) (xy 363.969905 -231.03156) (xy 363.919927 -231.03156) (xy 363.870564 -231.023741)
			(xy 363.823032 -231.008297) (xy 363.7785 -230.985607) (xy 363.738067 -230.956231) (xy 363.702727 -230.920891)
			(xy 363.673351 -230.880458) (xy 363.650661 -230.835926) (xy 363.635217 -230.788394) (xy 363.627398 -230.739031)
			(xy 363.320086 -230.739031) (xy 363.320072 -230.739742) (xy 363.311908 -230.789976) (xy 363.295792 -230.83825)
			(xy 363.272141 -230.883313) (xy 363.241568 -230.923999) (xy 363.204864 -230.959254) (xy 363.16298 -230.988164)
			(xy 363.117001 -231.009981) (xy 363.068117 -231.024141) (xy 363.017596 -231.030275) (xy 362.966744 -231.028226)
			(xy 362.91688 -231.018046) (xy 362.869294 -230.999999) (xy 362.82522 -230.974553) (xy 362.785798 -230.942366)
			(xy 362.75205 -230.904272) (xy 362.724849 -230.861258) (xy 362.704901 -230.814438) (xy 362.692722 -230.765024)
			(xy 362.688627 -230.714296) (xy 362.38053 -230.714296) (xy 362.380018 -230.739742) (xy 362.371854 -230.789976)
			(xy 362.355738 -230.83825) (xy 362.332087 -230.883313) (xy 362.301514 -230.923999) (xy 362.26481 -230.959254)
			(xy 362.222926 -230.988164) (xy 362.176947 -231.009981) (xy 362.128063 -231.024141) (xy 362.077542 -231.030275)
			(xy 362.02669 -231.028226) (xy 361.976826 -231.018046) (xy 361.92924 -230.999999) (xy 361.885166 -230.974553)
			(xy 361.845744 -230.942366) (xy 361.811996 -230.904272) (xy 361.784795 -230.861258) (xy 361.764847 -230.814438)
			(xy 361.752668 -230.765024) (xy 361.748573 -230.714296) (xy 361.442762 -230.714296) (xy 361.442272 -230.739285)
			(xy 361.434453 -230.788648) (xy 361.419009 -230.83618) (xy 361.396319 -230.880712) (xy 361.366943 -230.921145)
			(xy 361.331603 -230.956485) (xy 361.29117 -230.985861) (xy 361.246638 -231.008551) (xy 361.199106 -231.023995)
			(xy 361.149743 -231.031814) (xy 361.099765 -231.031814) (xy 361.050402 -231.023995) (xy 361.00287 -231.008551)
			(xy 360.958338 -230.985861) (xy 360.917905 -230.956485) (xy 360.882565 -230.921145) (xy 360.853189 -230.880712)
			(xy 360.830499 -230.83618) (xy 360.815055 -230.788648) (xy 360.807236 -230.739285) (xy 358.628714 -230.739285)
			(xy 358.620895 -230.788648) (xy 358.605451 -230.83618) (xy 358.582761 -230.880712) (xy 358.553385 -230.921145)
			(xy 358.518045 -230.956485) (xy 358.477612 -230.985861) (xy 358.43308 -231.008551) (xy 358.385548 -231.023995)
			(xy 358.336185 -231.031814) (xy 358.286207 -231.031814) (xy 358.236844 -231.023995) (xy 358.189312 -231.008551)
			(xy 358.14478 -230.985861) (xy 358.104347 -230.956485) (xy 358.069007 -230.921145) (xy 358.039631 -230.880712)
			(xy 358.016941 -230.83618) (xy 358.001497 -230.788648) (xy 357.993678 -230.739285) (xy 357.686361 -230.739285)
			(xy 357.686352 -230.739742) (xy 357.678188 -230.789976) (xy 357.662072 -230.83825) (xy 357.638421 -230.883313)
			(xy 357.607848 -230.923999) (xy 357.571144 -230.959254) (xy 357.52926 -230.988164) (xy 357.483281 -231.009981)
			(xy 357.434397 -231.024141) (xy 357.383876 -231.030275) (xy 357.333024 -231.028226) (xy 357.28316 -231.018046)
			(xy 357.235574 -230.999999) (xy 357.1915 -230.974553) (xy 357.152078 -230.942366) (xy 357.11833 -230.904272)
			(xy 357.091129 -230.861258) (xy 357.071181 -230.814438) (xy 357.059002 -230.765024) (xy 357.054907 -230.714296)
			(xy 356.74681 -230.714296) (xy 356.746298 -230.739742) (xy 356.738134 -230.789976) (xy 356.722018 -230.83825)
			(xy 356.698367 -230.883313) (xy 356.667794 -230.923999) (xy 356.63109 -230.959254) (xy 356.589206 -230.988164)
			(xy 356.543227 -231.009981) (xy 356.494343 -231.024141) (xy 356.443822 -231.030275) (xy 356.39297 -231.028226)
			(xy 356.343106 -231.018046) (xy 356.29552 -230.999999) (xy 356.251446 -230.974553) (xy 356.212024 -230.942366)
			(xy 356.178276 -230.904272) (xy 356.151075 -230.861258) (xy 356.131127 -230.814438) (xy 356.118948 -230.765024)
			(xy 356.114853 -230.714296) (xy 355.809037 -230.714296) (xy 355.808552 -230.739031) (xy 355.800733 -230.788394)
			(xy 355.785289 -230.835926) (xy 355.762599 -230.880458) (xy 355.733223 -230.920891) (xy 355.697883 -230.956231)
			(xy 355.65745 -230.985607) (xy 355.612918 -231.008297) (xy 355.565386 -231.023741) (xy 355.516023 -231.03156)
			(xy 355.466045 -231.03156) (xy 355.416682 -231.023741) (xy 355.36915 -231.008297) (xy 355.324618 -230.985607)
			(xy 355.284185 -230.956231) (xy 355.248845 -230.920891) (xy 355.219469 -230.880458) (xy 355.196779 -230.835926)
			(xy 355.181335 -230.788394) (xy 355.173516 -230.739031) (xy 352.988649 -230.739031) (xy 352.988644 -230.739285)
			(xy 352.980825 -230.788648) (xy 352.965381 -230.83618) (xy 352.942691 -230.880712) (xy 352.913315 -230.921145)
			(xy 352.877975 -230.956485) (xy 352.837542 -230.985861) (xy 352.79301 -231.008551) (xy 352.745478 -231.023995)
			(xy 352.696115 -231.031814) (xy 352.646137 -231.031814) (xy 352.596774 -231.023995) (xy 352.549242 -231.008551)
			(xy 352.50471 -230.985861) (xy 352.464277 -230.956485) (xy 352.428937 -230.921145) (xy 352.399561 -230.880712)
			(xy 352.376871 -230.83618) (xy 352.361427 -230.788648) (xy 352.353608 -230.739285) (xy 350.168736 -230.739285)
			(xy 350.160917 -230.788648) (xy 350.145473 -230.83618) (xy 350.122783 -230.880712) (xy 350.093407 -230.921145)
			(xy 350.058067 -230.956485) (xy 350.017634 -230.985861) (xy 349.973102 -231.008551) (xy 349.92557 -231.023995)
			(xy 349.876207 -231.031814) (xy 349.826229 -231.031814) (xy 349.776866 -231.023995) (xy 349.729334 -231.008551)
			(xy 349.684802 -230.985861) (xy 349.644369 -230.956485) (xy 349.609029 -230.921145) (xy 349.579653 -230.880712)
			(xy 349.556963 -230.83618) (xy 349.541519 -230.788648) (xy 349.5337 -230.739285) (xy 347.348574 -230.739285)
			(xy 347.340755 -230.788648) (xy 347.325311 -230.83618) (xy 347.302621 -230.880712) (xy 347.273245 -230.921145)
			(xy 347.237905 -230.956485) (xy 347.197472 -230.985861) (xy 347.15294 -231.008551) (xy 347.105408 -231.023995)
			(xy 347.056045 -231.031814) (xy 347.006067 -231.031814) (xy 346.956704 -231.023995) (xy 346.909172 -231.008551)
			(xy 346.86464 -230.985861) (xy 346.824207 -230.956485) (xy 346.788867 -230.921145) (xy 346.759491 -230.880712)
			(xy 346.736801 -230.83618) (xy 346.721357 -230.788648) (xy 346.713538 -230.739285) (xy 344.997532 -230.739285)
			(xy 344.997532 -231.490012) (xy 344.997786 -231.494584) (xy 344.999056 -231.523794) (xy 344.999056 -231.524048)
			(xy 345.304867 -231.524048) (xy 345.308962 -231.47332) (xy 345.321141 -231.423906) (xy 345.341089 -231.377086)
			(xy 345.36829 -231.334072) (xy 345.402038 -231.295978) (xy 345.44146 -231.263791) (xy 345.485534 -231.238345)
			(xy 345.53312 -231.220298) (xy 345.582984 -231.210118) (xy 345.633836 -231.208069) (xy 345.684357 -231.214203)
			(xy 345.733241 -231.228363) (xy 345.77922 -231.25018) (xy 345.821104 -231.27909) (xy 345.857808 -231.314345)
			(xy 345.888381 -231.355031) (xy 345.912032 -231.400094) (xy 345.928148 -231.448368) (xy 345.936312 -231.498602)
			(xy 345.936824 -231.524048) (xy 346.244921 -231.524048) (xy 346.249016 -231.47332) (xy 346.261195 -231.423906)
			(xy 346.281143 -231.377086) (xy 346.308344 -231.334072) (xy 346.342092 -231.295978) (xy 346.381514 -231.263791)
			(xy 346.425588 -231.238345) (xy 346.473174 -231.220298) (xy 346.523038 -231.210118) (xy 346.57389 -231.208069)
			(xy 346.624411 -231.214203) (xy 346.673295 -231.228363) (xy 346.719274 -231.25018) (xy 346.761158 -231.27909)
			(xy 346.797862 -231.314345) (xy 346.828435 -231.355031) (xy 346.852086 -231.400094) (xy 346.868202 -231.448368)
			(xy 346.876366 -231.498602) (xy 346.876878 -231.524048) (xy 346.876375 -231.549037) (xy 347.183692 -231.549037)
			(xy 347.183692 -231.499059) (xy 347.191511 -231.449696) (xy 347.206955 -231.402164) (xy 347.229645 -231.357632)
			(xy 347.259021 -231.317199) (xy 347.294361 -231.281859) (xy 347.334794 -231.252483) (xy 347.379326 -231.229793)
			(xy 347.426858 -231.214349) (xy 347.476221 -231.20653) (xy 347.526199 -231.20653) (xy 347.575562 -231.214349)
			(xy 347.623094 -231.229793) (xy 347.667626 -231.252483) (xy 347.708059 -231.281859) (xy 347.743399 -231.317199)
			(xy 347.772775 -231.357632) (xy 347.795465 -231.402164) (xy 347.810909 -231.449696) (xy 347.818728 -231.499059)
			(xy 347.819218 -231.524048) (xy 348.124775 -231.524048) (xy 348.12887 -231.47332) (xy 348.141049 -231.423906)
			(xy 348.160997 -231.377086) (xy 348.188198 -231.334072) (xy 348.221946 -231.295978) (xy 348.261368 -231.263791)
			(xy 348.305442 -231.238345) (xy 348.353028 -231.220298) (xy 348.402892 -231.210118) (xy 348.453744 -231.208069)
			(xy 348.504265 -231.214203) (xy 348.553149 -231.228363) (xy 348.599128 -231.25018) (xy 348.641012 -231.27909)
			(xy 348.677716 -231.314345) (xy 348.708289 -231.355031) (xy 348.73194 -231.400094) (xy 348.748056 -231.448368)
			(xy 348.75622 -231.498602) (xy 348.756732 -231.524048) (xy 349.064829 -231.524048) (xy 349.068924 -231.47332)
			(xy 349.081103 -231.423906) (xy 349.101051 -231.377086) (xy 349.128252 -231.334072) (xy 349.162 -231.295978)
			(xy 349.201422 -231.263791) (xy 349.245496 -231.238345) (xy 349.293082 -231.220298) (xy 349.342946 -231.210118)
			(xy 349.393798 -231.208069) (xy 349.444319 -231.214203) (xy 349.493203 -231.228363) (xy 349.539182 -231.25018)
			(xy 349.581066 -231.27909) (xy 349.61777 -231.314345) (xy 349.648343 -231.355031) (xy 349.671994 -231.400094)
			(xy 349.68811 -231.448368) (xy 349.696274 -231.498602) (xy 349.696786 -231.524048) (xy 349.696283 -231.549037)
			(xy 350.0036 -231.549037) (xy 350.0036 -231.499059) (xy 350.011419 -231.449696) (xy 350.026863 -231.402164)
			(xy 350.049553 -231.357632) (xy 350.078929 -231.317199) (xy 350.114269 -231.281859) (xy 350.154702 -231.252483)
			(xy 350.199234 -231.229793) (xy 350.246766 -231.214349) (xy 350.296129 -231.20653) (xy 350.346107 -231.20653)
			(xy 350.39547 -231.214349) (xy 350.443002 -231.229793) (xy 350.487534 -231.252483) (xy 350.527967 -231.281859)
			(xy 350.563307 -231.317199) (xy 350.592683 -231.357632) (xy 350.615373 -231.402164) (xy 350.630817 -231.449696)
			(xy 350.638636 -231.499059) (xy 350.639126 -231.524048) (xy 350.944937 -231.524048) (xy 350.949032 -231.47332)
			(xy 350.961211 -231.423906) (xy 350.981159 -231.377086) (xy 351.00836 -231.334072) (xy 351.042108 -231.295978)
			(xy 351.08153 -231.263791) (xy 351.125604 -231.238345) (xy 351.17319 -231.220298) (xy 351.223054 -231.210118)
			(xy 351.273906 -231.208069) (xy 351.324427 -231.214203) (xy 351.373311 -231.228363) (xy 351.41929 -231.25018)
			(xy 351.461174 -231.27909) (xy 351.497878 -231.314345) (xy 351.528451 -231.355031) (xy 351.552102 -231.400094)
			(xy 351.568218 -231.448368) (xy 351.576382 -231.498602) (xy 351.576894 -231.524048) (xy 351.884991 -231.524048)
			(xy 351.889086 -231.47332) (xy 351.901265 -231.423906) (xy 351.921213 -231.377086) (xy 351.948414 -231.334072)
			(xy 351.982162 -231.295978) (xy 352.021584 -231.263791) (xy 352.065658 -231.238345) (xy 352.113244 -231.220298)
			(xy 352.163108 -231.210118) (xy 352.21396 -231.208069) (xy 352.264481 -231.214203) (xy 352.313365 -231.228363)
			(xy 352.359344 -231.25018) (xy 352.401228 -231.27909) (xy 352.437932 -231.314345) (xy 352.468505 -231.355031)
			(xy 352.492156 -231.400094) (xy 352.508272 -231.448368) (xy 352.516436 -231.498602) (xy 352.516948 -231.524048)
			(xy 352.516445 -231.549037) (xy 352.823508 -231.549037) (xy 352.823508 -231.499059) (xy 352.831327 -231.449696)
			(xy 352.846771 -231.402164) (xy 352.869461 -231.357632) (xy 352.898837 -231.317199) (xy 352.934177 -231.281859)
			(xy 352.97461 -231.252483) (xy 353.019142 -231.229793) (xy 353.066674 -231.214349) (xy 353.116037 -231.20653)
			(xy 353.166015 -231.20653) (xy 353.215378 -231.214349) (xy 353.26291 -231.229793) (xy 353.307442 -231.252483)
			(xy 353.347875 -231.281859) (xy 353.383215 -231.317199) (xy 353.412591 -231.357632) (xy 353.435281 -231.402164)
			(xy 353.450725 -231.449696) (xy 353.458544 -231.499059) (xy 353.459034 -231.524048) (xy 353.764845 -231.524048)
			(xy 353.76894 -231.47332) (xy 353.781119 -231.423906) (xy 353.801067 -231.377086) (xy 353.828268 -231.334072)
			(xy 353.862016 -231.295978) (xy 353.901438 -231.263791) (xy 353.945512 -231.238345) (xy 353.993098 -231.220298)
			(xy 354.042962 -231.210118) (xy 354.093814 -231.208069) (xy 354.144335 -231.214203) (xy 354.193219 -231.228363)
			(xy 354.239198 -231.25018) (xy 354.281082 -231.27909) (xy 354.317786 -231.314345) (xy 354.348359 -231.355031)
			(xy 354.37201 -231.400094) (xy 354.388126 -231.448368) (xy 354.39629 -231.498602) (xy 354.396802 -231.524048)
			(xy 354.704899 -231.524048) (xy 354.708994 -231.47332) (xy 354.721173 -231.423906) (xy 354.741121 -231.377086)
			(xy 354.768322 -231.334072) (xy 354.80207 -231.295978) (xy 354.841492 -231.263791) (xy 354.885566 -231.238345)
			(xy 354.933152 -231.220298) (xy 354.983016 -231.210118) (xy 355.033868 -231.208069) (xy 355.084389 -231.214203)
			(xy 355.133273 -231.228363) (xy 355.179252 -231.25018) (xy 355.221136 -231.27909) (xy 355.25784 -231.314345)
			(xy 355.288413 -231.355031) (xy 355.312064 -231.400094) (xy 355.32818 -231.448368) (xy 355.336344 -231.498602)
			(xy 355.336856 -231.524048) (xy 355.336353 -231.549037) (xy 355.64367 -231.549037) (xy 355.64367 -231.499059)
			(xy 355.651489 -231.449696) (xy 355.666933 -231.402164) (xy 355.689623 -231.357632) (xy 355.718999 -231.317199)
			(xy 355.754339 -231.281859) (xy 355.794772 -231.252483) (xy 355.839304 -231.229793) (xy 355.886836 -231.214349)
			(xy 355.936199 -231.20653) (xy 355.986177 -231.20653) (xy 356.03554 -231.214349) (xy 356.083072 -231.229793)
			(xy 356.127604 -231.252483) (xy 356.168037 -231.281859) (xy 356.203377 -231.317199) (xy 356.232753 -231.357632)
			(xy 356.255443 -231.402164) (xy 356.270887 -231.449696) (xy 356.278706 -231.499059) (xy 356.279196 -231.524048)
			(xy 356.278706 -231.549037) (xy 363.157244 -231.549037) (xy 363.157244 -231.499059) (xy 363.165063 -231.449696)
			(xy 363.180507 -231.402164) (xy 363.203197 -231.357632) (xy 363.232573 -231.317199) (xy 363.267913 -231.281859)
			(xy 363.308346 -231.252483) (xy 363.352878 -231.229793) (xy 363.40041 -231.214349) (xy 363.449773 -231.20653)
			(xy 363.499751 -231.20653) (xy 363.549114 -231.214349) (xy 363.596646 -231.229793) (xy 363.641178 -231.252483)
			(xy 363.681611 -231.281859) (xy 363.716951 -231.317199) (xy 363.746327 -231.357632) (xy 363.769017 -231.402164)
			(xy 363.784461 -231.449696) (xy 363.79228 -231.499059) (xy 363.79277 -231.524048) (xy 364.098581 -231.524048)
			(xy 364.102676 -231.47332) (xy 364.114855 -231.423906) (xy 364.134803 -231.377086) (xy 364.162004 -231.334072)
			(xy 364.195752 -231.295978) (xy 364.235174 -231.263791) (xy 364.279248 -231.238345) (xy 364.326834 -231.220298)
			(xy 364.376698 -231.210118) (xy 364.42755 -231.208069) (xy 364.478071 -231.214203) (xy 364.526955 -231.228363)
			(xy 364.572934 -231.25018) (xy 364.614818 -231.27909) (xy 364.651522 -231.314345) (xy 364.682095 -231.355031)
			(xy 364.705746 -231.400094) (xy 364.721862 -231.448368) (xy 364.730026 -231.498602) (xy 364.730538 -231.524048)
			(xy 365.038635 -231.524048) (xy 365.04273 -231.47332) (xy 365.054909 -231.423906) (xy 365.074857 -231.377086)
			(xy 365.102058 -231.334072) (xy 365.135806 -231.295978) (xy 365.175228 -231.263791) (xy 365.219302 -231.238345)
			(xy 365.266888 -231.220298) (xy 365.316752 -231.210118) (xy 365.367604 -231.208069) (xy 365.418125 -231.214203)
			(xy 365.467009 -231.228363) (xy 365.512988 -231.25018) (xy 365.554872 -231.27909) (xy 365.591576 -231.314345)
			(xy 365.622149 -231.355031) (xy 365.6458 -231.400094) (xy 365.661916 -231.448368) (xy 365.67008 -231.498602)
			(xy 365.670592 -231.524048) (xy 365.670089 -231.549037) (xy 365.977406 -231.549037) (xy 365.977406 -231.499059)
			(xy 365.985225 -231.449696) (xy 366.000669 -231.402164) (xy 366.023359 -231.357632) (xy 366.052735 -231.317199)
			(xy 366.088075 -231.281859) (xy 366.128508 -231.252483) (xy 366.17304 -231.229793) (xy 366.220572 -231.214349)
			(xy 366.269935 -231.20653) (xy 366.319913 -231.20653) (xy 366.369276 -231.214349) (xy 366.416808 -231.229793)
			(xy 366.46134 -231.252483) (xy 366.501773 -231.281859) (xy 366.537113 -231.317199) (xy 366.566489 -231.357632)
			(xy 366.589179 -231.402164) (xy 366.604623 -231.449696) (xy 366.612442 -231.499059) (xy 366.612932 -231.524048)
			(xy 366.918489 -231.524048) (xy 366.922584 -231.47332) (xy 366.934763 -231.423906) (xy 366.954711 -231.377086)
			(xy 366.981912 -231.334072) (xy 367.01566 -231.295978) (xy 367.055082 -231.263791) (xy 367.099156 -231.238345)
			(xy 367.146742 -231.220298) (xy 367.196606 -231.210118) (xy 367.247458 -231.208069) (xy 367.297979 -231.214203)
			(xy 367.346863 -231.228363) (xy 367.392842 -231.25018) (xy 367.434726 -231.27909) (xy 367.47143 -231.314345)
			(xy 367.502003 -231.355031) (xy 367.525654 -231.400094) (xy 367.54177 -231.448368) (xy 367.549934 -231.498602)
			(xy 367.550446 -231.524048) (xy 367.858543 -231.524048) (xy 367.862638 -231.47332) (xy 367.874817 -231.423906)
			(xy 367.894765 -231.377086) (xy 367.921966 -231.334072) (xy 367.955714 -231.295978) (xy 367.995136 -231.263791)
			(xy 368.03921 -231.238345) (xy 368.086796 -231.220298) (xy 368.13666 -231.210118) (xy 368.187512 -231.208069)
			(xy 368.238033 -231.214203) (xy 368.286917 -231.228363) (xy 368.332896 -231.25018) (xy 368.37478 -231.27909)
			(xy 368.411484 -231.314345) (xy 368.442057 -231.355031) (xy 368.465708 -231.400094) (xy 368.481824 -231.448368)
			(xy 368.489988 -231.498602) (xy 368.4905 -231.524048) (xy 368.489997 -231.549037) (xy 368.797314 -231.549037)
			(xy 368.797314 -231.499059) (xy 368.805133 -231.449696) (xy 368.820577 -231.402164) (xy 368.843267 -231.357632)
			(xy 368.872643 -231.317199) (xy 368.907983 -231.281859) (xy 368.948416 -231.252483) (xy 368.992948 -231.229793)
			(xy 369.04048 -231.214349) (xy 369.089843 -231.20653) (xy 369.139821 -231.20653) (xy 369.189184 -231.214349)
			(xy 369.236716 -231.229793) (xy 369.281248 -231.252483) (xy 369.321681 -231.281859) (xy 369.357021 -231.317199)
			(xy 369.386397 -231.357632) (xy 369.409087 -231.402164) (xy 369.424531 -231.449696) (xy 369.43235 -231.499059)
			(xy 369.43284 -231.524048) (xy 369.738651 -231.524048) (xy 369.742746 -231.47332) (xy 369.754925 -231.423906)
			(xy 369.774873 -231.377086) (xy 369.802074 -231.334072) (xy 369.835822 -231.295978) (xy 369.875244 -231.263791)
			(xy 369.919318 -231.238345) (xy 369.966904 -231.220298) (xy 370.016768 -231.210118) (xy 370.06762 -231.208069)
			(xy 370.118141 -231.214203) (xy 370.167025 -231.228363) (xy 370.213004 -231.25018) (xy 370.254888 -231.27909)
			(xy 370.291592 -231.314345) (xy 370.322165 -231.355031) (xy 370.345816 -231.400094) (xy 370.361932 -231.448368)
			(xy 370.370096 -231.498602) (xy 370.370608 -231.524048) (xy 370.678451 -231.524048) (xy 370.682546 -231.47332)
			(xy 370.694725 -231.423906) (xy 370.714673 -231.377086) (xy 370.741874 -231.334072) (xy 370.775622 -231.295978)
			(xy 370.815044 -231.263791) (xy 370.859118 -231.238345) (xy 370.906704 -231.220298) (xy 370.956568 -231.210118)
			(xy 371.00742 -231.208069) (xy 371.057941 -231.214203) (xy 371.106825 -231.228363) (xy 371.152804 -231.25018)
			(xy 371.194688 -231.27909) (xy 371.231392 -231.314345) (xy 371.261965 -231.355031) (xy 371.285616 -231.400094)
			(xy 371.301732 -231.448368) (xy 371.309896 -231.498602) (xy 371.310408 -231.524048) (xy 371.309905 -231.549037)
			(xy 371.617222 -231.549037) (xy 371.617222 -231.499059) (xy 371.625041 -231.449696) (xy 371.640485 -231.402164)
			(xy 371.663175 -231.357632) (xy 371.692551 -231.317199) (xy 371.727891 -231.281859) (xy 371.768324 -231.252483)
			(xy 371.812856 -231.229793) (xy 371.860388 -231.214349) (xy 371.909751 -231.20653) (xy 371.959729 -231.20653)
			(xy 372.009092 -231.214349) (xy 372.056624 -231.229793) (xy 372.101156 -231.252483) (xy 372.141589 -231.281859)
			(xy 372.176929 -231.317199) (xy 372.206305 -231.357632) (xy 372.228995 -231.402164) (xy 372.244439 -231.449696)
			(xy 372.252258 -231.499059) (xy 372.252748 -231.524048) (xy 372.558559 -231.524048) (xy 372.562654 -231.47332)
			(xy 372.574833 -231.423906) (xy 372.594781 -231.377086) (xy 372.621982 -231.334072) (xy 372.65573 -231.295978)
			(xy 372.695152 -231.263791) (xy 372.739226 -231.238345) (xy 372.786812 -231.220298) (xy 372.836676 -231.210118)
			(xy 372.887528 -231.208069) (xy 372.938049 -231.214203) (xy 372.986933 -231.228363) (xy 373.032912 -231.25018)
			(xy 373.074796 -231.27909) (xy 373.1115 -231.314345) (xy 373.142073 -231.355031) (xy 373.165724 -231.400094)
			(xy 373.18184 -231.448368) (xy 373.190004 -231.498602) (xy 373.190516 -231.524048) (xy 373.498613 -231.524048)
			(xy 373.502708 -231.47332) (xy 373.514887 -231.423906) (xy 373.534835 -231.377086) (xy 373.562036 -231.334072)
			(xy 373.595784 -231.295978) (xy 373.635206 -231.263791) (xy 373.67928 -231.238345) (xy 373.726866 -231.220298)
			(xy 373.77673 -231.210118) (xy 373.827582 -231.208069) (xy 373.878103 -231.214203) (xy 373.926987 -231.228363)
			(xy 373.972966 -231.25018) (xy 374.01485 -231.27909) (xy 374.051554 -231.314345) (xy 374.082127 -231.355031)
			(xy 374.105778 -231.400094) (xy 374.121894 -231.448368) (xy 374.130058 -231.498602) (xy 374.13057 -231.524048)
			(xy 374.130058 -231.549494) (xy 374.121894 -231.599728) (xy 374.105778 -231.648002) (xy 374.082127 -231.693065)
			(xy 374.051554 -231.733751) (xy 374.01485 -231.769006) (xy 373.972966 -231.797916) (xy 373.926987 -231.819733)
			(xy 373.878103 -231.833893) (xy 373.827582 -231.840027) (xy 373.77673 -231.837978) (xy 373.726866 -231.827798)
			(xy 373.67928 -231.809751) (xy 373.635206 -231.784305) (xy 373.595784 -231.752118) (xy 373.562036 -231.714024)
			(xy 373.534835 -231.67101) (xy 373.514887 -231.62419) (xy 373.502708 -231.574776) (xy 373.498613 -231.524048)
			(xy 373.190516 -231.524048) (xy 373.190004 -231.549494) (xy 373.18184 -231.599728) (xy 373.165724 -231.648002)
			(xy 373.142073 -231.693065) (xy 373.1115 -231.733751) (xy 373.074796 -231.769006) (xy 373.032912 -231.797916)
			(xy 372.986933 -231.819733) (xy 372.938049 -231.833893) (xy 372.887528 -231.840027) (xy 372.836676 -231.837978)
			(xy 372.786812 -231.827798) (xy 372.739226 -231.809751) (xy 372.695152 -231.784305) (xy 372.65573 -231.752118)
			(xy 372.621982 -231.714024) (xy 372.594781 -231.67101) (xy 372.574833 -231.62419) (xy 372.562654 -231.574776)
			(xy 372.558559 -231.524048) (xy 372.252748 -231.524048) (xy 372.252258 -231.549037) (xy 372.244439 -231.5984)
			(xy 372.228995 -231.645932) (xy 372.206305 -231.690464) (xy 372.176929 -231.730897) (xy 372.141589 -231.766237)
			(xy 372.101156 -231.795613) (xy 372.056624 -231.818303) (xy 372.009092 -231.833747) (xy 371.959729 -231.841566)
			(xy 371.909751 -231.841566) (xy 371.860388 -231.833747) (xy 371.812856 -231.818303) (xy 371.768324 -231.795613)
			(xy 371.727891 -231.766237) (xy 371.692551 -231.730897) (xy 371.663175 -231.690464) (xy 371.640485 -231.645932)
			(xy 371.625041 -231.5984) (xy 371.617222 -231.549037) (xy 371.309905 -231.549037) (xy 371.309896 -231.549494)
			(xy 371.301732 -231.599728) (xy 371.285616 -231.648002) (xy 371.261965 -231.693065) (xy 371.231392 -231.733751)
			(xy 371.194688 -231.769006) (xy 371.152804 -231.797916) (xy 371.106825 -231.819733) (xy 371.057941 -231.833893)
			(xy 371.00742 -231.840027) (xy 370.956568 -231.837978) (xy 370.906704 -231.827798) (xy 370.859118 -231.809751)
			(xy 370.815044 -231.784305) (xy 370.775622 -231.752118) (xy 370.741874 -231.714024) (xy 370.714673 -231.67101)
			(xy 370.694725 -231.62419) (xy 370.682546 -231.574776) (xy 370.678451 -231.524048) (xy 370.370608 -231.524048)
			(xy 370.370096 -231.549494) (xy 370.361932 -231.599728) (xy 370.345816 -231.648002) (xy 370.322165 -231.693065)
			(xy 370.291592 -231.733751) (xy 370.254888 -231.769006) (xy 370.213004 -231.797916) (xy 370.167025 -231.819733)
			(xy 370.118141 -231.833893) (xy 370.06762 -231.840027) (xy 370.016768 -231.837978) (xy 369.966904 -231.827798)
			(xy 369.919318 -231.809751) (xy 369.875244 -231.784305) (xy 369.835822 -231.752118) (xy 369.802074 -231.714024)
			(xy 369.774873 -231.67101) (xy 369.754925 -231.62419) (xy 369.742746 -231.574776) (xy 369.738651 -231.524048)
			(xy 369.43284 -231.524048) (xy 369.43235 -231.549037) (xy 369.424531 -231.5984) (xy 369.409087 -231.645932)
			(xy 369.386397 -231.690464) (xy 369.357021 -231.730897) (xy 369.321681 -231.766237) (xy 369.281248 -231.795613)
			(xy 369.236716 -231.818303) (xy 369.189184 -231.833747) (xy 369.139821 -231.841566) (xy 369.089843 -231.841566)
			(xy 369.04048 -231.833747) (xy 368.992948 -231.818303) (xy 368.948416 -231.795613) (xy 368.907983 -231.766237)
			(xy 368.872643 -231.730897) (xy 368.843267 -231.690464) (xy 368.820577 -231.645932) (xy 368.805133 -231.5984)
			(xy 368.797314 -231.549037) (xy 368.489997 -231.549037) (xy 368.489988 -231.549494) (xy 368.481824 -231.599728)
			(xy 368.465708 -231.648002) (xy 368.442057 -231.693065) (xy 368.411484 -231.733751) (xy 368.37478 -231.769006)
			(xy 368.332896 -231.797916) (xy 368.286917 -231.819733) (xy 368.238033 -231.833893) (xy 368.187512 -231.840027)
			(xy 368.13666 -231.837978) (xy 368.086796 -231.827798) (xy 368.03921 -231.809751) (xy 367.995136 -231.784305)
			(xy 367.955714 -231.752118) (xy 367.921966 -231.714024) (xy 367.894765 -231.67101) (xy 367.874817 -231.62419)
			(xy 367.862638 -231.574776) (xy 367.858543 -231.524048) (xy 367.550446 -231.524048) (xy 367.549934 -231.549494)
			(xy 367.54177 -231.599728) (xy 367.525654 -231.648002) (xy 367.502003 -231.693065) (xy 367.47143 -231.733751)
			(xy 367.434726 -231.769006) (xy 367.392842 -231.797916) (xy 367.346863 -231.819733) (xy 367.297979 -231.833893)
			(xy 367.247458 -231.840027) (xy 367.196606 -231.837978) (xy 367.146742 -231.827798) (xy 367.099156 -231.809751)
			(xy 367.055082 -231.784305) (xy 367.01566 -231.752118) (xy 366.981912 -231.714024) (xy 366.954711 -231.67101)
			(xy 366.934763 -231.62419) (xy 366.922584 -231.574776) (xy 366.918489 -231.524048) (xy 366.612932 -231.524048)
			(xy 366.612442 -231.549037) (xy 366.604623 -231.5984) (xy 366.589179 -231.645932) (xy 366.566489 -231.690464)
			(xy 366.537113 -231.730897) (xy 366.501773 -231.766237) (xy 366.46134 -231.795613) (xy 366.416808 -231.818303)
			(xy 366.369276 -231.833747) (xy 366.319913 -231.841566) (xy 366.269935 -231.841566) (xy 366.220572 -231.833747)
			(xy 366.17304 -231.818303) (xy 366.128508 -231.795613) (xy 366.088075 -231.766237) (xy 366.052735 -231.730897)
			(xy 366.023359 -231.690464) (xy 366.000669 -231.645932) (xy 365.985225 -231.5984) (xy 365.977406 -231.549037)
			(xy 365.670089 -231.549037) (xy 365.67008 -231.549494) (xy 365.661916 -231.599728) (xy 365.6458 -231.648002)
			(xy 365.622149 -231.693065) (xy 365.591576 -231.733751) (xy 365.554872 -231.769006) (xy 365.512988 -231.797916)
			(xy 365.467009 -231.819733) (xy 365.418125 -231.833893) (xy 365.367604 -231.840027) (xy 365.316752 -231.837978)
			(xy 365.266888 -231.827798) (xy 365.219302 -231.809751) (xy 365.175228 -231.784305) (xy 365.135806 -231.752118)
			(xy 365.102058 -231.714024) (xy 365.074857 -231.67101) (xy 365.054909 -231.62419) (xy 365.04273 -231.574776)
			(xy 365.038635 -231.524048) (xy 364.730538 -231.524048) (xy 364.730026 -231.549494) (xy 364.721862 -231.599728)
			(xy 364.705746 -231.648002) (xy 364.682095 -231.693065) (xy 364.651522 -231.733751) (xy 364.614818 -231.769006)
			(xy 364.572934 -231.797916) (xy 364.526955 -231.819733) (xy 364.478071 -231.833893) (xy 364.42755 -231.840027)
			(xy 364.376698 -231.837978) (xy 364.326834 -231.827798) (xy 364.279248 -231.809751) (xy 364.235174 -231.784305)
			(xy 364.195752 -231.752118) (xy 364.162004 -231.714024) (xy 364.134803 -231.67101) (xy 364.114855 -231.62419)
			(xy 364.102676 -231.574776) (xy 364.098581 -231.524048) (xy 363.79277 -231.524048) (xy 363.79228 -231.549037)
			(xy 363.784461 -231.5984) (xy 363.769017 -231.645932) (xy 363.746327 -231.690464) (xy 363.716951 -231.730897)
			(xy 363.681611 -231.766237) (xy 363.641178 -231.795613) (xy 363.596646 -231.818303) (xy 363.549114 -231.833747)
			(xy 363.499751 -231.841566) (xy 363.449773 -231.841566) (xy 363.40041 -231.833747) (xy 363.352878 -231.818303)
			(xy 363.308346 -231.795613) (xy 363.267913 -231.766237) (xy 363.232573 -231.730897) (xy 363.203197 -231.690464)
			(xy 363.180507 -231.645932) (xy 363.165063 -231.5984) (xy 363.157244 -231.549037) (xy 356.278706 -231.549037)
			(xy 356.270887 -231.5984) (xy 356.255443 -231.645932) (xy 356.232753 -231.690464) (xy 356.203377 -231.730897)
			(xy 356.168037 -231.766237) (xy 356.127604 -231.795613) (xy 356.083072 -231.818303) (xy 356.03554 -231.833747)
			(xy 355.986177 -231.841566) (xy 355.936199 -231.841566) (xy 355.886836 -231.833747) (xy 355.839304 -231.818303)
			(xy 355.794772 -231.795613) (xy 355.754339 -231.766237) (xy 355.718999 -231.730897) (xy 355.689623 -231.690464)
			(xy 355.666933 -231.645932) (xy 355.651489 -231.5984) (xy 355.64367 -231.549037) (xy 355.336353 -231.549037)
			(xy 355.336344 -231.549494) (xy 355.32818 -231.599728) (xy 355.312064 -231.648002) (xy 355.288413 -231.693065)
			(xy 355.25784 -231.733751) (xy 355.221136 -231.769006) (xy 355.179252 -231.797916) (xy 355.133273 -231.819733)
			(xy 355.084389 -231.833893) (xy 355.033868 -231.840027) (xy 354.983016 -231.837978) (xy 354.933152 -231.827798)
			(xy 354.885566 -231.809751) (xy 354.841492 -231.784305) (xy 354.80207 -231.752118) (xy 354.768322 -231.714024)
			(xy 354.741121 -231.67101) (xy 354.721173 -231.62419) (xy 354.708994 -231.574776) (xy 354.704899 -231.524048)
			(xy 354.396802 -231.524048) (xy 354.39629 -231.549494) (xy 354.388126 -231.599728) (xy 354.37201 -231.648002)
			(xy 354.348359 -231.693065) (xy 354.317786 -231.733751) (xy 354.281082 -231.769006) (xy 354.239198 -231.797916)
			(xy 354.193219 -231.819733) (xy 354.144335 -231.833893) (xy 354.093814 -231.840027) (xy 354.042962 -231.837978)
			(xy 353.993098 -231.827798) (xy 353.945512 -231.809751) (xy 353.901438 -231.784305) (xy 353.862016 -231.752118)
			(xy 353.828268 -231.714024) (xy 353.801067 -231.67101) (xy 353.781119 -231.62419) (xy 353.76894 -231.574776)
			(xy 353.764845 -231.524048) (xy 353.459034 -231.524048) (xy 353.458544 -231.549037) (xy 353.450725 -231.5984)
			(xy 353.435281 -231.645932) (xy 353.412591 -231.690464) (xy 353.383215 -231.730897) (xy 353.347875 -231.766237)
			(xy 353.307442 -231.795613) (xy 353.26291 -231.818303) (xy 353.215378 -231.833747) (xy 353.166015 -231.841566)
			(xy 353.116037 -231.841566) (xy 353.066674 -231.833747) (xy 353.019142 -231.818303) (xy 352.97461 -231.795613)
			(xy 352.934177 -231.766237) (xy 352.898837 -231.730897) (xy 352.869461 -231.690464) (xy 352.846771 -231.645932)
			(xy 352.831327 -231.5984) (xy 352.823508 -231.549037) (xy 352.516445 -231.549037) (xy 352.516436 -231.549494)
			(xy 352.508272 -231.599728) (xy 352.492156 -231.648002) (xy 352.468505 -231.693065) (xy 352.437932 -231.733751)
			(xy 352.401228 -231.769006) (xy 352.359344 -231.797916) (xy 352.313365 -231.819733) (xy 352.264481 -231.833893)
			(xy 352.21396 -231.840027) (xy 352.163108 -231.837978) (xy 352.113244 -231.827798) (xy 352.065658 -231.809751)
			(xy 352.021584 -231.784305) (xy 351.982162 -231.752118) (xy 351.948414 -231.714024) (xy 351.921213 -231.67101)
			(xy 351.901265 -231.62419) (xy 351.889086 -231.574776) (xy 351.884991 -231.524048) (xy 351.576894 -231.524048)
			(xy 351.576382 -231.549494) (xy 351.568218 -231.599728) (xy 351.552102 -231.648002) (xy 351.528451 -231.693065)
			(xy 351.497878 -231.733751) (xy 351.461174 -231.769006) (xy 351.41929 -231.797916) (xy 351.373311 -231.819733)
			(xy 351.324427 -231.833893) (xy 351.273906 -231.840027) (xy 351.223054 -231.837978) (xy 351.17319 -231.827798)
			(xy 351.125604 -231.809751) (xy 351.08153 -231.784305) (xy 351.042108 -231.752118) (xy 351.00836 -231.714024)
			(xy 350.981159 -231.67101) (xy 350.961211 -231.62419) (xy 350.949032 -231.574776) (xy 350.944937 -231.524048)
			(xy 350.639126 -231.524048) (xy 350.638636 -231.549037) (xy 350.630817 -231.5984) (xy 350.615373 -231.645932)
			(xy 350.592683 -231.690464) (xy 350.563307 -231.730897) (xy 350.527967 -231.766237) (xy 350.487534 -231.795613)
			(xy 350.443002 -231.818303) (xy 350.39547 -231.833747) (xy 350.346107 -231.841566) (xy 350.296129 -231.841566)
			(xy 350.246766 -231.833747) (xy 350.199234 -231.818303) (xy 350.154702 -231.795613) (xy 350.114269 -231.766237)
			(xy 350.078929 -231.730897) (xy 350.049553 -231.690464) (xy 350.026863 -231.645932) (xy 350.011419 -231.5984)
			(xy 350.0036 -231.549037) (xy 349.696283 -231.549037) (xy 349.696274 -231.549494) (xy 349.68811 -231.599728)
			(xy 349.671994 -231.648002) (xy 349.648343 -231.693065) (xy 349.61777 -231.733751) (xy 349.581066 -231.769006)
			(xy 349.539182 -231.797916) (xy 349.493203 -231.819733) (xy 349.444319 -231.833893) (xy 349.393798 -231.840027)
			(xy 349.342946 -231.837978) (xy 349.293082 -231.827798) (xy 349.245496 -231.809751) (xy 349.201422 -231.784305)
			(xy 349.162 -231.752118) (xy 349.128252 -231.714024) (xy 349.101051 -231.67101) (xy 349.081103 -231.62419)
			(xy 349.068924 -231.574776) (xy 349.064829 -231.524048) (xy 348.756732 -231.524048) (xy 348.75622 -231.549494)
			(xy 348.748056 -231.599728) (xy 348.73194 -231.648002) (xy 348.708289 -231.693065) (xy 348.677716 -231.733751)
			(xy 348.641012 -231.769006) (xy 348.599128 -231.797916) (xy 348.553149 -231.819733) (xy 348.504265 -231.833893)
			(xy 348.453744 -231.840027) (xy 348.402892 -231.837978) (xy 348.353028 -231.827798) (xy 348.305442 -231.809751)
			(xy 348.261368 -231.784305) (xy 348.221946 -231.752118) (xy 348.188198 -231.714024) (xy 348.160997 -231.67101)
			(xy 348.141049 -231.62419) (xy 348.12887 -231.574776) (xy 348.124775 -231.524048) (xy 347.819218 -231.524048)
			(xy 347.818728 -231.549037) (xy 347.810909 -231.5984) (xy 347.795465 -231.645932) (xy 347.772775 -231.690464)
			(xy 347.743399 -231.730897) (xy 347.708059 -231.766237) (xy 347.667626 -231.795613) (xy 347.623094 -231.818303)
			(xy 347.575562 -231.833747) (xy 347.526199 -231.841566) (xy 347.476221 -231.841566) (xy 347.426858 -231.833747)
			(xy 347.379326 -231.818303) (xy 347.334794 -231.795613) (xy 347.294361 -231.766237) (xy 347.259021 -231.730897)
			(xy 347.229645 -231.690464) (xy 347.206955 -231.645932) (xy 347.191511 -231.5984) (xy 347.183692 -231.549037)
			(xy 346.876375 -231.549037) (xy 346.876366 -231.549494) (xy 346.868202 -231.599728) (xy 346.852086 -231.648002)
			(xy 346.828435 -231.693065) (xy 346.797862 -231.733751) (xy 346.761158 -231.769006) (xy 346.719274 -231.797916)
			(xy 346.673295 -231.819733) (xy 346.624411 -231.833893) (xy 346.57389 -231.840027) (xy 346.523038 -231.837978)
			(xy 346.473174 -231.827798) (xy 346.425588 -231.809751) (xy 346.381514 -231.784305) (xy 346.342092 -231.752118)
			(xy 346.308344 -231.714024) (xy 346.281143 -231.67101) (xy 346.261195 -231.62419) (xy 346.249016 -231.574776)
			(xy 346.244921 -231.524048) (xy 345.936824 -231.524048) (xy 345.936312 -231.549494) (xy 345.928148 -231.599728)
			(xy 345.912032 -231.648002) (xy 345.888381 -231.693065) (xy 345.857808 -231.733751) (xy 345.821104 -231.769006)
			(xy 345.77922 -231.797916) (xy 345.733241 -231.819733) (xy 345.684357 -231.833893) (xy 345.633836 -231.840027)
			(xy 345.582984 -231.837978) (xy 345.53312 -231.827798) (xy 345.485534 -231.809751) (xy 345.44146 -231.784305)
			(xy 345.402038 -231.752118) (xy 345.36829 -231.714024) (xy 345.341089 -231.67101) (xy 345.321141 -231.62419)
			(xy 345.308962 -231.574776) (xy 345.304867 -231.524048) (xy 344.999056 -231.524048) (xy 344.999056 -231.524302)
			(xy 344.997786 -231.553512) (xy 344.997532 -231.558084) (xy 344.997532 -231.919526) (xy 344.99804 -231.92928)
			(xy 345.005476 -231.947321) (xy 345.01201 -231.954578) (xy 345.072462 -232.007664) (xy 345.079276 -232.012685)
			(xy 345.095246 -232.018263) (xy 345.103704 -232.018586) (xy 345.110562 -232.018586) (xy 345.113356 -232.018332)
			(xy 345.122781 -232.017264) (xy 345.141717 -232.016123) (xy 345.151202 -232.016046) (xy 345.176195 -232.016537)
			(xy 345.225565 -232.024356) (xy 345.273103 -232.039803) (xy 345.317641 -232.062496) (xy 345.35808 -232.091877)
			(xy 345.393424 -232.127222) (xy 345.422805 -232.167661) (xy 345.445498 -232.212198) (xy 345.460944 -232.259737)
			(xy 345.468764 -232.309107) (xy 345.468764 -232.359043) (xy 345.773484 -232.359043) (xy 345.773484 -232.309065)
			(xy 345.781303 -232.259702) (xy 345.796747 -232.21217) (xy 345.819437 -232.167638) (xy 345.848813 -232.127205)
			(xy 345.884153 -232.091865) (xy 345.924586 -232.062489) (xy 345.969118 -232.039799) (xy 346.01665 -232.024355)
			(xy 346.066013 -232.016536) (xy 346.115991 -232.016536) (xy 346.165354 -232.024355) (xy 346.212886 -232.039799)
			(xy 346.257418 -232.062489) (xy 346.297851 -232.091865) (xy 346.333191 -232.127205) (xy 346.362567 -232.167638)
			(xy 346.385257 -232.21217) (xy 346.400701 -232.259702) (xy 346.40852 -232.309065) (xy 346.40901 -232.334054)
			(xy 346.40852 -232.359043) (xy 346.713538 -232.359043) (xy 346.713538 -232.309065) (xy 346.721357 -232.259702)
			(xy 346.736801 -232.21217) (xy 346.759491 -232.167638) (xy 346.788867 -232.127205) (xy 346.824207 -232.091865)
			(xy 346.86464 -232.062489) (xy 346.909172 -232.039799) (xy 346.956704 -232.024355) (xy 347.006067 -232.016536)
			(xy 347.056045 -232.016536) (xy 347.105408 -232.024355) (xy 347.15294 -232.039799) (xy 347.197472 -232.062489)
			(xy 347.237905 -232.091865) (xy 347.273245 -232.127205) (xy 347.302621 -232.167638) (xy 347.325311 -232.21217)
			(xy 347.340755 -232.259702) (xy 347.348574 -232.309065) (xy 347.349064 -232.334054) (xy 347.348574 -232.359043)
			(xy 347.653592 -232.359043) (xy 347.653592 -232.309065) (xy 347.661411 -232.259702) (xy 347.676855 -232.21217)
			(xy 347.699545 -232.167638) (xy 347.728921 -232.127205) (xy 347.764261 -232.091865) (xy 347.804694 -232.062489)
			(xy 347.849226 -232.039799) (xy 347.896758 -232.024355) (xy 347.946121 -232.016536) (xy 347.996099 -232.016536)
			(xy 348.045462 -232.024355) (xy 348.092994 -232.039799) (xy 348.137526 -232.062489) (xy 348.177959 -232.091865)
			(xy 348.213299 -232.127205) (xy 348.242675 -232.167638) (xy 348.265365 -232.21217) (xy 348.280809 -232.259702)
			(xy 348.288628 -232.309065) (xy 348.289118 -232.334054) (xy 348.288628 -232.359043) (xy 348.593646 -232.359043)
			(xy 348.593646 -232.309065) (xy 348.601465 -232.259702) (xy 348.616909 -232.21217) (xy 348.639599 -232.167638)
			(xy 348.668975 -232.127205) (xy 348.704315 -232.091865) (xy 348.744748 -232.062489) (xy 348.78928 -232.039799)
			(xy 348.836812 -232.024355) (xy 348.886175 -232.016536) (xy 348.936153 -232.016536) (xy 348.985516 -232.024355)
			(xy 349.033048 -232.039799) (xy 349.07758 -232.062489) (xy 349.118013 -232.091865) (xy 349.153353 -232.127205)
			(xy 349.182729 -232.167638) (xy 349.205419 -232.21217) (xy 349.220863 -232.259702) (xy 349.228682 -232.309065)
			(xy 349.229172 -232.334054) (xy 349.228682 -232.359043) (xy 349.5337 -232.359043) (xy 349.5337 -232.309065)
			(xy 349.541519 -232.259702) (xy 349.556963 -232.21217) (xy 349.579653 -232.167638) (xy 349.609029 -232.127205)
			(xy 349.644369 -232.091865) (xy 349.684802 -232.062489) (xy 349.729334 -232.039799) (xy 349.776866 -232.024355)
			(xy 349.826229 -232.016536) (xy 349.876207 -232.016536) (xy 349.92557 -232.024355) (xy 349.973102 -232.039799)
			(xy 350.017634 -232.062489) (xy 350.058067 -232.091865) (xy 350.093407 -232.127205) (xy 350.122783 -232.167638)
			(xy 350.145473 -232.21217) (xy 350.160917 -232.259702) (xy 350.168736 -232.309065) (xy 350.169226 -232.334054)
			(xy 350.168736 -232.359043) (xy 350.4735 -232.359043) (xy 350.4735 -232.309065) (xy 350.481319 -232.259702)
			(xy 350.496763 -232.21217) (xy 350.519453 -232.167638) (xy 350.548829 -232.127205) (xy 350.584169 -232.091865)
			(xy 350.624602 -232.062489) (xy 350.669134 -232.039799) (xy 350.716666 -232.024355) (xy 350.766029 -232.016536)
			(xy 350.816007 -232.016536) (xy 350.86537 -232.024355) (xy 350.912902 -232.039799) (xy 350.957434 -232.062489)
			(xy 350.997867 -232.091865) (xy 351.033207 -232.127205) (xy 351.062583 -232.167638) (xy 351.085273 -232.21217)
			(xy 351.100717 -232.259702) (xy 351.108536 -232.309065) (xy 351.109026 -232.334054) (xy 351.108536 -232.359043)
			(xy 351.413554 -232.359043) (xy 351.413554 -232.309065) (xy 351.421373 -232.259702) (xy 351.436817 -232.21217)
			(xy 351.459507 -232.167638) (xy 351.488883 -232.127205) (xy 351.524223 -232.091865) (xy 351.564656 -232.062489)
			(xy 351.609188 -232.039799) (xy 351.65672 -232.024355) (xy 351.706083 -232.016536) (xy 351.756061 -232.016536)
			(xy 351.805424 -232.024355) (xy 351.852956 -232.039799) (xy 351.897488 -232.062489) (xy 351.937921 -232.091865)
			(xy 351.973261 -232.127205) (xy 352.002637 -232.167638) (xy 352.025327 -232.21217) (xy 352.040771 -232.259702)
			(xy 352.04859 -232.309065) (xy 352.04908 -232.334054) (xy 352.04859 -232.359043) (xy 352.353608 -232.359043)
			(xy 352.353608 -232.309065) (xy 352.361427 -232.259702) (xy 352.376871 -232.21217) (xy 352.399561 -232.167638)
			(xy 352.428937 -232.127205) (xy 352.464277 -232.091865) (xy 352.50471 -232.062489) (xy 352.549242 -232.039799)
			(xy 352.596774 -232.024355) (xy 352.646137 -232.016536) (xy 352.696115 -232.016536) (xy 352.745478 -232.024355)
			(xy 352.79301 -232.039799) (xy 352.837542 -232.062489) (xy 352.877975 -232.091865) (xy 352.913315 -232.127205)
			(xy 352.942691 -232.167638) (xy 352.965381 -232.21217) (xy 352.980825 -232.259702) (xy 352.988644 -232.309065)
			(xy 352.989134 -232.334054) (xy 352.988644 -232.359043) (xy 353.293662 -232.359043) (xy 353.293662 -232.309065)
			(xy 353.301481 -232.259702) (xy 353.316925 -232.21217) (xy 353.339615 -232.167638) (xy 353.368991 -232.127205)
			(xy 353.404331 -232.091865) (xy 353.444764 -232.062489) (xy 353.489296 -232.039799) (xy 353.536828 -232.024355)
			(xy 353.586191 -232.016536) (xy 353.636169 -232.016536) (xy 353.685532 -232.024355) (xy 353.733064 -232.039799)
			(xy 353.777596 -232.062489) (xy 353.818029 -232.091865) (xy 353.853369 -232.127205) (xy 353.882745 -232.167638)
			(xy 353.905435 -232.21217) (xy 353.920879 -232.259702) (xy 353.928698 -232.309065) (xy 353.929188 -232.334054)
			(xy 353.928698 -232.359043) (xy 354.233716 -232.359043) (xy 354.233716 -232.309065) (xy 354.241535 -232.259702)
			(xy 354.256979 -232.21217) (xy 354.279669 -232.167638) (xy 354.309045 -232.127205) (xy 354.344385 -232.091865)
			(xy 354.384818 -232.062489) (xy 354.42935 -232.039799) (xy 354.476882 -232.024355) (xy 354.526245 -232.016536)
			(xy 354.576223 -232.016536) (xy 354.625586 -232.024355) (xy 354.673118 -232.039799) (xy 354.71765 -232.062489)
			(xy 354.758083 -232.091865) (xy 354.793423 -232.127205) (xy 354.822799 -232.167638) (xy 354.845489 -232.21217)
			(xy 354.860933 -232.259702) (xy 354.868752 -232.309065) (xy 354.869242 -232.334054) (xy 354.868752 -232.359043)
			(xy 355.173516 -232.359043) (xy 355.173516 -232.309065) (xy 355.181335 -232.259702) (xy 355.196779 -232.21217)
			(xy 355.219469 -232.167638) (xy 355.248845 -232.127205) (xy 355.284185 -232.091865) (xy 355.324618 -232.062489)
			(xy 355.36915 -232.039799) (xy 355.416682 -232.024355) (xy 355.466045 -232.016536) (xy 355.516023 -232.016536)
			(xy 355.565386 -232.024355) (xy 355.612918 -232.039799) (xy 355.65745 -232.062489) (xy 355.697883 -232.091865)
			(xy 355.733223 -232.127205) (xy 355.762599 -232.167638) (xy 355.785289 -232.21217) (xy 355.800733 -232.259702)
			(xy 355.808552 -232.309065) (xy 355.809042 -232.334054) (xy 356.114853 -232.334054) (xy 356.118948 -232.283326)
			(xy 356.131127 -232.233912) (xy 356.151075 -232.187092) (xy 356.178276 -232.144078) (xy 356.212024 -232.105984)
			(xy 356.251446 -232.073797) (xy 356.29552 -232.048351) (xy 356.343106 -232.030304) (xy 356.39297 -232.020124)
			(xy 356.443822 -232.018075) (xy 356.494343 -232.024209) (xy 356.543227 -232.038369) (xy 356.589206 -232.060186)
			(xy 356.63109 -232.089096) (xy 356.667794 -232.124351) (xy 356.698367 -232.165037) (xy 356.722018 -232.2101)
			(xy 356.738134 -232.258374) (xy 356.746298 -232.308608) (xy 356.74681 -232.334054) (xy 357.054907 -232.334054)
			(xy 357.059002 -232.283326) (xy 357.071181 -232.233912) (xy 357.091129 -232.187092) (xy 357.11833 -232.144078)
			(xy 357.152078 -232.105984) (xy 357.1915 -232.073797) (xy 357.235574 -232.048351) (xy 357.28316 -232.030304)
			(xy 357.333024 -232.020124) (xy 357.383876 -232.018075) (xy 357.434397 -232.024209) (xy 357.483281 -232.038369)
			(xy 357.52926 -232.060186) (xy 357.571144 -232.089096) (xy 357.607848 -232.124351) (xy 357.638421 -232.165037)
			(xy 357.662072 -232.2101) (xy 357.678188 -232.258374) (xy 357.686352 -232.308608) (xy 357.686864 -232.334054)
			(xy 357.686361 -232.359043) (xy 357.993678 -232.359043) (xy 357.993678 -232.309065) (xy 358.001497 -232.259702)
			(xy 358.016941 -232.21217) (xy 358.039631 -232.167638) (xy 358.069007 -232.127205) (xy 358.104347 -232.091865)
			(xy 358.14478 -232.062489) (xy 358.189312 -232.039799) (xy 358.236844 -232.024355) (xy 358.286207 -232.016536)
			(xy 358.336185 -232.016536) (xy 358.385548 -232.024355) (xy 358.43308 -232.039799) (xy 358.477612 -232.062489)
			(xy 358.518045 -232.091865) (xy 358.553385 -232.127205) (xy 358.582761 -232.167638) (xy 358.605451 -232.21217)
			(xy 358.620895 -232.259702) (xy 358.628714 -232.309065) (xy 358.629204 -232.334054) (xy 358.628714 -232.359043)
			(xy 360.807236 -232.359043) (xy 360.807236 -232.309065) (xy 360.815055 -232.259702) (xy 360.830499 -232.21217)
			(xy 360.853189 -232.167638) (xy 360.882565 -232.127205) (xy 360.917905 -232.091865) (xy 360.958338 -232.062489)
			(xy 361.00287 -232.039799) (xy 361.050402 -232.024355) (xy 361.099765 -232.016536) (xy 361.149743 -232.016536)
			(xy 361.199106 -232.024355) (xy 361.246638 -232.039799) (xy 361.29117 -232.062489) (xy 361.331603 -232.091865)
			(xy 361.366943 -232.127205) (xy 361.396319 -232.167638) (xy 361.419009 -232.21217) (xy 361.434453 -232.259702)
			(xy 361.442272 -232.309065) (xy 361.442762 -232.334054) (xy 361.748573 -232.334054) (xy 361.752668 -232.283326)
			(xy 361.764847 -232.233912) (xy 361.784795 -232.187092) (xy 361.811996 -232.144078) (xy 361.845744 -232.105984)
			(xy 361.885166 -232.073797) (xy 361.92924 -232.048351) (xy 361.976826 -232.030304) (xy 362.02669 -232.020124)
			(xy 362.077542 -232.018075) (xy 362.128063 -232.024209) (xy 362.176947 -232.038369) (xy 362.222926 -232.060186)
			(xy 362.26481 -232.089096) (xy 362.301514 -232.124351) (xy 362.332087 -232.165037) (xy 362.355738 -232.2101)
			(xy 362.371854 -232.258374) (xy 362.380018 -232.308608) (xy 362.38053 -232.334054) (xy 362.688627 -232.334054)
			(xy 362.692722 -232.283326) (xy 362.704901 -232.233912) (xy 362.724849 -232.187092) (xy 362.75205 -232.144078)
			(xy 362.785798 -232.105984) (xy 362.82522 -232.073797) (xy 362.869294 -232.048351) (xy 362.91688 -232.030304)
			(xy 362.966744 -232.020124) (xy 363.017596 -232.018075) (xy 363.068117 -232.024209) (xy 363.117001 -232.038369)
			(xy 363.16298 -232.060186) (xy 363.204864 -232.089096) (xy 363.241568 -232.124351) (xy 363.272141 -232.165037)
			(xy 363.295792 -232.2101) (xy 363.311908 -232.258374) (xy 363.320072 -232.308608) (xy 363.320584 -232.334054)
			(xy 363.320081 -232.359043) (xy 363.627398 -232.359043) (xy 363.627398 -232.309065) (xy 363.635217 -232.259702)
			(xy 363.650661 -232.21217) (xy 363.673351 -232.167638) (xy 363.702727 -232.127205) (xy 363.738067 -232.091865)
			(xy 363.7785 -232.062489) (xy 363.823032 -232.039799) (xy 363.870564 -232.024355) (xy 363.919927 -232.016536)
			(xy 363.969905 -232.016536) (xy 364.019268 -232.024355) (xy 364.0668 -232.039799) (xy 364.111332 -232.062489)
			(xy 364.151765 -232.091865) (xy 364.187105 -232.127205) (xy 364.216481 -232.167638) (xy 364.239171 -232.21217)
			(xy 364.254615 -232.259702) (xy 364.262434 -232.309065) (xy 364.262924 -232.334054) (xy 364.262434 -232.359043)
			(xy 364.567198 -232.359043) (xy 364.567198 -232.309065) (xy 364.575017 -232.259702) (xy 364.590461 -232.21217)
			(xy 364.613151 -232.167638) (xy 364.642527 -232.127205) (xy 364.677867 -232.091865) (xy 364.7183 -232.062489)
			(xy 364.762832 -232.039799) (xy 364.810364 -232.024355) (xy 364.859727 -232.016536) (xy 364.909705 -232.016536)
			(xy 364.959068 -232.024355) (xy 365.0066 -232.039799) (xy 365.051132 -232.062489) (xy 365.091565 -232.091865)
			(xy 365.126905 -232.127205) (xy 365.156281 -232.167638) (xy 365.178971 -232.21217) (xy 365.194415 -232.259702)
			(xy 365.202234 -232.309065) (xy 365.202724 -232.334054) (xy 365.202234 -232.359043) (xy 365.507252 -232.359043)
			(xy 365.507252 -232.309065) (xy 365.515071 -232.259702) (xy 365.530515 -232.21217) (xy 365.553205 -232.167638)
			(xy 365.582581 -232.127205) (xy 365.617921 -232.091865) (xy 365.658354 -232.062489) (xy 365.702886 -232.039799)
			(xy 365.750418 -232.024355) (xy 365.799781 -232.016536) (xy 365.849759 -232.016536) (xy 365.899122 -232.024355)
			(xy 365.946654 -232.039799) (xy 365.991186 -232.062489) (xy 366.031619 -232.091865) (xy 366.066959 -232.127205)
			(xy 366.096335 -232.167638) (xy 366.119025 -232.21217) (xy 366.134469 -232.259702) (xy 366.142288 -232.309065)
			(xy 366.142778 -232.334054) (xy 366.142288 -232.359043) (xy 366.447306 -232.359043) (xy 366.447306 -232.309065)
			(xy 366.455125 -232.259702) (xy 366.470569 -232.21217) (xy 366.493259 -232.167638) (xy 366.522635 -232.127205)
			(xy 366.557975 -232.091865) (xy 366.598408 -232.062489) (xy 366.64294 -232.039799) (xy 366.690472 -232.024355)
			(xy 366.739835 -232.016536) (xy 366.789813 -232.016536) (xy 366.839176 -232.024355) (xy 366.886708 -232.039799)
			(xy 366.93124 -232.062489) (xy 366.971673 -232.091865) (xy 367.007013 -232.127205) (xy 367.036389 -232.167638)
			(xy 367.059079 -232.21217) (xy 367.074523 -232.259702) (xy 367.082342 -232.309065) (xy 367.082832 -232.334054)
			(xy 367.082342 -232.359043) (xy 367.38736 -232.359043) (xy 367.38736 -232.309065) (xy 367.395179 -232.259702)
			(xy 367.410623 -232.21217) (xy 367.433313 -232.167638) (xy 367.462689 -232.127205) (xy 367.498029 -232.091865)
			(xy 367.538462 -232.062489) (xy 367.582994 -232.039799) (xy 367.630526 -232.024355) (xy 367.679889 -232.016536)
			(xy 367.729867 -232.016536) (xy 367.77923 -232.024355) (xy 367.826762 -232.039799) (xy 367.871294 -232.062489)
			(xy 367.911727 -232.091865) (xy 367.947067 -232.127205) (xy 367.976443 -232.167638) (xy 367.999133 -232.21217)
			(xy 368.014577 -232.259702) (xy 368.022396 -232.309065) (xy 368.022886 -232.334054) (xy 368.022396 -232.359043)
			(xy 368.32716 -232.359043) (xy 368.32716 -232.309065) (xy 368.334979 -232.259702) (xy 368.350423 -232.21217)
			(xy 368.373113 -232.167638) (xy 368.402489 -232.127205) (xy 368.437829 -232.091865) (xy 368.478262 -232.062489)
			(xy 368.522794 -232.039799) (xy 368.570326 -232.024355) (xy 368.619689 -232.016536) (xy 368.669667 -232.016536)
			(xy 368.71903 -232.024355) (xy 368.766562 -232.039799) (xy 368.811094 -232.062489) (xy 368.851527 -232.091865)
			(xy 368.886867 -232.127205) (xy 368.916243 -232.167638) (xy 368.938933 -232.21217) (xy 368.954377 -232.259702)
			(xy 368.962196 -232.309065) (xy 368.962686 -232.334054) (xy 368.962196 -232.359043) (xy 369.267214 -232.359043)
			(xy 369.267214 -232.309065) (xy 369.275033 -232.259702) (xy 369.290477 -232.21217) (xy 369.313167 -232.167638)
			(xy 369.342543 -232.127205) (xy 369.377883 -232.091865) (xy 369.418316 -232.062489) (xy 369.462848 -232.039799)
			(xy 369.51038 -232.024355) (xy 369.559743 -232.016536) (xy 369.609721 -232.016536) (xy 369.659084 -232.024355)
			(xy 369.706616 -232.039799) (xy 369.751148 -232.062489) (xy 369.791581 -232.091865) (xy 369.826921 -232.127205)
			(xy 369.856297 -232.167638) (xy 369.878987 -232.21217) (xy 369.894431 -232.259702) (xy 369.90225 -232.309065)
			(xy 369.90274 -232.334054) (xy 369.90225 -232.359043) (xy 370.207268 -232.359043) (xy 370.207268 -232.309065)
			(xy 370.215087 -232.259702) (xy 370.230531 -232.21217) (xy 370.253221 -232.167638) (xy 370.282597 -232.127205)
			(xy 370.317937 -232.091865) (xy 370.35837 -232.062489) (xy 370.402902 -232.039799) (xy 370.450434 -232.024355)
			(xy 370.499797 -232.016536) (xy 370.549775 -232.016536) (xy 370.599138 -232.024355) (xy 370.64667 -232.039799)
			(xy 370.691202 -232.062489) (xy 370.731635 -232.091865) (xy 370.766975 -232.127205) (xy 370.796351 -232.167638)
			(xy 370.819041 -232.21217) (xy 370.834485 -232.259702) (xy 370.842304 -232.309065) (xy 370.842794 -232.334054)
			(xy 370.842304 -232.359043) (xy 371.147322 -232.359043) (xy 371.147322 -232.309065) (xy 371.155141 -232.259702)
			(xy 371.170585 -232.21217) (xy 371.193275 -232.167638) (xy 371.222651 -232.127205) (xy 371.257991 -232.091865)
			(xy 371.298424 -232.062489) (xy 371.342956 -232.039799) (xy 371.390488 -232.024355) (xy 371.439851 -232.016536)
			(xy 371.489829 -232.016536) (xy 371.539192 -232.024355) (xy 371.586724 -232.039799) (xy 371.631256 -232.062489)
			(xy 371.671689 -232.091865) (xy 371.707029 -232.127205) (xy 371.736405 -232.167638) (xy 371.759095 -232.21217)
			(xy 371.774539 -232.259702) (xy 371.782358 -232.309065) (xy 371.782848 -232.334054) (xy 371.782358 -232.359043)
			(xy 372.087376 -232.359043) (xy 372.087376 -232.309065) (xy 372.095195 -232.259702) (xy 372.110639 -232.21217)
			(xy 372.133329 -232.167638) (xy 372.162705 -232.127205) (xy 372.198045 -232.091865) (xy 372.238478 -232.062489)
			(xy 372.28301 -232.039799) (xy 372.330542 -232.024355) (xy 372.379905 -232.016536) (xy 372.429883 -232.016536)
			(xy 372.479246 -232.024355) (xy 372.526778 -232.039799) (xy 372.57131 -232.062489) (xy 372.611743 -232.091865)
			(xy 372.647083 -232.127205) (xy 372.676459 -232.167638) (xy 372.699149 -232.21217) (xy 372.714593 -232.259702)
			(xy 372.722412 -232.309065) (xy 372.722902 -232.334054) (xy 372.722412 -232.359043) (xy 373.027176 -232.359043)
			(xy 373.027176 -232.309065) (xy 373.034995 -232.259702) (xy 373.050439 -232.21217) (xy 373.073129 -232.167638)
			(xy 373.102505 -232.127205) (xy 373.137845 -232.091865) (xy 373.178278 -232.062489) (xy 373.22281 -232.039799)
			(xy 373.270342 -232.024355) (xy 373.319705 -232.016536) (xy 373.369683 -232.016536) (xy 373.419046 -232.024355)
			(xy 373.466578 -232.039799) (xy 373.51111 -232.062489) (xy 373.551543 -232.091865) (xy 373.586883 -232.127205)
			(xy 373.616259 -232.167638) (xy 373.638949 -232.21217) (xy 373.654393 -232.259702) (xy 373.662212 -232.309065)
			(xy 373.662702 -232.334054) (xy 373.662212 -232.359043) (xy 373.654393 -232.408406) (xy 373.638949 -232.455938)
			(xy 373.616259 -232.50047) (xy 373.586883 -232.540903) (xy 373.551543 -232.576243) (xy 373.51111 -232.605619)
			(xy 373.466578 -232.628309) (xy 373.419046 -232.643753) (xy 373.369683 -232.651572) (xy 373.319705 -232.651572)
			(xy 373.270342 -232.643753) (xy 373.22281 -232.628309) (xy 373.178278 -232.605619) (xy 373.137845 -232.576243)
			(xy 373.102505 -232.540903) (xy 373.073129 -232.50047) (xy 373.050439 -232.455938) (xy 373.034995 -232.408406)
			(xy 373.027176 -232.359043) (xy 372.722412 -232.359043) (xy 372.714593 -232.408406) (xy 372.699149 -232.455938)
			(xy 372.676459 -232.50047) (xy 372.647083 -232.540903) (xy 372.611743 -232.576243) (xy 372.57131 -232.605619)
			(xy 372.526778 -232.628309) (xy 372.479246 -232.643753) (xy 372.429883 -232.651572) (xy 372.379905 -232.651572)
			(xy 372.330542 -232.643753) (xy 372.28301 -232.628309) (xy 372.238478 -232.605619) (xy 372.198045 -232.576243)
			(xy 372.162705 -232.540903) (xy 372.133329 -232.50047) (xy 372.110639 -232.455938) (xy 372.095195 -232.408406)
			(xy 372.087376 -232.359043) (xy 371.782358 -232.359043) (xy 371.774539 -232.408406) (xy 371.759095 -232.455938)
			(xy 371.736405 -232.50047) (xy 371.707029 -232.540903) (xy 371.671689 -232.576243) (xy 371.631256 -232.605619)
			(xy 371.586724 -232.628309) (xy 371.539192 -232.643753) (xy 371.489829 -232.651572) (xy 371.439851 -232.651572)
			(xy 371.390488 -232.643753) (xy 371.342956 -232.628309) (xy 371.298424 -232.605619) (xy 371.257991 -232.576243)
			(xy 371.222651 -232.540903) (xy 371.193275 -232.50047) (xy 371.170585 -232.455938) (xy 371.155141 -232.408406)
			(xy 371.147322 -232.359043) (xy 370.842304 -232.359043) (xy 370.834485 -232.408406) (xy 370.819041 -232.455938)
			(xy 370.796351 -232.50047) (xy 370.766975 -232.540903) (xy 370.731635 -232.576243) (xy 370.691202 -232.605619)
			(xy 370.64667 -232.628309) (xy 370.599138 -232.643753) (xy 370.549775 -232.651572) (xy 370.499797 -232.651572)
			(xy 370.450434 -232.643753) (xy 370.402902 -232.628309) (xy 370.35837 -232.605619) (xy 370.317937 -232.576243)
			(xy 370.282597 -232.540903) (xy 370.253221 -232.50047) (xy 370.230531 -232.455938) (xy 370.215087 -232.408406)
			(xy 370.207268 -232.359043) (xy 369.90225 -232.359043) (xy 369.894431 -232.408406) (xy 369.878987 -232.455938)
			(xy 369.856297 -232.50047) (xy 369.826921 -232.540903) (xy 369.791581 -232.576243) (xy 369.751148 -232.605619)
			(xy 369.706616 -232.628309) (xy 369.659084 -232.643753) (xy 369.609721 -232.651572) (xy 369.559743 -232.651572)
			(xy 369.51038 -232.643753) (xy 369.462848 -232.628309) (xy 369.418316 -232.605619) (xy 369.377883 -232.576243)
			(xy 369.342543 -232.540903) (xy 369.313167 -232.50047) (xy 369.290477 -232.455938) (xy 369.275033 -232.408406)
			(xy 369.267214 -232.359043) (xy 368.962196 -232.359043) (xy 368.954377 -232.408406) (xy 368.938933 -232.455938)
			(xy 368.916243 -232.50047) (xy 368.886867 -232.540903) (xy 368.851527 -232.576243) (xy 368.811094 -232.605619)
			(xy 368.766562 -232.628309) (xy 368.71903 -232.643753) (xy 368.669667 -232.651572) (xy 368.619689 -232.651572)
			(xy 368.570326 -232.643753) (xy 368.522794 -232.628309) (xy 368.478262 -232.605619) (xy 368.437829 -232.576243)
			(xy 368.402489 -232.540903) (xy 368.373113 -232.50047) (xy 368.350423 -232.455938) (xy 368.334979 -232.408406)
			(xy 368.32716 -232.359043) (xy 368.022396 -232.359043) (xy 368.014577 -232.408406) (xy 367.999133 -232.455938)
			(xy 367.976443 -232.50047) (xy 367.947067 -232.540903) (xy 367.911727 -232.576243) (xy 367.871294 -232.605619)
			(xy 367.826762 -232.628309) (xy 367.77923 -232.643753) (xy 367.729867 -232.651572) (xy 367.679889 -232.651572)
			(xy 367.630526 -232.643753) (xy 367.582994 -232.628309) (xy 367.538462 -232.605619) (xy 367.498029 -232.576243)
			(xy 367.462689 -232.540903) (xy 367.433313 -232.50047) (xy 367.410623 -232.455938) (xy 367.395179 -232.408406)
			(xy 367.38736 -232.359043) (xy 367.082342 -232.359043) (xy 367.074523 -232.408406) (xy 367.059079 -232.455938)
			(xy 367.036389 -232.50047) (xy 367.007013 -232.540903) (xy 366.971673 -232.576243) (xy 366.93124 -232.605619)
			(xy 366.886708 -232.628309) (xy 366.839176 -232.643753) (xy 366.789813 -232.651572) (xy 366.739835 -232.651572)
			(xy 366.690472 -232.643753) (xy 366.64294 -232.628309) (xy 366.598408 -232.605619) (xy 366.557975 -232.576243)
			(xy 366.522635 -232.540903) (xy 366.493259 -232.50047) (xy 366.470569 -232.455938) (xy 366.455125 -232.408406)
			(xy 366.447306 -232.359043) (xy 366.142288 -232.359043) (xy 366.134469 -232.408406) (xy 366.119025 -232.455938)
			(xy 366.096335 -232.50047) (xy 366.066959 -232.540903) (xy 366.031619 -232.576243) (xy 365.991186 -232.605619)
			(xy 365.946654 -232.628309) (xy 365.899122 -232.643753) (xy 365.849759 -232.651572) (xy 365.799781 -232.651572)
			(xy 365.750418 -232.643753) (xy 365.702886 -232.628309) (xy 365.658354 -232.605619) (xy 365.617921 -232.576243)
			(xy 365.582581 -232.540903) (xy 365.553205 -232.50047) (xy 365.530515 -232.455938) (xy 365.515071 -232.408406)
			(xy 365.507252 -232.359043) (xy 365.202234 -232.359043) (xy 365.194415 -232.408406) (xy 365.178971 -232.455938)
			(xy 365.156281 -232.50047) (xy 365.126905 -232.540903) (xy 365.091565 -232.576243) (xy 365.051132 -232.605619)
			(xy 365.0066 -232.628309) (xy 364.959068 -232.643753) (xy 364.909705 -232.651572) (xy 364.859727 -232.651572)
			(xy 364.810364 -232.643753) (xy 364.762832 -232.628309) (xy 364.7183 -232.605619) (xy 364.677867 -232.576243)
			(xy 364.642527 -232.540903) (xy 364.613151 -232.50047) (xy 364.590461 -232.455938) (xy 364.575017 -232.408406)
			(xy 364.567198 -232.359043) (xy 364.262434 -232.359043) (xy 364.254615 -232.408406) (xy 364.239171 -232.455938)
			(xy 364.216481 -232.50047) (xy 364.187105 -232.540903) (xy 364.151765 -232.576243) (xy 364.111332 -232.605619)
			(xy 364.0668 -232.628309) (xy 364.019268 -232.643753) (xy 363.969905 -232.651572) (xy 363.919927 -232.651572)
			(xy 363.870564 -232.643753) (xy 363.823032 -232.628309) (xy 363.7785 -232.605619) (xy 363.738067 -232.576243)
			(xy 363.702727 -232.540903) (xy 363.673351 -232.50047) (xy 363.650661 -232.455938) (xy 363.635217 -232.408406)
			(xy 363.627398 -232.359043) (xy 363.320081 -232.359043) (xy 363.320072 -232.3595) (xy 363.311908 -232.409734)
			(xy 363.295792 -232.458008) (xy 363.272141 -232.503071) (xy 363.241568 -232.543757) (xy 363.204864 -232.579012)
			(xy 363.16298 -232.607922) (xy 363.117001 -232.629739) (xy 363.068117 -232.643899) (xy 363.017596 -232.650033)
			(xy 362.966744 -232.647984) (xy 362.91688 -232.637804) (xy 362.869294 -232.619757) (xy 362.82522 -232.594311)
			(xy 362.785798 -232.562124) (xy 362.75205 -232.52403) (xy 362.724849 -232.481016) (xy 362.704901 -232.434196)
			(xy 362.692722 -232.384782) (xy 362.688627 -232.334054) (xy 362.38053 -232.334054) (xy 362.380018 -232.3595)
			(xy 362.371854 -232.409734) (xy 362.355738 -232.458008) (xy 362.332087 -232.503071) (xy 362.301514 -232.543757)
			(xy 362.26481 -232.579012) (xy 362.222926 -232.607922) (xy 362.176947 -232.629739) (xy 362.128063 -232.643899)
			(xy 362.077542 -232.650033) (xy 362.02669 -232.647984) (xy 361.976826 -232.637804) (xy 361.92924 -232.619757)
			(xy 361.885166 -232.594311) (xy 361.845744 -232.562124) (xy 361.811996 -232.52403) (xy 361.784795 -232.481016)
			(xy 361.764847 -232.434196) (xy 361.752668 -232.384782) (xy 361.748573 -232.334054) (xy 361.442762 -232.334054)
			(xy 361.442272 -232.359043) (xy 361.434453 -232.408406) (xy 361.419009 -232.455938) (xy 361.396319 -232.50047)
			(xy 361.366943 -232.540903) (xy 361.331603 -232.576243) (xy 361.29117 -232.605619) (xy 361.246638 -232.628309)
			(xy 361.199106 -232.643753) (xy 361.149743 -232.651572) (xy 361.099765 -232.651572) (xy 361.050402 -232.643753)
			(xy 361.00287 -232.628309) (xy 360.958338 -232.605619) (xy 360.917905 -232.576243) (xy 360.882565 -232.540903)
			(xy 360.853189 -232.50047) (xy 360.830499 -232.455938) (xy 360.815055 -232.408406) (xy 360.807236 -232.359043)
			(xy 358.628714 -232.359043) (xy 358.620895 -232.408406) (xy 358.605451 -232.455938) (xy 358.582761 -232.50047)
			(xy 358.553385 -232.540903) (xy 358.518045 -232.576243) (xy 358.477612 -232.605619) (xy 358.43308 -232.628309)
			(xy 358.385548 -232.643753) (xy 358.336185 -232.651572) (xy 358.286207 -232.651572) (xy 358.236844 -232.643753)
			(xy 358.189312 -232.628309) (xy 358.14478 -232.605619) (xy 358.104347 -232.576243) (xy 358.069007 -232.540903)
			(xy 358.039631 -232.50047) (xy 358.016941 -232.455938) (xy 358.001497 -232.408406) (xy 357.993678 -232.359043)
			(xy 357.686361 -232.359043) (xy 357.686352 -232.3595) (xy 357.678188 -232.409734) (xy 357.662072 -232.458008)
			(xy 357.638421 -232.503071) (xy 357.607848 -232.543757) (xy 357.571144 -232.579012) (xy 357.52926 -232.607922)
			(xy 357.483281 -232.629739) (xy 357.434397 -232.643899) (xy 357.383876 -232.650033) (xy 357.333024 -232.647984)
			(xy 357.28316 -232.637804) (xy 357.235574 -232.619757) (xy 357.1915 -232.594311) (xy 357.152078 -232.562124)
			(xy 357.11833 -232.52403) (xy 357.091129 -232.481016) (xy 357.071181 -232.434196) (xy 357.059002 -232.384782)
			(xy 357.054907 -232.334054) (xy 356.74681 -232.334054) (xy 356.746298 -232.3595) (xy 356.738134 -232.409734)
			(xy 356.722018 -232.458008) (xy 356.698367 -232.503071) (xy 356.667794 -232.543757) (xy 356.63109 -232.579012)
			(xy 356.589206 -232.607922) (xy 356.543227 -232.629739) (xy 356.494343 -232.643899) (xy 356.443822 -232.650033)
			(xy 356.39297 -232.647984) (xy 356.343106 -232.637804) (xy 356.29552 -232.619757) (xy 356.251446 -232.594311)
			(xy 356.212024 -232.562124) (xy 356.178276 -232.52403) (xy 356.151075 -232.481016) (xy 356.131127 -232.434196)
			(xy 356.118948 -232.384782) (xy 356.114853 -232.334054) (xy 355.809042 -232.334054) (xy 355.808552 -232.359043)
			(xy 355.800733 -232.408406) (xy 355.785289 -232.455938) (xy 355.762599 -232.50047) (xy 355.733223 -232.540903)
			(xy 355.697883 -232.576243) (xy 355.65745 -232.605619) (xy 355.612918 -232.628309) (xy 355.565386 -232.643753)
			(xy 355.516023 -232.651572) (xy 355.466045 -232.651572) (xy 355.416682 -232.643753) (xy 355.36915 -232.628309)
			(xy 355.324618 -232.605619) (xy 355.284185 -232.576243) (xy 355.248845 -232.540903) (xy 355.219469 -232.50047)
			(xy 355.196779 -232.455938) (xy 355.181335 -232.408406) (xy 355.173516 -232.359043) (xy 354.868752 -232.359043)
			(xy 354.860933 -232.408406) (xy 354.845489 -232.455938) (xy 354.822799 -232.50047) (xy 354.793423 -232.540903)
			(xy 354.758083 -232.576243) (xy 354.71765 -232.605619) (xy 354.673118 -232.628309) (xy 354.625586 -232.643753)
			(xy 354.576223 -232.651572) (xy 354.526245 -232.651572) (xy 354.476882 -232.643753) (xy 354.42935 -232.628309)
			(xy 354.384818 -232.605619) (xy 354.344385 -232.576243) (xy 354.309045 -232.540903) (xy 354.279669 -232.50047)
			(xy 354.256979 -232.455938) (xy 354.241535 -232.408406) (xy 354.233716 -232.359043) (xy 353.928698 -232.359043)
			(xy 353.920879 -232.408406) (xy 353.905435 -232.455938) (xy 353.882745 -232.50047) (xy 353.853369 -232.540903)
			(xy 353.818029 -232.576243) (xy 353.777596 -232.605619) (xy 353.733064 -232.628309) (xy 353.685532 -232.643753)
			(xy 353.636169 -232.651572) (xy 353.586191 -232.651572) (xy 353.536828 -232.643753) (xy 353.489296 -232.628309)
			(xy 353.444764 -232.605619) (xy 353.404331 -232.576243) (xy 353.368991 -232.540903) (xy 353.339615 -232.50047)
			(xy 353.316925 -232.455938) (xy 353.301481 -232.408406) (xy 353.293662 -232.359043) (xy 352.988644 -232.359043)
			(xy 352.980825 -232.408406) (xy 352.965381 -232.455938) (xy 352.942691 -232.50047) (xy 352.913315 -232.540903)
			(xy 352.877975 -232.576243) (xy 352.837542 -232.605619) (xy 352.79301 -232.628309) (xy 352.745478 -232.643753)
			(xy 352.696115 -232.651572) (xy 352.646137 -232.651572) (xy 352.596774 -232.643753) (xy 352.549242 -232.628309)
			(xy 352.50471 -232.605619) (xy 352.464277 -232.576243) (xy 352.428937 -232.540903) (xy 352.399561 -232.50047)
			(xy 352.376871 -232.455938) (xy 352.361427 -232.408406) (xy 352.353608 -232.359043) (xy 352.04859 -232.359043)
			(xy 352.040771 -232.408406) (xy 352.025327 -232.455938) (xy 352.002637 -232.50047) (xy 351.973261 -232.540903)
			(xy 351.937921 -232.576243) (xy 351.897488 -232.605619) (xy 351.852956 -232.628309) (xy 351.805424 -232.643753)
			(xy 351.756061 -232.651572) (xy 351.706083 -232.651572) (xy 351.65672 -232.643753) (xy 351.609188 -232.628309)
			(xy 351.564656 -232.605619) (xy 351.524223 -232.576243) (xy 351.488883 -232.540903) (xy 351.459507 -232.50047)
			(xy 351.436817 -232.455938) (xy 351.421373 -232.408406) (xy 351.413554 -232.359043) (xy 351.108536 -232.359043)
			(xy 351.100717 -232.408406) (xy 351.085273 -232.455938) (xy 351.062583 -232.50047) (xy 351.033207 -232.540903)
			(xy 350.997867 -232.576243) (xy 350.957434 -232.605619) (xy 350.912902 -232.628309) (xy 350.86537 -232.643753)
			(xy 350.816007 -232.651572) (xy 350.766029 -232.651572) (xy 350.716666 -232.643753) (xy 350.669134 -232.628309)
			(xy 350.624602 -232.605619) (xy 350.584169 -232.576243) (xy 350.548829 -232.540903) (xy 350.519453 -232.50047)
			(xy 350.496763 -232.455938) (xy 350.481319 -232.408406) (xy 350.4735 -232.359043) (xy 350.168736 -232.359043)
			(xy 350.160917 -232.408406) (xy 350.145473 -232.455938) (xy 350.122783 -232.50047) (xy 350.093407 -232.540903)
			(xy 350.058067 -232.576243) (xy 350.017634 -232.605619) (xy 349.973102 -232.628309) (xy 349.92557 -232.643753)
			(xy 349.876207 -232.651572) (xy 349.826229 -232.651572) (xy 349.776866 -232.643753) (xy 349.729334 -232.628309)
			(xy 349.684802 -232.605619) (xy 349.644369 -232.576243) (xy 349.609029 -232.540903) (xy 349.579653 -232.50047)
			(xy 349.556963 -232.455938) (xy 349.541519 -232.408406) (xy 349.5337 -232.359043) (xy 349.228682 -232.359043)
			(xy 349.220863 -232.408406) (xy 349.205419 -232.455938) (xy 349.182729 -232.50047) (xy 349.153353 -232.540903)
			(xy 349.118013 -232.576243) (xy 349.07758 -232.605619) (xy 349.033048 -232.628309) (xy 348.985516 -232.643753)
			(xy 348.936153 -232.651572) (xy 348.886175 -232.651572) (xy 348.836812 -232.643753) (xy 348.78928 -232.628309)
			(xy 348.744748 -232.605619) (xy 348.704315 -232.576243) (xy 348.668975 -232.540903) (xy 348.639599 -232.50047)
			(xy 348.616909 -232.455938) (xy 348.601465 -232.408406) (xy 348.593646 -232.359043) (xy 348.288628 -232.359043)
			(xy 348.280809 -232.408406) (xy 348.265365 -232.455938) (xy 348.242675 -232.50047) (xy 348.213299 -232.540903)
			(xy 348.177959 -232.576243) (xy 348.137526 -232.605619) (xy 348.092994 -232.628309) (xy 348.045462 -232.643753)
			(xy 347.996099 -232.651572) (xy 347.946121 -232.651572) (xy 347.896758 -232.643753) (xy 347.849226 -232.628309)
			(xy 347.804694 -232.605619) (xy 347.764261 -232.576243) (xy 347.728921 -232.540903) (xy 347.699545 -232.50047)
			(xy 347.676855 -232.455938) (xy 347.661411 -232.408406) (xy 347.653592 -232.359043) (xy 347.348574 -232.359043)
			(xy 347.340755 -232.408406) (xy 347.325311 -232.455938) (xy 347.302621 -232.50047) (xy 347.273245 -232.540903)
			(xy 347.237905 -232.576243) (xy 347.197472 -232.605619) (xy 347.15294 -232.628309) (xy 347.105408 -232.643753)
			(xy 347.056045 -232.651572) (xy 347.006067 -232.651572) (xy 346.956704 -232.643753) (xy 346.909172 -232.628309)
			(xy 346.86464 -232.605619) (xy 346.824207 -232.576243) (xy 346.788867 -232.540903) (xy 346.759491 -232.50047)
			(xy 346.736801 -232.455938) (xy 346.721357 -232.408406) (xy 346.713538 -232.359043) (xy 346.40852 -232.359043)
			(xy 346.400701 -232.408406) (xy 346.385257 -232.455938) (xy 346.362567 -232.50047) (xy 346.333191 -232.540903)
			(xy 346.297851 -232.576243) (xy 346.257418 -232.605619) (xy 346.212886 -232.628309) (xy 346.165354 -232.643753)
			(xy 346.115991 -232.651572) (xy 346.066013 -232.651572) (xy 346.01665 -232.643753) (xy 345.969118 -232.628309)
			(xy 345.924586 -232.605619) (xy 345.884153 -232.576243) (xy 345.848813 -232.540903) (xy 345.819437 -232.50047)
			(xy 345.796747 -232.455938) (xy 345.781303 -232.408406) (xy 345.773484 -232.359043) (xy 345.468764 -232.359043)
			(xy 345.468764 -232.359093) (xy 345.460944 -232.408463) (xy 345.445498 -232.456002) (xy 345.422805 -232.500539)
			(xy 345.393424 -232.540978) (xy 345.35808 -232.576323) (xy 345.317641 -232.605704) (xy 345.273103 -232.628397)
			(xy 345.225565 -232.643844) (xy 345.176195 -232.651663) (xy 345.151202 -232.652062) (xy 345.141014 -232.651997)
			(xy 345.120678 -232.650727) (xy 345.110562 -232.649522) (xy 345.09964 -232.648252) (xy 345.089988 -232.651046)
			(xy 345.084904 -232.652757) (xy 345.075555 -232.658012) (xy 345.071446 -232.66146) (xy 345.051888 -232.678478)
			(xy 345.01201 -232.71353) (xy 345.005454 -232.720778) (xy 344.997995 -232.73882) (xy 344.997532 -232.748582)
			(xy 344.997532 -233.110024) (xy 344.997786 -233.114596) (xy 344.999056 -233.143806) (xy 344.999056 -233.14406)
			(xy 345.304867 -233.14406) (xy 345.308962 -233.093332) (xy 345.321141 -233.043918) (xy 345.341089 -232.997098)
			(xy 345.36829 -232.954084) (xy 345.402038 -232.91599) (xy 345.44146 -232.883803) (xy 345.485534 -232.858357)
			(xy 345.53312 -232.84031) (xy 345.582984 -232.83013) (xy 345.633836 -232.828081) (xy 345.684357 -232.834215)
			(xy 345.733241 -232.848375) (xy 345.77922 -232.870192) (xy 345.821104 -232.899102) (xy 345.857808 -232.934357)
			(xy 345.888381 -232.975043) (xy 345.912032 -233.020106) (xy 345.928148 -233.06838) (xy 345.936312 -233.118614)
			(xy 345.936824 -233.14406) (xy 346.244921 -233.14406) (xy 346.249016 -233.093332) (xy 346.261195 -233.043918)
			(xy 346.281143 -232.997098) (xy 346.308344 -232.954084) (xy 346.342092 -232.91599) (xy 346.381514 -232.883803)
			(xy 346.425588 -232.858357) (xy 346.473174 -232.84031) (xy 346.523038 -232.83013) (xy 346.57389 -232.828081)
			(xy 346.624411 -232.834215) (xy 346.673295 -232.848375) (xy 346.719274 -232.870192) (xy 346.761158 -232.899102)
			(xy 346.797862 -232.934357) (xy 346.828435 -232.975043) (xy 346.852086 -233.020106) (xy 346.868202 -233.06838)
			(xy 346.876366 -233.118614) (xy 346.876878 -233.14406) (xy 346.876375 -233.169049) (xy 347.183692 -233.169049)
			(xy 347.183692 -233.119071) (xy 347.191511 -233.069708) (xy 347.206955 -233.022176) (xy 347.229645 -232.977644)
			(xy 347.259021 -232.937211) (xy 347.294361 -232.901871) (xy 347.334794 -232.872495) (xy 347.379326 -232.849805)
			(xy 347.426858 -232.834361) (xy 347.476221 -232.826542) (xy 347.526199 -232.826542) (xy 347.575562 -232.834361)
			(xy 347.623094 -232.849805) (xy 347.667626 -232.872495) (xy 347.708059 -232.901871) (xy 347.743399 -232.937211)
			(xy 347.772775 -232.977644) (xy 347.795465 -233.022176) (xy 347.810909 -233.069708) (xy 347.818728 -233.119071)
			(xy 347.819218 -233.14406) (xy 348.124775 -233.14406) (xy 348.12887 -233.093332) (xy 348.141049 -233.043918)
			(xy 348.160997 -232.997098) (xy 348.188198 -232.954084) (xy 348.221946 -232.91599) (xy 348.261368 -232.883803)
			(xy 348.305442 -232.858357) (xy 348.353028 -232.84031) (xy 348.402892 -232.83013) (xy 348.453744 -232.828081)
			(xy 348.504265 -232.834215) (xy 348.553149 -232.848375) (xy 348.599128 -232.870192) (xy 348.641012 -232.899102)
			(xy 348.677716 -232.934357) (xy 348.708289 -232.975043) (xy 348.73194 -233.020106) (xy 348.748056 -233.06838)
			(xy 348.75622 -233.118614) (xy 348.756732 -233.14406) (xy 349.064829 -233.14406) (xy 349.068924 -233.093332)
			(xy 349.081103 -233.043918) (xy 349.101051 -232.997098) (xy 349.128252 -232.954084) (xy 349.162 -232.91599)
			(xy 349.201422 -232.883803) (xy 349.245496 -232.858357) (xy 349.293082 -232.84031) (xy 349.342946 -232.83013)
			(xy 349.393798 -232.828081) (xy 349.444319 -232.834215) (xy 349.493203 -232.848375) (xy 349.539182 -232.870192)
			(xy 349.581066 -232.899102) (xy 349.61777 -232.934357) (xy 349.648343 -232.975043) (xy 349.671994 -233.020106)
			(xy 349.68811 -233.06838) (xy 349.696274 -233.118614) (xy 349.696786 -233.14406) (xy 349.696283 -233.169049)
			(xy 350.0036 -233.169049) (xy 350.0036 -233.119071) (xy 350.011419 -233.069708) (xy 350.026863 -233.022176)
			(xy 350.049553 -232.977644) (xy 350.078929 -232.937211) (xy 350.114269 -232.901871) (xy 350.154702 -232.872495)
			(xy 350.199234 -232.849805) (xy 350.246766 -232.834361) (xy 350.296129 -232.826542) (xy 350.346107 -232.826542)
			(xy 350.39547 -232.834361) (xy 350.443002 -232.849805) (xy 350.487534 -232.872495) (xy 350.527967 -232.901871)
			(xy 350.563307 -232.937211) (xy 350.592683 -232.977644) (xy 350.615373 -233.022176) (xy 350.630817 -233.069708)
			(xy 350.638636 -233.119071) (xy 350.639126 -233.14406) (xy 350.944937 -233.14406) (xy 350.949032 -233.093332)
			(xy 350.961211 -233.043918) (xy 350.981159 -232.997098) (xy 351.00836 -232.954084) (xy 351.042108 -232.91599)
			(xy 351.08153 -232.883803) (xy 351.125604 -232.858357) (xy 351.17319 -232.84031) (xy 351.223054 -232.83013)
			(xy 351.273906 -232.828081) (xy 351.324427 -232.834215) (xy 351.373311 -232.848375) (xy 351.41929 -232.870192)
			(xy 351.461174 -232.899102) (xy 351.497878 -232.934357) (xy 351.528451 -232.975043) (xy 351.552102 -233.020106)
			(xy 351.568218 -233.06838) (xy 351.576382 -233.118614) (xy 351.576894 -233.14406) (xy 351.884991 -233.14406)
			(xy 351.889086 -233.093332) (xy 351.901265 -233.043918) (xy 351.921213 -232.997098) (xy 351.948414 -232.954084)
			(xy 351.982162 -232.91599) (xy 352.021584 -232.883803) (xy 352.065658 -232.858357) (xy 352.113244 -232.84031)
			(xy 352.163108 -232.83013) (xy 352.21396 -232.828081) (xy 352.264481 -232.834215) (xy 352.313365 -232.848375)
			(xy 352.359344 -232.870192) (xy 352.401228 -232.899102) (xy 352.437932 -232.934357) (xy 352.468505 -232.975043)
			(xy 352.492156 -233.020106) (xy 352.508272 -233.06838) (xy 352.516436 -233.118614) (xy 352.516948 -233.14406)
			(xy 352.516445 -233.169049) (xy 352.823508 -233.169049) (xy 352.823508 -233.119071) (xy 352.831327 -233.069708)
			(xy 352.846771 -233.022176) (xy 352.869461 -232.977644) (xy 352.898837 -232.937211) (xy 352.934177 -232.901871)
			(xy 352.97461 -232.872495) (xy 353.019142 -232.849805) (xy 353.066674 -232.834361) (xy 353.116037 -232.826542)
			(xy 353.166015 -232.826542) (xy 353.215378 -232.834361) (xy 353.26291 -232.849805) (xy 353.307442 -232.872495)
			(xy 353.347875 -232.901871) (xy 353.383215 -232.937211) (xy 353.412591 -232.977644) (xy 353.435281 -233.022176)
			(xy 353.450725 -233.069708) (xy 353.458544 -233.119071) (xy 353.459034 -233.14406) (xy 353.764845 -233.14406)
			(xy 353.76894 -233.093332) (xy 353.781119 -233.043918) (xy 353.801067 -232.997098) (xy 353.828268 -232.954084)
			(xy 353.862016 -232.91599) (xy 353.901438 -232.883803) (xy 353.945512 -232.858357) (xy 353.993098 -232.84031)
			(xy 354.042962 -232.83013) (xy 354.093814 -232.828081) (xy 354.144335 -232.834215) (xy 354.193219 -232.848375)
			(xy 354.239198 -232.870192) (xy 354.281082 -232.899102) (xy 354.317786 -232.934357) (xy 354.348359 -232.975043)
			(xy 354.37201 -233.020106) (xy 354.388126 -233.06838) (xy 354.39629 -233.118614) (xy 354.396802 -233.14406)
			(xy 354.704899 -233.14406) (xy 354.708994 -233.093332) (xy 354.721173 -233.043918) (xy 354.741121 -232.997098)
			(xy 354.768322 -232.954084) (xy 354.80207 -232.91599) (xy 354.841492 -232.883803) (xy 354.885566 -232.858357)
			(xy 354.933152 -232.84031) (xy 354.983016 -232.83013) (xy 355.033868 -232.828081) (xy 355.084389 -232.834215)
			(xy 355.133273 -232.848375) (xy 355.179252 -232.870192) (xy 355.221136 -232.899102) (xy 355.25784 -232.934357)
			(xy 355.288413 -232.975043) (xy 355.312064 -233.020106) (xy 355.32818 -233.06838) (xy 355.336344 -233.118614)
			(xy 355.336856 -233.14406) (xy 355.336353 -233.169049) (xy 355.64367 -233.169049) (xy 355.64367 -233.119071)
			(xy 355.651489 -233.069708) (xy 355.666933 -233.022176) (xy 355.689623 -232.977644) (xy 355.718999 -232.937211)
			(xy 355.754339 -232.901871) (xy 355.794772 -232.872495) (xy 355.839304 -232.849805) (xy 355.886836 -232.834361)
			(xy 355.936199 -232.826542) (xy 355.986177 -232.826542) (xy 356.03554 -232.834361) (xy 356.083072 -232.849805)
			(xy 356.127604 -232.872495) (xy 356.168037 -232.901871) (xy 356.203377 -232.937211) (xy 356.232753 -232.977644)
			(xy 356.255443 -233.022176) (xy 356.270887 -233.069708) (xy 356.278706 -233.119071) (xy 356.279196 -233.14406)
			(xy 356.278706 -233.169049) (xy 356.583724 -233.169049) (xy 356.583724 -233.119071) (xy 356.591543 -233.069708)
			(xy 356.606987 -233.022176) (xy 356.629677 -232.977644) (xy 356.659053 -232.937211) (xy 356.694393 -232.901871)
			(xy 356.734826 -232.872495) (xy 356.779358 -232.849805) (xy 356.82689 -232.834361) (xy 356.876253 -232.826542)
			(xy 356.926231 -232.826542) (xy 356.975594 -232.834361) (xy 357.023126 -232.849805) (xy 357.067658 -232.872495)
			(xy 357.108091 -232.901871) (xy 357.143431 -232.937211) (xy 357.172807 -232.977644) (xy 357.195497 -233.022176)
			(xy 357.210941 -233.069708) (xy 357.21876 -233.119071) (xy 357.21925 -233.14406) (xy 357.21876 -233.169049)
			(xy 357.523524 -233.169049) (xy 357.523524 -233.119071) (xy 357.531343 -233.069708) (xy 357.546787 -233.022176)
			(xy 357.569477 -232.977644) (xy 357.598853 -232.937211) (xy 357.634193 -232.901871) (xy 357.674626 -232.872495)
			(xy 357.719158 -232.849805) (xy 357.76669 -232.834361) (xy 357.816053 -232.826542) (xy 357.866031 -232.826542)
			(xy 357.915394 -232.834361) (xy 357.962926 -232.849805) (xy 358.007458 -232.872495) (xy 358.047891 -232.901871)
			(xy 358.083231 -232.937211) (xy 358.112607 -232.977644) (xy 358.135297 -233.022176) (xy 358.150741 -233.069708)
			(xy 358.15856 -233.119071) (xy 358.15905 -233.14406) (xy 358.15856 -233.169049) (xy 361.27739 -233.169049)
			(xy 361.27739 -233.119071) (xy 361.285209 -233.069708) (xy 361.300653 -233.022176) (xy 361.323343 -232.977644)
			(xy 361.352719 -232.937211) (xy 361.388059 -232.901871) (xy 361.428492 -232.872495) (xy 361.473024 -232.849805)
			(xy 361.520556 -232.834361) (xy 361.569919 -232.826542) (xy 361.619897 -232.826542) (xy 361.66926 -232.834361)
			(xy 361.716792 -232.849805) (xy 361.761324 -232.872495) (xy 361.801757 -232.901871) (xy 361.837097 -232.937211)
			(xy 361.866473 -232.977644) (xy 361.889163 -233.022176) (xy 361.904607 -233.069708) (xy 361.912426 -233.119071)
			(xy 361.912916 -233.14406) (xy 361.912426 -233.169049) (xy 362.21719 -233.169049) (xy 362.21719 -233.119071)
			(xy 362.225009 -233.069708) (xy 362.240453 -233.022176) (xy 362.263143 -232.977644) (xy 362.292519 -232.937211)
			(xy 362.327859 -232.901871) (xy 362.368292 -232.872495) (xy 362.412824 -232.849805) (xy 362.460356 -232.834361)
			(xy 362.509719 -232.826542) (xy 362.559697 -232.826542) (xy 362.60906 -232.834361) (xy 362.656592 -232.849805)
			(xy 362.701124 -232.872495) (xy 362.741557 -232.901871) (xy 362.776897 -232.937211) (xy 362.806273 -232.977644)
			(xy 362.828963 -233.022176) (xy 362.844407 -233.069708) (xy 362.852226 -233.119071) (xy 362.852716 -233.14406)
			(xy 362.852226 -233.169049) (xy 363.157244 -233.169049) (xy 363.157244 -233.119071) (xy 363.165063 -233.069708)
			(xy 363.180507 -233.022176) (xy 363.203197 -232.977644) (xy 363.232573 -232.937211) (xy 363.267913 -232.901871)
			(xy 363.308346 -232.872495) (xy 363.352878 -232.849805) (xy 363.40041 -232.834361) (xy 363.449773 -232.826542)
			(xy 363.499751 -232.826542) (xy 363.549114 -232.834361) (xy 363.596646 -232.849805) (xy 363.641178 -232.872495)
			(xy 363.681611 -232.901871) (xy 363.716951 -232.937211) (xy 363.746327 -232.977644) (xy 363.769017 -233.022176)
			(xy 363.784461 -233.069708) (xy 363.79228 -233.119071) (xy 363.79277 -233.14406) (xy 364.098581 -233.14406)
			(xy 364.102676 -233.093332) (xy 364.114855 -233.043918) (xy 364.134803 -232.997098) (xy 364.162004 -232.954084)
			(xy 364.195752 -232.91599) (xy 364.235174 -232.883803) (xy 364.279248 -232.858357) (xy 364.326834 -232.84031)
			(xy 364.376698 -232.83013) (xy 364.42755 -232.828081) (xy 364.478071 -232.834215) (xy 364.526955 -232.848375)
			(xy 364.572934 -232.870192) (xy 364.614818 -232.899102) (xy 364.651522 -232.934357) (xy 364.682095 -232.975043)
			(xy 364.705746 -233.020106) (xy 364.721862 -233.06838) (xy 364.730026 -233.118614) (xy 364.730538 -233.14406)
			(xy 365.038635 -233.14406) (xy 365.04273 -233.093332) (xy 365.054909 -233.043918) (xy 365.074857 -232.997098)
			(xy 365.102058 -232.954084) (xy 365.135806 -232.91599) (xy 365.175228 -232.883803) (xy 365.219302 -232.858357)
			(xy 365.266888 -232.84031) (xy 365.316752 -232.83013) (xy 365.367604 -232.828081) (xy 365.418125 -232.834215)
			(xy 365.467009 -232.848375) (xy 365.512988 -232.870192) (xy 365.554872 -232.899102) (xy 365.591576 -232.934357)
			(xy 365.622149 -232.975043) (xy 365.6458 -233.020106) (xy 365.661916 -233.06838) (xy 365.67008 -233.118614)
			(xy 365.670592 -233.14406) (xy 365.670089 -233.169049) (xy 365.977406 -233.169049) (xy 365.977406 -233.119071)
			(xy 365.985225 -233.069708) (xy 366.000669 -233.022176) (xy 366.023359 -232.977644) (xy 366.052735 -232.937211)
			(xy 366.088075 -232.901871) (xy 366.128508 -232.872495) (xy 366.17304 -232.849805) (xy 366.220572 -232.834361)
			(xy 366.269935 -232.826542) (xy 366.319913 -232.826542) (xy 366.369276 -232.834361) (xy 366.416808 -232.849805)
			(xy 366.46134 -232.872495) (xy 366.501773 -232.901871) (xy 366.537113 -232.937211) (xy 366.566489 -232.977644)
			(xy 366.589179 -233.022176) (xy 366.604623 -233.069708) (xy 366.612442 -233.119071) (xy 366.612932 -233.14406)
			(xy 366.918489 -233.14406) (xy 366.922584 -233.093332) (xy 366.934763 -233.043918) (xy 366.954711 -232.997098)
			(xy 366.981912 -232.954084) (xy 367.01566 -232.91599) (xy 367.055082 -232.883803) (xy 367.099156 -232.858357)
			(xy 367.146742 -232.84031) (xy 367.196606 -232.83013) (xy 367.247458 -232.828081) (xy 367.297979 -232.834215)
			(xy 367.346863 -232.848375) (xy 367.392842 -232.870192) (xy 367.434726 -232.899102) (xy 367.47143 -232.934357)
			(xy 367.502003 -232.975043) (xy 367.525654 -233.020106) (xy 367.54177 -233.06838) (xy 367.549934 -233.118614)
			(xy 367.550446 -233.14406) (xy 367.858543 -233.14406) (xy 367.862638 -233.093332) (xy 367.874817 -233.043918)
			(xy 367.894765 -232.997098) (xy 367.921966 -232.954084) (xy 367.955714 -232.91599) (xy 367.995136 -232.883803)
			(xy 368.03921 -232.858357) (xy 368.086796 -232.84031) (xy 368.13666 -232.83013) (xy 368.187512 -232.828081)
			(xy 368.238033 -232.834215) (xy 368.286917 -232.848375) (xy 368.332896 -232.870192) (xy 368.37478 -232.899102)
			(xy 368.411484 -232.934357) (xy 368.442057 -232.975043) (xy 368.465708 -233.020106) (xy 368.481824 -233.06838)
			(xy 368.489988 -233.118614) (xy 368.4905 -233.14406) (xy 368.489997 -233.169049) (xy 368.797314 -233.169049)
			(xy 368.797314 -233.119071) (xy 368.805133 -233.069708) (xy 368.820577 -233.022176) (xy 368.843267 -232.977644)
			(xy 368.872643 -232.937211) (xy 368.907983 -232.901871) (xy 368.948416 -232.872495) (xy 368.992948 -232.849805)
			(xy 369.04048 -232.834361) (xy 369.089843 -232.826542) (xy 369.139821 -232.826542) (xy 369.189184 -232.834361)
			(xy 369.236716 -232.849805) (xy 369.281248 -232.872495) (xy 369.321681 -232.901871) (xy 369.357021 -232.937211)
			(xy 369.386397 -232.977644) (xy 369.409087 -233.022176) (xy 369.424531 -233.069708) (xy 369.43235 -233.119071)
			(xy 369.43284 -233.14406) (xy 369.738651 -233.14406) (xy 369.742746 -233.093332) (xy 369.754925 -233.043918)
			(xy 369.774873 -232.997098) (xy 369.802074 -232.954084) (xy 369.835822 -232.91599) (xy 369.875244 -232.883803)
			(xy 369.919318 -232.858357) (xy 369.966904 -232.84031) (xy 370.016768 -232.83013) (xy 370.06762 -232.828081)
			(xy 370.118141 -232.834215) (xy 370.167025 -232.848375) (xy 370.213004 -232.870192) (xy 370.254888 -232.899102)
			(xy 370.291592 -232.934357) (xy 370.322165 -232.975043) (xy 370.345816 -233.020106) (xy 370.361932 -233.06838)
			(xy 370.370096 -233.118614) (xy 370.370608 -233.14406) (xy 370.678451 -233.14406) (xy 370.682546 -233.093332)
			(xy 370.694725 -233.043918) (xy 370.714673 -232.997098) (xy 370.741874 -232.954084) (xy 370.775622 -232.91599)
			(xy 370.815044 -232.883803) (xy 370.859118 -232.858357) (xy 370.906704 -232.84031) (xy 370.956568 -232.83013)
			(xy 371.00742 -232.828081) (xy 371.057941 -232.834215) (xy 371.106825 -232.848375) (xy 371.152804 -232.870192)
			(xy 371.194688 -232.899102) (xy 371.231392 -232.934357) (xy 371.261965 -232.975043) (xy 371.285616 -233.020106)
			(xy 371.301732 -233.06838) (xy 371.309896 -233.118614) (xy 371.310408 -233.14406) (xy 371.309905 -233.169049)
			(xy 371.617222 -233.169049) (xy 371.617222 -233.119071) (xy 371.625041 -233.069708) (xy 371.640485 -233.022176)
			(xy 371.663175 -232.977644) (xy 371.692551 -232.937211) (xy 371.727891 -232.901871) (xy 371.768324 -232.872495)
			(xy 371.812856 -232.849805) (xy 371.860388 -232.834361) (xy 371.909751 -232.826542) (xy 371.959729 -232.826542)
			(xy 372.009092 -232.834361) (xy 372.056624 -232.849805) (xy 372.101156 -232.872495) (xy 372.141589 -232.901871)
			(xy 372.176929 -232.937211) (xy 372.206305 -232.977644) (xy 372.228995 -233.022176) (xy 372.244439 -233.069708)
			(xy 372.252258 -233.119071) (xy 372.252748 -233.14406) (xy 372.558559 -233.14406) (xy 372.562654 -233.093332)
			(xy 372.574833 -233.043918) (xy 372.594781 -232.997098) (xy 372.621982 -232.954084) (xy 372.65573 -232.91599)
			(xy 372.695152 -232.883803) (xy 372.739226 -232.858357) (xy 372.786812 -232.84031) (xy 372.836676 -232.83013)
			(xy 372.887528 -232.828081) (xy 372.938049 -232.834215) (xy 372.986933 -232.848375) (xy 373.032912 -232.870192)
			(xy 373.074796 -232.899102) (xy 373.1115 -232.934357) (xy 373.142073 -232.975043) (xy 373.165724 -233.020106)
			(xy 373.18184 -233.06838) (xy 373.190004 -233.118614) (xy 373.190516 -233.14406) (xy 373.498613 -233.14406)
			(xy 373.502708 -233.093332) (xy 373.514887 -233.043918) (xy 373.534835 -232.997098) (xy 373.562036 -232.954084)
			(xy 373.595784 -232.91599) (xy 373.635206 -232.883803) (xy 373.67928 -232.858357) (xy 373.726866 -232.84031)
			(xy 373.77673 -232.83013) (xy 373.827582 -232.828081) (xy 373.878103 -232.834215) (xy 373.926987 -232.848375)
			(xy 373.972966 -232.870192) (xy 374.01485 -232.899102) (xy 374.051554 -232.934357) (xy 374.082127 -232.975043)
			(xy 374.105778 -233.020106) (xy 374.121894 -233.06838) (xy 374.130058 -233.118614) (xy 374.13057 -233.14406)
			(xy 374.130058 -233.169506) (xy 374.121894 -233.21974) (xy 374.105778 -233.268014) (xy 374.082127 -233.313077)
			(xy 374.051554 -233.353763) (xy 374.01485 -233.389018) (xy 373.972966 -233.417928) (xy 373.926987 -233.439745)
			(xy 373.878103 -233.453905) (xy 373.827582 -233.460039) (xy 373.77673 -233.45799) (xy 373.726866 -233.44781)
			(xy 373.67928 -233.429763) (xy 373.635206 -233.404317) (xy 373.595784 -233.37213) (xy 373.562036 -233.334036)
			(xy 373.534835 -233.291022) (xy 373.514887 -233.244202) (xy 373.502708 -233.194788) (xy 373.498613 -233.14406)
			(xy 373.190516 -233.14406) (xy 373.190004 -233.169506) (xy 373.18184 -233.21974) (xy 373.165724 -233.268014)
			(xy 373.142073 -233.313077) (xy 373.1115 -233.353763) (xy 373.074796 -233.389018) (xy 373.032912 -233.417928)
			(xy 372.986933 -233.439745) (xy 372.938049 -233.453905) (xy 372.887528 -233.460039) (xy 372.836676 -233.45799)
			(xy 372.786812 -233.44781) (xy 372.739226 -233.429763) (xy 372.695152 -233.404317) (xy 372.65573 -233.37213)
			(xy 372.621982 -233.334036) (xy 372.594781 -233.291022) (xy 372.574833 -233.244202) (xy 372.562654 -233.194788)
			(xy 372.558559 -233.14406) (xy 372.252748 -233.14406) (xy 372.252258 -233.169049) (xy 372.244439 -233.218412)
			(xy 372.228995 -233.265944) (xy 372.206305 -233.310476) (xy 372.176929 -233.350909) (xy 372.141589 -233.386249)
			(xy 372.101156 -233.415625) (xy 372.056624 -233.438315) (xy 372.009092 -233.453759) (xy 371.959729 -233.461578)
			(xy 371.909751 -233.461578) (xy 371.860388 -233.453759) (xy 371.812856 -233.438315) (xy 371.768324 -233.415625)
			(xy 371.727891 -233.386249) (xy 371.692551 -233.350909) (xy 371.663175 -233.310476) (xy 371.640485 -233.265944)
			(xy 371.625041 -233.218412) (xy 371.617222 -233.169049) (xy 371.309905 -233.169049) (xy 371.309896 -233.169506)
			(xy 371.301732 -233.21974) (xy 371.285616 -233.268014) (xy 371.261965 -233.313077) (xy 371.231392 -233.353763)
			(xy 371.194688 -233.389018) (xy 371.152804 -233.417928) (xy 371.106825 -233.439745) (xy 371.057941 -233.453905)
			(xy 371.00742 -233.460039) (xy 370.956568 -233.45799) (xy 370.906704 -233.44781) (xy 370.859118 -233.429763)
			(xy 370.815044 -233.404317) (xy 370.775622 -233.37213) (xy 370.741874 -233.334036) (xy 370.714673 -233.291022)
			(xy 370.694725 -233.244202) (xy 370.682546 -233.194788) (xy 370.678451 -233.14406) (xy 370.370608 -233.14406)
			(xy 370.370096 -233.169506) (xy 370.361932 -233.21974) (xy 370.345816 -233.268014) (xy 370.322165 -233.313077)
			(xy 370.291592 -233.353763) (xy 370.254888 -233.389018) (xy 370.213004 -233.417928) (xy 370.167025 -233.439745)
			(xy 370.118141 -233.453905) (xy 370.06762 -233.460039) (xy 370.016768 -233.45799) (xy 369.966904 -233.44781)
			(xy 369.919318 -233.429763) (xy 369.875244 -233.404317) (xy 369.835822 -233.37213) (xy 369.802074 -233.334036)
			(xy 369.774873 -233.291022) (xy 369.754925 -233.244202) (xy 369.742746 -233.194788) (xy 369.738651 -233.14406)
			(xy 369.43284 -233.14406) (xy 369.43235 -233.169049) (xy 369.424531 -233.218412) (xy 369.409087 -233.265944)
			(xy 369.386397 -233.310476) (xy 369.357021 -233.350909) (xy 369.321681 -233.386249) (xy 369.281248 -233.415625)
			(xy 369.236716 -233.438315) (xy 369.189184 -233.453759) (xy 369.139821 -233.461578) (xy 369.089843 -233.461578)
			(xy 369.04048 -233.453759) (xy 368.992948 -233.438315) (xy 368.948416 -233.415625) (xy 368.907983 -233.386249)
			(xy 368.872643 -233.350909) (xy 368.843267 -233.310476) (xy 368.820577 -233.265944) (xy 368.805133 -233.218412)
			(xy 368.797314 -233.169049) (xy 368.489997 -233.169049) (xy 368.489988 -233.169506) (xy 368.481824 -233.21974)
			(xy 368.465708 -233.268014) (xy 368.442057 -233.313077) (xy 368.411484 -233.353763) (xy 368.37478 -233.389018)
			(xy 368.332896 -233.417928) (xy 368.286917 -233.439745) (xy 368.238033 -233.453905) (xy 368.187512 -233.460039)
			(xy 368.13666 -233.45799) (xy 368.086796 -233.44781) (xy 368.03921 -233.429763) (xy 367.995136 -233.404317)
			(xy 367.955714 -233.37213) (xy 367.921966 -233.334036) (xy 367.894765 -233.291022) (xy 367.874817 -233.244202)
			(xy 367.862638 -233.194788) (xy 367.858543 -233.14406) (xy 367.550446 -233.14406) (xy 367.549934 -233.169506)
			(xy 367.54177 -233.21974) (xy 367.525654 -233.268014) (xy 367.502003 -233.313077) (xy 367.47143 -233.353763)
			(xy 367.434726 -233.389018) (xy 367.392842 -233.417928) (xy 367.346863 -233.439745) (xy 367.297979 -233.453905)
			(xy 367.247458 -233.460039) (xy 367.196606 -233.45799) (xy 367.146742 -233.44781) (xy 367.099156 -233.429763)
			(xy 367.055082 -233.404317) (xy 367.01566 -233.37213) (xy 366.981912 -233.334036) (xy 366.954711 -233.291022)
			(xy 366.934763 -233.244202) (xy 366.922584 -233.194788) (xy 366.918489 -233.14406) (xy 366.612932 -233.14406)
			(xy 366.612442 -233.169049) (xy 366.604623 -233.218412) (xy 366.589179 -233.265944) (xy 366.566489 -233.310476)
			(xy 366.537113 -233.350909) (xy 366.501773 -233.386249) (xy 366.46134 -233.415625) (xy 366.416808 -233.438315)
			(xy 366.369276 -233.453759) (xy 366.319913 -233.461578) (xy 366.269935 -233.461578) (xy 366.220572 -233.453759)
			(xy 366.17304 -233.438315) (xy 366.128508 -233.415625) (xy 366.088075 -233.386249) (xy 366.052735 -233.350909)
			(xy 366.023359 -233.310476) (xy 366.000669 -233.265944) (xy 365.985225 -233.218412) (xy 365.977406 -233.169049)
			(xy 365.670089 -233.169049) (xy 365.67008 -233.169506) (xy 365.661916 -233.21974) (xy 365.6458 -233.268014)
			(xy 365.622149 -233.313077) (xy 365.591576 -233.353763) (xy 365.554872 -233.389018) (xy 365.512988 -233.417928)
			(xy 365.467009 -233.439745) (xy 365.418125 -233.453905) (xy 365.367604 -233.460039) (xy 365.316752 -233.45799)
			(xy 365.266888 -233.44781) (xy 365.219302 -233.429763) (xy 365.175228 -233.404317) (xy 365.135806 -233.37213)
			(xy 365.102058 -233.334036) (xy 365.074857 -233.291022) (xy 365.054909 -233.244202) (xy 365.04273 -233.194788)
			(xy 365.038635 -233.14406) (xy 364.730538 -233.14406) (xy 364.730026 -233.169506) (xy 364.721862 -233.21974)
			(xy 364.705746 -233.268014) (xy 364.682095 -233.313077) (xy 364.651522 -233.353763) (xy 364.614818 -233.389018)
			(xy 364.572934 -233.417928) (xy 364.526955 -233.439745) (xy 364.478071 -233.453905) (xy 364.42755 -233.460039)
			(xy 364.376698 -233.45799) (xy 364.326834 -233.44781) (xy 364.279248 -233.429763) (xy 364.235174 -233.404317)
			(xy 364.195752 -233.37213) (xy 364.162004 -233.334036) (xy 364.134803 -233.291022) (xy 364.114855 -233.244202)
			(xy 364.102676 -233.194788) (xy 364.098581 -233.14406) (xy 363.79277 -233.14406) (xy 363.79228 -233.169049)
			(xy 363.784461 -233.218412) (xy 363.769017 -233.265944) (xy 363.746327 -233.310476) (xy 363.716951 -233.350909)
			(xy 363.681611 -233.386249) (xy 363.641178 -233.415625) (xy 363.596646 -233.438315) (xy 363.549114 -233.453759)
			(xy 363.499751 -233.461578) (xy 363.449773 -233.461578) (xy 363.40041 -233.453759) (xy 363.352878 -233.438315)
			(xy 363.308346 -233.415625) (xy 363.267913 -233.386249) (xy 363.232573 -233.350909) (xy 363.203197 -233.310476)
			(xy 363.180507 -233.265944) (xy 363.165063 -233.218412) (xy 363.157244 -233.169049) (xy 362.852226 -233.169049)
			(xy 362.844407 -233.218412) (xy 362.828963 -233.265944) (xy 362.806273 -233.310476) (xy 362.776897 -233.350909)
			(xy 362.741557 -233.386249) (xy 362.701124 -233.415625) (xy 362.656592 -233.438315) (xy 362.60906 -233.453759)
			(xy 362.559697 -233.461578) (xy 362.509719 -233.461578) (xy 362.460356 -233.453759) (xy 362.412824 -233.438315)
			(xy 362.368292 -233.415625) (xy 362.327859 -233.386249) (xy 362.292519 -233.350909) (xy 362.263143 -233.310476)
			(xy 362.240453 -233.265944) (xy 362.225009 -233.218412) (xy 362.21719 -233.169049) (xy 361.912426 -233.169049)
			(xy 361.904607 -233.218412) (xy 361.889163 -233.265944) (xy 361.866473 -233.310476) (xy 361.837097 -233.350909)
			(xy 361.801757 -233.386249) (xy 361.761324 -233.415625) (xy 361.716792 -233.438315) (xy 361.66926 -233.453759)
			(xy 361.619897 -233.461578) (xy 361.569919 -233.461578) (xy 361.520556 -233.453759) (xy 361.473024 -233.438315)
			(xy 361.428492 -233.415625) (xy 361.388059 -233.386249) (xy 361.352719 -233.350909) (xy 361.323343 -233.310476)
			(xy 361.300653 -233.265944) (xy 361.285209 -233.218412) (xy 361.27739 -233.169049) (xy 358.15856 -233.169049)
			(xy 358.150741 -233.218412) (xy 358.135297 -233.265944) (xy 358.112607 -233.310476) (xy 358.083231 -233.350909)
			(xy 358.047891 -233.386249) (xy 358.007458 -233.415625) (xy 357.962926 -233.438315) (xy 357.915394 -233.453759)
			(xy 357.866031 -233.461578) (xy 357.816053 -233.461578) (xy 357.76669 -233.453759) (xy 357.719158 -233.438315)
			(xy 357.674626 -233.415625) (xy 357.634193 -233.386249) (xy 357.598853 -233.350909) (xy 357.569477 -233.310476)
			(xy 357.546787 -233.265944) (xy 357.531343 -233.218412) (xy 357.523524 -233.169049) (xy 357.21876 -233.169049)
			(xy 357.210941 -233.218412) (xy 357.195497 -233.265944) (xy 357.172807 -233.310476) (xy 357.143431 -233.350909)
			(xy 357.108091 -233.386249) (xy 357.067658 -233.415625) (xy 357.023126 -233.438315) (xy 356.975594 -233.453759)
			(xy 356.926231 -233.461578) (xy 356.876253 -233.461578) (xy 356.82689 -233.453759) (xy 356.779358 -233.438315)
			(xy 356.734826 -233.415625) (xy 356.694393 -233.386249) (xy 356.659053 -233.350909) (xy 356.629677 -233.310476)
			(xy 356.606987 -233.265944) (xy 356.591543 -233.218412) (xy 356.583724 -233.169049) (xy 356.278706 -233.169049)
			(xy 356.270887 -233.218412) (xy 356.255443 -233.265944) (xy 356.232753 -233.310476) (xy 356.203377 -233.350909)
			(xy 356.168037 -233.386249) (xy 356.127604 -233.415625) (xy 356.083072 -233.438315) (xy 356.03554 -233.453759)
			(xy 355.986177 -233.461578) (xy 355.936199 -233.461578) (xy 355.886836 -233.453759) (xy 355.839304 -233.438315)
			(xy 355.794772 -233.415625) (xy 355.754339 -233.386249) (xy 355.718999 -233.350909) (xy 355.689623 -233.310476)
			(xy 355.666933 -233.265944) (xy 355.651489 -233.218412) (xy 355.64367 -233.169049) (xy 355.336353 -233.169049)
			(xy 355.336344 -233.169506) (xy 355.32818 -233.21974) (xy 355.312064 -233.268014) (xy 355.288413 -233.313077)
			(xy 355.25784 -233.353763) (xy 355.221136 -233.389018) (xy 355.179252 -233.417928) (xy 355.133273 -233.439745)
			(xy 355.084389 -233.453905) (xy 355.033868 -233.460039) (xy 354.983016 -233.45799) (xy 354.933152 -233.44781)
			(xy 354.885566 -233.429763) (xy 354.841492 -233.404317) (xy 354.80207 -233.37213) (xy 354.768322 -233.334036)
			(xy 354.741121 -233.291022) (xy 354.721173 -233.244202) (xy 354.708994 -233.194788) (xy 354.704899 -233.14406)
			(xy 354.396802 -233.14406) (xy 354.39629 -233.169506) (xy 354.388126 -233.21974) (xy 354.37201 -233.268014)
			(xy 354.348359 -233.313077) (xy 354.317786 -233.353763) (xy 354.281082 -233.389018) (xy 354.239198 -233.417928)
			(xy 354.193219 -233.439745) (xy 354.144335 -233.453905) (xy 354.093814 -233.460039) (xy 354.042962 -233.45799)
			(xy 353.993098 -233.44781) (xy 353.945512 -233.429763) (xy 353.901438 -233.404317) (xy 353.862016 -233.37213)
			(xy 353.828268 -233.334036) (xy 353.801067 -233.291022) (xy 353.781119 -233.244202) (xy 353.76894 -233.194788)
			(xy 353.764845 -233.14406) (xy 353.459034 -233.14406) (xy 353.458544 -233.169049) (xy 353.450725 -233.218412)
			(xy 353.435281 -233.265944) (xy 353.412591 -233.310476) (xy 353.383215 -233.350909) (xy 353.347875 -233.386249)
			(xy 353.307442 -233.415625) (xy 353.26291 -233.438315) (xy 353.215378 -233.453759) (xy 353.166015 -233.461578)
			(xy 353.116037 -233.461578) (xy 353.066674 -233.453759) (xy 353.019142 -233.438315) (xy 352.97461 -233.415625)
			(xy 352.934177 -233.386249) (xy 352.898837 -233.350909) (xy 352.869461 -233.310476) (xy 352.846771 -233.265944)
			(xy 352.831327 -233.218412) (xy 352.823508 -233.169049) (xy 352.516445 -233.169049) (xy 352.516436 -233.169506)
			(xy 352.508272 -233.21974) (xy 352.492156 -233.268014) (xy 352.468505 -233.313077) (xy 352.437932 -233.353763)
			(xy 352.401228 -233.389018) (xy 352.359344 -233.417928) (xy 352.313365 -233.439745) (xy 352.264481 -233.453905)
			(xy 352.21396 -233.460039) (xy 352.163108 -233.45799) (xy 352.113244 -233.44781) (xy 352.065658 -233.429763)
			(xy 352.021584 -233.404317) (xy 351.982162 -233.37213) (xy 351.948414 -233.334036) (xy 351.921213 -233.291022)
			(xy 351.901265 -233.244202) (xy 351.889086 -233.194788) (xy 351.884991 -233.14406) (xy 351.576894 -233.14406)
			(xy 351.576382 -233.169506) (xy 351.568218 -233.21974) (xy 351.552102 -233.268014) (xy 351.528451 -233.313077)
			(xy 351.497878 -233.353763) (xy 351.461174 -233.389018) (xy 351.41929 -233.417928) (xy 351.373311 -233.439745)
			(xy 351.324427 -233.453905) (xy 351.273906 -233.460039) (xy 351.223054 -233.45799) (xy 351.17319 -233.44781)
			(xy 351.125604 -233.429763) (xy 351.08153 -233.404317) (xy 351.042108 -233.37213) (xy 351.00836 -233.334036)
			(xy 350.981159 -233.291022) (xy 350.961211 -233.244202) (xy 350.949032 -233.194788) (xy 350.944937 -233.14406)
			(xy 350.639126 -233.14406) (xy 350.638636 -233.169049) (xy 350.630817 -233.218412) (xy 350.615373 -233.265944)
			(xy 350.592683 -233.310476) (xy 350.563307 -233.350909) (xy 350.527967 -233.386249) (xy 350.487534 -233.415625)
			(xy 350.443002 -233.438315) (xy 350.39547 -233.453759) (xy 350.346107 -233.461578) (xy 350.296129 -233.461578)
			(xy 350.246766 -233.453759) (xy 350.199234 -233.438315) (xy 350.154702 -233.415625) (xy 350.114269 -233.386249)
			(xy 350.078929 -233.350909) (xy 350.049553 -233.310476) (xy 350.026863 -233.265944) (xy 350.011419 -233.218412)
			(xy 350.0036 -233.169049) (xy 349.696283 -233.169049) (xy 349.696274 -233.169506) (xy 349.68811 -233.21974)
			(xy 349.671994 -233.268014) (xy 349.648343 -233.313077) (xy 349.61777 -233.353763) (xy 349.581066 -233.389018)
			(xy 349.539182 -233.417928) (xy 349.493203 -233.439745) (xy 349.444319 -233.453905) (xy 349.393798 -233.460039)
			(xy 349.342946 -233.45799) (xy 349.293082 -233.44781) (xy 349.245496 -233.429763) (xy 349.201422 -233.404317)
			(xy 349.162 -233.37213) (xy 349.128252 -233.334036) (xy 349.101051 -233.291022) (xy 349.081103 -233.244202)
			(xy 349.068924 -233.194788) (xy 349.064829 -233.14406) (xy 348.756732 -233.14406) (xy 348.75622 -233.169506)
			(xy 348.748056 -233.21974) (xy 348.73194 -233.268014) (xy 348.708289 -233.313077) (xy 348.677716 -233.353763)
			(xy 348.641012 -233.389018) (xy 348.599128 -233.417928) (xy 348.553149 -233.439745) (xy 348.504265 -233.453905)
			(xy 348.453744 -233.460039) (xy 348.402892 -233.45799) (xy 348.353028 -233.44781) (xy 348.305442 -233.429763)
			(xy 348.261368 -233.404317) (xy 348.221946 -233.37213) (xy 348.188198 -233.334036) (xy 348.160997 -233.291022)
			(xy 348.141049 -233.244202) (xy 348.12887 -233.194788) (xy 348.124775 -233.14406) (xy 347.819218 -233.14406)
			(xy 347.818728 -233.169049) (xy 347.810909 -233.218412) (xy 347.795465 -233.265944) (xy 347.772775 -233.310476)
			(xy 347.743399 -233.350909) (xy 347.708059 -233.386249) (xy 347.667626 -233.415625) (xy 347.623094 -233.438315)
			(xy 347.575562 -233.453759) (xy 347.526199 -233.461578) (xy 347.476221 -233.461578) (xy 347.426858 -233.453759)
			(xy 347.379326 -233.438315) (xy 347.334794 -233.415625) (xy 347.294361 -233.386249) (xy 347.259021 -233.350909)
			(xy 347.229645 -233.310476) (xy 347.206955 -233.265944) (xy 347.191511 -233.218412) (xy 347.183692 -233.169049)
			(xy 346.876375 -233.169049) (xy 346.876366 -233.169506) (xy 346.868202 -233.21974) (xy 346.852086 -233.268014)
			(xy 346.828435 -233.313077) (xy 346.797862 -233.353763) (xy 346.761158 -233.389018) (xy 346.719274 -233.417928)
			(xy 346.673295 -233.439745) (xy 346.624411 -233.453905) (xy 346.57389 -233.460039) (xy 346.523038 -233.45799)
			(xy 346.473174 -233.44781) (xy 346.425588 -233.429763) (xy 346.381514 -233.404317) (xy 346.342092 -233.37213)
			(xy 346.308344 -233.334036) (xy 346.281143 -233.291022) (xy 346.261195 -233.244202) (xy 346.249016 -233.194788)
			(xy 346.244921 -233.14406) (xy 345.936824 -233.14406) (xy 345.936312 -233.169506) (xy 345.928148 -233.21974)
			(xy 345.912032 -233.268014) (xy 345.888381 -233.313077) (xy 345.857808 -233.353763) (xy 345.821104 -233.389018)
			(xy 345.77922 -233.417928) (xy 345.733241 -233.439745) (xy 345.684357 -233.453905) (xy 345.633836 -233.460039)
			(xy 345.582984 -233.45799) (xy 345.53312 -233.44781) (xy 345.485534 -233.429763) (xy 345.44146 -233.404317)
			(xy 345.402038 -233.37213) (xy 345.36829 -233.334036) (xy 345.341089 -233.291022) (xy 345.321141 -233.244202)
			(xy 345.308962 -233.194788) (xy 345.304867 -233.14406) (xy 344.999056 -233.14406) (xy 344.999056 -233.144314)
			(xy 344.997786 -233.173524) (xy 344.997532 -233.178096) (xy 344.997532 -233.979055) (xy 346.713538 -233.979055)
			(xy 346.713538 -233.929077) (xy 346.721357 -233.879714) (xy 346.736801 -233.832182) (xy 346.759491 -233.78765)
			(xy 346.788867 -233.747217) (xy 346.824207 -233.711877) (xy 346.86464 -233.682501) (xy 346.909172 -233.659811)
			(xy 346.956704 -233.644367) (xy 347.006067 -233.636548) (xy 347.056045 -233.636548) (xy 347.105408 -233.644367)
			(xy 347.15294 -233.659811) (xy 347.197472 -233.682501) (xy 347.237905 -233.711877) (xy 347.273245 -233.747217)
			(xy 347.302621 -233.78765) (xy 347.325311 -233.832182) (xy 347.340755 -233.879714) (xy 347.348574 -233.929077)
			(xy 347.349064 -233.954066) (xy 347.348574 -233.979055) (xy 349.5337 -233.979055) (xy 349.5337 -233.929077)
			(xy 349.541519 -233.879714) (xy 349.556963 -233.832182) (xy 349.579653 -233.78765) (xy 349.609029 -233.747217)
			(xy 349.644369 -233.711877) (xy 349.684802 -233.682501) (xy 349.729334 -233.659811) (xy 349.776866 -233.644367)
			(xy 349.826229 -233.636548) (xy 349.876207 -233.636548) (xy 349.92557 -233.644367) (xy 349.973102 -233.659811)
			(xy 350.017634 -233.682501) (xy 350.058067 -233.711877) (xy 350.093407 -233.747217) (xy 350.122783 -233.78765)
			(xy 350.145473 -233.832182) (xy 350.160917 -233.879714) (xy 350.168736 -233.929077) (xy 350.169226 -233.954066)
			(xy 350.168736 -233.979055) (xy 352.353608 -233.979055) (xy 352.353608 -233.929077) (xy 352.361427 -233.879714)
			(xy 352.376871 -233.832182) (xy 352.399561 -233.78765) (xy 352.428937 -233.747217) (xy 352.464277 -233.711877)
			(xy 352.50471 -233.682501) (xy 352.549242 -233.659811) (xy 352.596774 -233.644367) (xy 352.646137 -233.636548)
			(xy 352.696115 -233.636548) (xy 352.745478 -233.644367) (xy 352.79301 -233.659811) (xy 352.837542 -233.682501)
			(xy 352.877975 -233.711877) (xy 352.913315 -233.747217) (xy 352.942691 -233.78765) (xy 352.965381 -233.832182)
			(xy 352.980825 -233.879714) (xy 352.988644 -233.929077) (xy 352.989134 -233.954066) (xy 352.988644 -233.979055)
			(xy 355.173516 -233.979055) (xy 355.173516 -233.929077) (xy 355.181335 -233.879714) (xy 355.196779 -233.832182)
			(xy 355.219469 -233.78765) (xy 355.248845 -233.747217) (xy 355.284185 -233.711877) (xy 355.324618 -233.682501)
			(xy 355.36915 -233.659811) (xy 355.416682 -233.644367) (xy 355.466045 -233.636548) (xy 355.516023 -233.636548)
			(xy 355.565386 -233.644367) (xy 355.612918 -233.659811) (xy 355.65745 -233.682501) (xy 355.697883 -233.711877)
			(xy 355.733223 -233.747217) (xy 355.762599 -233.78765) (xy 355.785289 -233.832182) (xy 355.800733 -233.879714)
			(xy 355.808552 -233.929077) (xy 355.809042 -233.954066) (xy 356.114853 -233.954066) (xy 356.118948 -233.903338)
			(xy 356.131127 -233.853924) (xy 356.151075 -233.807104) (xy 356.178276 -233.76409) (xy 356.212024 -233.725996)
			(xy 356.251446 -233.693809) (xy 356.29552 -233.668363) (xy 356.343106 -233.650316) (xy 356.39297 -233.640136)
			(xy 356.443822 -233.638087) (xy 356.494343 -233.644221) (xy 356.543227 -233.658381) (xy 356.589206 -233.680198)
			(xy 356.63109 -233.709108) (xy 356.667794 -233.744363) (xy 356.698367 -233.785049) (xy 356.722018 -233.830112)
			(xy 356.738134 -233.878386) (xy 356.746298 -233.92862) (xy 356.74681 -233.954066) (xy 357.054907 -233.954066)
			(xy 357.059002 -233.903338) (xy 357.071181 -233.853924) (xy 357.091129 -233.807104) (xy 357.11833 -233.76409)
			(xy 357.152078 -233.725996) (xy 357.1915 -233.693809) (xy 357.235574 -233.668363) (xy 357.28316 -233.650316)
			(xy 357.333024 -233.640136) (xy 357.383876 -233.638087) (xy 357.434397 -233.644221) (xy 357.483281 -233.658381)
			(xy 357.52926 -233.680198) (xy 357.571144 -233.709108) (xy 357.607848 -233.744363) (xy 357.638421 -233.785049)
			(xy 357.662072 -233.830112) (xy 357.678188 -233.878386) (xy 357.686352 -233.92862) (xy 357.686864 -233.954066)
			(xy 357.686361 -233.979055) (xy 357.993678 -233.979055) (xy 357.993678 -233.929077) (xy 358.001497 -233.879714)
			(xy 358.016941 -233.832182) (xy 358.039631 -233.78765) (xy 358.069007 -233.747217) (xy 358.104347 -233.711877)
			(xy 358.14478 -233.682501) (xy 358.189312 -233.659811) (xy 358.236844 -233.644367) (xy 358.286207 -233.636548)
			(xy 358.336185 -233.636548) (xy 358.385548 -233.644367) (xy 358.43308 -233.659811) (xy 358.477612 -233.682501)
			(xy 358.518045 -233.711877) (xy 358.553385 -233.747217) (xy 358.582761 -233.78765) (xy 358.605451 -233.832182)
			(xy 358.620895 -233.879714) (xy 358.628714 -233.929077) (xy 358.629204 -233.954066) (xy 358.628714 -233.979055)
			(xy 360.807236 -233.979055) (xy 360.807236 -233.929077) (xy 360.815055 -233.879714) (xy 360.830499 -233.832182)
			(xy 360.853189 -233.78765) (xy 360.882565 -233.747217) (xy 360.917905 -233.711877) (xy 360.958338 -233.682501)
			(xy 361.00287 -233.659811) (xy 361.050402 -233.644367) (xy 361.099765 -233.636548) (xy 361.149743 -233.636548)
			(xy 361.199106 -233.644367) (xy 361.246638 -233.659811) (xy 361.29117 -233.682501) (xy 361.331603 -233.711877)
			(xy 361.366943 -233.747217) (xy 361.396319 -233.78765) (xy 361.419009 -233.832182) (xy 361.434453 -233.879714)
			(xy 361.442272 -233.929077) (xy 361.442762 -233.954066) (xy 361.748573 -233.954066) (xy 361.752668 -233.903338)
			(xy 361.764847 -233.853924) (xy 361.784795 -233.807104) (xy 361.811996 -233.76409) (xy 361.845744 -233.725996)
			(xy 361.885166 -233.693809) (xy 361.92924 -233.668363) (xy 361.976826 -233.650316) (xy 362.02669 -233.640136)
			(xy 362.077542 -233.638087) (xy 362.128063 -233.644221) (xy 362.176947 -233.658381) (xy 362.222926 -233.680198)
			(xy 362.26481 -233.709108) (xy 362.301514 -233.744363) (xy 362.332087 -233.785049) (xy 362.355738 -233.830112)
			(xy 362.371854 -233.878386) (xy 362.380018 -233.92862) (xy 362.38053 -233.954066) (xy 362.688627 -233.954066)
			(xy 362.692722 -233.903338) (xy 362.704901 -233.853924) (xy 362.724849 -233.807104) (xy 362.75205 -233.76409)
			(xy 362.785798 -233.725996) (xy 362.82522 -233.693809) (xy 362.869294 -233.668363) (xy 362.91688 -233.650316)
			(xy 362.966744 -233.640136) (xy 363.017596 -233.638087) (xy 363.068117 -233.644221) (xy 363.117001 -233.658381)
			(xy 363.16298 -233.680198) (xy 363.204864 -233.709108) (xy 363.241568 -233.744363) (xy 363.272141 -233.785049)
			(xy 363.295792 -233.830112) (xy 363.311908 -233.878386) (xy 363.320072 -233.92862) (xy 363.320584 -233.954066)
			(xy 363.320081 -233.979055) (xy 363.627398 -233.979055) (xy 363.627398 -233.929077) (xy 363.635217 -233.879714)
			(xy 363.650661 -233.832182) (xy 363.673351 -233.78765) (xy 363.702727 -233.747217) (xy 363.738067 -233.711877)
			(xy 363.7785 -233.682501) (xy 363.823032 -233.659811) (xy 363.870564 -233.644367) (xy 363.919927 -233.636548)
			(xy 363.969905 -233.636548) (xy 364.019268 -233.644367) (xy 364.0668 -233.659811) (xy 364.111332 -233.682501)
			(xy 364.151765 -233.711877) (xy 364.187105 -233.747217) (xy 364.216481 -233.78765) (xy 364.239171 -233.832182)
			(xy 364.254615 -233.879714) (xy 364.262434 -233.929077) (xy 364.262924 -233.954066) (xy 364.262434 -233.979055)
			(xy 366.447306 -233.979055) (xy 366.447306 -233.929077) (xy 366.455125 -233.879714) (xy 366.470569 -233.832182)
			(xy 366.493259 -233.78765) (xy 366.522635 -233.747217) (xy 366.557975 -233.711877) (xy 366.598408 -233.682501)
			(xy 366.64294 -233.659811) (xy 366.690472 -233.644367) (xy 366.739835 -233.636548) (xy 366.789813 -233.636548)
			(xy 366.839176 -233.644367) (xy 366.886708 -233.659811) (xy 366.93124 -233.682501) (xy 366.971673 -233.711877)
			(xy 367.007013 -233.747217) (xy 367.036389 -233.78765) (xy 367.059079 -233.832182) (xy 367.074523 -233.879714)
			(xy 367.082342 -233.929077) (xy 367.082832 -233.954066) (xy 367.082342 -233.979055) (xy 369.267214 -233.979055)
			(xy 369.267214 -233.929077) (xy 369.275033 -233.879714) (xy 369.290477 -233.832182) (xy 369.313167 -233.78765)
			(xy 369.342543 -233.747217) (xy 369.377883 -233.711877) (xy 369.418316 -233.682501) (xy 369.462848 -233.659811)
			(xy 369.51038 -233.644367) (xy 369.559743 -233.636548) (xy 369.609721 -233.636548) (xy 369.659084 -233.644367)
			(xy 369.706616 -233.659811) (xy 369.751148 -233.682501) (xy 369.791581 -233.711877) (xy 369.826921 -233.747217)
			(xy 369.856297 -233.78765) (xy 369.878987 -233.832182) (xy 369.894431 -233.879714) (xy 369.90225 -233.929077)
			(xy 369.90274 -233.954066) (xy 369.90225 -233.979055) (xy 372.087376 -233.979055) (xy 372.087376 -233.929077)
			(xy 372.095195 -233.879714) (xy 372.110639 -233.832182) (xy 372.133329 -233.78765) (xy 372.162705 -233.747217)
			(xy 372.198045 -233.711877) (xy 372.238478 -233.682501) (xy 372.28301 -233.659811) (xy 372.330542 -233.644367)
			(xy 372.379905 -233.636548) (xy 372.429883 -233.636548) (xy 372.479246 -233.644367) (xy 372.526778 -233.659811)
			(xy 372.57131 -233.682501) (xy 372.611743 -233.711877) (xy 372.647083 -233.747217) (xy 372.676459 -233.78765)
			(xy 372.699149 -233.832182) (xy 372.714593 -233.879714) (xy 372.722412 -233.929077) (xy 372.722902 -233.954066)
			(xy 372.722412 -233.979055) (xy 372.714593 -234.028418) (xy 372.699149 -234.07595) (xy 372.676459 -234.120482)
			(xy 372.647083 -234.160915) (xy 372.611743 -234.196255) (xy 372.57131 -234.225631) (xy 372.526778 -234.248321)
			(xy 372.479246 -234.263765) (xy 372.429883 -234.271584) (xy 372.379905 -234.271584) (xy 372.330542 -234.263765)
			(xy 372.28301 -234.248321) (xy 372.238478 -234.225631) (xy 372.198045 -234.196255) (xy 372.162705 -234.160915)
			(xy 372.133329 -234.120482) (xy 372.110639 -234.07595) (xy 372.095195 -234.028418) (xy 372.087376 -233.979055)
			(xy 369.90225 -233.979055) (xy 369.894431 -234.028418) (xy 369.878987 -234.07595) (xy 369.856297 -234.120482)
			(xy 369.826921 -234.160915) (xy 369.791581 -234.196255) (xy 369.751148 -234.225631) (xy 369.706616 -234.248321)
			(xy 369.659084 -234.263765) (xy 369.609721 -234.271584) (xy 369.559743 -234.271584) (xy 369.51038 -234.263765)
			(xy 369.462848 -234.248321) (xy 369.418316 -234.225631) (xy 369.377883 -234.196255) (xy 369.342543 -234.160915)
			(xy 369.313167 -234.120482) (xy 369.290477 -234.07595) (xy 369.275033 -234.028418) (xy 369.267214 -233.979055)
			(xy 367.082342 -233.979055) (xy 367.074523 -234.028418) (xy 367.059079 -234.07595) (xy 367.036389 -234.120482)
			(xy 367.007013 -234.160915) (xy 366.971673 -234.196255) (xy 366.93124 -234.225631) (xy 366.886708 -234.248321)
			(xy 366.839176 -234.263765) (xy 366.789813 -234.271584) (xy 366.739835 -234.271584) (xy 366.690472 -234.263765)
			(xy 366.64294 -234.248321) (xy 366.598408 -234.225631) (xy 366.557975 -234.196255) (xy 366.522635 -234.160915)
			(xy 366.493259 -234.120482) (xy 366.470569 -234.07595) (xy 366.455125 -234.028418) (xy 366.447306 -233.979055)
			(xy 364.262434 -233.979055) (xy 364.254615 -234.028418) (xy 364.239171 -234.07595) (xy 364.216481 -234.120482)
			(xy 364.187105 -234.160915) (xy 364.151765 -234.196255) (xy 364.111332 -234.225631) (xy 364.0668 -234.248321)
			(xy 364.019268 -234.263765) (xy 363.969905 -234.271584) (xy 363.919927 -234.271584) (xy 363.870564 -234.263765)
			(xy 363.823032 -234.248321) (xy 363.7785 -234.225631) (xy 363.738067 -234.196255) (xy 363.702727 -234.160915)
			(xy 363.673351 -234.120482) (xy 363.650661 -234.07595) (xy 363.635217 -234.028418) (xy 363.627398 -233.979055)
			(xy 363.320081 -233.979055) (xy 363.320072 -233.979512) (xy 363.311908 -234.029746) (xy 363.295792 -234.07802)
			(xy 363.272141 -234.123083) (xy 363.241568 -234.163769) (xy 363.204864 -234.199024) (xy 363.16298 -234.227934)
			(xy 363.117001 -234.249751) (xy 363.068117 -234.263911) (xy 363.017596 -234.270045) (xy 362.966744 -234.267996)
			(xy 362.91688 -234.257816) (xy 362.869294 -234.239769) (xy 362.82522 -234.214323) (xy 362.785798 -234.182136)
			(xy 362.75205 -234.144042) (xy 362.724849 -234.101028) (xy 362.704901 -234.054208) (xy 362.692722 -234.004794)
			(xy 362.688627 -233.954066) (xy 362.38053 -233.954066) (xy 362.380018 -233.979512) (xy 362.371854 -234.029746)
			(xy 362.355738 -234.07802) (xy 362.332087 -234.123083) (xy 362.301514 -234.163769) (xy 362.26481 -234.199024)
			(xy 362.222926 -234.227934) (xy 362.176947 -234.249751) (xy 362.128063 -234.263911) (xy 362.077542 -234.270045)
			(xy 362.02669 -234.267996) (xy 361.976826 -234.257816) (xy 361.92924 -234.239769) (xy 361.885166 -234.214323)
			(xy 361.845744 -234.182136) (xy 361.811996 -234.144042) (xy 361.784795 -234.101028) (xy 361.764847 -234.054208)
			(xy 361.752668 -234.004794) (xy 361.748573 -233.954066) (xy 361.442762 -233.954066) (xy 361.442272 -233.979055)
			(xy 361.434453 -234.028418) (xy 361.419009 -234.07595) (xy 361.396319 -234.120482) (xy 361.366943 -234.160915)
			(xy 361.331603 -234.196255) (xy 361.29117 -234.225631) (xy 361.246638 -234.248321) (xy 361.199106 -234.263765)
			(xy 361.149743 -234.271584) (xy 361.099765 -234.271584) (xy 361.050402 -234.263765) (xy 361.00287 -234.248321)
			(xy 360.958338 -234.225631) (xy 360.917905 -234.196255) (xy 360.882565 -234.160915) (xy 360.853189 -234.120482)
			(xy 360.830499 -234.07595) (xy 360.815055 -234.028418) (xy 360.807236 -233.979055) (xy 358.628714 -233.979055)
			(xy 358.620895 -234.028418) (xy 358.605451 -234.07595) (xy 358.582761 -234.120482) (xy 358.553385 -234.160915)
			(xy 358.518045 -234.196255) (xy 358.477612 -234.225631) (xy 358.43308 -234.248321) (xy 358.385548 -234.263765)
			(xy 358.336185 -234.271584) (xy 358.286207 -234.271584) (xy 358.236844 -234.263765) (xy 358.189312 -234.248321)
			(xy 358.14478 -234.225631) (xy 358.104347 -234.196255) (xy 358.069007 -234.160915) (xy 358.039631 -234.120482)
			(xy 358.016941 -234.07595) (xy 358.001497 -234.028418) (xy 357.993678 -233.979055) (xy 357.686361 -233.979055)
			(xy 357.686352 -233.979512) (xy 357.678188 -234.029746) (xy 357.662072 -234.07802) (xy 357.638421 -234.123083)
			(xy 357.607848 -234.163769) (xy 357.571144 -234.199024) (xy 357.52926 -234.227934) (xy 357.483281 -234.249751)
			(xy 357.434397 -234.263911) (xy 357.383876 -234.270045) (xy 357.333024 -234.267996) (xy 357.28316 -234.257816)
			(xy 357.235574 -234.239769) (xy 357.1915 -234.214323) (xy 357.152078 -234.182136) (xy 357.11833 -234.144042)
			(xy 357.091129 -234.101028) (xy 357.071181 -234.054208) (xy 357.059002 -234.004794) (xy 357.054907 -233.954066)
			(xy 356.74681 -233.954066) (xy 356.746298 -233.979512) (xy 356.738134 -234.029746) (xy 356.722018 -234.07802)
			(xy 356.698367 -234.123083) (xy 356.667794 -234.163769) (xy 356.63109 -234.199024) (xy 356.589206 -234.227934)
			(xy 356.543227 -234.249751) (xy 356.494343 -234.263911) (xy 356.443822 -234.270045) (xy 356.39297 -234.267996)
			(xy 356.343106 -234.257816) (xy 356.29552 -234.239769) (xy 356.251446 -234.214323) (xy 356.212024 -234.182136)
			(xy 356.178276 -234.144042) (xy 356.151075 -234.101028) (xy 356.131127 -234.054208) (xy 356.118948 -234.004794)
			(xy 356.114853 -233.954066) (xy 355.809042 -233.954066) (xy 355.808552 -233.979055) (xy 355.800733 -234.028418)
			(xy 355.785289 -234.07595) (xy 355.762599 -234.120482) (xy 355.733223 -234.160915) (xy 355.697883 -234.196255)
			(xy 355.65745 -234.225631) (xy 355.612918 -234.248321) (xy 355.565386 -234.263765) (xy 355.516023 -234.271584)
			(xy 355.466045 -234.271584) (xy 355.416682 -234.263765) (xy 355.36915 -234.248321) (xy 355.324618 -234.225631)
			(xy 355.284185 -234.196255) (xy 355.248845 -234.160915) (xy 355.219469 -234.120482) (xy 355.196779 -234.07595)
			(xy 355.181335 -234.028418) (xy 355.173516 -233.979055) (xy 352.988644 -233.979055) (xy 352.980825 -234.028418)
			(xy 352.965381 -234.07595) (xy 352.942691 -234.120482) (xy 352.913315 -234.160915) (xy 352.877975 -234.196255)
			(xy 352.837542 -234.225631) (xy 352.79301 -234.248321) (xy 352.745478 -234.263765) (xy 352.696115 -234.271584)
			(xy 352.646137 -234.271584) (xy 352.596774 -234.263765) (xy 352.549242 -234.248321) (xy 352.50471 -234.225631)
			(xy 352.464277 -234.196255) (xy 352.428937 -234.160915) (xy 352.399561 -234.120482) (xy 352.376871 -234.07595)
			(xy 352.361427 -234.028418) (xy 352.353608 -233.979055) (xy 350.168736 -233.979055) (xy 350.160917 -234.028418)
			(xy 350.145473 -234.07595) (xy 350.122783 -234.120482) (xy 350.093407 -234.160915) (xy 350.058067 -234.196255)
			(xy 350.017634 -234.225631) (xy 349.973102 -234.248321) (xy 349.92557 -234.263765) (xy 349.876207 -234.271584)
			(xy 349.826229 -234.271584) (xy 349.776866 -234.263765) (xy 349.729334 -234.248321) (xy 349.684802 -234.225631)
			(xy 349.644369 -234.196255) (xy 349.609029 -234.160915) (xy 349.579653 -234.120482) (xy 349.556963 -234.07595)
			(xy 349.541519 -234.028418) (xy 349.5337 -233.979055) (xy 347.348574 -233.979055) (xy 347.340755 -234.028418)
			(xy 347.325311 -234.07595) (xy 347.302621 -234.120482) (xy 347.273245 -234.160915) (xy 347.237905 -234.196255)
			(xy 347.197472 -234.225631) (xy 347.15294 -234.248321) (xy 347.105408 -234.263765) (xy 347.056045 -234.271584)
			(xy 347.006067 -234.271584) (xy 346.956704 -234.263765) (xy 346.909172 -234.248321) (xy 346.86464 -234.225631)
			(xy 346.824207 -234.196255) (xy 346.788867 -234.160915) (xy 346.759491 -234.120482) (xy 346.736801 -234.07595)
			(xy 346.721357 -234.028418) (xy 346.713538 -233.979055) (xy 344.997532 -233.979055) (xy 344.997532 -234.730036)
			(xy 344.997786 -234.734608) (xy 344.999056 -234.763818) (xy 344.999056 -234.764072) (xy 345.304867 -234.764072)
			(xy 345.308962 -234.713344) (xy 345.321141 -234.66393) (xy 345.341089 -234.61711) (xy 345.36829 -234.574096)
			(xy 345.402038 -234.536002) (xy 345.44146 -234.503815) (xy 345.485534 -234.478369) (xy 345.53312 -234.460322)
			(xy 345.582984 -234.450142) (xy 345.633836 -234.448093) (xy 345.684357 -234.454227) (xy 345.733241 -234.468387)
			(xy 345.77922 -234.490204) (xy 345.821104 -234.519114) (xy 345.857808 -234.554369) (xy 345.888381 -234.595055)
			(xy 345.912032 -234.640118) (xy 345.928148 -234.688392) (xy 345.936312 -234.738626) (xy 345.936824 -234.764072)
			(xy 346.244921 -234.764072) (xy 346.249016 -234.713344) (xy 346.261195 -234.66393) (xy 346.281143 -234.61711)
			(xy 346.308344 -234.574096) (xy 346.342092 -234.536002) (xy 346.381514 -234.503815) (xy 346.425588 -234.478369)
			(xy 346.473174 -234.460322) (xy 346.523038 -234.450142) (xy 346.57389 -234.448093) (xy 346.624411 -234.454227)
			(xy 346.673295 -234.468387) (xy 346.719274 -234.490204) (xy 346.761158 -234.519114) (xy 346.797862 -234.554369)
			(xy 346.828435 -234.595055) (xy 346.852086 -234.640118) (xy 346.868202 -234.688392) (xy 346.876366 -234.738626)
			(xy 346.876878 -234.764072) (xy 346.876375 -234.789061) (xy 347.183692 -234.789061) (xy 347.183692 -234.739083)
			(xy 347.191511 -234.68972) (xy 347.206955 -234.642188) (xy 347.229645 -234.597656) (xy 347.259021 -234.557223)
			(xy 347.294361 -234.521883) (xy 347.334794 -234.492507) (xy 347.379326 -234.469817) (xy 347.426858 -234.454373)
			(xy 347.476221 -234.446554) (xy 347.526199 -234.446554) (xy 347.575562 -234.454373) (xy 347.623094 -234.469817)
			(xy 347.667626 -234.492507) (xy 347.708059 -234.521883) (xy 347.743399 -234.557223) (xy 347.772775 -234.597656)
			(xy 347.795465 -234.642188) (xy 347.810909 -234.68972) (xy 347.818728 -234.739083) (xy 347.819218 -234.764072)
			(xy 348.124775 -234.764072) (xy 348.12887 -234.713344) (xy 348.141049 -234.66393) (xy 348.160997 -234.61711)
			(xy 348.188198 -234.574096) (xy 348.221946 -234.536002) (xy 348.261368 -234.503815) (xy 348.305442 -234.478369)
			(xy 348.353028 -234.460322) (xy 348.402892 -234.450142) (xy 348.453744 -234.448093) (xy 348.504265 -234.454227)
			(xy 348.553149 -234.468387) (xy 348.599128 -234.490204) (xy 348.641012 -234.519114) (xy 348.677716 -234.554369)
			(xy 348.708289 -234.595055) (xy 348.73194 -234.640118) (xy 348.748056 -234.688392) (xy 348.75622 -234.738626)
			(xy 348.756732 -234.764072) (xy 349.064829 -234.764072) (xy 349.068924 -234.713344) (xy 349.081103 -234.66393)
			(xy 349.101051 -234.61711) (xy 349.128252 -234.574096) (xy 349.162 -234.536002) (xy 349.201422 -234.503815)
			(xy 349.245496 -234.478369) (xy 349.293082 -234.460322) (xy 349.342946 -234.450142) (xy 349.393798 -234.448093)
			(xy 349.444319 -234.454227) (xy 349.493203 -234.468387) (xy 349.539182 -234.490204) (xy 349.581066 -234.519114)
			(xy 349.61777 -234.554369) (xy 349.648343 -234.595055) (xy 349.671994 -234.640118) (xy 349.68811 -234.688392)
			(xy 349.696274 -234.738626) (xy 349.696786 -234.764072) (xy 349.696283 -234.789061) (xy 350.0036 -234.789061)
			(xy 350.0036 -234.739083) (xy 350.011419 -234.68972) (xy 350.026863 -234.642188) (xy 350.049553 -234.597656)
			(xy 350.078929 -234.557223) (xy 350.114269 -234.521883) (xy 350.154702 -234.492507) (xy 350.199234 -234.469817)
			(xy 350.246766 -234.454373) (xy 350.296129 -234.446554) (xy 350.346107 -234.446554) (xy 350.39547 -234.454373)
			(xy 350.443002 -234.469817) (xy 350.487534 -234.492507) (xy 350.527967 -234.521883) (xy 350.563307 -234.557223)
			(xy 350.592683 -234.597656) (xy 350.615373 -234.642188) (xy 350.630817 -234.68972) (xy 350.638636 -234.739083)
			(xy 350.639126 -234.764072) (xy 350.944937 -234.764072) (xy 350.949032 -234.713344) (xy 350.961211 -234.66393)
			(xy 350.981159 -234.61711) (xy 351.00836 -234.574096) (xy 351.042108 -234.536002) (xy 351.08153 -234.503815)
			(xy 351.125604 -234.478369) (xy 351.17319 -234.460322) (xy 351.223054 -234.450142) (xy 351.273906 -234.448093)
			(xy 351.324427 -234.454227) (xy 351.373311 -234.468387) (xy 351.41929 -234.490204) (xy 351.461174 -234.519114)
			(xy 351.497878 -234.554369) (xy 351.528451 -234.595055) (xy 351.552102 -234.640118) (xy 351.568218 -234.688392)
			(xy 351.576382 -234.738626) (xy 351.576894 -234.764072) (xy 351.884991 -234.764072) (xy 351.889086 -234.713344)
			(xy 351.901265 -234.66393) (xy 351.921213 -234.61711) (xy 351.948414 -234.574096) (xy 351.982162 -234.536002)
			(xy 352.021584 -234.503815) (xy 352.065658 -234.478369) (xy 352.113244 -234.460322) (xy 352.163108 -234.450142)
			(xy 352.21396 -234.448093) (xy 352.264481 -234.454227) (xy 352.313365 -234.468387) (xy 352.359344 -234.490204)
			(xy 352.401228 -234.519114) (xy 352.437932 -234.554369) (xy 352.468505 -234.595055) (xy 352.492156 -234.640118)
			(xy 352.508272 -234.688392) (xy 352.516436 -234.738626) (xy 352.516948 -234.764072) (xy 352.516445 -234.789061)
			(xy 352.823508 -234.789061) (xy 352.823508 -234.739083) (xy 352.831327 -234.68972) (xy 352.846771 -234.642188)
			(xy 352.869461 -234.597656) (xy 352.898837 -234.557223) (xy 352.934177 -234.521883) (xy 352.97461 -234.492507)
			(xy 353.019142 -234.469817) (xy 353.066674 -234.454373) (xy 353.116037 -234.446554) (xy 353.166015 -234.446554)
			(xy 353.215378 -234.454373) (xy 353.26291 -234.469817) (xy 353.307442 -234.492507) (xy 353.347875 -234.521883)
			(xy 353.383215 -234.557223) (xy 353.412591 -234.597656) (xy 353.435281 -234.642188) (xy 353.450725 -234.68972)
			(xy 353.458544 -234.739083) (xy 353.459034 -234.764072) (xy 353.764845 -234.764072) (xy 353.76894 -234.713344)
			(xy 353.781119 -234.66393) (xy 353.801067 -234.61711) (xy 353.828268 -234.574096) (xy 353.862016 -234.536002)
			(xy 353.901438 -234.503815) (xy 353.945512 -234.478369) (xy 353.993098 -234.460322) (xy 354.042962 -234.450142)
			(xy 354.093814 -234.448093) (xy 354.144335 -234.454227) (xy 354.193219 -234.468387) (xy 354.239198 -234.490204)
			(xy 354.281082 -234.519114) (xy 354.317786 -234.554369) (xy 354.348359 -234.595055) (xy 354.37201 -234.640118)
			(xy 354.388126 -234.688392) (xy 354.39629 -234.738626) (xy 354.396802 -234.764072) (xy 354.704899 -234.764072)
			(xy 354.708994 -234.713344) (xy 354.721173 -234.66393) (xy 354.741121 -234.61711) (xy 354.768322 -234.574096)
			(xy 354.80207 -234.536002) (xy 354.841492 -234.503815) (xy 354.885566 -234.478369) (xy 354.933152 -234.460322)
			(xy 354.983016 -234.450142) (xy 355.033868 -234.448093) (xy 355.084389 -234.454227) (xy 355.133273 -234.468387)
			(xy 355.179252 -234.490204) (xy 355.221136 -234.519114) (xy 355.25784 -234.554369) (xy 355.288413 -234.595055)
			(xy 355.312064 -234.640118) (xy 355.32818 -234.688392) (xy 355.336344 -234.738626) (xy 355.336856 -234.764072)
			(xy 355.336353 -234.789061) (xy 355.64367 -234.789061) (xy 355.64367 -234.739083) (xy 355.651489 -234.68972)
			(xy 355.666933 -234.642188) (xy 355.689623 -234.597656) (xy 355.718999 -234.557223) (xy 355.754339 -234.521883)
			(xy 355.794772 -234.492507) (xy 355.839304 -234.469817) (xy 355.886836 -234.454373) (xy 355.936199 -234.446554)
			(xy 355.986177 -234.446554) (xy 356.03554 -234.454373) (xy 356.083072 -234.469817) (xy 356.127604 -234.492507)
			(xy 356.168037 -234.521883) (xy 356.203377 -234.557223) (xy 356.232753 -234.597656) (xy 356.255443 -234.642188)
			(xy 356.270887 -234.68972) (xy 356.278706 -234.739083) (xy 356.279196 -234.764072) (xy 356.278706 -234.789061)
			(xy 363.157244 -234.789061) (xy 363.157244 -234.739083) (xy 363.165063 -234.68972) (xy 363.180507 -234.642188)
			(xy 363.203197 -234.597656) (xy 363.232573 -234.557223) (xy 363.267913 -234.521883) (xy 363.308346 -234.492507)
			(xy 363.352878 -234.469817) (xy 363.40041 -234.454373) (xy 363.449773 -234.446554) (xy 363.499751 -234.446554)
			(xy 363.549114 -234.454373) (xy 363.596646 -234.469817) (xy 363.641178 -234.492507) (xy 363.681611 -234.521883)
			(xy 363.716951 -234.557223) (xy 363.746327 -234.597656) (xy 363.769017 -234.642188) (xy 363.784461 -234.68972)
			(xy 363.79228 -234.739083) (xy 363.79277 -234.764072) (xy 364.098581 -234.764072) (xy 364.102676 -234.713344)
			(xy 364.114855 -234.66393) (xy 364.134803 -234.61711) (xy 364.162004 -234.574096) (xy 364.195752 -234.536002)
			(xy 364.235174 -234.503815) (xy 364.279248 -234.478369) (xy 364.326834 -234.460322) (xy 364.376698 -234.450142)
			(xy 364.42755 -234.448093) (xy 364.478071 -234.454227) (xy 364.526955 -234.468387) (xy 364.572934 -234.490204)
			(xy 364.614818 -234.519114) (xy 364.651522 -234.554369) (xy 364.682095 -234.595055) (xy 364.705746 -234.640118)
			(xy 364.721862 -234.688392) (xy 364.730026 -234.738626) (xy 364.730538 -234.764072) (xy 365.038635 -234.764072)
			(xy 365.04273 -234.713344) (xy 365.054909 -234.66393) (xy 365.074857 -234.61711) (xy 365.102058 -234.574096)
			(xy 365.135806 -234.536002) (xy 365.175228 -234.503815) (xy 365.219302 -234.478369) (xy 365.266888 -234.460322)
			(xy 365.316752 -234.450142) (xy 365.367604 -234.448093) (xy 365.418125 -234.454227) (xy 365.467009 -234.468387)
			(xy 365.512988 -234.490204) (xy 365.554872 -234.519114) (xy 365.591576 -234.554369) (xy 365.622149 -234.595055)
			(xy 365.6458 -234.640118) (xy 365.661916 -234.688392) (xy 365.67008 -234.738626) (xy 365.670592 -234.764072)
			(xy 365.670089 -234.789061) (xy 365.977406 -234.789061) (xy 365.977406 -234.739083) (xy 365.985225 -234.68972)
			(xy 366.000669 -234.642188) (xy 366.023359 -234.597656) (xy 366.052735 -234.557223) (xy 366.088075 -234.521883)
			(xy 366.128508 -234.492507) (xy 366.17304 -234.469817) (xy 366.220572 -234.454373) (xy 366.269935 -234.446554)
			(xy 366.319913 -234.446554) (xy 366.369276 -234.454373) (xy 366.416808 -234.469817) (xy 366.46134 -234.492507)
			(xy 366.501773 -234.521883) (xy 366.537113 -234.557223) (xy 366.566489 -234.597656) (xy 366.589179 -234.642188)
			(xy 366.604623 -234.68972) (xy 366.612442 -234.739083) (xy 366.612932 -234.764072) (xy 366.918489 -234.764072)
			(xy 366.922584 -234.713344) (xy 366.934763 -234.66393) (xy 366.954711 -234.61711) (xy 366.981912 -234.574096)
			(xy 367.01566 -234.536002) (xy 367.055082 -234.503815) (xy 367.099156 -234.478369) (xy 367.146742 -234.460322)
			(xy 367.196606 -234.450142) (xy 367.247458 -234.448093) (xy 367.297979 -234.454227) (xy 367.346863 -234.468387)
			(xy 367.392842 -234.490204) (xy 367.434726 -234.519114) (xy 367.47143 -234.554369) (xy 367.502003 -234.595055)
			(xy 367.525654 -234.640118) (xy 367.54177 -234.688392) (xy 367.549934 -234.738626) (xy 367.550446 -234.764072)
			(xy 367.858543 -234.764072) (xy 367.862638 -234.713344) (xy 367.874817 -234.66393) (xy 367.894765 -234.61711)
			(xy 367.921966 -234.574096) (xy 367.955714 -234.536002) (xy 367.995136 -234.503815) (xy 368.03921 -234.478369)
			(xy 368.086796 -234.460322) (xy 368.13666 -234.450142) (xy 368.187512 -234.448093) (xy 368.238033 -234.454227)
			(xy 368.286917 -234.468387) (xy 368.332896 -234.490204) (xy 368.37478 -234.519114) (xy 368.411484 -234.554369)
			(xy 368.442057 -234.595055) (xy 368.465708 -234.640118) (xy 368.481824 -234.688392) (xy 368.489988 -234.738626)
			(xy 368.4905 -234.764072) (xy 368.489997 -234.789061) (xy 368.797314 -234.789061) (xy 368.797314 -234.739083)
			(xy 368.805133 -234.68972) (xy 368.820577 -234.642188) (xy 368.843267 -234.597656) (xy 368.872643 -234.557223)
			(xy 368.907983 -234.521883) (xy 368.948416 -234.492507) (xy 368.992948 -234.469817) (xy 369.04048 -234.454373)
			(xy 369.089843 -234.446554) (xy 369.139821 -234.446554) (xy 369.189184 -234.454373) (xy 369.236716 -234.469817)
			(xy 369.281248 -234.492507) (xy 369.321681 -234.521883) (xy 369.357021 -234.557223) (xy 369.386397 -234.597656)
			(xy 369.409087 -234.642188) (xy 369.424531 -234.68972) (xy 369.43235 -234.739083) (xy 369.43284 -234.764072)
			(xy 369.738651 -234.764072) (xy 369.742746 -234.713344) (xy 369.754925 -234.66393) (xy 369.774873 -234.61711)
			(xy 369.802074 -234.574096) (xy 369.835822 -234.536002) (xy 369.875244 -234.503815) (xy 369.919318 -234.478369)
			(xy 369.966904 -234.460322) (xy 370.016768 -234.450142) (xy 370.06762 -234.448093) (xy 370.118141 -234.454227)
			(xy 370.167025 -234.468387) (xy 370.213004 -234.490204) (xy 370.254888 -234.519114) (xy 370.291592 -234.554369)
			(xy 370.322165 -234.595055) (xy 370.345816 -234.640118) (xy 370.361932 -234.688392) (xy 370.370096 -234.738626)
			(xy 370.370608 -234.764072) (xy 370.678451 -234.764072) (xy 370.682546 -234.713344) (xy 370.694725 -234.66393)
			(xy 370.714673 -234.61711) (xy 370.741874 -234.574096) (xy 370.775622 -234.536002) (xy 370.815044 -234.503815)
			(xy 370.859118 -234.478369) (xy 370.906704 -234.460322) (xy 370.956568 -234.450142) (xy 371.00742 -234.448093)
			(xy 371.057941 -234.454227) (xy 371.106825 -234.468387) (xy 371.152804 -234.490204) (xy 371.194688 -234.519114)
			(xy 371.231392 -234.554369) (xy 371.261965 -234.595055) (xy 371.285616 -234.640118) (xy 371.301732 -234.688392)
			(xy 371.309896 -234.738626) (xy 371.310408 -234.764072) (xy 371.309905 -234.789061) (xy 371.617222 -234.789061)
			(xy 371.617222 -234.739083) (xy 371.625041 -234.68972) (xy 371.640485 -234.642188) (xy 371.663175 -234.597656)
			(xy 371.692551 -234.557223) (xy 371.727891 -234.521883) (xy 371.768324 -234.492507) (xy 371.812856 -234.469817)
			(xy 371.860388 -234.454373) (xy 371.909751 -234.446554) (xy 371.959729 -234.446554) (xy 372.009092 -234.454373)
			(xy 372.056624 -234.469817) (xy 372.101156 -234.492507) (xy 372.141589 -234.521883) (xy 372.176929 -234.557223)
			(xy 372.206305 -234.597656) (xy 372.228995 -234.642188) (xy 372.244439 -234.68972) (xy 372.252258 -234.739083)
			(xy 372.252748 -234.764072) (xy 372.558559 -234.764072) (xy 372.562654 -234.713344) (xy 372.574833 -234.66393)
			(xy 372.594781 -234.61711) (xy 372.621982 -234.574096) (xy 372.65573 -234.536002) (xy 372.695152 -234.503815)
			(xy 372.739226 -234.478369) (xy 372.786812 -234.460322) (xy 372.836676 -234.450142) (xy 372.887528 -234.448093)
			(xy 372.938049 -234.454227) (xy 372.986933 -234.468387) (xy 373.032912 -234.490204) (xy 373.074796 -234.519114)
			(xy 373.1115 -234.554369) (xy 373.142073 -234.595055) (xy 373.165724 -234.640118) (xy 373.18184 -234.688392)
			(xy 373.190004 -234.738626) (xy 373.190516 -234.764072) (xy 373.498613 -234.764072) (xy 373.502708 -234.713344)
			(xy 373.514887 -234.66393) (xy 373.534835 -234.61711) (xy 373.562036 -234.574096) (xy 373.595784 -234.536002)
			(xy 373.635206 -234.503815) (xy 373.67928 -234.478369) (xy 373.726866 -234.460322) (xy 373.77673 -234.450142)
			(xy 373.827582 -234.448093) (xy 373.878103 -234.454227) (xy 373.926987 -234.468387) (xy 373.972966 -234.490204)
			(xy 374.01485 -234.519114) (xy 374.051554 -234.554369) (xy 374.082127 -234.595055) (xy 374.105778 -234.640118)
			(xy 374.121894 -234.688392) (xy 374.130058 -234.738626) (xy 374.13057 -234.764072) (xy 374.130058 -234.789518)
			(xy 374.121894 -234.839752) (xy 374.105778 -234.888026) (xy 374.082127 -234.933089) (xy 374.051554 -234.973775)
			(xy 374.01485 -235.00903) (xy 373.972966 -235.03794) (xy 373.926987 -235.059757) (xy 373.878103 -235.073917)
			(xy 373.827582 -235.080051) (xy 373.77673 -235.078002) (xy 373.726866 -235.067822) (xy 373.67928 -235.049775)
			(xy 373.635206 -235.024329) (xy 373.595784 -234.992142) (xy 373.562036 -234.954048) (xy 373.534835 -234.911034)
			(xy 373.514887 -234.864214) (xy 373.502708 -234.8148) (xy 373.498613 -234.764072) (xy 373.190516 -234.764072)
			(xy 373.190004 -234.789518) (xy 373.18184 -234.839752) (xy 373.165724 -234.888026) (xy 373.142073 -234.933089)
			(xy 373.1115 -234.973775) (xy 373.074796 -235.00903) (xy 373.032912 -235.03794) (xy 372.986933 -235.059757)
			(xy 372.938049 -235.073917) (xy 372.887528 -235.080051) (xy 372.836676 -235.078002) (xy 372.786812 -235.067822)
			(xy 372.739226 -235.049775) (xy 372.695152 -235.024329) (xy 372.65573 -234.992142) (xy 372.621982 -234.954048)
			(xy 372.594781 -234.911034) (xy 372.574833 -234.864214) (xy 372.562654 -234.8148) (xy 372.558559 -234.764072)
			(xy 372.252748 -234.764072) (xy 372.252258 -234.789061) (xy 372.244439 -234.838424) (xy 372.228995 -234.885956)
			(xy 372.206305 -234.930488) (xy 372.176929 -234.970921) (xy 372.141589 -235.006261) (xy 372.101156 -235.035637)
			(xy 372.056624 -235.058327) (xy 372.009092 -235.073771) (xy 371.959729 -235.08159) (xy 371.909751 -235.08159)
			(xy 371.860388 -235.073771) (xy 371.812856 -235.058327) (xy 371.768324 -235.035637) (xy 371.727891 -235.006261)
			(xy 371.692551 -234.970921) (xy 371.663175 -234.930488) (xy 371.640485 -234.885956) (xy 371.625041 -234.838424)
			(xy 371.617222 -234.789061) (xy 371.309905 -234.789061) (xy 371.309896 -234.789518) (xy 371.301732 -234.839752)
			(xy 371.285616 -234.888026) (xy 371.261965 -234.933089) (xy 371.231392 -234.973775) (xy 371.194688 -235.00903)
			(xy 371.152804 -235.03794) (xy 371.106825 -235.059757) (xy 371.057941 -235.073917) (xy 371.00742 -235.080051)
			(xy 370.956568 -235.078002) (xy 370.906704 -235.067822) (xy 370.859118 -235.049775) (xy 370.815044 -235.024329)
			(xy 370.775622 -234.992142) (xy 370.741874 -234.954048) (xy 370.714673 -234.911034) (xy 370.694725 -234.864214)
			(xy 370.682546 -234.8148) (xy 370.678451 -234.764072) (xy 370.370608 -234.764072) (xy 370.370096 -234.789518)
			(xy 370.361932 -234.839752) (xy 370.345816 -234.888026) (xy 370.322165 -234.933089) (xy 370.291592 -234.973775)
			(xy 370.254888 -235.00903) (xy 370.213004 -235.03794) (xy 370.167025 -235.059757) (xy 370.118141 -235.073917)
			(xy 370.06762 -235.080051) (xy 370.016768 -235.078002) (xy 369.966904 -235.067822) (xy 369.919318 -235.049775)
			(xy 369.875244 -235.024329) (xy 369.835822 -234.992142) (xy 369.802074 -234.954048) (xy 369.774873 -234.911034)
			(xy 369.754925 -234.864214) (xy 369.742746 -234.8148) (xy 369.738651 -234.764072) (xy 369.43284 -234.764072)
			(xy 369.43235 -234.789061) (xy 369.424531 -234.838424) (xy 369.409087 -234.885956) (xy 369.386397 -234.930488)
			(xy 369.357021 -234.970921) (xy 369.321681 -235.006261) (xy 369.281248 -235.035637) (xy 369.236716 -235.058327)
			(xy 369.189184 -235.073771) (xy 369.139821 -235.08159) (xy 369.089843 -235.08159) (xy 369.04048 -235.073771)
			(xy 368.992948 -235.058327) (xy 368.948416 -235.035637) (xy 368.907983 -235.006261) (xy 368.872643 -234.970921)
			(xy 368.843267 -234.930488) (xy 368.820577 -234.885956) (xy 368.805133 -234.838424) (xy 368.797314 -234.789061)
			(xy 368.489997 -234.789061) (xy 368.489988 -234.789518) (xy 368.481824 -234.839752) (xy 368.465708 -234.888026)
			(xy 368.442057 -234.933089) (xy 368.411484 -234.973775) (xy 368.37478 -235.00903) (xy 368.332896 -235.03794)
			(xy 368.286917 -235.059757) (xy 368.238033 -235.073917) (xy 368.187512 -235.080051) (xy 368.13666 -235.078002)
			(xy 368.086796 -235.067822) (xy 368.03921 -235.049775) (xy 367.995136 -235.024329) (xy 367.955714 -234.992142)
			(xy 367.921966 -234.954048) (xy 367.894765 -234.911034) (xy 367.874817 -234.864214) (xy 367.862638 -234.8148)
			(xy 367.858543 -234.764072) (xy 367.550446 -234.764072) (xy 367.549934 -234.789518) (xy 367.54177 -234.839752)
			(xy 367.525654 -234.888026) (xy 367.502003 -234.933089) (xy 367.47143 -234.973775) (xy 367.434726 -235.00903)
			(xy 367.392842 -235.03794) (xy 367.346863 -235.059757) (xy 367.297979 -235.073917) (xy 367.247458 -235.080051)
			(xy 367.196606 -235.078002) (xy 367.146742 -235.067822) (xy 367.099156 -235.049775) (xy 367.055082 -235.024329)
			(xy 367.01566 -234.992142) (xy 366.981912 -234.954048) (xy 366.954711 -234.911034) (xy 366.934763 -234.864214)
			(xy 366.922584 -234.8148) (xy 366.918489 -234.764072) (xy 366.612932 -234.764072) (xy 366.612442 -234.789061)
			(xy 366.604623 -234.838424) (xy 366.589179 -234.885956) (xy 366.566489 -234.930488) (xy 366.537113 -234.970921)
			(xy 366.501773 -235.006261) (xy 366.46134 -235.035637) (xy 366.416808 -235.058327) (xy 366.369276 -235.073771)
			(xy 366.319913 -235.08159) (xy 366.269935 -235.08159) (xy 366.220572 -235.073771) (xy 366.17304 -235.058327)
			(xy 366.128508 -235.035637) (xy 366.088075 -235.006261) (xy 366.052735 -234.970921) (xy 366.023359 -234.930488)
			(xy 366.000669 -234.885956) (xy 365.985225 -234.838424) (xy 365.977406 -234.789061) (xy 365.670089 -234.789061)
			(xy 365.67008 -234.789518) (xy 365.661916 -234.839752) (xy 365.6458 -234.888026) (xy 365.622149 -234.933089)
			(xy 365.591576 -234.973775) (xy 365.554872 -235.00903) (xy 365.512988 -235.03794) (xy 365.467009 -235.059757)
			(xy 365.418125 -235.073917) (xy 365.367604 -235.080051) (xy 365.316752 -235.078002) (xy 365.266888 -235.067822)
			(xy 365.219302 -235.049775) (xy 365.175228 -235.024329) (xy 365.135806 -234.992142) (xy 365.102058 -234.954048)
			(xy 365.074857 -234.911034) (xy 365.054909 -234.864214) (xy 365.04273 -234.8148) (xy 365.038635 -234.764072)
			(xy 364.730538 -234.764072) (xy 364.730026 -234.789518) (xy 364.721862 -234.839752) (xy 364.705746 -234.888026)
			(xy 364.682095 -234.933089) (xy 364.651522 -234.973775) (xy 364.614818 -235.00903) (xy 364.572934 -235.03794)
			(xy 364.526955 -235.059757) (xy 364.478071 -235.073917) (xy 364.42755 -235.080051) (xy 364.376698 -235.078002)
			(xy 364.326834 -235.067822) (xy 364.279248 -235.049775) (xy 364.235174 -235.024329) (xy 364.195752 -234.992142)
			(xy 364.162004 -234.954048) (xy 364.134803 -234.911034) (xy 364.114855 -234.864214) (xy 364.102676 -234.8148)
			(xy 364.098581 -234.764072) (xy 363.79277 -234.764072) (xy 363.79228 -234.789061) (xy 363.784461 -234.838424)
			(xy 363.769017 -234.885956) (xy 363.746327 -234.930488) (xy 363.716951 -234.970921) (xy 363.681611 -235.006261)
			(xy 363.641178 -235.035637) (xy 363.596646 -235.058327) (xy 363.549114 -235.073771) (xy 363.499751 -235.08159)
			(xy 363.449773 -235.08159) (xy 363.40041 -235.073771) (xy 363.352878 -235.058327) (xy 363.308346 -235.035637)
			(xy 363.267913 -235.006261) (xy 363.232573 -234.970921) (xy 363.203197 -234.930488) (xy 363.180507 -234.885956)
			(xy 363.165063 -234.838424) (xy 363.157244 -234.789061) (xy 356.278706 -234.789061) (xy 356.270887 -234.838424)
			(xy 356.255443 -234.885956) (xy 356.232753 -234.930488) (xy 356.203377 -234.970921) (xy 356.168037 -235.006261)
			(xy 356.127604 -235.035637) (xy 356.083072 -235.058327) (xy 356.03554 -235.073771) (xy 355.986177 -235.08159)
			(xy 355.936199 -235.08159) (xy 355.886836 -235.073771) (xy 355.839304 -235.058327) (xy 355.794772 -235.035637)
			(xy 355.754339 -235.006261) (xy 355.718999 -234.970921) (xy 355.689623 -234.930488) (xy 355.666933 -234.885956)
			(xy 355.651489 -234.838424) (xy 355.64367 -234.789061) (xy 355.336353 -234.789061) (xy 355.336344 -234.789518)
			(xy 355.32818 -234.839752) (xy 355.312064 -234.888026) (xy 355.288413 -234.933089) (xy 355.25784 -234.973775)
			(xy 355.221136 -235.00903) (xy 355.179252 -235.03794) (xy 355.133273 -235.059757) (xy 355.084389 -235.073917)
			(xy 355.033868 -235.080051) (xy 354.983016 -235.078002) (xy 354.933152 -235.067822) (xy 354.885566 -235.049775)
			(xy 354.841492 -235.024329) (xy 354.80207 -234.992142) (xy 354.768322 -234.954048) (xy 354.741121 -234.911034)
			(xy 354.721173 -234.864214) (xy 354.708994 -234.8148) (xy 354.704899 -234.764072) (xy 354.396802 -234.764072)
			(xy 354.39629 -234.789518) (xy 354.388126 -234.839752) (xy 354.37201 -234.888026) (xy 354.348359 -234.933089)
			(xy 354.317786 -234.973775) (xy 354.281082 -235.00903) (xy 354.239198 -235.03794) (xy 354.193219 -235.059757)
			(xy 354.144335 -235.073917) (xy 354.093814 -235.080051) (xy 354.042962 -235.078002) (xy 353.993098 -235.067822)
			(xy 353.945512 -235.049775) (xy 353.901438 -235.024329) (xy 353.862016 -234.992142) (xy 353.828268 -234.954048)
			(xy 353.801067 -234.911034) (xy 353.781119 -234.864214) (xy 353.76894 -234.8148) (xy 353.764845 -234.764072)
			(xy 353.459034 -234.764072) (xy 353.458544 -234.789061) (xy 353.450725 -234.838424) (xy 353.435281 -234.885956)
			(xy 353.412591 -234.930488) (xy 353.383215 -234.970921) (xy 353.347875 -235.006261) (xy 353.307442 -235.035637)
			(xy 353.26291 -235.058327) (xy 353.215378 -235.073771) (xy 353.166015 -235.08159) (xy 353.116037 -235.08159)
			(xy 353.066674 -235.073771) (xy 353.019142 -235.058327) (xy 352.97461 -235.035637) (xy 352.934177 -235.006261)
			(xy 352.898837 -234.970921) (xy 352.869461 -234.930488) (xy 352.846771 -234.885956) (xy 352.831327 -234.838424)
			(xy 352.823508 -234.789061) (xy 352.516445 -234.789061) (xy 352.516436 -234.789518) (xy 352.508272 -234.839752)
			(xy 352.492156 -234.888026) (xy 352.468505 -234.933089) (xy 352.437932 -234.973775) (xy 352.401228 -235.00903)
			(xy 352.359344 -235.03794) (xy 352.313365 -235.059757) (xy 352.264481 -235.073917) (xy 352.21396 -235.080051)
			(xy 352.163108 -235.078002) (xy 352.113244 -235.067822) (xy 352.065658 -235.049775) (xy 352.021584 -235.024329)
			(xy 351.982162 -234.992142) (xy 351.948414 -234.954048) (xy 351.921213 -234.911034) (xy 351.901265 -234.864214)
			(xy 351.889086 -234.8148) (xy 351.884991 -234.764072) (xy 351.576894 -234.764072) (xy 351.576382 -234.789518)
			(xy 351.568218 -234.839752) (xy 351.552102 -234.888026) (xy 351.528451 -234.933089) (xy 351.497878 -234.973775)
			(xy 351.461174 -235.00903) (xy 351.41929 -235.03794) (xy 351.373311 -235.059757) (xy 351.324427 -235.073917)
			(xy 351.273906 -235.080051) (xy 351.223054 -235.078002) (xy 351.17319 -235.067822) (xy 351.125604 -235.049775)
			(xy 351.08153 -235.024329) (xy 351.042108 -234.992142) (xy 351.00836 -234.954048) (xy 350.981159 -234.911034)
			(xy 350.961211 -234.864214) (xy 350.949032 -234.8148) (xy 350.944937 -234.764072) (xy 350.639126 -234.764072)
			(xy 350.638636 -234.789061) (xy 350.630817 -234.838424) (xy 350.615373 -234.885956) (xy 350.592683 -234.930488)
			(xy 350.563307 -234.970921) (xy 350.527967 -235.006261) (xy 350.487534 -235.035637) (xy 350.443002 -235.058327)
			(xy 350.39547 -235.073771) (xy 350.346107 -235.08159) (xy 350.296129 -235.08159) (xy 350.246766 -235.073771)
			(xy 350.199234 -235.058327) (xy 350.154702 -235.035637) (xy 350.114269 -235.006261) (xy 350.078929 -234.970921)
			(xy 350.049553 -234.930488) (xy 350.026863 -234.885956) (xy 350.011419 -234.838424) (xy 350.0036 -234.789061)
			(xy 349.696283 -234.789061) (xy 349.696274 -234.789518) (xy 349.68811 -234.839752) (xy 349.671994 -234.888026)
			(xy 349.648343 -234.933089) (xy 349.61777 -234.973775) (xy 349.581066 -235.00903) (xy 349.539182 -235.03794)
			(xy 349.493203 -235.059757) (xy 349.444319 -235.073917) (xy 349.393798 -235.080051) (xy 349.342946 -235.078002)
			(xy 349.293082 -235.067822) (xy 349.245496 -235.049775) (xy 349.201422 -235.024329) (xy 349.162 -234.992142)
			(xy 349.128252 -234.954048) (xy 349.101051 -234.911034) (xy 349.081103 -234.864214) (xy 349.068924 -234.8148)
			(xy 349.064829 -234.764072) (xy 348.756732 -234.764072) (xy 348.75622 -234.789518) (xy 348.748056 -234.839752)
			(xy 348.73194 -234.888026) (xy 348.708289 -234.933089) (xy 348.677716 -234.973775) (xy 348.641012 -235.00903)
			(xy 348.599128 -235.03794) (xy 348.553149 -235.059757) (xy 348.504265 -235.073917) (xy 348.453744 -235.080051)
			(xy 348.402892 -235.078002) (xy 348.353028 -235.067822) (xy 348.305442 -235.049775) (xy 348.261368 -235.024329)
			(xy 348.221946 -234.992142) (xy 348.188198 -234.954048) (xy 348.160997 -234.911034) (xy 348.141049 -234.864214)
			(xy 348.12887 -234.8148) (xy 348.124775 -234.764072) (xy 347.819218 -234.764072) (xy 347.818728 -234.789061)
			(xy 347.810909 -234.838424) (xy 347.795465 -234.885956) (xy 347.772775 -234.930488) (xy 347.743399 -234.970921)
			(xy 347.708059 -235.006261) (xy 347.667626 -235.035637) (xy 347.623094 -235.058327) (xy 347.575562 -235.073771)
			(xy 347.526199 -235.08159) (xy 347.476221 -235.08159) (xy 347.426858 -235.073771) (xy 347.379326 -235.058327)
			(xy 347.334794 -235.035637) (xy 347.294361 -235.006261) (xy 347.259021 -234.970921) (xy 347.229645 -234.930488)
			(xy 347.206955 -234.885956) (xy 347.191511 -234.838424) (xy 347.183692 -234.789061) (xy 346.876375 -234.789061)
			(xy 346.876366 -234.789518) (xy 346.868202 -234.839752) (xy 346.852086 -234.888026) (xy 346.828435 -234.933089)
			(xy 346.797862 -234.973775) (xy 346.761158 -235.00903) (xy 346.719274 -235.03794) (xy 346.673295 -235.059757)
			(xy 346.624411 -235.073917) (xy 346.57389 -235.080051) (xy 346.523038 -235.078002) (xy 346.473174 -235.067822)
			(xy 346.425588 -235.049775) (xy 346.381514 -235.024329) (xy 346.342092 -234.992142) (xy 346.308344 -234.954048)
			(xy 346.281143 -234.911034) (xy 346.261195 -234.864214) (xy 346.249016 -234.8148) (xy 346.244921 -234.764072)
			(xy 345.936824 -234.764072) (xy 345.936312 -234.789518) (xy 345.928148 -234.839752) (xy 345.912032 -234.888026)
			(xy 345.888381 -234.933089) (xy 345.857808 -234.973775) (xy 345.821104 -235.00903) (xy 345.77922 -235.03794)
			(xy 345.733241 -235.059757) (xy 345.684357 -235.073917) (xy 345.633836 -235.080051) (xy 345.582984 -235.078002)
			(xy 345.53312 -235.067822) (xy 345.485534 -235.049775) (xy 345.44146 -235.024329) (xy 345.402038 -234.992142)
			(xy 345.36829 -234.954048) (xy 345.341089 -234.911034) (xy 345.321141 -234.864214) (xy 345.308962 -234.8148)
			(xy 345.304867 -234.764072) (xy 344.999056 -234.764072) (xy 344.999056 -234.764326) (xy 344.997786 -234.793536)
			(xy 344.997532 -234.798108) (xy 344.997532 -235.15955) (xy 344.998044 -235.169302) (xy 345.005486 -235.187337)
			(xy 345.01201 -235.194602) (xy 345.072462 -235.247688) (xy 345.079274 -235.252715) (xy 345.095244 -235.258302)
			(xy 345.103704 -235.25861) (xy 345.110562 -235.25861) (xy 345.113356 -235.258356) (xy 345.122781 -235.257288)
			(xy 345.141717 -235.256147) (xy 345.151202 -235.25607) (xy 345.176193 -235.256561) (xy 345.225559 -235.26438)
			(xy 345.273094 -235.279825) (xy 345.317628 -235.302516) (xy 345.358064 -235.331895) (xy 345.393406 -235.367238)
			(xy 345.422785 -235.407674) (xy 345.445476 -235.452208) (xy 345.460921 -235.499743) (xy 345.46874 -235.549109)
			(xy 345.46874 -235.599067) (xy 345.773484 -235.599067) (xy 345.773484 -235.549089) (xy 345.781303 -235.499726)
			(xy 345.796747 -235.452194) (xy 345.819437 -235.407662) (xy 345.848813 -235.367229) (xy 345.884153 -235.331889)
			(xy 345.924586 -235.302513) (xy 345.969118 -235.279823) (xy 346.01665 -235.264379) (xy 346.066013 -235.25656)
			(xy 346.115991 -235.25656) (xy 346.165354 -235.264379) (xy 346.212886 -235.279823) (xy 346.257418 -235.302513)
			(xy 346.297851 -235.331889) (xy 346.333191 -235.367229) (xy 346.362567 -235.407662) (xy 346.385257 -235.452194)
			(xy 346.400701 -235.499726) (xy 346.40852 -235.549089) (xy 346.40901 -235.574078) (xy 346.40852 -235.599067)
			(xy 346.713538 -235.599067) (xy 346.713538 -235.549089) (xy 346.721357 -235.499726) (xy 346.736801 -235.452194)
			(xy 346.759491 -235.407662) (xy 346.788867 -235.367229) (xy 346.824207 -235.331889) (xy 346.86464 -235.302513)
			(xy 346.909172 -235.279823) (xy 346.956704 -235.264379) (xy 347.006067 -235.25656) (xy 347.056045 -235.25656)
			(xy 347.105408 -235.264379) (xy 347.15294 -235.279823) (xy 347.197472 -235.302513) (xy 347.237905 -235.331889)
			(xy 347.273245 -235.367229) (xy 347.302621 -235.407662) (xy 347.325311 -235.452194) (xy 347.340755 -235.499726)
			(xy 347.348574 -235.549089) (xy 347.349064 -235.574078) (xy 347.348574 -235.599067) (xy 347.653592 -235.599067)
			(xy 347.653592 -235.549089) (xy 347.661411 -235.499726) (xy 347.676855 -235.452194) (xy 347.699545 -235.407662)
			(xy 347.728921 -235.367229) (xy 347.764261 -235.331889) (xy 347.804694 -235.302513) (xy 347.849226 -235.279823)
			(xy 347.896758 -235.264379) (xy 347.946121 -235.25656) (xy 347.996099 -235.25656) (xy 348.045462 -235.264379)
			(xy 348.092994 -235.279823) (xy 348.137526 -235.302513) (xy 348.177959 -235.331889) (xy 348.213299 -235.367229)
			(xy 348.242675 -235.407662) (xy 348.265365 -235.452194) (xy 348.280809 -235.499726) (xy 348.288628 -235.549089)
			(xy 348.289118 -235.574078) (xy 348.288628 -235.599067) (xy 348.593646 -235.599067) (xy 348.593646 -235.549089)
			(xy 348.601465 -235.499726) (xy 348.616909 -235.452194) (xy 348.639599 -235.407662) (xy 348.668975 -235.367229)
			(xy 348.704315 -235.331889) (xy 348.744748 -235.302513) (xy 348.78928 -235.279823) (xy 348.836812 -235.264379)
			(xy 348.886175 -235.25656) (xy 348.936153 -235.25656) (xy 348.985516 -235.264379) (xy 349.033048 -235.279823)
			(xy 349.07758 -235.302513) (xy 349.118013 -235.331889) (xy 349.153353 -235.367229) (xy 349.182729 -235.407662)
			(xy 349.205419 -235.452194) (xy 349.220863 -235.499726) (xy 349.228682 -235.549089) (xy 349.229172 -235.574078)
			(xy 349.228682 -235.599067) (xy 349.5337 -235.599067) (xy 349.5337 -235.549089) (xy 349.541519 -235.499726)
			(xy 349.556963 -235.452194) (xy 349.579653 -235.407662) (xy 349.609029 -235.367229) (xy 349.644369 -235.331889)
			(xy 349.684802 -235.302513) (xy 349.729334 -235.279823) (xy 349.776866 -235.264379) (xy 349.826229 -235.25656)
			(xy 349.876207 -235.25656) (xy 349.92557 -235.264379) (xy 349.973102 -235.279823) (xy 350.017634 -235.302513)
			(xy 350.058067 -235.331889) (xy 350.093407 -235.367229) (xy 350.122783 -235.407662) (xy 350.145473 -235.452194)
			(xy 350.160917 -235.499726) (xy 350.168736 -235.549089) (xy 350.169226 -235.574078) (xy 350.168736 -235.599067)
			(xy 350.4735 -235.599067) (xy 350.4735 -235.549089) (xy 350.481319 -235.499726) (xy 350.496763 -235.452194)
			(xy 350.519453 -235.407662) (xy 350.548829 -235.367229) (xy 350.584169 -235.331889) (xy 350.624602 -235.302513)
			(xy 350.669134 -235.279823) (xy 350.716666 -235.264379) (xy 350.766029 -235.25656) (xy 350.816007 -235.25656)
			(xy 350.86537 -235.264379) (xy 350.912902 -235.279823) (xy 350.957434 -235.302513) (xy 350.997867 -235.331889)
			(xy 351.033207 -235.367229) (xy 351.062583 -235.407662) (xy 351.085273 -235.452194) (xy 351.100717 -235.499726)
			(xy 351.108536 -235.549089) (xy 351.109026 -235.574078) (xy 351.108536 -235.599067) (xy 351.413554 -235.599067)
			(xy 351.413554 -235.549089) (xy 351.421373 -235.499726) (xy 351.436817 -235.452194) (xy 351.459507 -235.407662)
			(xy 351.488883 -235.367229) (xy 351.524223 -235.331889) (xy 351.564656 -235.302513) (xy 351.609188 -235.279823)
			(xy 351.65672 -235.264379) (xy 351.706083 -235.25656) (xy 351.756061 -235.25656) (xy 351.805424 -235.264379)
			(xy 351.852956 -235.279823) (xy 351.897488 -235.302513) (xy 351.937921 -235.331889) (xy 351.973261 -235.367229)
			(xy 352.002637 -235.407662) (xy 352.025327 -235.452194) (xy 352.040771 -235.499726) (xy 352.04859 -235.549089)
			(xy 352.04908 -235.574078) (xy 352.04859 -235.599067) (xy 352.353608 -235.599067) (xy 352.353608 -235.549089)
			(xy 352.361427 -235.499726) (xy 352.376871 -235.452194) (xy 352.399561 -235.407662) (xy 352.428937 -235.367229)
			(xy 352.464277 -235.331889) (xy 352.50471 -235.302513) (xy 352.549242 -235.279823) (xy 352.596774 -235.264379)
			(xy 352.646137 -235.25656) (xy 352.696115 -235.25656) (xy 352.745478 -235.264379) (xy 352.79301 -235.279823)
			(xy 352.837542 -235.302513) (xy 352.877975 -235.331889) (xy 352.913315 -235.367229) (xy 352.942691 -235.407662)
			(xy 352.965381 -235.452194) (xy 352.980825 -235.499726) (xy 352.988644 -235.549089) (xy 352.989134 -235.574078)
			(xy 352.988644 -235.599067) (xy 353.293662 -235.599067) (xy 353.293662 -235.549089) (xy 353.301481 -235.499726)
			(xy 353.316925 -235.452194) (xy 353.339615 -235.407662) (xy 353.368991 -235.367229) (xy 353.404331 -235.331889)
			(xy 353.444764 -235.302513) (xy 353.489296 -235.279823) (xy 353.536828 -235.264379) (xy 353.586191 -235.25656)
			(xy 353.636169 -235.25656) (xy 353.685532 -235.264379) (xy 353.733064 -235.279823) (xy 353.777596 -235.302513)
			(xy 353.818029 -235.331889) (xy 353.853369 -235.367229) (xy 353.882745 -235.407662) (xy 353.905435 -235.452194)
			(xy 353.920879 -235.499726) (xy 353.928698 -235.549089) (xy 353.929188 -235.574078) (xy 353.928698 -235.599067)
			(xy 354.233716 -235.599067) (xy 354.233716 -235.549089) (xy 354.241535 -235.499726) (xy 354.256979 -235.452194)
			(xy 354.279669 -235.407662) (xy 354.309045 -235.367229) (xy 354.344385 -235.331889) (xy 354.384818 -235.302513)
			(xy 354.42935 -235.279823) (xy 354.476882 -235.264379) (xy 354.526245 -235.25656) (xy 354.576223 -235.25656)
			(xy 354.625586 -235.264379) (xy 354.673118 -235.279823) (xy 354.71765 -235.302513) (xy 354.758083 -235.331889)
			(xy 354.793423 -235.367229) (xy 354.822799 -235.407662) (xy 354.845489 -235.452194) (xy 354.860933 -235.499726)
			(xy 354.868752 -235.549089) (xy 354.869242 -235.574078) (xy 354.868752 -235.599067) (xy 355.173516 -235.599067)
			(xy 355.173516 -235.549089) (xy 355.181335 -235.499726) (xy 355.196779 -235.452194) (xy 355.219469 -235.407662)
			(xy 355.248845 -235.367229) (xy 355.284185 -235.331889) (xy 355.324618 -235.302513) (xy 355.36915 -235.279823)
			(xy 355.416682 -235.264379) (xy 355.466045 -235.25656) (xy 355.516023 -235.25656) (xy 355.565386 -235.264379)
			(xy 355.612918 -235.279823) (xy 355.65745 -235.302513) (xy 355.697883 -235.331889) (xy 355.733223 -235.367229)
			(xy 355.762599 -235.407662) (xy 355.785289 -235.452194) (xy 355.800733 -235.499726) (xy 355.808552 -235.549089)
			(xy 355.809042 -235.574078) (xy 356.114853 -235.574078) (xy 356.118948 -235.52335) (xy 356.131127 -235.473936)
			(xy 356.151075 -235.427116) (xy 356.178276 -235.384102) (xy 356.212024 -235.346008) (xy 356.251446 -235.313821)
			(xy 356.29552 -235.288375) (xy 356.343106 -235.270328) (xy 356.39297 -235.260148) (xy 356.443822 -235.258099)
			(xy 356.494343 -235.264233) (xy 356.543227 -235.278393) (xy 356.589206 -235.30021) (xy 356.63109 -235.32912)
			(xy 356.667794 -235.364375) (xy 356.698367 -235.405061) (xy 356.722018 -235.450124) (xy 356.738134 -235.498398)
			(xy 356.746298 -235.548632) (xy 356.74681 -235.574078) (xy 357.054907 -235.574078) (xy 357.059002 -235.52335)
			(xy 357.071181 -235.473936) (xy 357.091129 -235.427116) (xy 357.11833 -235.384102) (xy 357.152078 -235.346008)
			(xy 357.1915 -235.313821) (xy 357.235574 -235.288375) (xy 357.28316 -235.270328) (xy 357.333024 -235.260148)
			(xy 357.383876 -235.258099) (xy 357.434397 -235.264233) (xy 357.483281 -235.278393) (xy 357.52926 -235.30021)
			(xy 357.571144 -235.32912) (xy 357.607848 -235.364375) (xy 357.638421 -235.405061) (xy 357.662072 -235.450124)
			(xy 357.678188 -235.498398) (xy 357.686352 -235.548632) (xy 357.686864 -235.574078) (xy 357.686361 -235.599067)
			(xy 357.993678 -235.599067) (xy 357.993678 -235.549089) (xy 358.001497 -235.499726) (xy 358.016941 -235.452194)
			(xy 358.039631 -235.407662) (xy 358.069007 -235.367229) (xy 358.104347 -235.331889) (xy 358.14478 -235.302513)
			(xy 358.189312 -235.279823) (xy 358.236844 -235.264379) (xy 358.286207 -235.25656) (xy 358.336185 -235.25656)
			(xy 358.385548 -235.264379) (xy 358.43308 -235.279823) (xy 358.477612 -235.302513) (xy 358.518045 -235.331889)
			(xy 358.553385 -235.367229) (xy 358.582761 -235.407662) (xy 358.605451 -235.452194) (xy 358.620895 -235.499726)
			(xy 358.628714 -235.549089) (xy 358.629204 -235.574078) (xy 358.628714 -235.599067) (xy 360.807236 -235.599067)
			(xy 360.807236 -235.549089) (xy 360.815055 -235.499726) (xy 360.830499 -235.452194) (xy 360.853189 -235.407662)
			(xy 360.882565 -235.367229) (xy 360.917905 -235.331889) (xy 360.958338 -235.302513) (xy 361.00287 -235.279823)
			(xy 361.050402 -235.264379) (xy 361.099765 -235.25656) (xy 361.149743 -235.25656) (xy 361.199106 -235.264379)
			(xy 361.246638 -235.279823) (xy 361.29117 -235.302513) (xy 361.331603 -235.331889) (xy 361.366943 -235.367229)
			(xy 361.396319 -235.407662) (xy 361.419009 -235.452194) (xy 361.434453 -235.499726) (xy 361.442272 -235.549089)
			(xy 361.442762 -235.574078) (xy 361.748573 -235.574078) (xy 361.752668 -235.52335) (xy 361.764847 -235.473936)
			(xy 361.784795 -235.427116) (xy 361.811996 -235.384102) (xy 361.845744 -235.346008) (xy 361.885166 -235.313821)
			(xy 361.92924 -235.288375) (xy 361.976826 -235.270328) (xy 362.02669 -235.260148) (xy 362.077542 -235.258099)
			(xy 362.128063 -235.264233) (xy 362.176947 -235.278393) (xy 362.222926 -235.30021) (xy 362.26481 -235.32912)
			(xy 362.301514 -235.364375) (xy 362.332087 -235.405061) (xy 362.355738 -235.450124) (xy 362.371854 -235.498398)
			(xy 362.380018 -235.548632) (xy 362.38053 -235.574078) (xy 362.688627 -235.574078) (xy 362.692722 -235.52335)
			(xy 362.704901 -235.473936) (xy 362.724849 -235.427116) (xy 362.75205 -235.384102) (xy 362.785798 -235.346008)
			(xy 362.82522 -235.313821) (xy 362.869294 -235.288375) (xy 362.91688 -235.270328) (xy 362.966744 -235.260148)
			(xy 363.017596 -235.258099) (xy 363.068117 -235.264233) (xy 363.117001 -235.278393) (xy 363.16298 -235.30021)
			(xy 363.204864 -235.32912) (xy 363.241568 -235.364375) (xy 363.272141 -235.405061) (xy 363.295792 -235.450124)
			(xy 363.311908 -235.498398) (xy 363.320072 -235.548632) (xy 363.320584 -235.574078) (xy 363.320081 -235.599067)
			(xy 363.627398 -235.599067) (xy 363.627398 -235.549089) (xy 363.635217 -235.499726) (xy 363.650661 -235.452194)
			(xy 363.673351 -235.407662) (xy 363.702727 -235.367229) (xy 363.738067 -235.331889) (xy 363.7785 -235.302513)
			(xy 363.823032 -235.279823) (xy 363.870564 -235.264379) (xy 363.919927 -235.25656) (xy 363.969905 -235.25656)
			(xy 364.019268 -235.264379) (xy 364.0668 -235.279823) (xy 364.111332 -235.302513) (xy 364.151765 -235.331889)
			(xy 364.187105 -235.367229) (xy 364.216481 -235.407662) (xy 364.239171 -235.452194) (xy 364.254615 -235.499726)
			(xy 364.262434 -235.549089) (xy 364.262924 -235.574078) (xy 364.262434 -235.599067) (xy 364.567198 -235.599067)
			(xy 364.567198 -235.549089) (xy 364.575017 -235.499726) (xy 364.590461 -235.452194) (xy 364.613151 -235.407662)
			(xy 364.642527 -235.367229) (xy 364.677867 -235.331889) (xy 364.7183 -235.302513) (xy 364.762832 -235.279823)
			(xy 364.810364 -235.264379) (xy 364.859727 -235.25656) (xy 364.909705 -235.25656) (xy 364.959068 -235.264379)
			(xy 365.0066 -235.279823) (xy 365.051132 -235.302513) (xy 365.091565 -235.331889) (xy 365.126905 -235.367229)
			(xy 365.156281 -235.407662) (xy 365.178971 -235.452194) (xy 365.194415 -235.499726) (xy 365.202234 -235.549089)
			(xy 365.202724 -235.574078) (xy 365.202234 -235.599067) (xy 365.507252 -235.599067) (xy 365.507252 -235.549089)
			(xy 365.515071 -235.499726) (xy 365.530515 -235.452194) (xy 365.553205 -235.407662) (xy 365.582581 -235.367229)
			(xy 365.617921 -235.331889) (xy 365.658354 -235.302513) (xy 365.702886 -235.279823) (xy 365.750418 -235.264379)
			(xy 365.799781 -235.25656) (xy 365.849759 -235.25656) (xy 365.899122 -235.264379) (xy 365.946654 -235.279823)
			(xy 365.991186 -235.302513) (xy 366.031619 -235.331889) (xy 366.066959 -235.367229) (xy 366.096335 -235.407662)
			(xy 366.119025 -235.452194) (xy 366.134469 -235.499726) (xy 366.142288 -235.549089) (xy 366.142778 -235.574078)
			(xy 366.142288 -235.599067) (xy 366.447306 -235.599067) (xy 366.447306 -235.549089) (xy 366.455125 -235.499726)
			(xy 366.470569 -235.452194) (xy 366.493259 -235.407662) (xy 366.522635 -235.367229) (xy 366.557975 -235.331889)
			(xy 366.598408 -235.302513) (xy 366.64294 -235.279823) (xy 366.690472 -235.264379) (xy 366.739835 -235.25656)
			(xy 366.789813 -235.25656) (xy 366.839176 -235.264379) (xy 366.886708 -235.279823) (xy 366.93124 -235.302513)
			(xy 366.971673 -235.331889) (xy 367.007013 -235.367229) (xy 367.036389 -235.407662) (xy 367.059079 -235.452194)
			(xy 367.074523 -235.499726) (xy 367.082342 -235.549089) (xy 367.082832 -235.574078) (xy 367.082342 -235.599067)
			(xy 367.38736 -235.599067) (xy 367.38736 -235.549089) (xy 367.395179 -235.499726) (xy 367.410623 -235.452194)
			(xy 367.433313 -235.407662) (xy 367.462689 -235.367229) (xy 367.498029 -235.331889) (xy 367.538462 -235.302513)
			(xy 367.582994 -235.279823) (xy 367.630526 -235.264379) (xy 367.679889 -235.25656) (xy 367.729867 -235.25656)
			(xy 367.77923 -235.264379) (xy 367.826762 -235.279823) (xy 367.871294 -235.302513) (xy 367.911727 -235.331889)
			(xy 367.947067 -235.367229) (xy 367.976443 -235.407662) (xy 367.999133 -235.452194) (xy 368.014577 -235.499726)
			(xy 368.022396 -235.549089) (xy 368.022886 -235.574078) (xy 368.022396 -235.599067) (xy 368.32716 -235.599067)
			(xy 368.32716 -235.549089) (xy 368.334979 -235.499726) (xy 368.350423 -235.452194) (xy 368.373113 -235.407662)
			(xy 368.402489 -235.367229) (xy 368.437829 -235.331889) (xy 368.478262 -235.302513) (xy 368.522794 -235.279823)
			(xy 368.570326 -235.264379) (xy 368.619689 -235.25656) (xy 368.669667 -235.25656) (xy 368.71903 -235.264379)
			(xy 368.766562 -235.279823) (xy 368.811094 -235.302513) (xy 368.851527 -235.331889) (xy 368.886867 -235.367229)
			(xy 368.916243 -235.407662) (xy 368.938933 -235.452194) (xy 368.954377 -235.499726) (xy 368.962196 -235.549089)
			(xy 368.962686 -235.574078) (xy 368.962196 -235.599067) (xy 369.267214 -235.599067) (xy 369.267214 -235.549089)
			(xy 369.275033 -235.499726) (xy 369.290477 -235.452194) (xy 369.313167 -235.407662) (xy 369.342543 -235.367229)
			(xy 369.377883 -235.331889) (xy 369.418316 -235.302513) (xy 369.462848 -235.279823) (xy 369.51038 -235.264379)
			(xy 369.559743 -235.25656) (xy 369.609721 -235.25656) (xy 369.659084 -235.264379) (xy 369.706616 -235.279823)
			(xy 369.751148 -235.302513) (xy 369.791581 -235.331889) (xy 369.826921 -235.367229) (xy 369.856297 -235.407662)
			(xy 369.878987 -235.452194) (xy 369.894431 -235.499726) (xy 369.90225 -235.549089) (xy 369.90274 -235.574078)
			(xy 369.90225 -235.599067) (xy 370.207268 -235.599067) (xy 370.207268 -235.549089) (xy 370.215087 -235.499726)
			(xy 370.230531 -235.452194) (xy 370.253221 -235.407662) (xy 370.282597 -235.367229) (xy 370.317937 -235.331889)
			(xy 370.35837 -235.302513) (xy 370.402902 -235.279823) (xy 370.450434 -235.264379) (xy 370.499797 -235.25656)
			(xy 370.549775 -235.25656) (xy 370.599138 -235.264379) (xy 370.64667 -235.279823) (xy 370.691202 -235.302513)
			(xy 370.731635 -235.331889) (xy 370.766975 -235.367229) (xy 370.796351 -235.407662) (xy 370.819041 -235.452194)
			(xy 370.834485 -235.499726) (xy 370.842304 -235.549089) (xy 370.842794 -235.574078) (xy 370.842304 -235.599067)
			(xy 371.147322 -235.599067) (xy 371.147322 -235.549089) (xy 371.155141 -235.499726) (xy 371.170585 -235.452194)
			(xy 371.193275 -235.407662) (xy 371.222651 -235.367229) (xy 371.257991 -235.331889) (xy 371.298424 -235.302513)
			(xy 371.342956 -235.279823) (xy 371.390488 -235.264379) (xy 371.439851 -235.25656) (xy 371.489829 -235.25656)
			(xy 371.539192 -235.264379) (xy 371.586724 -235.279823) (xy 371.631256 -235.302513) (xy 371.671689 -235.331889)
			(xy 371.707029 -235.367229) (xy 371.736405 -235.407662) (xy 371.759095 -235.452194) (xy 371.774539 -235.499726)
			(xy 371.782358 -235.549089) (xy 371.782848 -235.574078) (xy 371.782358 -235.599067) (xy 372.087376 -235.599067)
			(xy 372.087376 -235.549089) (xy 372.095195 -235.499726) (xy 372.110639 -235.452194) (xy 372.133329 -235.407662)
			(xy 372.162705 -235.367229) (xy 372.198045 -235.331889) (xy 372.238478 -235.302513) (xy 372.28301 -235.279823)
			(xy 372.330542 -235.264379) (xy 372.379905 -235.25656) (xy 372.429883 -235.25656) (xy 372.479246 -235.264379)
			(xy 372.526778 -235.279823) (xy 372.57131 -235.302513) (xy 372.611743 -235.331889) (xy 372.647083 -235.367229)
			(xy 372.676459 -235.407662) (xy 372.699149 -235.452194) (xy 372.714593 -235.499726) (xy 372.722412 -235.549089)
			(xy 372.722902 -235.574078) (xy 372.722412 -235.599067) (xy 373.027176 -235.599067) (xy 373.027176 -235.549089)
			(xy 373.034995 -235.499726) (xy 373.050439 -235.452194) (xy 373.073129 -235.407662) (xy 373.102505 -235.367229)
			(xy 373.137845 -235.331889) (xy 373.178278 -235.302513) (xy 373.22281 -235.279823) (xy 373.270342 -235.264379)
			(xy 373.319705 -235.25656) (xy 373.369683 -235.25656) (xy 373.419046 -235.264379) (xy 373.466578 -235.279823)
			(xy 373.51111 -235.302513) (xy 373.551543 -235.331889) (xy 373.586883 -235.367229) (xy 373.616259 -235.407662)
			(xy 373.638949 -235.452194) (xy 373.654393 -235.499726) (xy 373.662212 -235.549089) (xy 373.662702 -235.574078)
			(xy 373.662212 -235.599067) (xy 373.654393 -235.64843) (xy 373.638949 -235.695962) (xy 373.616259 -235.740494)
			(xy 373.586883 -235.780927) (xy 373.551543 -235.816267) (xy 373.51111 -235.845643) (xy 373.466578 -235.868333)
			(xy 373.419046 -235.883777) (xy 373.369683 -235.891596) (xy 373.319705 -235.891596) (xy 373.270342 -235.883777)
			(xy 373.22281 -235.868333) (xy 373.178278 -235.845643) (xy 373.137845 -235.816267) (xy 373.102505 -235.780927)
			(xy 373.073129 -235.740494) (xy 373.050439 -235.695962) (xy 373.034995 -235.64843) (xy 373.027176 -235.599067)
			(xy 372.722412 -235.599067) (xy 372.714593 -235.64843) (xy 372.699149 -235.695962) (xy 372.676459 -235.740494)
			(xy 372.647083 -235.780927) (xy 372.611743 -235.816267) (xy 372.57131 -235.845643) (xy 372.526778 -235.868333)
			(xy 372.479246 -235.883777) (xy 372.429883 -235.891596) (xy 372.379905 -235.891596) (xy 372.330542 -235.883777)
			(xy 372.28301 -235.868333) (xy 372.238478 -235.845643) (xy 372.198045 -235.816267) (xy 372.162705 -235.780927)
			(xy 372.133329 -235.740494) (xy 372.110639 -235.695962) (xy 372.095195 -235.64843) (xy 372.087376 -235.599067)
			(xy 371.782358 -235.599067) (xy 371.774539 -235.64843) (xy 371.759095 -235.695962) (xy 371.736405 -235.740494)
			(xy 371.707029 -235.780927) (xy 371.671689 -235.816267) (xy 371.631256 -235.845643) (xy 371.586724 -235.868333)
			(xy 371.539192 -235.883777) (xy 371.489829 -235.891596) (xy 371.439851 -235.891596) (xy 371.390488 -235.883777)
			(xy 371.342956 -235.868333) (xy 371.298424 -235.845643) (xy 371.257991 -235.816267) (xy 371.222651 -235.780927)
			(xy 371.193275 -235.740494) (xy 371.170585 -235.695962) (xy 371.155141 -235.64843) (xy 371.147322 -235.599067)
			(xy 370.842304 -235.599067) (xy 370.834485 -235.64843) (xy 370.819041 -235.695962) (xy 370.796351 -235.740494)
			(xy 370.766975 -235.780927) (xy 370.731635 -235.816267) (xy 370.691202 -235.845643) (xy 370.64667 -235.868333)
			(xy 370.599138 -235.883777) (xy 370.549775 -235.891596) (xy 370.499797 -235.891596) (xy 370.450434 -235.883777)
			(xy 370.402902 -235.868333) (xy 370.35837 -235.845643) (xy 370.317937 -235.816267) (xy 370.282597 -235.780927)
			(xy 370.253221 -235.740494) (xy 370.230531 -235.695962) (xy 370.215087 -235.64843) (xy 370.207268 -235.599067)
			(xy 369.90225 -235.599067) (xy 369.894431 -235.64843) (xy 369.878987 -235.695962) (xy 369.856297 -235.740494)
			(xy 369.826921 -235.780927) (xy 369.791581 -235.816267) (xy 369.751148 -235.845643) (xy 369.706616 -235.868333)
			(xy 369.659084 -235.883777) (xy 369.609721 -235.891596) (xy 369.559743 -235.891596) (xy 369.51038 -235.883777)
			(xy 369.462848 -235.868333) (xy 369.418316 -235.845643) (xy 369.377883 -235.816267) (xy 369.342543 -235.780927)
			(xy 369.313167 -235.740494) (xy 369.290477 -235.695962) (xy 369.275033 -235.64843) (xy 369.267214 -235.599067)
			(xy 368.962196 -235.599067) (xy 368.954377 -235.64843) (xy 368.938933 -235.695962) (xy 368.916243 -235.740494)
			(xy 368.886867 -235.780927) (xy 368.851527 -235.816267) (xy 368.811094 -235.845643) (xy 368.766562 -235.868333)
			(xy 368.71903 -235.883777) (xy 368.669667 -235.891596) (xy 368.619689 -235.891596) (xy 368.570326 -235.883777)
			(xy 368.522794 -235.868333) (xy 368.478262 -235.845643) (xy 368.437829 -235.816267) (xy 368.402489 -235.780927)
			(xy 368.373113 -235.740494) (xy 368.350423 -235.695962) (xy 368.334979 -235.64843) (xy 368.32716 -235.599067)
			(xy 368.022396 -235.599067) (xy 368.014577 -235.64843) (xy 367.999133 -235.695962) (xy 367.976443 -235.740494)
			(xy 367.947067 -235.780927) (xy 367.911727 -235.816267) (xy 367.871294 -235.845643) (xy 367.826762 -235.868333)
			(xy 367.77923 -235.883777) (xy 367.729867 -235.891596) (xy 367.679889 -235.891596) (xy 367.630526 -235.883777)
			(xy 367.582994 -235.868333) (xy 367.538462 -235.845643) (xy 367.498029 -235.816267) (xy 367.462689 -235.780927)
			(xy 367.433313 -235.740494) (xy 367.410623 -235.695962) (xy 367.395179 -235.64843) (xy 367.38736 -235.599067)
			(xy 367.082342 -235.599067) (xy 367.074523 -235.64843) (xy 367.059079 -235.695962) (xy 367.036389 -235.740494)
			(xy 367.007013 -235.780927) (xy 366.971673 -235.816267) (xy 366.93124 -235.845643) (xy 366.886708 -235.868333)
			(xy 366.839176 -235.883777) (xy 366.789813 -235.891596) (xy 366.739835 -235.891596) (xy 366.690472 -235.883777)
			(xy 366.64294 -235.868333) (xy 366.598408 -235.845643) (xy 366.557975 -235.816267) (xy 366.522635 -235.780927)
			(xy 366.493259 -235.740494) (xy 366.470569 -235.695962) (xy 366.455125 -235.64843) (xy 366.447306 -235.599067)
			(xy 366.142288 -235.599067) (xy 366.134469 -235.64843) (xy 366.119025 -235.695962) (xy 366.096335 -235.740494)
			(xy 366.066959 -235.780927) (xy 366.031619 -235.816267) (xy 365.991186 -235.845643) (xy 365.946654 -235.868333)
			(xy 365.899122 -235.883777) (xy 365.849759 -235.891596) (xy 365.799781 -235.891596) (xy 365.750418 -235.883777)
			(xy 365.702886 -235.868333) (xy 365.658354 -235.845643) (xy 365.617921 -235.816267) (xy 365.582581 -235.780927)
			(xy 365.553205 -235.740494) (xy 365.530515 -235.695962) (xy 365.515071 -235.64843) (xy 365.507252 -235.599067)
			(xy 365.202234 -235.599067) (xy 365.194415 -235.64843) (xy 365.178971 -235.695962) (xy 365.156281 -235.740494)
			(xy 365.126905 -235.780927) (xy 365.091565 -235.816267) (xy 365.051132 -235.845643) (xy 365.0066 -235.868333)
			(xy 364.959068 -235.883777) (xy 364.909705 -235.891596) (xy 364.859727 -235.891596) (xy 364.810364 -235.883777)
			(xy 364.762832 -235.868333) (xy 364.7183 -235.845643) (xy 364.677867 -235.816267) (xy 364.642527 -235.780927)
			(xy 364.613151 -235.740494) (xy 364.590461 -235.695962) (xy 364.575017 -235.64843) (xy 364.567198 -235.599067)
			(xy 364.262434 -235.599067) (xy 364.254615 -235.64843) (xy 364.239171 -235.695962) (xy 364.216481 -235.740494)
			(xy 364.187105 -235.780927) (xy 364.151765 -235.816267) (xy 364.111332 -235.845643) (xy 364.0668 -235.868333)
			(xy 364.019268 -235.883777) (xy 363.969905 -235.891596) (xy 363.919927 -235.891596) (xy 363.870564 -235.883777)
			(xy 363.823032 -235.868333) (xy 363.7785 -235.845643) (xy 363.738067 -235.816267) (xy 363.702727 -235.780927)
			(xy 363.673351 -235.740494) (xy 363.650661 -235.695962) (xy 363.635217 -235.64843) (xy 363.627398 -235.599067)
			(xy 363.320081 -235.599067) (xy 363.320072 -235.599524) (xy 363.311908 -235.649758) (xy 363.295792 -235.698032)
			(xy 363.272141 -235.743095) (xy 363.241568 -235.783781) (xy 363.204864 -235.819036) (xy 363.16298 -235.847946)
			(xy 363.117001 -235.869763) (xy 363.068117 -235.883923) (xy 363.017596 -235.890057) (xy 362.966744 -235.888008)
			(xy 362.91688 -235.877828) (xy 362.869294 -235.859781) (xy 362.82522 -235.834335) (xy 362.785798 -235.802148)
			(xy 362.75205 -235.764054) (xy 362.724849 -235.72104) (xy 362.704901 -235.67422) (xy 362.692722 -235.624806)
			(xy 362.688627 -235.574078) (xy 362.38053 -235.574078) (xy 362.380018 -235.599524) (xy 362.371854 -235.649758)
			(xy 362.355738 -235.698032) (xy 362.332087 -235.743095) (xy 362.301514 -235.783781) (xy 362.26481 -235.819036)
			(xy 362.222926 -235.847946) (xy 362.176947 -235.869763) (xy 362.128063 -235.883923) (xy 362.077542 -235.890057)
			(xy 362.02669 -235.888008) (xy 361.976826 -235.877828) (xy 361.92924 -235.859781) (xy 361.885166 -235.834335)
			(xy 361.845744 -235.802148) (xy 361.811996 -235.764054) (xy 361.784795 -235.72104) (xy 361.764847 -235.67422)
			(xy 361.752668 -235.624806) (xy 361.748573 -235.574078) (xy 361.442762 -235.574078) (xy 361.442272 -235.599067)
			(xy 361.434453 -235.64843) (xy 361.419009 -235.695962) (xy 361.396319 -235.740494) (xy 361.366943 -235.780927)
			(xy 361.331603 -235.816267) (xy 361.29117 -235.845643) (xy 361.246638 -235.868333) (xy 361.199106 -235.883777)
			(xy 361.149743 -235.891596) (xy 361.099765 -235.891596) (xy 361.050402 -235.883777) (xy 361.00287 -235.868333)
			(xy 360.958338 -235.845643) (xy 360.917905 -235.816267) (xy 360.882565 -235.780927) (xy 360.853189 -235.740494)
			(xy 360.830499 -235.695962) (xy 360.815055 -235.64843) (xy 360.807236 -235.599067) (xy 358.628714 -235.599067)
			(xy 358.620895 -235.64843) (xy 358.605451 -235.695962) (xy 358.582761 -235.740494) (xy 358.553385 -235.780927)
			(xy 358.518045 -235.816267) (xy 358.477612 -235.845643) (xy 358.43308 -235.868333) (xy 358.385548 -235.883777)
			(xy 358.336185 -235.891596) (xy 358.286207 -235.891596) (xy 358.236844 -235.883777) (xy 358.189312 -235.868333)
			(xy 358.14478 -235.845643) (xy 358.104347 -235.816267) (xy 358.069007 -235.780927) (xy 358.039631 -235.740494)
			(xy 358.016941 -235.695962) (xy 358.001497 -235.64843) (xy 357.993678 -235.599067) (xy 357.686361 -235.599067)
			(xy 357.686352 -235.599524) (xy 357.678188 -235.649758) (xy 357.662072 -235.698032) (xy 357.638421 -235.743095)
			(xy 357.607848 -235.783781) (xy 357.571144 -235.819036) (xy 357.52926 -235.847946) (xy 357.483281 -235.869763)
			(xy 357.434397 -235.883923) (xy 357.383876 -235.890057) (xy 357.333024 -235.888008) (xy 357.28316 -235.877828)
			(xy 357.235574 -235.859781) (xy 357.1915 -235.834335) (xy 357.152078 -235.802148) (xy 357.11833 -235.764054)
			(xy 357.091129 -235.72104) (xy 357.071181 -235.67422) (xy 357.059002 -235.624806) (xy 357.054907 -235.574078)
			(xy 356.74681 -235.574078) (xy 356.746298 -235.599524) (xy 356.738134 -235.649758) (xy 356.722018 -235.698032)
			(xy 356.698367 -235.743095) (xy 356.667794 -235.783781) (xy 356.63109 -235.819036) (xy 356.589206 -235.847946)
			(xy 356.543227 -235.869763) (xy 356.494343 -235.883923) (xy 356.443822 -235.890057) (xy 356.39297 -235.888008)
			(xy 356.343106 -235.877828) (xy 356.29552 -235.859781) (xy 356.251446 -235.834335) (xy 356.212024 -235.802148)
			(xy 356.178276 -235.764054) (xy 356.151075 -235.72104) (xy 356.131127 -235.67422) (xy 356.118948 -235.624806)
			(xy 356.114853 -235.574078) (xy 355.809042 -235.574078) (xy 355.808552 -235.599067) (xy 355.800733 -235.64843)
			(xy 355.785289 -235.695962) (xy 355.762599 -235.740494) (xy 355.733223 -235.780927) (xy 355.697883 -235.816267)
			(xy 355.65745 -235.845643) (xy 355.612918 -235.868333) (xy 355.565386 -235.883777) (xy 355.516023 -235.891596)
			(xy 355.466045 -235.891596) (xy 355.416682 -235.883777) (xy 355.36915 -235.868333) (xy 355.324618 -235.845643)
			(xy 355.284185 -235.816267) (xy 355.248845 -235.780927) (xy 355.219469 -235.740494) (xy 355.196779 -235.695962)
			(xy 355.181335 -235.64843) (xy 355.173516 -235.599067) (xy 354.868752 -235.599067) (xy 354.860933 -235.64843)
			(xy 354.845489 -235.695962) (xy 354.822799 -235.740494) (xy 354.793423 -235.780927) (xy 354.758083 -235.816267)
			(xy 354.71765 -235.845643) (xy 354.673118 -235.868333) (xy 354.625586 -235.883777) (xy 354.576223 -235.891596)
			(xy 354.526245 -235.891596) (xy 354.476882 -235.883777) (xy 354.42935 -235.868333) (xy 354.384818 -235.845643)
			(xy 354.344385 -235.816267) (xy 354.309045 -235.780927) (xy 354.279669 -235.740494) (xy 354.256979 -235.695962)
			(xy 354.241535 -235.64843) (xy 354.233716 -235.599067) (xy 353.928698 -235.599067) (xy 353.920879 -235.64843)
			(xy 353.905435 -235.695962) (xy 353.882745 -235.740494) (xy 353.853369 -235.780927) (xy 353.818029 -235.816267)
			(xy 353.777596 -235.845643) (xy 353.733064 -235.868333) (xy 353.685532 -235.883777) (xy 353.636169 -235.891596)
			(xy 353.586191 -235.891596) (xy 353.536828 -235.883777) (xy 353.489296 -235.868333) (xy 353.444764 -235.845643)
			(xy 353.404331 -235.816267) (xy 353.368991 -235.780927) (xy 353.339615 -235.740494) (xy 353.316925 -235.695962)
			(xy 353.301481 -235.64843) (xy 353.293662 -235.599067) (xy 352.988644 -235.599067) (xy 352.980825 -235.64843)
			(xy 352.965381 -235.695962) (xy 352.942691 -235.740494) (xy 352.913315 -235.780927) (xy 352.877975 -235.816267)
			(xy 352.837542 -235.845643) (xy 352.79301 -235.868333) (xy 352.745478 -235.883777) (xy 352.696115 -235.891596)
			(xy 352.646137 -235.891596) (xy 352.596774 -235.883777) (xy 352.549242 -235.868333) (xy 352.50471 -235.845643)
			(xy 352.464277 -235.816267) (xy 352.428937 -235.780927) (xy 352.399561 -235.740494) (xy 352.376871 -235.695962)
			(xy 352.361427 -235.64843) (xy 352.353608 -235.599067) (xy 352.04859 -235.599067) (xy 352.040771 -235.64843)
			(xy 352.025327 -235.695962) (xy 352.002637 -235.740494) (xy 351.973261 -235.780927) (xy 351.937921 -235.816267)
			(xy 351.897488 -235.845643) (xy 351.852956 -235.868333) (xy 351.805424 -235.883777) (xy 351.756061 -235.891596)
			(xy 351.706083 -235.891596) (xy 351.65672 -235.883777) (xy 351.609188 -235.868333) (xy 351.564656 -235.845643)
			(xy 351.524223 -235.816267) (xy 351.488883 -235.780927) (xy 351.459507 -235.740494) (xy 351.436817 -235.695962)
			(xy 351.421373 -235.64843) (xy 351.413554 -235.599067) (xy 351.108536 -235.599067) (xy 351.100717 -235.64843)
			(xy 351.085273 -235.695962) (xy 351.062583 -235.740494) (xy 351.033207 -235.780927) (xy 350.997867 -235.816267)
			(xy 350.957434 -235.845643) (xy 350.912902 -235.868333) (xy 350.86537 -235.883777) (xy 350.816007 -235.891596)
			(xy 350.766029 -235.891596) (xy 350.716666 -235.883777) (xy 350.669134 -235.868333) (xy 350.624602 -235.845643)
			(xy 350.584169 -235.816267) (xy 350.548829 -235.780927) (xy 350.519453 -235.740494) (xy 350.496763 -235.695962)
			(xy 350.481319 -235.64843) (xy 350.4735 -235.599067) (xy 350.168736 -235.599067) (xy 350.160917 -235.64843)
			(xy 350.145473 -235.695962) (xy 350.122783 -235.740494) (xy 350.093407 -235.780927) (xy 350.058067 -235.816267)
			(xy 350.017634 -235.845643) (xy 349.973102 -235.868333) (xy 349.92557 -235.883777) (xy 349.876207 -235.891596)
			(xy 349.826229 -235.891596) (xy 349.776866 -235.883777) (xy 349.729334 -235.868333) (xy 349.684802 -235.845643)
			(xy 349.644369 -235.816267) (xy 349.609029 -235.780927) (xy 349.579653 -235.740494) (xy 349.556963 -235.695962)
			(xy 349.541519 -235.64843) (xy 349.5337 -235.599067) (xy 349.228682 -235.599067) (xy 349.220863 -235.64843)
			(xy 349.205419 -235.695962) (xy 349.182729 -235.740494) (xy 349.153353 -235.780927) (xy 349.118013 -235.816267)
			(xy 349.07758 -235.845643) (xy 349.033048 -235.868333) (xy 348.985516 -235.883777) (xy 348.936153 -235.891596)
			(xy 348.886175 -235.891596) (xy 348.836812 -235.883777) (xy 348.78928 -235.868333) (xy 348.744748 -235.845643)
			(xy 348.704315 -235.816267) (xy 348.668975 -235.780927) (xy 348.639599 -235.740494) (xy 348.616909 -235.695962)
			(xy 348.601465 -235.64843) (xy 348.593646 -235.599067) (xy 348.288628 -235.599067) (xy 348.280809 -235.64843)
			(xy 348.265365 -235.695962) (xy 348.242675 -235.740494) (xy 348.213299 -235.780927) (xy 348.177959 -235.816267)
			(xy 348.137526 -235.845643) (xy 348.092994 -235.868333) (xy 348.045462 -235.883777) (xy 347.996099 -235.891596)
			(xy 347.946121 -235.891596) (xy 347.896758 -235.883777) (xy 347.849226 -235.868333) (xy 347.804694 -235.845643)
			(xy 347.764261 -235.816267) (xy 347.728921 -235.780927) (xy 347.699545 -235.740494) (xy 347.676855 -235.695962)
			(xy 347.661411 -235.64843) (xy 347.653592 -235.599067) (xy 347.348574 -235.599067) (xy 347.340755 -235.64843)
			(xy 347.325311 -235.695962) (xy 347.302621 -235.740494) (xy 347.273245 -235.780927) (xy 347.237905 -235.816267)
			(xy 347.197472 -235.845643) (xy 347.15294 -235.868333) (xy 347.105408 -235.883777) (xy 347.056045 -235.891596)
			(xy 347.006067 -235.891596) (xy 346.956704 -235.883777) (xy 346.909172 -235.868333) (xy 346.86464 -235.845643)
			(xy 346.824207 -235.816267) (xy 346.788867 -235.780927) (xy 346.759491 -235.740494) (xy 346.736801 -235.695962)
			(xy 346.721357 -235.64843) (xy 346.713538 -235.599067) (xy 346.40852 -235.599067) (xy 346.400701 -235.64843)
			(xy 346.385257 -235.695962) (xy 346.362567 -235.740494) (xy 346.333191 -235.780927) (xy 346.297851 -235.816267)
			(xy 346.257418 -235.845643) (xy 346.212886 -235.868333) (xy 346.165354 -235.883777) (xy 346.115991 -235.891596)
			(xy 346.066013 -235.891596) (xy 346.01665 -235.883777) (xy 345.969118 -235.868333) (xy 345.924586 -235.845643)
			(xy 345.884153 -235.816267) (xy 345.848813 -235.780927) (xy 345.819437 -235.740494) (xy 345.796747 -235.695962)
			(xy 345.781303 -235.64843) (xy 345.773484 -235.599067) (xy 345.46874 -235.599067) (xy 345.46874 -235.599091)
			(xy 345.460921 -235.648457) (xy 345.445476 -235.695992) (xy 345.422785 -235.740526) (xy 345.393406 -235.780962)
			(xy 345.358064 -235.816305) (xy 345.317628 -235.845684) (xy 345.273094 -235.868375) (xy 345.225559 -235.88382)
			(xy 345.176193 -235.891639) (xy 345.151202 -235.892086) (xy 345.141014 -235.892021) (xy 345.120678 -235.890751)
			(xy 345.110562 -235.889546) (xy 345.09964 -235.888276) (xy 345.089988 -235.89107) (xy 345.084905 -235.892782)
			(xy 345.075557 -235.898039) (xy 345.071446 -235.901484) (xy 345.051888 -235.918502) (xy 345.01201 -235.953554)
			(xy 345.005457 -235.960803) (xy 344.998007 -235.978846) (xy 344.997532 -235.988606) (xy 344.997532 -236.350048)
			(xy 344.997786 -236.35462) (xy 344.999056 -236.38383) (xy 344.999056 -236.384084) (xy 345.304867 -236.384084)
			(xy 345.308962 -236.333356) (xy 345.321141 -236.283942) (xy 345.341089 -236.237122) (xy 345.36829 -236.194108)
			(xy 345.402038 -236.156014) (xy 345.44146 -236.123827) (xy 345.485534 -236.098381) (xy 345.53312 -236.080334)
			(xy 345.582984 -236.070154) (xy 345.633836 -236.068105) (xy 345.684357 -236.074239) (xy 345.733241 -236.088399)
			(xy 345.77922 -236.110216) (xy 345.821104 -236.139126) (xy 345.857808 -236.174381) (xy 345.888381 -236.215067)
			(xy 345.912032 -236.26013) (xy 345.928148 -236.308404) (xy 345.936312 -236.358638) (xy 345.936824 -236.384084)
			(xy 346.244921 -236.384084) (xy 346.249016 -236.333356) (xy 346.261195 -236.283942) (xy 346.281143 -236.237122)
			(xy 346.308344 -236.194108) (xy 346.342092 -236.156014) (xy 346.381514 -236.123827) (xy 346.425588 -236.098381)
			(xy 346.473174 -236.080334) (xy 346.523038 -236.070154) (xy 346.57389 -236.068105) (xy 346.624411 -236.074239)
			(xy 346.673295 -236.088399) (xy 346.719274 -236.110216) (xy 346.761158 -236.139126) (xy 346.797862 -236.174381)
			(xy 346.828435 -236.215067) (xy 346.852086 -236.26013) (xy 346.868202 -236.308404) (xy 346.876366 -236.358638)
			(xy 346.876878 -236.384084) (xy 346.876375 -236.409073) (xy 347.183692 -236.409073) (xy 347.183692 -236.359095)
			(xy 347.191511 -236.309732) (xy 347.206955 -236.2622) (xy 347.229645 -236.217668) (xy 347.259021 -236.177235)
			(xy 347.294361 -236.141895) (xy 347.334794 -236.112519) (xy 347.379326 -236.089829) (xy 347.426858 -236.074385)
			(xy 347.476221 -236.066566) (xy 347.526199 -236.066566) (xy 347.575562 -236.074385) (xy 347.623094 -236.089829)
			(xy 347.667626 -236.112519) (xy 347.708059 -236.141895) (xy 347.743399 -236.177235) (xy 347.772775 -236.217668)
			(xy 347.795465 -236.2622) (xy 347.810909 -236.309732) (xy 347.818728 -236.359095) (xy 347.819218 -236.384084)
			(xy 348.124775 -236.384084) (xy 348.12887 -236.333356) (xy 348.141049 -236.283942) (xy 348.160997 -236.237122)
			(xy 348.188198 -236.194108) (xy 348.221946 -236.156014) (xy 348.261368 -236.123827) (xy 348.305442 -236.098381)
			(xy 348.353028 -236.080334) (xy 348.402892 -236.070154) (xy 348.453744 -236.068105) (xy 348.504265 -236.074239)
			(xy 348.553149 -236.088399) (xy 348.599128 -236.110216) (xy 348.641012 -236.139126) (xy 348.677716 -236.174381)
			(xy 348.708289 -236.215067) (xy 348.73194 -236.26013) (xy 348.748056 -236.308404) (xy 348.75622 -236.358638)
			(xy 348.756732 -236.384084) (xy 349.064829 -236.384084) (xy 349.068924 -236.333356) (xy 349.081103 -236.283942)
			(xy 349.101051 -236.237122) (xy 349.128252 -236.194108) (xy 349.162 -236.156014) (xy 349.201422 -236.123827)
			(xy 349.245496 -236.098381) (xy 349.293082 -236.080334) (xy 349.342946 -236.070154) (xy 349.393798 -236.068105)
			(xy 349.444319 -236.074239) (xy 349.493203 -236.088399) (xy 349.539182 -236.110216) (xy 349.581066 -236.139126)
			(xy 349.61777 -236.174381) (xy 349.648343 -236.215067) (xy 349.671994 -236.26013) (xy 349.68811 -236.308404)
			(xy 349.696274 -236.358638) (xy 349.696786 -236.384084) (xy 349.696283 -236.409073) (xy 350.0036 -236.409073)
			(xy 350.0036 -236.359095) (xy 350.011419 -236.309732) (xy 350.026863 -236.2622) (xy 350.049553 -236.217668)
			(xy 350.078929 -236.177235) (xy 350.114269 -236.141895) (xy 350.154702 -236.112519) (xy 350.199234 -236.089829)
			(xy 350.246766 -236.074385) (xy 350.296129 -236.066566) (xy 350.346107 -236.066566) (xy 350.39547 -236.074385)
			(xy 350.443002 -236.089829) (xy 350.487534 -236.112519) (xy 350.527967 -236.141895) (xy 350.563307 -236.177235)
			(xy 350.592683 -236.217668) (xy 350.615373 -236.2622) (xy 350.630817 -236.309732) (xy 350.638636 -236.359095)
			(xy 350.639126 -236.384084) (xy 350.638636 -236.409073) (xy 352.823508 -236.409073) (xy 352.823508 -236.359095)
			(xy 352.831327 -236.309732) (xy 352.846771 -236.2622) (xy 352.869461 -236.217668) (xy 352.898837 -236.177235)
			(xy 352.934177 -236.141895) (xy 352.97461 -236.112519) (xy 353.019142 -236.089829) (xy 353.066674 -236.074385)
			(xy 353.116037 -236.066566) (xy 353.166015 -236.066566) (xy 353.215378 -236.074385) (xy 353.26291 -236.089829)
			(xy 353.307442 -236.112519) (xy 353.347875 -236.141895) (xy 353.383215 -236.177235) (xy 353.412591 -236.217668)
			(xy 353.435281 -236.2622) (xy 353.450725 -236.309732) (xy 353.458544 -236.359095) (xy 353.459034 -236.384084)
			(xy 353.458544 -236.409073) (xy 355.64367 -236.409073) (xy 355.64367 -236.359095) (xy 355.651489 -236.309732)
			(xy 355.666933 -236.2622) (xy 355.689623 -236.217668) (xy 355.718999 -236.177235) (xy 355.754339 -236.141895)
			(xy 355.794772 -236.112519) (xy 355.839304 -236.089829) (xy 355.886836 -236.074385) (xy 355.936199 -236.066566)
			(xy 355.986177 -236.066566) (xy 356.03554 -236.074385) (xy 356.083072 -236.089829) (xy 356.127604 -236.112519)
			(xy 356.168037 -236.141895) (xy 356.203377 -236.177235) (xy 356.232753 -236.217668) (xy 356.255443 -236.2622)
			(xy 356.270887 -236.309732) (xy 356.278706 -236.359095) (xy 356.279196 -236.384084) (xy 356.278706 -236.409073)
			(xy 356.583724 -236.409073) (xy 356.583724 -236.359095) (xy 356.591543 -236.309732) (xy 356.606987 -236.2622)
			(xy 356.629677 -236.217668) (xy 356.659053 -236.177235) (xy 356.694393 -236.141895) (xy 356.734826 -236.112519)
			(xy 356.779358 -236.089829) (xy 356.82689 -236.074385) (xy 356.876253 -236.066566) (xy 356.926231 -236.066566)
			(xy 356.975594 -236.074385) (xy 357.023126 -236.089829) (xy 357.067658 -236.112519) (xy 357.108091 -236.141895)
			(xy 357.143431 -236.177235) (xy 357.172807 -236.217668) (xy 357.195497 -236.2622) (xy 357.210941 -236.309732)
			(xy 357.21876 -236.359095) (xy 357.21925 -236.384084) (xy 357.21876 -236.409073) (xy 357.523524 -236.409073)
			(xy 357.523524 -236.359095) (xy 357.531343 -236.309732) (xy 357.546787 -236.2622) (xy 357.569477 -236.217668)
			(xy 357.598853 -236.177235) (xy 357.634193 -236.141895) (xy 357.674626 -236.112519) (xy 357.719158 -236.089829)
			(xy 357.76669 -236.074385) (xy 357.816053 -236.066566) (xy 357.866031 -236.066566) (xy 357.915394 -236.074385)
			(xy 357.962926 -236.089829) (xy 358.007458 -236.112519) (xy 358.047891 -236.141895) (xy 358.083231 -236.177235)
			(xy 358.112607 -236.217668) (xy 358.135297 -236.2622) (xy 358.150741 -236.309732) (xy 358.15856 -236.359095)
			(xy 358.15905 -236.384084) (xy 358.15856 -236.409073) (xy 361.27739 -236.409073) (xy 361.27739 -236.359095)
			(xy 361.285209 -236.309732) (xy 361.300653 -236.2622) (xy 361.323343 -236.217668) (xy 361.352719 -236.177235)
			(xy 361.388059 -236.141895) (xy 361.428492 -236.112519) (xy 361.473024 -236.089829) (xy 361.520556 -236.074385)
			(xy 361.569919 -236.066566) (xy 361.619897 -236.066566) (xy 361.66926 -236.074385) (xy 361.716792 -236.089829)
			(xy 361.761324 -236.112519) (xy 361.801757 -236.141895) (xy 361.837097 -236.177235) (xy 361.866473 -236.217668)
			(xy 361.889163 -236.2622) (xy 361.904607 -236.309732) (xy 361.912426 -236.359095) (xy 361.912916 -236.384084)
			(xy 361.912426 -236.409073) (xy 362.21719 -236.409073) (xy 362.21719 -236.359095) (xy 362.225009 -236.309732)
			(xy 362.240453 -236.2622) (xy 362.263143 -236.217668) (xy 362.292519 -236.177235) (xy 362.327859 -236.141895)
			(xy 362.368292 -236.112519) (xy 362.412824 -236.089829) (xy 362.460356 -236.074385) (xy 362.509719 -236.066566)
			(xy 362.559697 -236.066566) (xy 362.60906 -236.074385) (xy 362.656592 -236.089829) (xy 362.701124 -236.112519)
			(xy 362.741557 -236.141895) (xy 362.776897 -236.177235) (xy 362.806273 -236.217668) (xy 362.828963 -236.2622)
			(xy 362.844407 -236.309732) (xy 362.852226 -236.359095) (xy 362.852716 -236.384084) (xy 362.852226 -236.409073)
			(xy 363.157244 -236.409073) (xy 363.157244 -236.359095) (xy 363.165063 -236.309732) (xy 363.180507 -236.2622)
			(xy 363.203197 -236.217668) (xy 363.232573 -236.177235) (xy 363.267913 -236.141895) (xy 363.308346 -236.112519)
			(xy 363.352878 -236.089829) (xy 363.40041 -236.074385) (xy 363.449773 -236.066566) (xy 363.499751 -236.066566)
			(xy 363.549114 -236.074385) (xy 363.596646 -236.089829) (xy 363.641178 -236.112519) (xy 363.681611 -236.141895)
			(xy 363.716951 -236.177235) (xy 363.746327 -236.217668) (xy 363.769017 -236.2622) (xy 363.784461 -236.309732)
			(xy 363.79228 -236.359095) (xy 363.79277 -236.384084) (xy 363.79228 -236.409073) (xy 365.977406 -236.409073)
			(xy 365.977406 -236.359095) (xy 365.985225 -236.309732) (xy 366.000669 -236.2622) (xy 366.023359 -236.217668)
			(xy 366.052735 -236.177235) (xy 366.088075 -236.141895) (xy 366.128508 -236.112519) (xy 366.17304 -236.089829)
			(xy 366.220572 -236.074385) (xy 366.269935 -236.066566) (xy 366.319913 -236.066566) (xy 366.369276 -236.074385)
			(xy 366.416808 -236.089829) (xy 366.46134 -236.112519) (xy 366.501773 -236.141895) (xy 366.537113 -236.177235)
			(xy 366.566489 -236.217668) (xy 366.589179 -236.2622) (xy 366.604623 -236.309732) (xy 366.612442 -236.359095)
			(xy 366.612932 -236.384084) (xy 366.612442 -236.409073) (xy 368.797314 -236.409073) (xy 368.797314 -236.359095)
			(xy 368.805133 -236.309732) (xy 368.820577 -236.2622) (xy 368.843267 -236.217668) (xy 368.872643 -236.177235)
			(xy 368.907983 -236.141895) (xy 368.948416 -236.112519) (xy 368.992948 -236.089829) (xy 369.04048 -236.074385)
			(xy 369.089843 -236.066566) (xy 369.139821 -236.066566) (xy 369.189184 -236.074385) (xy 369.236716 -236.089829)
			(xy 369.281248 -236.112519) (xy 369.321681 -236.141895) (xy 369.357021 -236.177235) (xy 369.386397 -236.217668)
			(xy 369.409087 -236.2622) (xy 369.424531 -236.309732) (xy 369.43235 -236.359095) (xy 369.43284 -236.384084)
			(xy 369.738651 -236.384084) (xy 369.742746 -236.333356) (xy 369.754925 -236.283942) (xy 369.774873 -236.237122)
			(xy 369.802074 -236.194108) (xy 369.835822 -236.156014) (xy 369.875244 -236.123827) (xy 369.919318 -236.098381)
			(xy 369.966904 -236.080334) (xy 370.016768 -236.070154) (xy 370.06762 -236.068105) (xy 370.118141 -236.074239)
			(xy 370.167025 -236.088399) (xy 370.213004 -236.110216) (xy 370.254888 -236.139126) (xy 370.291592 -236.174381)
			(xy 370.322165 -236.215067) (xy 370.345816 -236.26013) (xy 370.361932 -236.308404) (xy 370.370096 -236.358638)
			(xy 370.370608 -236.384084) (xy 370.678451 -236.384084) (xy 370.682546 -236.333356) (xy 370.694725 -236.283942)
			(xy 370.714673 -236.237122) (xy 370.741874 -236.194108) (xy 370.775622 -236.156014) (xy 370.815044 -236.123827)
			(xy 370.859118 -236.098381) (xy 370.906704 -236.080334) (xy 370.956568 -236.070154) (xy 371.00742 -236.068105)
			(xy 371.057941 -236.074239) (xy 371.106825 -236.088399) (xy 371.152804 -236.110216) (xy 371.194688 -236.139126)
			(xy 371.231392 -236.174381) (xy 371.261965 -236.215067) (xy 371.285616 -236.26013) (xy 371.301732 -236.308404)
			(xy 371.309896 -236.358638) (xy 371.310408 -236.384084) (xy 371.309905 -236.409073) (xy 371.617222 -236.409073)
			(xy 371.617222 -236.359095) (xy 371.625041 -236.309732) (xy 371.640485 -236.2622) (xy 371.663175 -236.217668)
			(xy 371.692551 -236.177235) (xy 371.727891 -236.141895) (xy 371.768324 -236.112519) (xy 371.812856 -236.089829)
			(xy 371.860388 -236.074385) (xy 371.909751 -236.066566) (xy 371.959729 -236.066566) (xy 372.009092 -236.074385)
			(xy 372.056624 -236.089829) (xy 372.101156 -236.112519) (xy 372.141589 -236.141895) (xy 372.176929 -236.177235)
			(xy 372.206305 -236.217668) (xy 372.228995 -236.2622) (xy 372.244439 -236.309732) (xy 372.252258 -236.359095)
			(xy 372.252748 -236.384084) (xy 372.558559 -236.384084) (xy 372.562654 -236.333356) (xy 372.574833 -236.283942)
			(xy 372.594781 -236.237122) (xy 372.621982 -236.194108) (xy 372.65573 -236.156014) (xy 372.695152 -236.123827)
			(xy 372.739226 -236.098381) (xy 372.786812 -236.080334) (xy 372.836676 -236.070154) (xy 372.887528 -236.068105)
			(xy 372.938049 -236.074239) (xy 372.986933 -236.088399) (xy 373.032912 -236.110216) (xy 373.074796 -236.139126)
			(xy 373.1115 -236.174381) (xy 373.142073 -236.215067) (xy 373.165724 -236.26013) (xy 373.18184 -236.308404)
			(xy 373.190004 -236.358638) (xy 373.190516 -236.384084) (xy 373.498613 -236.384084) (xy 373.502708 -236.333356)
			(xy 373.514887 -236.283942) (xy 373.534835 -236.237122) (xy 373.562036 -236.194108) (xy 373.595784 -236.156014)
			(xy 373.635206 -236.123827) (xy 373.67928 -236.098381) (xy 373.726866 -236.080334) (xy 373.77673 -236.070154)
			(xy 373.827582 -236.068105) (xy 373.878103 -236.074239) (xy 373.926987 -236.088399) (xy 373.972966 -236.110216)
			(xy 374.01485 -236.139126) (xy 374.051554 -236.174381) (xy 374.082127 -236.215067) (xy 374.105778 -236.26013)
			(xy 374.121894 -236.308404) (xy 374.130058 -236.358638) (xy 374.13057 -236.384084) (xy 374.130058 -236.40953)
			(xy 374.121894 -236.459764) (xy 374.105778 -236.508038) (xy 374.082127 -236.553101) (xy 374.051554 -236.593787)
			(xy 374.01485 -236.629042) (xy 373.972966 -236.657952) (xy 373.926987 -236.679769) (xy 373.878103 -236.693929)
			(xy 373.827582 -236.700063) (xy 373.77673 -236.698014) (xy 373.726866 -236.687834) (xy 373.67928 -236.669787)
			(xy 373.635206 -236.644341) (xy 373.595784 -236.612154) (xy 373.562036 -236.57406) (xy 373.534835 -236.531046)
			(xy 373.514887 -236.484226) (xy 373.502708 -236.434812) (xy 373.498613 -236.384084) (xy 373.190516 -236.384084)
			(xy 373.190004 -236.40953) (xy 373.18184 -236.459764) (xy 373.165724 -236.508038) (xy 373.142073 -236.553101)
			(xy 373.1115 -236.593787) (xy 373.074796 -236.629042) (xy 373.032912 -236.657952) (xy 372.986933 -236.679769)
			(xy 372.938049 -236.693929) (xy 372.887528 -236.700063) (xy 372.836676 -236.698014) (xy 372.786812 -236.687834)
			(xy 372.739226 -236.669787) (xy 372.695152 -236.644341) (xy 372.65573 -236.612154) (xy 372.621982 -236.57406)
			(xy 372.594781 -236.531046) (xy 372.574833 -236.484226) (xy 372.562654 -236.434812) (xy 372.558559 -236.384084)
			(xy 372.252748 -236.384084) (xy 372.252258 -236.409073) (xy 372.244439 -236.458436) (xy 372.228995 -236.505968)
			(xy 372.206305 -236.5505) (xy 372.176929 -236.590933) (xy 372.141589 -236.626273) (xy 372.101156 -236.655649)
			(xy 372.056624 -236.678339) (xy 372.009092 -236.693783) (xy 371.959729 -236.701602) (xy 371.909751 -236.701602)
			(xy 371.860388 -236.693783) (xy 371.812856 -236.678339) (xy 371.768324 -236.655649) (xy 371.727891 -236.626273)
			(xy 371.692551 -236.590933) (xy 371.663175 -236.5505) (xy 371.640485 -236.505968) (xy 371.625041 -236.458436)
			(xy 371.617222 -236.409073) (xy 371.309905 -236.409073) (xy 371.309896 -236.40953) (xy 371.301732 -236.459764)
			(xy 371.285616 -236.508038) (xy 371.261965 -236.553101) (xy 371.231392 -236.593787) (xy 371.194688 -236.629042)
			(xy 371.152804 -236.657952) (xy 371.106825 -236.679769) (xy 371.057941 -236.693929) (xy 371.00742 -236.700063)
			(xy 370.956568 -236.698014) (xy 370.906704 -236.687834) (xy 370.859118 -236.669787) (xy 370.815044 -236.644341)
			(xy 370.775622 -236.612154) (xy 370.741874 -236.57406) (xy 370.714673 -236.531046) (xy 370.694725 -236.484226)
			(xy 370.682546 -236.434812) (xy 370.678451 -236.384084) (xy 370.370608 -236.384084) (xy 370.370096 -236.40953)
			(xy 370.361932 -236.459764) (xy 370.345816 -236.508038) (xy 370.322165 -236.553101) (xy 370.291592 -236.593787)
			(xy 370.254888 -236.629042) (xy 370.213004 -236.657952) (xy 370.167025 -236.679769) (xy 370.118141 -236.693929)
			(xy 370.06762 -236.700063) (xy 370.016768 -236.698014) (xy 369.966904 -236.687834) (xy 369.919318 -236.669787)
			(xy 369.875244 -236.644341) (xy 369.835822 -236.612154) (xy 369.802074 -236.57406) (xy 369.774873 -236.531046)
			(xy 369.754925 -236.484226) (xy 369.742746 -236.434812) (xy 369.738651 -236.384084) (xy 369.43284 -236.384084)
			(xy 369.43235 -236.409073) (xy 369.424531 -236.458436) (xy 369.409087 -236.505968) (xy 369.386397 -236.5505)
			(xy 369.357021 -236.590933) (xy 369.321681 -236.626273) (xy 369.281248 -236.655649) (xy 369.236716 -236.678339)
			(xy 369.189184 -236.693783) (xy 369.139821 -236.701602) (xy 369.089843 -236.701602) (xy 369.04048 -236.693783)
			(xy 368.992948 -236.678339) (xy 368.948416 -236.655649) (xy 368.907983 -236.626273) (xy 368.872643 -236.590933)
			(xy 368.843267 -236.5505) (xy 368.820577 -236.505968) (xy 368.805133 -236.458436) (xy 368.797314 -236.409073)
			(xy 366.612442 -236.409073) (xy 366.604623 -236.458436) (xy 366.589179 -236.505968) (xy 366.566489 -236.5505)
			(xy 366.537113 -236.590933) (xy 366.501773 -236.626273) (xy 366.46134 -236.655649) (xy 366.416808 -236.678339)
			(xy 366.369276 -236.693783) (xy 366.319913 -236.701602) (xy 366.269935 -236.701602) (xy 366.220572 -236.693783)
			(xy 366.17304 -236.678339) (xy 366.128508 -236.655649) (xy 366.088075 -236.626273) (xy 366.052735 -236.590933)
			(xy 366.023359 -236.5505) (xy 366.000669 -236.505968) (xy 365.985225 -236.458436) (xy 365.977406 -236.409073)
			(xy 363.79228 -236.409073) (xy 363.784461 -236.458436) (xy 363.769017 -236.505968) (xy 363.746327 -236.5505)
			(xy 363.716951 -236.590933) (xy 363.681611 -236.626273) (xy 363.641178 -236.655649) (xy 363.596646 -236.678339)
			(xy 363.549114 -236.693783) (xy 363.499751 -236.701602) (xy 363.449773 -236.701602) (xy 363.40041 -236.693783)
			(xy 363.352878 -236.678339) (xy 363.308346 -236.655649) (xy 363.267913 -236.626273) (xy 363.232573 -236.590933)
			(xy 363.203197 -236.5505) (xy 363.180507 -236.505968) (xy 363.165063 -236.458436) (xy 363.157244 -236.409073)
			(xy 362.852226 -236.409073) (xy 362.844407 -236.458436) (xy 362.828963 -236.505968) (xy 362.806273 -236.5505)
			(xy 362.776897 -236.590933) (xy 362.741557 -236.626273) (xy 362.701124 -236.655649) (xy 362.656592 -236.678339)
			(xy 362.60906 -236.693783) (xy 362.559697 -236.701602) (xy 362.509719 -236.701602) (xy 362.460356 -236.693783)
			(xy 362.412824 -236.678339) (xy 362.368292 -236.655649) (xy 362.327859 -236.626273) (xy 362.292519 -236.590933)
			(xy 362.263143 -236.5505) (xy 362.240453 -236.505968) (xy 362.225009 -236.458436) (xy 362.21719 -236.409073)
			(xy 361.912426 -236.409073) (xy 361.904607 -236.458436) (xy 361.889163 -236.505968) (xy 361.866473 -236.5505)
			(xy 361.837097 -236.590933) (xy 361.801757 -236.626273) (xy 361.761324 -236.655649) (xy 361.716792 -236.678339)
			(xy 361.66926 -236.693783) (xy 361.619897 -236.701602) (xy 361.569919 -236.701602) (xy 361.520556 -236.693783)
			(xy 361.473024 -236.678339) (xy 361.428492 -236.655649) (xy 361.388059 -236.626273) (xy 361.352719 -236.590933)
			(xy 361.323343 -236.5505) (xy 361.300653 -236.505968) (xy 361.285209 -236.458436) (xy 361.27739 -236.409073)
			(xy 358.15856 -236.409073) (xy 358.150741 -236.458436) (xy 358.135297 -236.505968) (xy 358.112607 -236.5505)
			(xy 358.083231 -236.590933) (xy 358.047891 -236.626273) (xy 358.007458 -236.655649) (xy 357.962926 -236.678339)
			(xy 357.915394 -236.693783) (xy 357.866031 -236.701602) (xy 357.816053 -236.701602) (xy 357.76669 -236.693783)
			(xy 357.719158 -236.678339) (xy 357.674626 -236.655649) (xy 357.634193 -236.626273) (xy 357.598853 -236.590933)
			(xy 357.569477 -236.5505) (xy 357.546787 -236.505968) (xy 357.531343 -236.458436) (xy 357.523524 -236.409073)
			(xy 357.21876 -236.409073) (xy 357.210941 -236.458436) (xy 357.195497 -236.505968) (xy 357.172807 -236.5505)
			(xy 357.143431 -236.590933) (xy 357.108091 -236.626273) (xy 357.067658 -236.655649) (xy 357.023126 -236.678339)
			(xy 356.975594 -236.693783) (xy 356.926231 -236.701602) (xy 356.876253 -236.701602) (xy 356.82689 -236.693783)
			(xy 356.779358 -236.678339) (xy 356.734826 -236.655649) (xy 356.694393 -236.626273) (xy 356.659053 -236.590933)
			(xy 356.629677 -236.5505) (xy 356.606987 -236.505968) (xy 356.591543 -236.458436) (xy 356.583724 -236.409073)
			(xy 356.278706 -236.409073) (xy 356.270887 -236.458436) (xy 356.255443 -236.505968) (xy 356.232753 -236.5505)
			(xy 356.203377 -236.590933) (xy 356.168037 -236.626273) (xy 356.127604 -236.655649) (xy 356.083072 -236.678339)
			(xy 356.03554 -236.693783) (xy 355.986177 -236.701602) (xy 355.936199 -236.701602) (xy 355.886836 -236.693783)
			(xy 355.839304 -236.678339) (xy 355.794772 -236.655649) (xy 355.754339 -236.626273) (xy 355.718999 -236.590933)
			(xy 355.689623 -236.5505) (xy 355.666933 -236.505968) (xy 355.651489 -236.458436) (xy 355.64367 -236.409073)
			(xy 353.458544 -236.409073) (xy 353.450725 -236.458436) (xy 353.435281 -236.505968) (xy 353.412591 -236.5505)
			(xy 353.383215 -236.590933) (xy 353.347875 -236.626273) (xy 353.307442 -236.655649) (xy 353.26291 -236.678339)
			(xy 353.215378 -236.693783) (xy 353.166015 -236.701602) (xy 353.116037 -236.701602) (xy 353.066674 -236.693783)
			(xy 353.019142 -236.678339) (xy 352.97461 -236.655649) (xy 352.934177 -236.626273) (xy 352.898837 -236.590933)
			(xy 352.869461 -236.5505) (xy 352.846771 -236.505968) (xy 352.831327 -236.458436) (xy 352.823508 -236.409073)
			(xy 350.638636 -236.409073) (xy 350.630817 -236.458436) (xy 350.615373 -236.505968) (xy 350.592683 -236.5505)
			(xy 350.563307 -236.590933) (xy 350.527967 -236.626273) (xy 350.487534 -236.655649) (xy 350.443002 -236.678339)
			(xy 350.39547 -236.693783) (xy 350.346107 -236.701602) (xy 350.296129 -236.701602) (xy 350.246766 -236.693783)
			(xy 350.199234 -236.678339) (xy 350.154702 -236.655649) (xy 350.114269 -236.626273) (xy 350.078929 -236.590933)
			(xy 350.049553 -236.5505) (xy 350.026863 -236.505968) (xy 350.011419 -236.458436) (xy 350.0036 -236.409073)
			(xy 349.696283 -236.409073) (xy 349.696274 -236.40953) (xy 349.68811 -236.459764) (xy 349.671994 -236.508038)
			(xy 349.648343 -236.553101) (xy 349.61777 -236.593787) (xy 349.581066 -236.629042) (xy 349.539182 -236.657952)
			(xy 349.493203 -236.679769) (xy 349.444319 -236.693929) (xy 349.393798 -236.700063) (xy 349.342946 -236.698014)
			(xy 349.293082 -236.687834) (xy 349.245496 -236.669787) (xy 349.201422 -236.644341) (xy 349.162 -236.612154)
			(xy 349.128252 -236.57406) (xy 349.101051 -236.531046) (xy 349.081103 -236.484226) (xy 349.068924 -236.434812)
			(xy 349.064829 -236.384084) (xy 348.756732 -236.384084) (xy 348.75622 -236.40953) (xy 348.748056 -236.459764)
			(xy 348.73194 -236.508038) (xy 348.708289 -236.553101) (xy 348.677716 -236.593787) (xy 348.641012 -236.629042)
			(xy 348.599128 -236.657952) (xy 348.553149 -236.679769) (xy 348.504265 -236.693929) (xy 348.453744 -236.700063)
			(xy 348.402892 -236.698014) (xy 348.353028 -236.687834) (xy 348.305442 -236.669787) (xy 348.261368 -236.644341)
			(xy 348.221946 -236.612154) (xy 348.188198 -236.57406) (xy 348.160997 -236.531046) (xy 348.141049 -236.484226)
			(xy 348.12887 -236.434812) (xy 348.124775 -236.384084) (xy 347.819218 -236.384084) (xy 347.818728 -236.409073)
			(xy 347.810909 -236.458436) (xy 347.795465 -236.505968) (xy 347.772775 -236.5505) (xy 347.743399 -236.590933)
			(xy 347.708059 -236.626273) (xy 347.667626 -236.655649) (xy 347.623094 -236.678339) (xy 347.575562 -236.693783)
			(xy 347.526199 -236.701602) (xy 347.476221 -236.701602) (xy 347.426858 -236.693783) (xy 347.379326 -236.678339)
			(xy 347.334794 -236.655649) (xy 347.294361 -236.626273) (xy 347.259021 -236.590933) (xy 347.229645 -236.5505)
			(xy 347.206955 -236.505968) (xy 347.191511 -236.458436) (xy 347.183692 -236.409073) (xy 346.876375 -236.409073)
			(xy 346.876366 -236.40953) (xy 346.868202 -236.459764) (xy 346.852086 -236.508038) (xy 346.828435 -236.553101)
			(xy 346.797862 -236.593787) (xy 346.761158 -236.629042) (xy 346.719274 -236.657952) (xy 346.673295 -236.679769)
			(xy 346.624411 -236.693929) (xy 346.57389 -236.700063) (xy 346.523038 -236.698014) (xy 346.473174 -236.687834)
			(xy 346.425588 -236.669787) (xy 346.381514 -236.644341) (xy 346.342092 -236.612154) (xy 346.308344 -236.57406)
			(xy 346.281143 -236.531046) (xy 346.261195 -236.484226) (xy 346.249016 -236.434812) (xy 346.244921 -236.384084)
			(xy 345.936824 -236.384084) (xy 345.936312 -236.40953) (xy 345.928148 -236.459764) (xy 345.912032 -236.508038)
			(xy 345.888381 -236.553101) (xy 345.857808 -236.593787) (xy 345.821104 -236.629042) (xy 345.77922 -236.657952)
			(xy 345.733241 -236.679769) (xy 345.684357 -236.693929) (xy 345.633836 -236.700063) (xy 345.582984 -236.698014)
			(xy 345.53312 -236.687834) (xy 345.485534 -236.669787) (xy 345.44146 -236.644341) (xy 345.402038 -236.612154)
			(xy 345.36829 -236.57406) (xy 345.341089 -236.531046) (xy 345.321141 -236.484226) (xy 345.308962 -236.434812)
			(xy 345.304867 -236.384084) (xy 344.999056 -236.384084) (xy 344.999056 -236.384338) (xy 344.997786 -236.413548)
			(xy 344.997532 -236.41812) (xy 344.997532 -236.779562) (xy 344.998047 -236.789313) (xy 345.005491 -236.807345)
			(xy 345.01201 -236.814614) (xy 345.072462 -236.8677) (xy 345.079274 -236.872726) (xy 345.095244 -236.878312)
			(xy 345.103704 -236.878622) (xy 345.110562 -236.878622) (xy 345.113356 -236.878368) (xy 345.122781 -236.8773)
			(xy 345.141717 -236.876159) (xy 345.151202 -236.876082) (xy 345.176192 -236.876573) (xy 345.225556 -236.884391)
			(xy 345.27309 -236.899836) (xy 345.317622 -236.922527) (xy 345.358056 -236.951904) (xy 345.393397 -236.987245)
			(xy 345.422774 -237.02768) (xy 345.445465 -237.072212) (xy 345.460909 -237.119746) (xy 345.468728 -237.16911)
			(xy 345.468728 -237.219079) (xy 345.773484 -237.219079) (xy 345.773484 -237.169101) (xy 345.781303 -237.119738)
			(xy 345.796747 -237.072206) (xy 345.819437 -237.027674) (xy 345.848813 -236.987241) (xy 345.884153 -236.951901)
			(xy 345.924586 -236.922525) (xy 345.969118 -236.899835) (xy 346.01665 -236.884391) (xy 346.066013 -236.876572)
			(xy 346.115991 -236.876572) (xy 346.165354 -236.884391) (xy 346.212886 -236.899835) (xy 346.257418 -236.922525)
			(xy 346.297851 -236.951901) (xy 346.333191 -236.987241) (xy 346.362567 -237.027674) (xy 346.385257 -237.072206)
			(xy 346.400701 -237.119738) (xy 346.40852 -237.169101) (xy 346.40901 -237.19409) (xy 346.40852 -237.219079)
			(xy 346.713538 -237.219079) (xy 346.713538 -237.169101) (xy 346.721357 -237.119738) (xy 346.736801 -237.072206)
			(xy 346.759491 -237.027674) (xy 346.788867 -236.987241) (xy 346.824207 -236.951901) (xy 346.86464 -236.922525)
			(xy 346.909172 -236.899835) (xy 346.956704 -236.884391) (xy 347.006067 -236.876572) (xy 347.056045 -236.876572)
			(xy 347.105408 -236.884391) (xy 347.15294 -236.899835) (xy 347.197472 -236.922525) (xy 347.237905 -236.951901)
			(xy 347.273245 -236.987241) (xy 347.302621 -237.027674) (xy 347.325311 -237.072206) (xy 347.340755 -237.119738)
			(xy 347.348574 -237.169101) (xy 347.349064 -237.19409) (xy 347.348574 -237.219079) (xy 347.653592 -237.219079)
			(xy 347.653592 -237.169101) (xy 347.661411 -237.119738) (xy 347.676855 -237.072206) (xy 347.699545 -237.027674)
			(xy 347.728921 -236.987241) (xy 347.764261 -236.951901) (xy 347.804694 -236.922525) (xy 347.849226 -236.899835)
			(xy 347.896758 -236.884391) (xy 347.946121 -236.876572) (xy 347.996099 -236.876572) (xy 348.045462 -236.884391)
			(xy 348.092994 -236.899835) (xy 348.137526 -236.922525) (xy 348.177959 -236.951901) (xy 348.213299 -236.987241)
			(xy 348.242675 -237.027674) (xy 348.265365 -237.072206) (xy 348.280809 -237.119738) (xy 348.288628 -237.169101)
			(xy 348.289118 -237.19409) (xy 348.288628 -237.219079) (xy 348.593646 -237.219079) (xy 348.593646 -237.169101)
			(xy 348.601465 -237.119738) (xy 348.616909 -237.072206) (xy 348.639599 -237.027674) (xy 348.668975 -236.987241)
			(xy 348.704315 -236.951901) (xy 348.744748 -236.922525) (xy 348.78928 -236.899835) (xy 348.836812 -236.884391)
			(xy 348.886175 -236.876572) (xy 348.936153 -236.876572) (xy 348.985516 -236.884391) (xy 349.033048 -236.899835)
			(xy 349.07758 -236.922525) (xy 349.118013 -236.951901) (xy 349.153353 -236.987241) (xy 349.182729 -237.027674)
			(xy 349.205419 -237.072206) (xy 349.220863 -237.119738) (xy 349.228682 -237.169101) (xy 349.229172 -237.19409)
			(xy 349.228682 -237.219079) (xy 349.5337 -237.219079) (xy 349.5337 -237.169101) (xy 349.541519 -237.119738)
			(xy 349.556963 -237.072206) (xy 349.579653 -237.027674) (xy 349.609029 -236.987241) (xy 349.644369 -236.951901)
			(xy 349.684802 -236.922525) (xy 349.729334 -236.899835) (xy 349.776866 -236.884391) (xy 349.826229 -236.876572)
			(xy 349.876207 -236.876572) (xy 349.92557 -236.884391) (xy 349.973102 -236.899835) (xy 350.017634 -236.922525)
			(xy 350.058067 -236.951901) (xy 350.093407 -236.987241) (xy 350.122783 -237.027674) (xy 350.145473 -237.072206)
			(xy 350.160917 -237.119738) (xy 350.168736 -237.169101) (xy 350.169226 -237.19409) (xy 350.168736 -237.219079)
			(xy 350.4735 -237.219079) (xy 350.4735 -237.169101) (xy 350.481319 -237.119738) (xy 350.496763 -237.072206)
			(xy 350.519453 -237.027674) (xy 350.548829 -236.987241) (xy 350.584169 -236.951901) (xy 350.624602 -236.922525)
			(xy 350.669134 -236.899835) (xy 350.716666 -236.884391) (xy 350.766029 -236.876572) (xy 350.816007 -236.876572)
			(xy 350.86537 -236.884391) (xy 350.912902 -236.899835) (xy 350.957434 -236.922525) (xy 350.997867 -236.951901)
			(xy 351.033207 -236.987241) (xy 351.062583 -237.027674) (xy 351.085273 -237.072206) (xy 351.100717 -237.119738)
			(xy 351.108536 -237.169101) (xy 351.109026 -237.19409) (xy 351.108536 -237.219079) (xy 351.413554 -237.219079)
			(xy 351.413554 -237.169101) (xy 351.421373 -237.119738) (xy 351.436817 -237.072206) (xy 351.459507 -237.027674)
			(xy 351.488883 -236.987241) (xy 351.524223 -236.951901) (xy 351.564656 -236.922525) (xy 351.609188 -236.899835)
			(xy 351.65672 -236.884391) (xy 351.706083 -236.876572) (xy 351.756061 -236.876572) (xy 351.805424 -236.884391)
			(xy 351.852956 -236.899835) (xy 351.897488 -236.922525) (xy 351.937921 -236.951901) (xy 351.973261 -236.987241)
			(xy 352.002637 -237.027674) (xy 352.025327 -237.072206) (xy 352.040771 -237.119738) (xy 352.04859 -237.169101)
			(xy 352.04908 -237.19409) (xy 352.04859 -237.219079) (xy 352.353608 -237.219079) (xy 352.353608 -237.169101)
			(xy 352.361427 -237.119738) (xy 352.376871 -237.072206) (xy 352.399561 -237.027674) (xy 352.428937 -236.987241)
			(xy 352.464277 -236.951901) (xy 352.50471 -236.922525) (xy 352.549242 -236.899835) (xy 352.596774 -236.884391)
			(xy 352.646137 -236.876572) (xy 352.696115 -236.876572) (xy 352.745478 -236.884391) (xy 352.79301 -236.899835)
			(xy 352.837542 -236.922525) (xy 352.877975 -236.951901) (xy 352.913315 -236.987241) (xy 352.942691 -237.027674)
			(xy 352.965381 -237.072206) (xy 352.980825 -237.119738) (xy 352.988644 -237.169101) (xy 352.989134 -237.19409)
			(xy 352.988644 -237.219079) (xy 353.293662 -237.219079) (xy 353.293662 -237.169101) (xy 353.301481 -237.119738)
			(xy 353.316925 -237.072206) (xy 353.339615 -237.027674) (xy 353.368991 -236.987241) (xy 353.404331 -236.951901)
			(xy 353.444764 -236.922525) (xy 353.489296 -236.899835) (xy 353.536828 -236.884391) (xy 353.586191 -236.876572)
			(xy 353.636169 -236.876572) (xy 353.685532 -236.884391) (xy 353.733064 -236.899835) (xy 353.777596 -236.922525)
			(xy 353.818029 -236.951901) (xy 353.853369 -236.987241) (xy 353.882745 -237.027674) (xy 353.905435 -237.072206)
			(xy 353.920879 -237.119738) (xy 353.928698 -237.169101) (xy 353.929188 -237.19409) (xy 353.928698 -237.219079)
			(xy 354.233716 -237.219079) (xy 354.233716 -237.169101) (xy 354.241535 -237.119738) (xy 354.256979 -237.072206)
			(xy 354.279669 -237.027674) (xy 354.309045 -236.987241) (xy 354.344385 -236.951901) (xy 354.384818 -236.922525)
			(xy 354.42935 -236.899835) (xy 354.476882 -236.884391) (xy 354.526245 -236.876572) (xy 354.576223 -236.876572)
			(xy 354.625586 -236.884391) (xy 354.673118 -236.899835) (xy 354.71765 -236.922525) (xy 354.758083 -236.951901)
			(xy 354.793423 -236.987241) (xy 354.822799 -237.027674) (xy 354.845489 -237.072206) (xy 354.860933 -237.119738)
			(xy 354.868752 -237.169101) (xy 354.869242 -237.19409) (xy 354.868752 -237.219079) (xy 355.173516 -237.219079)
			(xy 355.173516 -237.169101) (xy 355.181335 -237.119738) (xy 355.196779 -237.072206) (xy 355.219469 -237.027674)
			(xy 355.248845 -236.987241) (xy 355.284185 -236.951901) (xy 355.324618 -236.922525) (xy 355.36915 -236.899835)
			(xy 355.416682 -236.884391) (xy 355.466045 -236.876572) (xy 355.516023 -236.876572) (xy 355.565386 -236.884391)
			(xy 355.612918 -236.899835) (xy 355.65745 -236.922525) (xy 355.697883 -236.951901) (xy 355.733223 -236.987241)
			(xy 355.762599 -237.027674) (xy 355.785289 -237.072206) (xy 355.800733 -237.119738) (xy 355.808552 -237.169101)
			(xy 355.809042 -237.19409) (xy 355.808552 -237.219079) (xy 357.993678 -237.219079) (xy 357.993678 -237.169101)
			(xy 358.001497 -237.119738) (xy 358.016941 -237.072206) (xy 358.039631 -237.027674) (xy 358.069007 -236.987241)
			(xy 358.104347 -236.951901) (xy 358.14478 -236.922525) (xy 358.189312 -236.899835) (xy 358.236844 -236.884391)
			(xy 358.286207 -236.876572) (xy 358.336185 -236.876572) (xy 358.385548 -236.884391) (xy 358.43308 -236.899835)
			(xy 358.477612 -236.922525) (xy 358.518045 -236.951901) (xy 358.553385 -236.987241) (xy 358.582761 -237.027674)
			(xy 358.605451 -237.072206) (xy 358.620895 -237.119738) (xy 358.628714 -237.169101) (xy 358.629204 -237.19409)
			(xy 358.628714 -237.219079) (xy 360.807236 -237.219079) (xy 360.807236 -237.169101) (xy 360.815055 -237.119738)
			(xy 360.830499 -237.072206) (xy 360.853189 -237.027674) (xy 360.882565 -236.987241) (xy 360.917905 -236.951901)
			(xy 360.958338 -236.922525) (xy 361.00287 -236.899835) (xy 361.050402 -236.884391) (xy 361.099765 -236.876572)
			(xy 361.149743 -236.876572) (xy 361.199106 -236.884391) (xy 361.246638 -236.899835) (xy 361.29117 -236.922525)
			(xy 361.331603 -236.951901) (xy 361.366943 -236.987241) (xy 361.396319 -237.027674) (xy 361.419009 -237.072206)
			(xy 361.434453 -237.119738) (xy 361.442272 -237.169101) (xy 361.442762 -237.19409) (xy 361.442272 -237.219079)
			(xy 363.627398 -237.219079) (xy 363.627398 -237.169101) (xy 363.635217 -237.119738) (xy 363.650661 -237.072206)
			(xy 363.673351 -237.027674) (xy 363.702727 -236.987241) (xy 363.738067 -236.951901) (xy 363.7785 -236.922525)
			(xy 363.823032 -236.899835) (xy 363.870564 -236.884391) (xy 363.919927 -236.876572) (xy 363.969905 -236.876572)
			(xy 364.019268 -236.884391) (xy 364.0668 -236.899835) (xy 364.111332 -236.922525) (xy 364.151765 -236.951901)
			(xy 364.187105 -236.987241) (xy 364.216481 -237.027674) (xy 364.239171 -237.072206) (xy 364.254615 -237.119738)
			(xy 364.262434 -237.169101) (xy 364.262924 -237.19409) (xy 364.262434 -237.219079) (xy 364.567198 -237.219079)
			(xy 364.567198 -237.169101) (xy 364.575017 -237.119738) (xy 364.590461 -237.072206) (xy 364.613151 -237.027674)
			(xy 364.642527 -236.987241) (xy 364.677867 -236.951901) (xy 364.7183 -236.922525) (xy 364.762832 -236.899835)
			(xy 364.810364 -236.884391) (xy 364.859727 -236.876572) (xy 364.909705 -236.876572) (xy 364.959068 -236.884391)
			(xy 365.0066 -236.899835) (xy 365.051132 -236.922525) (xy 365.091565 -236.951901) (xy 365.126905 -236.987241)
			(xy 365.156281 -237.027674) (xy 365.178971 -237.072206) (xy 365.194415 -237.119738) (xy 365.202234 -237.169101)
			(xy 365.202724 -237.19409) (xy 365.202234 -237.219079) (xy 365.507252 -237.219079) (xy 365.507252 -237.169101)
			(xy 365.515071 -237.119738) (xy 365.530515 -237.072206) (xy 365.553205 -237.027674) (xy 365.582581 -236.987241)
			(xy 365.617921 -236.951901) (xy 365.658354 -236.922525) (xy 365.702886 -236.899835) (xy 365.750418 -236.884391)
			(xy 365.799781 -236.876572) (xy 365.849759 -236.876572) (xy 365.899122 -236.884391) (xy 365.946654 -236.899835)
			(xy 365.991186 -236.922525) (xy 366.031619 -236.951901) (xy 366.066959 -236.987241) (xy 366.096335 -237.027674)
			(xy 366.119025 -237.072206) (xy 366.134469 -237.119738) (xy 366.142288 -237.169101) (xy 366.142778 -237.19409)
			(xy 366.142288 -237.219079) (xy 366.447306 -237.219079) (xy 366.447306 -237.169101) (xy 366.455125 -237.119738)
			(xy 366.470569 -237.072206) (xy 366.493259 -237.027674) (xy 366.522635 -236.987241) (xy 366.557975 -236.951901)
			(xy 366.598408 -236.922525) (xy 366.64294 -236.899835) (xy 366.690472 -236.884391) (xy 366.739835 -236.876572)
			(xy 366.789813 -236.876572) (xy 366.839176 -236.884391) (xy 366.886708 -236.899835) (xy 366.93124 -236.922525)
			(xy 366.971673 -236.951901) (xy 367.007013 -236.987241) (xy 367.036389 -237.027674) (xy 367.059079 -237.072206)
			(xy 367.074523 -237.119738) (xy 367.082342 -237.169101) (xy 367.082832 -237.19409) (xy 367.082342 -237.219079)
			(xy 367.38736 -237.219079) (xy 367.38736 -237.169101) (xy 367.395179 -237.119738) (xy 367.410623 -237.072206)
			(xy 367.433313 -237.027674) (xy 367.462689 -236.987241) (xy 367.498029 -236.951901) (xy 367.538462 -236.922525)
			(xy 367.582994 -236.899835) (xy 367.630526 -236.884391) (xy 367.679889 -236.876572) (xy 367.729867 -236.876572)
			(xy 367.77923 -236.884391) (xy 367.826762 -236.899835) (xy 367.871294 -236.922525) (xy 367.911727 -236.951901)
			(xy 367.947067 -236.987241) (xy 367.976443 -237.027674) (xy 367.999133 -237.072206) (xy 368.014577 -237.119738)
			(xy 368.022396 -237.169101) (xy 368.022886 -237.19409) (xy 368.022396 -237.219079) (xy 368.32716 -237.219079)
			(xy 368.32716 -237.169101) (xy 368.334979 -237.119738) (xy 368.350423 -237.072206) (xy 368.373113 -237.027674)
			(xy 368.402489 -236.987241) (xy 368.437829 -236.951901) (xy 368.478262 -236.922525) (xy 368.522794 -236.899835)
			(xy 368.570326 -236.884391) (xy 368.619689 -236.876572) (xy 368.669667 -236.876572) (xy 368.71903 -236.884391)
			(xy 368.766562 -236.899835) (xy 368.811094 -236.922525) (xy 368.851527 -236.951901) (xy 368.886867 -236.987241)
			(xy 368.916243 -237.027674) (xy 368.938933 -237.072206) (xy 368.954377 -237.119738) (xy 368.962196 -237.169101)
			(xy 368.962686 -237.19409) (xy 368.962196 -237.219079) (xy 369.267214 -237.219079) (xy 369.267214 -237.169101)
			(xy 369.275033 -237.119738) (xy 369.290477 -237.072206) (xy 369.313167 -237.027674) (xy 369.342543 -236.987241)
			(xy 369.377883 -236.951901) (xy 369.418316 -236.922525) (xy 369.462848 -236.899835) (xy 369.51038 -236.884391)
			(xy 369.559743 -236.876572) (xy 369.609721 -236.876572) (xy 369.659084 -236.884391) (xy 369.706616 -236.899835)
			(xy 369.751148 -236.922525) (xy 369.791581 -236.951901) (xy 369.826921 -236.987241) (xy 369.856297 -237.027674)
			(xy 369.878987 -237.072206) (xy 369.894431 -237.119738) (xy 369.90225 -237.169101) (xy 369.90274 -237.19409)
			(xy 369.90225 -237.219079) (xy 370.207268 -237.219079) (xy 370.207268 -237.169101) (xy 370.215087 -237.119738)
			(xy 370.230531 -237.072206) (xy 370.253221 -237.027674) (xy 370.282597 -236.987241) (xy 370.317937 -236.951901)
			(xy 370.35837 -236.922525) (xy 370.402902 -236.899835) (xy 370.450434 -236.884391) (xy 370.499797 -236.876572)
			(xy 370.549775 -236.876572) (xy 370.599138 -236.884391) (xy 370.64667 -236.899835) (xy 370.691202 -236.922525)
			(xy 370.731635 -236.951901) (xy 370.766975 -236.987241) (xy 370.796351 -237.027674) (xy 370.819041 -237.072206)
			(xy 370.834485 -237.119738) (xy 370.842304 -237.169101) (xy 370.842794 -237.19409) (xy 370.842304 -237.219079)
			(xy 371.147322 -237.219079) (xy 371.147322 -237.169101) (xy 371.155141 -237.119738) (xy 371.170585 -237.072206)
			(xy 371.193275 -237.027674) (xy 371.222651 -236.987241) (xy 371.257991 -236.951901) (xy 371.298424 -236.922525)
			(xy 371.342956 -236.899835) (xy 371.390488 -236.884391) (xy 371.439851 -236.876572) (xy 371.489829 -236.876572)
			(xy 371.539192 -236.884391) (xy 371.586724 -236.899835) (xy 371.631256 -236.922525) (xy 371.671689 -236.951901)
			(xy 371.707029 -236.987241) (xy 371.736405 -237.027674) (xy 371.759095 -237.072206) (xy 371.774539 -237.119738)
			(xy 371.782358 -237.169101) (xy 371.782848 -237.19409) (xy 371.782358 -237.219079) (xy 372.087376 -237.219079)
			(xy 372.087376 -237.169101) (xy 372.095195 -237.119738) (xy 372.110639 -237.072206) (xy 372.133329 -237.027674)
			(xy 372.162705 -236.987241) (xy 372.198045 -236.951901) (xy 372.238478 -236.922525) (xy 372.28301 -236.899835)
			(xy 372.330542 -236.884391) (xy 372.379905 -236.876572) (xy 372.429883 -236.876572) (xy 372.479246 -236.884391)
			(xy 372.526778 -236.899835) (xy 372.57131 -236.922525) (xy 372.611743 -236.951901) (xy 372.647083 -236.987241)
			(xy 372.676459 -237.027674) (xy 372.699149 -237.072206) (xy 372.714593 -237.119738) (xy 372.722412 -237.169101)
			(xy 372.722902 -237.19409) (xy 372.722412 -237.219079) (xy 373.027176 -237.219079) (xy 373.027176 -237.169101)
			(xy 373.034995 -237.119738) (xy 373.050439 -237.072206) (xy 373.073129 -237.027674) (xy 373.102505 -236.987241)
			(xy 373.137845 -236.951901) (xy 373.178278 -236.922525) (xy 373.22281 -236.899835) (xy 373.270342 -236.884391)
			(xy 373.319705 -236.876572) (xy 373.369683 -236.876572) (xy 373.419046 -236.884391) (xy 373.466578 -236.899835)
			(xy 373.51111 -236.922525) (xy 373.551543 -236.951901) (xy 373.586883 -236.987241) (xy 373.616259 -237.027674)
			(xy 373.638949 -237.072206) (xy 373.654393 -237.119738) (xy 373.662212 -237.169101) (xy 373.662702 -237.19409)
			(xy 373.662212 -237.219079) (xy 373.654393 -237.268442) (xy 373.638949 -237.315974) (xy 373.616259 -237.360506)
			(xy 373.586883 -237.400939) (xy 373.551543 -237.436279) (xy 373.51111 -237.465655) (xy 373.466578 -237.488345)
			(xy 373.419046 -237.503789) (xy 373.369683 -237.511608) (xy 373.319705 -237.511608) (xy 373.270342 -237.503789)
			(xy 373.22281 -237.488345) (xy 373.178278 -237.465655) (xy 373.137845 -237.436279) (xy 373.102505 -237.400939)
			(xy 373.073129 -237.360506) (xy 373.050439 -237.315974) (xy 373.034995 -237.268442) (xy 373.027176 -237.219079)
			(xy 372.722412 -237.219079) (xy 372.714593 -237.268442) (xy 372.699149 -237.315974) (xy 372.676459 -237.360506)
			(xy 372.647083 -237.400939) (xy 372.611743 -237.436279) (xy 372.57131 -237.465655) (xy 372.526778 -237.488345)
			(xy 372.479246 -237.503789) (xy 372.429883 -237.511608) (xy 372.379905 -237.511608) (xy 372.330542 -237.503789)
			(xy 372.28301 -237.488345) (xy 372.238478 -237.465655) (xy 372.198045 -237.436279) (xy 372.162705 -237.400939)
			(xy 372.133329 -237.360506) (xy 372.110639 -237.315974) (xy 372.095195 -237.268442) (xy 372.087376 -237.219079)
			(xy 371.782358 -237.219079) (xy 371.774539 -237.268442) (xy 371.759095 -237.315974) (xy 371.736405 -237.360506)
			(xy 371.707029 -237.400939) (xy 371.671689 -237.436279) (xy 371.631256 -237.465655) (xy 371.586724 -237.488345)
			(xy 371.539192 -237.503789) (xy 371.489829 -237.511608) (xy 371.439851 -237.511608) (xy 371.390488 -237.503789)
			(xy 371.342956 -237.488345) (xy 371.298424 -237.465655) (xy 371.257991 -237.436279) (xy 371.222651 -237.400939)
			(xy 371.193275 -237.360506) (xy 371.170585 -237.315974) (xy 371.155141 -237.268442) (xy 371.147322 -237.219079)
			(xy 370.842304 -237.219079) (xy 370.834485 -237.268442) (xy 370.819041 -237.315974) (xy 370.796351 -237.360506)
			(xy 370.766975 -237.400939) (xy 370.731635 -237.436279) (xy 370.691202 -237.465655) (xy 370.64667 -237.488345)
			(xy 370.599138 -237.503789) (xy 370.549775 -237.511608) (xy 370.499797 -237.511608) (xy 370.450434 -237.503789)
			(xy 370.402902 -237.488345) (xy 370.35837 -237.465655) (xy 370.317937 -237.436279) (xy 370.282597 -237.400939)
			(xy 370.253221 -237.360506) (xy 370.230531 -237.315974) (xy 370.215087 -237.268442) (xy 370.207268 -237.219079)
			(xy 369.90225 -237.219079) (xy 369.894431 -237.268442) (xy 369.878987 -237.315974) (xy 369.856297 -237.360506)
			(xy 369.826921 -237.400939) (xy 369.791581 -237.436279) (xy 369.751148 -237.465655) (xy 369.706616 -237.488345)
			(xy 369.659084 -237.503789) (xy 369.609721 -237.511608) (xy 369.559743 -237.511608) (xy 369.51038 -237.503789)
			(xy 369.462848 -237.488345) (xy 369.418316 -237.465655) (xy 369.377883 -237.436279) (xy 369.342543 -237.400939)
			(xy 369.313167 -237.360506) (xy 369.290477 -237.315974) (xy 369.275033 -237.268442) (xy 369.267214 -237.219079)
			(xy 368.962196 -237.219079) (xy 368.954377 -237.268442) (xy 368.938933 -237.315974) (xy 368.916243 -237.360506)
			(xy 368.886867 -237.400939) (xy 368.851527 -237.436279) (xy 368.811094 -237.465655) (xy 368.766562 -237.488345)
			(xy 368.71903 -237.503789) (xy 368.669667 -237.511608) (xy 368.619689 -237.511608) (xy 368.570326 -237.503789)
			(xy 368.522794 -237.488345) (xy 368.478262 -237.465655) (xy 368.437829 -237.436279) (xy 368.402489 -237.400939)
			(xy 368.373113 -237.360506) (xy 368.350423 -237.315974) (xy 368.334979 -237.268442) (xy 368.32716 -237.219079)
			(xy 368.022396 -237.219079) (xy 368.014577 -237.268442) (xy 367.999133 -237.315974) (xy 367.976443 -237.360506)
			(xy 367.947067 -237.400939) (xy 367.911727 -237.436279) (xy 367.871294 -237.465655) (xy 367.826762 -237.488345)
			(xy 367.77923 -237.503789) (xy 367.729867 -237.511608) (xy 367.679889 -237.511608) (xy 367.630526 -237.503789)
			(xy 367.582994 -237.488345) (xy 367.538462 -237.465655) (xy 367.498029 -237.436279) (xy 367.462689 -237.400939)
			(xy 367.433313 -237.360506) (xy 367.410623 -237.315974) (xy 367.395179 -237.268442) (xy 367.38736 -237.219079)
			(xy 367.082342 -237.219079) (xy 367.074523 -237.268442) (xy 367.059079 -237.315974) (xy 367.036389 -237.360506)
			(xy 367.007013 -237.400939) (xy 366.971673 -237.436279) (xy 366.93124 -237.465655) (xy 366.886708 -237.488345)
			(xy 366.839176 -237.503789) (xy 366.789813 -237.511608) (xy 366.739835 -237.511608) (xy 366.690472 -237.503789)
			(xy 366.64294 -237.488345) (xy 366.598408 -237.465655) (xy 366.557975 -237.436279) (xy 366.522635 -237.400939)
			(xy 366.493259 -237.360506) (xy 366.470569 -237.315974) (xy 366.455125 -237.268442) (xy 366.447306 -237.219079)
			(xy 366.142288 -237.219079) (xy 366.134469 -237.268442) (xy 366.119025 -237.315974) (xy 366.096335 -237.360506)
			(xy 366.066959 -237.400939) (xy 366.031619 -237.436279) (xy 365.991186 -237.465655) (xy 365.946654 -237.488345)
			(xy 365.899122 -237.503789) (xy 365.849759 -237.511608) (xy 365.799781 -237.511608) (xy 365.750418 -237.503789)
			(xy 365.702886 -237.488345) (xy 365.658354 -237.465655) (xy 365.617921 -237.436279) (xy 365.582581 -237.400939)
			(xy 365.553205 -237.360506) (xy 365.530515 -237.315974) (xy 365.515071 -237.268442) (xy 365.507252 -237.219079)
			(xy 365.202234 -237.219079) (xy 365.194415 -237.268442) (xy 365.178971 -237.315974) (xy 365.156281 -237.360506)
			(xy 365.126905 -237.400939) (xy 365.091565 -237.436279) (xy 365.051132 -237.465655) (xy 365.0066 -237.488345)
			(xy 364.959068 -237.503789) (xy 364.909705 -237.511608) (xy 364.859727 -237.511608) (xy 364.810364 -237.503789)
			(xy 364.762832 -237.488345) (xy 364.7183 -237.465655) (xy 364.677867 -237.436279) (xy 364.642527 -237.400939)
			(xy 364.613151 -237.360506) (xy 364.590461 -237.315974) (xy 364.575017 -237.268442) (xy 364.567198 -237.219079)
			(xy 364.262434 -237.219079) (xy 364.254615 -237.268442) (xy 364.239171 -237.315974) (xy 364.216481 -237.360506)
			(xy 364.187105 -237.400939) (xy 364.151765 -237.436279) (xy 364.111332 -237.465655) (xy 364.0668 -237.488345)
			(xy 364.019268 -237.503789) (xy 363.969905 -237.511608) (xy 363.919927 -237.511608) (xy 363.870564 -237.503789)
			(xy 363.823032 -237.488345) (xy 363.7785 -237.465655) (xy 363.738067 -237.436279) (xy 363.702727 -237.400939)
			(xy 363.673351 -237.360506) (xy 363.650661 -237.315974) (xy 363.635217 -237.268442) (xy 363.627398 -237.219079)
			(xy 361.442272 -237.219079) (xy 361.434453 -237.268442) (xy 361.419009 -237.315974) (xy 361.396319 -237.360506)
			(xy 361.366943 -237.400939) (xy 361.331603 -237.436279) (xy 361.29117 -237.465655) (xy 361.246638 -237.488345)
			(xy 361.199106 -237.503789) (xy 361.149743 -237.511608) (xy 361.099765 -237.511608) (xy 361.050402 -237.503789)
			(xy 361.00287 -237.488345) (xy 360.958338 -237.465655) (xy 360.917905 -237.436279) (xy 360.882565 -237.400939)
			(xy 360.853189 -237.360506) (xy 360.830499 -237.315974) (xy 360.815055 -237.268442) (xy 360.807236 -237.219079)
			(xy 358.628714 -237.219079) (xy 358.620895 -237.268442) (xy 358.605451 -237.315974) (xy 358.582761 -237.360506)
			(xy 358.553385 -237.400939) (xy 358.518045 -237.436279) (xy 358.477612 -237.465655) (xy 358.43308 -237.488345)
			(xy 358.385548 -237.503789) (xy 358.336185 -237.511608) (xy 358.286207 -237.511608) (xy 358.236844 -237.503789)
			(xy 358.189312 -237.488345) (xy 358.14478 -237.465655) (xy 358.104347 -237.436279) (xy 358.069007 -237.400939)
			(xy 358.039631 -237.360506) (xy 358.016941 -237.315974) (xy 358.001497 -237.268442) (xy 357.993678 -237.219079)
			(xy 355.808552 -237.219079) (xy 355.800733 -237.268442) (xy 355.785289 -237.315974) (xy 355.762599 -237.360506)
			(xy 355.733223 -237.400939) (xy 355.697883 -237.436279) (xy 355.65745 -237.465655) (xy 355.612918 -237.488345)
			(xy 355.565386 -237.503789) (xy 355.516023 -237.511608) (xy 355.466045 -237.511608) (xy 355.416682 -237.503789)
			(xy 355.36915 -237.488345) (xy 355.324618 -237.465655) (xy 355.284185 -237.436279) (xy 355.248845 -237.400939)
			(xy 355.219469 -237.360506) (xy 355.196779 -237.315974) (xy 355.181335 -237.268442) (xy 355.173516 -237.219079)
			(xy 354.868752 -237.219079) (xy 354.860933 -237.268442) (xy 354.845489 -237.315974) (xy 354.822799 -237.360506)
			(xy 354.793423 -237.400939) (xy 354.758083 -237.436279) (xy 354.71765 -237.465655) (xy 354.673118 -237.488345)
			(xy 354.625586 -237.503789) (xy 354.576223 -237.511608) (xy 354.526245 -237.511608) (xy 354.476882 -237.503789)
			(xy 354.42935 -237.488345) (xy 354.384818 -237.465655) (xy 354.344385 -237.436279) (xy 354.309045 -237.400939)
			(xy 354.279669 -237.360506) (xy 354.256979 -237.315974) (xy 354.241535 -237.268442) (xy 354.233716 -237.219079)
			(xy 353.928698 -237.219079) (xy 353.920879 -237.268442) (xy 353.905435 -237.315974) (xy 353.882745 -237.360506)
			(xy 353.853369 -237.400939) (xy 353.818029 -237.436279) (xy 353.777596 -237.465655) (xy 353.733064 -237.488345)
			(xy 353.685532 -237.503789) (xy 353.636169 -237.511608) (xy 353.586191 -237.511608) (xy 353.536828 -237.503789)
			(xy 353.489296 -237.488345) (xy 353.444764 -237.465655) (xy 353.404331 -237.436279) (xy 353.368991 -237.400939)
			(xy 353.339615 -237.360506) (xy 353.316925 -237.315974) (xy 353.301481 -237.268442) (xy 353.293662 -237.219079)
			(xy 352.988644 -237.219079) (xy 352.980825 -237.268442) (xy 352.965381 -237.315974) (xy 352.942691 -237.360506)
			(xy 352.913315 -237.400939) (xy 352.877975 -237.436279) (xy 352.837542 -237.465655) (xy 352.79301 -237.488345)
			(xy 352.745478 -237.503789) (xy 352.696115 -237.511608) (xy 352.646137 -237.511608) (xy 352.596774 -237.503789)
			(xy 352.549242 -237.488345) (xy 352.50471 -237.465655) (xy 352.464277 -237.436279) (xy 352.428937 -237.400939)
			(xy 352.399561 -237.360506) (xy 352.376871 -237.315974) (xy 352.361427 -237.268442) (xy 352.353608 -237.219079)
			(xy 352.04859 -237.219079) (xy 352.040771 -237.268442) (xy 352.025327 -237.315974) (xy 352.002637 -237.360506)
			(xy 351.973261 -237.400939) (xy 351.937921 -237.436279) (xy 351.897488 -237.465655) (xy 351.852956 -237.488345)
			(xy 351.805424 -237.503789) (xy 351.756061 -237.511608) (xy 351.706083 -237.511608) (xy 351.65672 -237.503789)
			(xy 351.609188 -237.488345) (xy 351.564656 -237.465655) (xy 351.524223 -237.436279) (xy 351.488883 -237.400939)
			(xy 351.459507 -237.360506) (xy 351.436817 -237.315974) (xy 351.421373 -237.268442) (xy 351.413554 -237.219079)
			(xy 351.108536 -237.219079) (xy 351.100717 -237.268442) (xy 351.085273 -237.315974) (xy 351.062583 -237.360506)
			(xy 351.033207 -237.400939) (xy 350.997867 -237.436279) (xy 350.957434 -237.465655) (xy 350.912902 -237.488345)
			(xy 350.86537 -237.503789) (xy 350.816007 -237.511608) (xy 350.766029 -237.511608) (xy 350.716666 -237.503789)
			(xy 350.669134 -237.488345) (xy 350.624602 -237.465655) (xy 350.584169 -237.436279) (xy 350.548829 -237.400939)
			(xy 350.519453 -237.360506) (xy 350.496763 -237.315974) (xy 350.481319 -237.268442) (xy 350.4735 -237.219079)
			(xy 350.168736 -237.219079) (xy 350.160917 -237.268442) (xy 350.145473 -237.315974) (xy 350.122783 -237.360506)
			(xy 350.093407 -237.400939) (xy 350.058067 -237.436279) (xy 350.017634 -237.465655) (xy 349.973102 -237.488345)
			(xy 349.92557 -237.503789) (xy 349.876207 -237.511608) (xy 349.826229 -237.511608) (xy 349.776866 -237.503789)
			(xy 349.729334 -237.488345) (xy 349.684802 -237.465655) (xy 349.644369 -237.436279) (xy 349.609029 -237.400939)
			(xy 349.579653 -237.360506) (xy 349.556963 -237.315974) (xy 349.541519 -237.268442) (xy 349.5337 -237.219079)
			(xy 349.228682 -237.219079) (xy 349.220863 -237.268442) (xy 349.205419 -237.315974) (xy 349.182729 -237.360506)
			(xy 349.153353 -237.400939) (xy 349.118013 -237.436279) (xy 349.07758 -237.465655) (xy 349.033048 -237.488345)
			(xy 348.985516 -237.503789) (xy 348.936153 -237.511608) (xy 348.886175 -237.511608) (xy 348.836812 -237.503789)
			(xy 348.78928 -237.488345) (xy 348.744748 -237.465655) (xy 348.704315 -237.436279) (xy 348.668975 -237.400939)
			(xy 348.639599 -237.360506) (xy 348.616909 -237.315974) (xy 348.601465 -237.268442) (xy 348.593646 -237.219079)
			(xy 348.288628 -237.219079) (xy 348.280809 -237.268442) (xy 348.265365 -237.315974) (xy 348.242675 -237.360506)
			(xy 348.213299 -237.400939) (xy 348.177959 -237.436279) (xy 348.137526 -237.465655) (xy 348.092994 -237.488345)
			(xy 348.045462 -237.503789) (xy 347.996099 -237.511608) (xy 347.946121 -237.511608) (xy 347.896758 -237.503789)
			(xy 347.849226 -237.488345) (xy 347.804694 -237.465655) (xy 347.764261 -237.436279) (xy 347.728921 -237.400939)
			(xy 347.699545 -237.360506) (xy 347.676855 -237.315974) (xy 347.661411 -237.268442) (xy 347.653592 -237.219079)
			(xy 347.348574 -237.219079) (xy 347.340755 -237.268442) (xy 347.325311 -237.315974) (xy 347.302621 -237.360506)
			(xy 347.273245 -237.400939) (xy 347.237905 -237.436279) (xy 347.197472 -237.465655) (xy 347.15294 -237.488345)
			(xy 347.105408 -237.503789) (xy 347.056045 -237.511608) (xy 347.006067 -237.511608) (xy 346.956704 -237.503789)
			(xy 346.909172 -237.488345) (xy 346.86464 -237.465655) (xy 346.824207 -237.436279) (xy 346.788867 -237.400939)
			(xy 346.759491 -237.360506) (xy 346.736801 -237.315974) (xy 346.721357 -237.268442) (xy 346.713538 -237.219079)
			(xy 346.40852 -237.219079) (xy 346.400701 -237.268442) (xy 346.385257 -237.315974) (xy 346.362567 -237.360506)
			(xy 346.333191 -237.400939) (xy 346.297851 -237.436279) (xy 346.257418 -237.465655) (xy 346.212886 -237.488345)
			(xy 346.165354 -237.503789) (xy 346.115991 -237.511608) (xy 346.066013 -237.511608) (xy 346.01665 -237.503789)
			(xy 345.969118 -237.488345) (xy 345.924586 -237.465655) (xy 345.884153 -237.436279) (xy 345.848813 -237.400939)
			(xy 345.819437 -237.360506) (xy 345.796747 -237.315974) (xy 345.781303 -237.268442) (xy 345.773484 -237.219079)
			(xy 345.468728 -237.219079) (xy 345.468728 -237.21909) (xy 345.460909 -237.268454) (xy 345.445465 -237.315988)
			(xy 345.422774 -237.36052) (xy 345.393397 -237.400955) (xy 345.358056 -237.436296) (xy 345.317622 -237.465673)
			(xy 345.27309 -237.488364) (xy 345.225556 -237.503809) (xy 345.176192 -237.511627) (xy 345.151202 -237.512098)
			(xy 345.141014 -237.512033) (xy 345.120678 -237.510763) (xy 345.110562 -237.509558) (xy 345.09964 -237.508288)
			(xy 345.089988 -237.511082) (xy 345.084905 -237.512794) (xy 345.075558 -237.518052) (xy 345.071446 -237.521496)
			(xy 345.051888 -237.538514) (xy 345.01201 -237.573566) (xy 345.005459 -237.580816) (xy 344.998013 -237.598858)
			(xy 344.997532 -237.608618) (xy 344.997532 -237.97006) (xy 344.997786 -237.974632) (xy 344.999056 -238.003842)
			(xy 344.999056 -238.00435) (xy 344.997981 -238.029085) (xy 345.303584 -238.029085) (xy 345.303584 -237.979107)
			(xy 345.311403 -237.929744) (xy 345.326847 -237.882212) (xy 345.349537 -237.83768) (xy 345.378913 -237.797247)
			(xy 345.414253 -237.761907) (xy 345.454686 -237.732531) (xy 345.499218 -237.709841) (xy 345.54675 -237.694397)
			(xy 345.596113 -237.686578) (xy 345.646091 -237.686578) (xy 345.695454 -237.694397) (xy 345.742986 -237.709841)
			(xy 345.787518 -237.732531) (xy 345.827951 -237.761907) (xy 345.863291 -237.797247) (xy 345.892667 -237.83768)
			(xy 345.915357 -237.882212) (xy 345.930801 -237.929744) (xy 345.93862 -237.979107) (xy 345.93911 -238.004096)
			(xy 345.93862 -238.029085) (xy 346.243638 -238.029085) (xy 346.243638 -237.979107) (xy 346.251457 -237.929744)
			(xy 346.266901 -237.882212) (xy 346.289591 -237.83768) (xy 346.318967 -237.797247) (xy 346.354307 -237.761907)
			(xy 346.39474 -237.732531) (xy 346.439272 -237.709841) (xy 346.486804 -237.694397) (xy 346.536167 -237.686578)
			(xy 346.586145 -237.686578) (xy 346.635508 -237.694397) (xy 346.68304 -237.709841) (xy 346.727572 -237.732531)
			(xy 346.768005 -237.761907) (xy 346.803345 -237.797247) (xy 346.832721 -237.83768) (xy 346.855411 -237.882212)
			(xy 346.870855 -237.929744) (xy 346.878674 -237.979107) (xy 346.879164 -238.004096) (xy 346.878674 -238.029085)
			(xy 347.183692 -238.029085) (xy 347.183692 -237.979107) (xy 347.191511 -237.929744) (xy 347.206955 -237.882212)
			(xy 347.229645 -237.83768) (xy 347.259021 -237.797247) (xy 347.294361 -237.761907) (xy 347.334794 -237.732531)
			(xy 347.379326 -237.709841) (xy 347.426858 -237.694397) (xy 347.476221 -237.686578) (xy 347.526199 -237.686578)
			(xy 347.575562 -237.694397) (xy 347.623094 -237.709841) (xy 347.667626 -237.732531) (xy 347.708059 -237.761907)
			(xy 347.743399 -237.797247) (xy 347.772775 -237.83768) (xy 347.795465 -237.882212) (xy 347.810909 -237.929744)
			(xy 347.818728 -237.979107) (xy 347.819218 -238.004096) (xy 347.818728 -238.029085) (xy 348.123492 -238.029085)
			(xy 348.123492 -237.979107) (xy 348.131311 -237.929744) (xy 348.146755 -237.882212) (xy 348.169445 -237.83768)
			(xy 348.198821 -237.797247) (xy 348.234161 -237.761907) (xy 348.274594 -237.732531) (xy 348.319126 -237.709841)
			(xy 348.366658 -237.694397) (xy 348.416021 -237.686578) (xy 348.465999 -237.686578) (xy 348.515362 -237.694397)
			(xy 348.562894 -237.709841) (xy 348.607426 -237.732531) (xy 348.647859 -237.761907) (xy 348.683199 -237.797247)
			(xy 348.712575 -237.83768) (xy 348.735265 -237.882212) (xy 348.750709 -237.929744) (xy 348.758528 -237.979107)
			(xy 348.759018 -238.004096) (xy 348.758528 -238.029085) (xy 349.063546 -238.029085) (xy 349.063546 -237.979107)
			(xy 349.071365 -237.929744) (xy 349.086809 -237.882212) (xy 349.109499 -237.83768) (xy 349.138875 -237.797247)
			(xy 349.174215 -237.761907) (xy 349.214648 -237.732531) (xy 349.25918 -237.709841) (xy 349.306712 -237.694397)
			(xy 349.356075 -237.686578) (xy 349.406053 -237.686578) (xy 349.455416 -237.694397) (xy 349.502948 -237.709841)
			(xy 349.54748 -237.732531) (xy 349.587913 -237.761907) (xy 349.623253 -237.797247) (xy 349.652629 -237.83768)
			(xy 349.675319 -237.882212) (xy 349.690763 -237.929744) (xy 349.698582 -237.979107) (xy 349.699072 -238.004096)
			(xy 349.698582 -238.029085) (xy 350.0036 -238.029085) (xy 350.0036 -237.979107) (xy 350.011419 -237.929744)
			(xy 350.026863 -237.882212) (xy 350.049553 -237.83768) (xy 350.078929 -237.797247) (xy 350.114269 -237.761907)
			(xy 350.154702 -237.732531) (xy 350.199234 -237.709841) (xy 350.246766 -237.694397) (xy 350.296129 -237.686578)
			(xy 350.346107 -237.686578) (xy 350.39547 -237.694397) (xy 350.443002 -237.709841) (xy 350.487534 -237.732531)
			(xy 350.527967 -237.761907) (xy 350.563307 -237.797247) (xy 350.592683 -237.83768) (xy 350.615373 -237.882212)
			(xy 350.630817 -237.929744) (xy 350.638636 -237.979107) (xy 350.639126 -238.004096) (xy 350.638636 -238.029085)
			(xy 350.943654 -238.029085) (xy 350.943654 -237.979107) (xy 350.951473 -237.929744) (xy 350.966917 -237.882212)
			(xy 350.989607 -237.83768) (xy 351.018983 -237.797247) (xy 351.054323 -237.761907) (xy 351.094756 -237.732531)
			(xy 351.139288 -237.709841) (xy 351.18682 -237.694397) (xy 351.236183 -237.686578) (xy 351.286161 -237.686578)
			(xy 351.335524 -237.694397) (xy 351.383056 -237.709841) (xy 351.427588 -237.732531) (xy 351.468021 -237.761907)
			(xy 351.503361 -237.797247) (xy 351.532737 -237.83768) (xy 351.555427 -237.882212) (xy 351.570871 -237.929744)
			(xy 351.57869 -237.979107) (xy 351.57918 -238.004096) (xy 351.57869 -238.029085) (xy 351.883708 -238.029085)
			(xy 351.883708 -237.979107) (xy 351.891527 -237.929744) (xy 351.906971 -237.882212) (xy 351.929661 -237.83768)
			(xy 351.959037 -237.797247) (xy 351.994377 -237.761907) (xy 352.03481 -237.732531) (xy 352.079342 -237.709841)
			(xy 352.126874 -237.694397) (xy 352.176237 -237.686578) (xy 352.226215 -237.686578) (xy 352.275578 -237.694397)
			(xy 352.32311 -237.709841) (xy 352.367642 -237.732531) (xy 352.408075 -237.761907) (xy 352.443415 -237.797247)
			(xy 352.472791 -237.83768) (xy 352.495481 -237.882212) (xy 352.510925 -237.929744) (xy 352.518744 -237.979107)
			(xy 352.519234 -238.004096) (xy 352.518744 -238.029085) (xy 352.823508 -238.029085) (xy 352.823508 -237.979107)
			(xy 352.831327 -237.929744) (xy 352.846771 -237.882212) (xy 352.869461 -237.83768) (xy 352.898837 -237.797247)
			(xy 352.934177 -237.761907) (xy 352.97461 -237.732531) (xy 353.019142 -237.709841) (xy 353.066674 -237.694397)
			(xy 353.116037 -237.686578) (xy 353.166015 -237.686578) (xy 353.215378 -237.694397) (xy 353.26291 -237.709841)
			(xy 353.307442 -237.732531) (xy 353.347875 -237.761907) (xy 353.383215 -237.797247) (xy 353.412591 -237.83768)
			(xy 353.435281 -237.882212) (xy 353.450725 -237.929744) (xy 353.458544 -237.979107) (xy 353.459034 -238.004096)
			(xy 353.764845 -238.004096) (xy 353.76894 -237.953368) (xy 353.781119 -237.903954) (xy 353.801067 -237.857134)
			(xy 353.828268 -237.81412) (xy 353.862016 -237.776026) (xy 353.901438 -237.743839) (xy 353.945512 -237.718393)
			(xy 353.993098 -237.700346) (xy 354.042962 -237.690166) (xy 354.093814 -237.688117) (xy 354.144335 -237.694251)
			(xy 354.193219 -237.708411) (xy 354.239198 -237.730228) (xy 354.281082 -237.759138) (xy 354.317786 -237.794393)
			(xy 354.348359 -237.835079) (xy 354.37201 -237.880142) (xy 354.388126 -237.928416) (xy 354.39629 -237.97865)
			(xy 354.396802 -238.004096) (xy 354.704899 -238.004096) (xy 354.708994 -237.953368) (xy 354.721173 -237.903954)
			(xy 354.741121 -237.857134) (xy 354.768322 -237.81412) (xy 354.80207 -237.776026) (xy 354.841492 -237.743839)
			(xy 354.885566 -237.718393) (xy 354.933152 -237.700346) (xy 354.983016 -237.690166) (xy 355.033868 -237.688117)
			(xy 355.084389 -237.694251) (xy 355.133273 -237.708411) (xy 355.179252 -237.730228) (xy 355.221136 -237.759138)
			(xy 355.25784 -237.794393) (xy 355.288413 -237.835079) (xy 355.312064 -237.880142) (xy 355.32818 -237.928416)
			(xy 355.336344 -237.97865) (xy 355.336856 -238.004096) (xy 355.336353 -238.029085) (xy 355.64367 -238.029085)
			(xy 355.64367 -237.979107) (xy 355.651489 -237.929744) (xy 355.666933 -237.882212) (xy 355.689623 -237.83768)
			(xy 355.718999 -237.797247) (xy 355.754339 -237.761907) (xy 355.794772 -237.732531) (xy 355.839304 -237.709841)
			(xy 355.886836 -237.694397) (xy 355.936199 -237.686578) (xy 355.986177 -237.686578) (xy 356.03554 -237.694397)
			(xy 356.083072 -237.709841) (xy 356.127604 -237.732531) (xy 356.168037 -237.761907) (xy 356.203377 -237.797247)
			(xy 356.232753 -237.83768) (xy 356.255443 -237.882212) (xy 356.270887 -237.929744) (xy 356.278706 -237.979107)
			(xy 356.279196 -238.004096) (xy 356.278706 -238.029085) (xy 356.583724 -238.029085) (xy 356.583724 -237.979107)
			(xy 356.591543 -237.929744) (xy 356.606987 -237.882212) (xy 356.629677 -237.83768) (xy 356.659053 -237.797247)
			(xy 356.694393 -237.761907) (xy 356.734826 -237.732531) (xy 356.779358 -237.709841) (xy 356.82689 -237.694397)
			(xy 356.876253 -237.686578) (xy 356.926231 -237.686578) (xy 356.975594 -237.694397) (xy 357.023126 -237.709841)
			(xy 357.067658 -237.732531) (xy 357.108091 -237.761907) (xy 357.143431 -237.797247) (xy 357.172807 -237.83768)
			(xy 357.195497 -237.882212) (xy 357.210941 -237.929744) (xy 357.21876 -237.979107) (xy 357.21925 -238.004096)
			(xy 357.21876 -238.029085) (xy 357.523524 -238.029085) (xy 357.523524 -237.979107) (xy 357.531343 -237.929744)
			(xy 357.546787 -237.882212) (xy 357.569477 -237.83768) (xy 357.598853 -237.797247) (xy 357.634193 -237.761907)
			(xy 357.674626 -237.732531) (xy 357.719158 -237.709841) (xy 357.76669 -237.694397) (xy 357.816053 -237.686578)
			(xy 357.866031 -237.686578) (xy 357.915394 -237.694397) (xy 357.962926 -237.709841) (xy 358.007458 -237.732531)
			(xy 358.047891 -237.761907) (xy 358.083231 -237.797247) (xy 358.112607 -237.83768) (xy 358.135297 -237.882212)
			(xy 358.150741 -237.929744) (xy 358.15856 -237.979107) (xy 358.15905 -238.004096) (xy 358.15856 -238.029085)
			(xy 361.27739 -238.029085) (xy 361.27739 -237.979107) (xy 361.285209 -237.929744) (xy 361.300653 -237.882212)
			(xy 361.323343 -237.83768) (xy 361.352719 -237.797247) (xy 361.388059 -237.761907) (xy 361.428492 -237.732531)
			(xy 361.473024 -237.709841) (xy 361.520556 -237.694397) (xy 361.569919 -237.686578) (xy 361.619897 -237.686578)
			(xy 361.66926 -237.694397) (xy 361.716792 -237.709841) (xy 361.761324 -237.732531) (xy 361.801757 -237.761907)
			(xy 361.837097 -237.797247) (xy 361.866473 -237.83768) (xy 361.889163 -237.882212) (xy 361.904607 -237.929744)
			(xy 361.912426 -237.979107) (xy 361.912916 -238.004096) (xy 361.912426 -238.029085) (xy 362.21719 -238.029085)
			(xy 362.21719 -237.979107) (xy 362.225009 -237.929744) (xy 362.240453 -237.882212) (xy 362.263143 -237.83768)
			(xy 362.292519 -237.797247) (xy 362.327859 -237.761907) (xy 362.368292 -237.732531) (xy 362.412824 -237.709841)
			(xy 362.460356 -237.694397) (xy 362.509719 -237.686578) (xy 362.559697 -237.686578) (xy 362.60906 -237.694397)
			(xy 362.656592 -237.709841) (xy 362.701124 -237.732531) (xy 362.741557 -237.761907) (xy 362.776897 -237.797247)
			(xy 362.806273 -237.83768) (xy 362.828963 -237.882212) (xy 362.844407 -237.929744) (xy 362.852226 -237.979107)
			(xy 362.852716 -238.004096) (xy 362.852226 -238.029085) (xy 363.157244 -238.029085) (xy 363.157244 -237.979107)
			(xy 363.165063 -237.929744) (xy 363.180507 -237.882212) (xy 363.203197 -237.83768) (xy 363.232573 -237.797247)
			(xy 363.267913 -237.761907) (xy 363.308346 -237.732531) (xy 363.352878 -237.709841) (xy 363.40041 -237.694397)
			(xy 363.449773 -237.686578) (xy 363.499751 -237.686578) (xy 363.549114 -237.694397) (xy 363.596646 -237.709841)
			(xy 363.641178 -237.732531) (xy 363.681611 -237.761907) (xy 363.716951 -237.797247) (xy 363.746327 -237.83768)
			(xy 363.769017 -237.882212) (xy 363.784461 -237.929744) (xy 363.79228 -237.979107) (xy 363.79277 -238.004096)
			(xy 364.098581 -238.004096) (xy 364.102676 -237.953368) (xy 364.114855 -237.903954) (xy 364.134803 -237.857134)
			(xy 364.162004 -237.81412) (xy 364.195752 -237.776026) (xy 364.235174 -237.743839) (xy 364.279248 -237.718393)
			(xy 364.326834 -237.700346) (xy 364.376698 -237.690166) (xy 364.42755 -237.688117) (xy 364.478071 -237.694251)
			(xy 364.526955 -237.708411) (xy 364.572934 -237.730228) (xy 364.614818 -237.759138) (xy 364.651522 -237.794393)
			(xy 364.682095 -237.835079) (xy 364.705746 -237.880142) (xy 364.721862 -237.928416) (xy 364.730026 -237.97865)
			(xy 364.730538 -238.004096) (xy 365.038635 -238.004096) (xy 365.04273 -237.953368) (xy 365.054909 -237.903954)
			(xy 365.074857 -237.857134) (xy 365.102058 -237.81412) (xy 365.135806 -237.776026) (xy 365.175228 -237.743839)
			(xy 365.219302 -237.718393) (xy 365.266888 -237.700346) (xy 365.316752 -237.690166) (xy 365.367604 -237.688117)
			(xy 365.418125 -237.694251) (xy 365.467009 -237.708411) (xy 365.512988 -237.730228) (xy 365.554872 -237.759138)
			(xy 365.591576 -237.794393) (xy 365.622149 -237.835079) (xy 365.6458 -237.880142) (xy 365.661916 -237.928416)
			(xy 365.67008 -237.97865) (xy 365.670592 -238.004096) (xy 365.670089 -238.029085) (xy 365.977406 -238.029085)
			(xy 365.977406 -237.979107) (xy 365.985225 -237.929744) (xy 366.000669 -237.882212) (xy 366.023359 -237.83768)
			(xy 366.052735 -237.797247) (xy 366.088075 -237.761907) (xy 366.128508 -237.732531) (xy 366.17304 -237.709841)
			(xy 366.220572 -237.694397) (xy 366.269935 -237.686578) (xy 366.319913 -237.686578) (xy 366.369276 -237.694397)
			(xy 366.416808 -237.709841) (xy 366.46134 -237.732531) (xy 366.501773 -237.761907) (xy 366.537113 -237.797247)
			(xy 366.566489 -237.83768) (xy 366.589179 -237.882212) (xy 366.604623 -237.929744) (xy 366.612442 -237.979107)
			(xy 366.612932 -238.004096) (xy 366.612442 -238.029085) (xy 366.917206 -238.029085) (xy 366.917206 -237.979107)
			(xy 366.925025 -237.929744) (xy 366.940469 -237.882212) (xy 366.963159 -237.83768) (xy 366.992535 -237.797247)
			(xy 367.027875 -237.761907) (xy 367.068308 -237.732531) (xy 367.11284 -237.709841) (xy 367.160372 -237.694397)
			(xy 367.209735 -237.686578) (xy 367.259713 -237.686578) (xy 367.309076 -237.694397) (xy 367.356608 -237.709841)
			(xy 367.40114 -237.732531) (xy 367.441573 -237.761907) (xy 367.476913 -237.797247) (xy 367.506289 -237.83768)
			(xy 367.528979 -237.882212) (xy 367.544423 -237.929744) (xy 367.552242 -237.979107) (xy 367.552732 -238.004096)
			(xy 367.552242 -238.029085) (xy 367.85726 -238.029085) (xy 367.85726 -237.979107) (xy 367.865079 -237.929744)
			(xy 367.880523 -237.882212) (xy 367.903213 -237.83768) (xy 367.932589 -237.797247) (xy 367.967929 -237.761907)
			(xy 368.008362 -237.732531) (xy 368.052894 -237.709841) (xy 368.100426 -237.694397) (xy 368.149789 -237.686578)
			(xy 368.199767 -237.686578) (xy 368.24913 -237.694397) (xy 368.296662 -237.709841) (xy 368.341194 -237.732531)
			(xy 368.381627 -237.761907) (xy 368.416967 -237.797247) (xy 368.446343 -237.83768) (xy 368.469033 -237.882212)
			(xy 368.484477 -237.929744) (xy 368.492296 -237.979107) (xy 368.492786 -238.004096) (xy 368.492296 -238.029085)
			(xy 368.797314 -238.029085) (xy 368.797314 -237.979107) (xy 368.805133 -237.929744) (xy 368.820577 -237.882212)
			(xy 368.843267 -237.83768) (xy 368.872643 -237.797247) (xy 368.907983 -237.761907) (xy 368.948416 -237.732531)
			(xy 368.992948 -237.709841) (xy 369.04048 -237.694397) (xy 369.089843 -237.686578) (xy 369.139821 -237.686578)
			(xy 369.189184 -237.694397) (xy 369.236716 -237.709841) (xy 369.281248 -237.732531) (xy 369.321681 -237.761907)
			(xy 369.357021 -237.797247) (xy 369.386397 -237.83768) (xy 369.409087 -237.882212) (xy 369.424531 -237.929744)
			(xy 369.43235 -237.979107) (xy 369.43284 -238.004096) (xy 369.43235 -238.029085) (xy 369.737368 -238.029085)
			(xy 369.737368 -237.979107) (xy 369.745187 -237.929744) (xy 369.760631 -237.882212) (xy 369.783321 -237.83768)
			(xy 369.812697 -237.797247) (xy 369.848037 -237.761907) (xy 369.88847 -237.732531) (xy 369.933002 -237.709841)
			(xy 369.980534 -237.694397) (xy 370.029897 -237.686578) (xy 370.079875 -237.686578) (xy 370.129238 -237.694397)
			(xy 370.17677 -237.709841) (xy 370.221302 -237.732531) (xy 370.261735 -237.761907) (xy 370.297075 -237.797247)
			(xy 370.326451 -237.83768) (xy 370.349141 -237.882212) (xy 370.364585 -237.929744) (xy 370.372404 -237.979107)
			(xy 370.372894 -238.004096) (xy 370.372404 -238.029085) (xy 370.677168 -238.029085) (xy 370.677168 -237.979107)
			(xy 370.684987 -237.929744) (xy 370.700431 -237.882212) (xy 370.723121 -237.83768) (xy 370.752497 -237.797247)
			(xy 370.787837 -237.761907) (xy 370.82827 -237.732531) (xy 370.872802 -237.709841) (xy 370.920334 -237.694397)
			(xy 370.969697 -237.686578) (xy 371.019675 -237.686578) (xy 371.069038 -237.694397) (xy 371.11657 -237.709841)
			(xy 371.161102 -237.732531) (xy 371.201535 -237.761907) (xy 371.236875 -237.797247) (xy 371.266251 -237.83768)
			(xy 371.288941 -237.882212) (xy 371.304385 -237.929744) (xy 371.312204 -237.979107) (xy 371.312694 -238.004096)
			(xy 371.312204 -238.029085) (xy 371.617222 -238.029085) (xy 371.617222 -237.979107) (xy 371.625041 -237.929744)
			(xy 371.640485 -237.882212) (xy 371.663175 -237.83768) (xy 371.692551 -237.797247) (xy 371.727891 -237.761907)
			(xy 371.768324 -237.732531) (xy 371.812856 -237.709841) (xy 371.860388 -237.694397) (xy 371.909751 -237.686578)
			(xy 371.959729 -237.686578) (xy 372.009092 -237.694397) (xy 372.056624 -237.709841) (xy 372.101156 -237.732531)
			(xy 372.141589 -237.761907) (xy 372.176929 -237.797247) (xy 372.206305 -237.83768) (xy 372.228995 -237.882212)
			(xy 372.244439 -237.929744) (xy 372.252258 -237.979107) (xy 372.252748 -238.004096) (xy 372.252258 -238.029085)
			(xy 372.557276 -238.029085) (xy 372.557276 -237.979107) (xy 372.565095 -237.929744) (xy 372.580539 -237.882212)
			(xy 372.603229 -237.83768) (xy 372.632605 -237.797247) (xy 372.667945 -237.761907) (xy 372.708378 -237.732531)
			(xy 372.75291 -237.709841) (xy 372.800442 -237.694397) (xy 372.849805 -237.686578) (xy 372.899783 -237.686578)
			(xy 372.949146 -237.694397) (xy 372.996678 -237.709841) (xy 373.04121 -237.732531) (xy 373.081643 -237.761907)
			(xy 373.116983 -237.797247) (xy 373.146359 -237.83768) (xy 373.169049 -237.882212) (xy 373.184493 -237.929744)
			(xy 373.192312 -237.979107) (xy 373.192802 -238.004096) (xy 373.192312 -238.029085) (xy 373.49733 -238.029085)
			(xy 373.49733 -237.979107) (xy 373.505149 -237.929744) (xy 373.520593 -237.882212) (xy 373.543283 -237.83768)
			(xy 373.572659 -237.797247) (xy 373.607999 -237.761907) (xy 373.648432 -237.732531) (xy 373.692964 -237.709841)
			(xy 373.740496 -237.694397) (xy 373.789859 -237.686578) (xy 373.839837 -237.686578) (xy 373.8892 -237.694397)
			(xy 373.936732 -237.709841) (xy 373.981264 -237.732531) (xy 374.021697 -237.761907) (xy 374.057037 -237.797247)
			(xy 374.086413 -237.83768) (xy 374.109103 -237.882212) (xy 374.124547 -237.929744) (xy 374.132366 -237.979107)
			(xy 374.132856 -238.004096) (xy 374.132366 -238.029085) (xy 374.124547 -238.078448) (xy 374.109103 -238.12598)
			(xy 374.086413 -238.170512) (xy 374.057037 -238.210945) (xy 374.021697 -238.246285) (xy 373.981264 -238.275661)
			(xy 373.936732 -238.298351) (xy 373.8892 -238.313795) (xy 373.839837 -238.321614) (xy 373.789859 -238.321614)
			(xy 373.740496 -238.313795) (xy 373.692964 -238.298351) (xy 373.648432 -238.275661) (xy 373.607999 -238.246285)
			(xy 373.572659 -238.210945) (xy 373.543283 -238.170512) (xy 373.520593 -238.12598) (xy 373.505149 -238.078448)
			(xy 373.49733 -238.029085) (xy 373.192312 -238.029085) (xy 373.184493 -238.078448) (xy 373.169049 -238.12598)
			(xy 373.146359 -238.170512) (xy 373.116983 -238.210945) (xy 373.081643 -238.246285) (xy 373.04121 -238.275661)
			(xy 372.996678 -238.298351) (xy 372.949146 -238.313795) (xy 372.899783 -238.321614) (xy 372.849805 -238.321614)
			(xy 372.800442 -238.313795) (xy 372.75291 -238.298351) (xy 372.708378 -238.275661) (xy 372.667945 -238.246285)
			(xy 372.632605 -238.210945) (xy 372.603229 -238.170512) (xy 372.580539 -238.12598) (xy 372.565095 -238.078448)
			(xy 372.557276 -238.029085) (xy 372.252258 -238.029085) (xy 372.244439 -238.078448) (xy 372.228995 -238.12598)
			(xy 372.206305 -238.170512) (xy 372.176929 -238.210945) (xy 372.141589 -238.246285) (xy 372.101156 -238.275661)
			(xy 372.056624 -238.298351) (xy 372.009092 -238.313795) (xy 371.959729 -238.321614) (xy 371.909751 -238.321614)
			(xy 371.860388 -238.313795) (xy 371.812856 -238.298351) (xy 371.768324 -238.275661) (xy 371.727891 -238.246285)
			(xy 371.692551 -238.210945) (xy 371.663175 -238.170512) (xy 371.640485 -238.12598) (xy 371.625041 -238.078448)
			(xy 371.617222 -238.029085) (xy 371.312204 -238.029085) (xy 371.304385 -238.078448) (xy 371.288941 -238.12598)
			(xy 371.266251 -238.170512) (xy 371.236875 -238.210945) (xy 371.201535 -238.246285) (xy 371.161102 -238.275661)
			(xy 371.11657 -238.298351) (xy 371.069038 -238.313795) (xy 371.019675 -238.321614) (xy 370.969697 -238.321614)
			(xy 370.920334 -238.313795) (xy 370.872802 -238.298351) (xy 370.82827 -238.275661) (xy 370.787837 -238.246285)
			(xy 370.752497 -238.210945) (xy 370.723121 -238.170512) (xy 370.700431 -238.12598) (xy 370.684987 -238.078448)
			(xy 370.677168 -238.029085) (xy 370.372404 -238.029085) (xy 370.364585 -238.078448) (xy 370.349141 -238.12598)
			(xy 370.326451 -238.170512) (xy 370.297075 -238.210945) (xy 370.261735 -238.246285) (xy 370.221302 -238.275661)
			(xy 370.17677 -238.298351) (xy 370.129238 -238.313795) (xy 370.079875 -238.321614) (xy 370.029897 -238.321614)
			(xy 369.980534 -238.313795) (xy 369.933002 -238.298351) (xy 369.88847 -238.275661) (xy 369.848037 -238.246285)
			(xy 369.812697 -238.210945) (xy 369.783321 -238.170512) (xy 369.760631 -238.12598) (xy 369.745187 -238.078448)
			(xy 369.737368 -238.029085) (xy 369.43235 -238.029085) (xy 369.424531 -238.078448) (xy 369.409087 -238.12598)
			(xy 369.386397 -238.170512) (xy 369.357021 -238.210945) (xy 369.321681 -238.246285) (xy 369.281248 -238.275661)
			(xy 369.236716 -238.298351) (xy 369.189184 -238.313795) (xy 369.139821 -238.321614) (xy 369.089843 -238.321614)
			(xy 369.04048 -238.313795) (xy 368.992948 -238.298351) (xy 368.948416 -238.275661) (xy 368.907983 -238.246285)
			(xy 368.872643 -238.210945) (xy 368.843267 -238.170512) (xy 368.820577 -238.12598) (xy 368.805133 -238.078448)
			(xy 368.797314 -238.029085) (xy 368.492296 -238.029085) (xy 368.484477 -238.078448) (xy 368.469033 -238.12598)
			(xy 368.446343 -238.170512) (xy 368.416967 -238.210945) (xy 368.381627 -238.246285) (xy 368.341194 -238.275661)
			(xy 368.296662 -238.298351) (xy 368.24913 -238.313795) (xy 368.199767 -238.321614) (xy 368.149789 -238.321614)
			(xy 368.100426 -238.313795) (xy 368.052894 -238.298351) (xy 368.008362 -238.275661) (xy 367.967929 -238.246285)
			(xy 367.932589 -238.210945) (xy 367.903213 -238.170512) (xy 367.880523 -238.12598) (xy 367.865079 -238.078448)
			(xy 367.85726 -238.029085) (xy 367.552242 -238.029085) (xy 367.544423 -238.078448) (xy 367.528979 -238.12598)
			(xy 367.506289 -238.170512) (xy 367.476913 -238.210945) (xy 367.441573 -238.246285) (xy 367.40114 -238.275661)
			(xy 367.356608 -238.298351) (xy 367.309076 -238.313795) (xy 367.259713 -238.321614) (xy 367.209735 -238.321614)
			(xy 367.160372 -238.313795) (xy 367.11284 -238.298351) (xy 367.068308 -238.275661) (xy 367.027875 -238.246285)
			(xy 366.992535 -238.210945) (xy 366.963159 -238.170512) (xy 366.940469 -238.12598) (xy 366.925025 -238.078448)
			(xy 366.917206 -238.029085) (xy 366.612442 -238.029085) (xy 366.604623 -238.078448) (xy 366.589179 -238.12598)
			(xy 366.566489 -238.170512) (xy 366.537113 -238.210945) (xy 366.501773 -238.246285) (xy 366.46134 -238.275661)
			(xy 366.416808 -238.298351) (xy 366.369276 -238.313795) (xy 366.319913 -238.321614) (xy 366.269935 -238.321614)
			(xy 366.220572 -238.313795) (xy 366.17304 -238.298351) (xy 366.128508 -238.275661) (xy 366.088075 -238.246285)
			(xy 366.052735 -238.210945) (xy 366.023359 -238.170512) (xy 366.000669 -238.12598) (xy 365.985225 -238.078448)
			(xy 365.977406 -238.029085) (xy 365.670089 -238.029085) (xy 365.67008 -238.029542) (xy 365.661916 -238.079776)
			(xy 365.6458 -238.12805) (xy 365.622149 -238.173113) (xy 365.591576 -238.213799) (xy 365.554872 -238.249054)
			(xy 365.512988 -238.277964) (xy 365.467009 -238.299781) (xy 365.418125 -238.313941) (xy 365.367604 -238.320075)
			(xy 365.316752 -238.318026) (xy 365.266888 -238.307846) (xy 365.219302 -238.289799) (xy 365.175228 -238.264353)
			(xy 365.135806 -238.232166) (xy 365.102058 -238.194072) (xy 365.074857 -238.151058) (xy 365.054909 -238.104238)
			(xy 365.04273 -238.054824) (xy 365.038635 -238.004096) (xy 364.730538 -238.004096) (xy 364.730026 -238.029542)
			(xy 364.721862 -238.079776) (xy 364.705746 -238.12805) (xy 364.682095 -238.173113) (xy 364.651522 -238.213799)
			(xy 364.614818 -238.249054) (xy 364.572934 -238.277964) (xy 364.526955 -238.299781) (xy 364.478071 -238.313941)
			(xy 364.42755 -238.320075) (xy 364.376698 -238.318026) (xy 364.326834 -238.307846) (xy 364.279248 -238.289799)
			(xy 364.235174 -238.264353) (xy 364.195752 -238.232166) (xy 364.162004 -238.194072) (xy 364.134803 -238.151058)
			(xy 364.114855 -238.104238) (xy 364.102676 -238.054824) (xy 364.098581 -238.004096) (xy 363.79277 -238.004096)
			(xy 363.79228 -238.029085) (xy 363.784461 -238.078448) (xy 363.769017 -238.12598) (xy 363.746327 -238.170512)
			(xy 363.716951 -238.210945) (xy 363.681611 -238.246285) (xy 363.641178 -238.275661) (xy 363.596646 -238.298351)
			(xy 363.549114 -238.313795) (xy 363.499751 -238.321614) (xy 363.449773 -238.321614) (xy 363.40041 -238.313795)
			(xy 363.352878 -238.298351) (xy 363.308346 -238.275661) (xy 363.267913 -238.246285) (xy 363.232573 -238.210945)
			(xy 363.203197 -238.170512) (xy 363.180507 -238.12598) (xy 363.165063 -238.078448) (xy 363.157244 -238.029085)
			(xy 362.852226 -238.029085) (xy 362.844407 -238.078448) (xy 362.828963 -238.12598) (xy 362.806273 -238.170512)
			(xy 362.776897 -238.210945) (xy 362.741557 -238.246285) (xy 362.701124 -238.275661) (xy 362.656592 -238.298351)
			(xy 362.60906 -238.313795) (xy 362.559697 -238.321614) (xy 362.509719 -238.321614) (xy 362.460356 -238.313795)
			(xy 362.412824 -238.298351) (xy 362.368292 -238.275661) (xy 362.327859 -238.246285) (xy 362.292519 -238.210945)
			(xy 362.263143 -238.170512) (xy 362.240453 -238.12598) (xy 362.225009 -238.078448) (xy 362.21719 -238.029085)
			(xy 361.912426 -238.029085) (xy 361.904607 -238.078448) (xy 361.889163 -238.12598) (xy 361.866473 -238.170512)
			(xy 361.837097 -238.210945) (xy 361.801757 -238.246285) (xy 361.761324 -238.275661) (xy 361.716792 -238.298351)
			(xy 361.66926 -238.313795) (xy 361.619897 -238.321614) (xy 361.569919 -238.321614) (xy 361.520556 -238.313795)
			(xy 361.473024 -238.298351) (xy 361.428492 -238.275661) (xy 361.388059 -238.246285) (xy 361.352719 -238.210945)
			(xy 361.323343 -238.170512) (xy 361.300653 -238.12598) (xy 361.285209 -238.078448) (xy 361.27739 -238.029085)
			(xy 358.15856 -238.029085) (xy 358.150741 -238.078448) (xy 358.135297 -238.12598) (xy 358.112607 -238.170512)
			(xy 358.083231 -238.210945) (xy 358.047891 -238.246285) (xy 358.007458 -238.275661) (xy 357.962926 -238.298351)
			(xy 357.915394 -238.313795) (xy 357.866031 -238.321614) (xy 357.816053 -238.321614) (xy 357.76669 -238.313795)
			(xy 357.719158 -238.298351) (xy 357.674626 -238.275661) (xy 357.634193 -238.246285) (xy 357.598853 -238.210945)
			(xy 357.569477 -238.170512) (xy 357.546787 -238.12598) (xy 357.531343 -238.078448) (xy 357.523524 -238.029085)
			(xy 357.21876 -238.029085) (xy 357.210941 -238.078448) (xy 357.195497 -238.12598) (xy 357.172807 -238.170512)
			(xy 357.143431 -238.210945) (xy 357.108091 -238.246285) (xy 357.067658 -238.275661) (xy 357.023126 -238.298351)
			(xy 356.975594 -238.313795) (xy 356.926231 -238.321614) (xy 356.876253 -238.321614) (xy 356.82689 -238.313795)
			(xy 356.779358 -238.298351) (xy 356.734826 -238.275661) (xy 356.694393 -238.246285) (xy 356.659053 -238.210945)
			(xy 356.629677 -238.170512) (xy 356.606987 -238.12598) (xy 356.591543 -238.078448) (xy 356.583724 -238.029085)
			(xy 356.278706 -238.029085) (xy 356.270887 -238.078448) (xy 356.255443 -238.12598) (xy 356.232753 -238.170512)
			(xy 356.203377 -238.210945) (xy 356.168037 -238.246285) (xy 356.127604 -238.275661) (xy 356.083072 -238.298351)
			(xy 356.03554 -238.313795) (xy 355.986177 -238.321614) (xy 355.936199 -238.321614) (xy 355.886836 -238.313795)
			(xy 355.839304 -238.298351) (xy 355.794772 -238.275661) (xy 355.754339 -238.246285) (xy 355.718999 -238.210945)
			(xy 355.689623 -238.170512) (xy 355.666933 -238.12598) (xy 355.651489 -238.078448) (xy 355.64367 -238.029085)
			(xy 355.336353 -238.029085) (xy 355.336344 -238.029542) (xy 355.32818 -238.079776) (xy 355.312064 -238.12805)
			(xy 355.288413 -238.173113) (xy 355.25784 -238.213799) (xy 355.221136 -238.249054) (xy 355.179252 -238.277964)
			(xy 355.133273 -238.299781) (xy 355.084389 -238.313941) (xy 355.033868 -238.320075) (xy 354.983016 -238.318026)
			(xy 354.933152 -238.307846) (xy 354.885566 -238.289799) (xy 354.841492 -238.264353) (xy 354.80207 -238.232166)
			(xy 354.768322 -238.194072) (xy 354.741121 -238.151058) (xy 354.721173 -238.104238) (xy 354.708994 -238.054824)
			(xy 354.704899 -238.004096) (xy 354.396802 -238.004096) (xy 354.39629 -238.029542) (xy 354.388126 -238.079776)
			(xy 354.37201 -238.12805) (xy 354.348359 -238.173113) (xy 354.317786 -238.213799) (xy 354.281082 -238.249054)
			(xy 354.239198 -238.277964) (xy 354.193219 -238.299781) (xy 354.144335 -238.313941) (xy 354.093814 -238.320075)
			(xy 354.042962 -238.318026) (xy 353.993098 -238.307846) (xy 353.945512 -238.289799) (xy 353.901438 -238.264353)
			(xy 353.862016 -238.232166) (xy 353.828268 -238.194072) (xy 353.801067 -238.151058) (xy 353.781119 -238.104238)
			(xy 353.76894 -238.054824) (xy 353.764845 -238.004096) (xy 353.459034 -238.004096) (xy 353.458544 -238.029085)
			(xy 353.450725 -238.078448) (xy 353.435281 -238.12598) (xy 353.412591 -238.170512) (xy 353.383215 -238.210945)
			(xy 353.347875 -238.246285) (xy 353.307442 -238.275661) (xy 353.26291 -238.298351) (xy 353.215378 -238.313795)
			(xy 353.166015 -238.321614) (xy 353.116037 -238.321614) (xy 353.066674 -238.313795) (xy 353.019142 -238.298351)
			(xy 352.97461 -238.275661) (xy 352.934177 -238.246285) (xy 352.898837 -238.210945) (xy 352.869461 -238.170512)
			(xy 352.846771 -238.12598) (xy 352.831327 -238.078448) (xy 352.823508 -238.029085) (xy 352.518744 -238.029085)
			(xy 352.510925 -238.078448) (xy 352.495481 -238.12598) (xy 352.472791 -238.170512) (xy 352.443415 -238.210945)
			(xy 352.408075 -238.246285) (xy 352.367642 -238.275661) (xy 352.32311 -238.298351) (xy 352.275578 -238.313795)
			(xy 352.226215 -238.321614) (xy 352.176237 -238.321614) (xy 352.126874 -238.313795) (xy 352.079342 -238.298351)
			(xy 352.03481 -238.275661) (xy 351.994377 -238.246285) (xy 351.959037 -238.210945) (xy 351.929661 -238.170512)
			(xy 351.906971 -238.12598) (xy 351.891527 -238.078448) (xy 351.883708 -238.029085) (xy 351.57869 -238.029085)
			(xy 351.570871 -238.078448) (xy 351.555427 -238.12598) (xy 351.532737 -238.170512) (xy 351.503361 -238.210945)
			(xy 351.468021 -238.246285) (xy 351.427588 -238.275661) (xy 351.383056 -238.298351) (xy 351.335524 -238.313795)
			(xy 351.286161 -238.321614) (xy 351.236183 -238.321614) (xy 351.18682 -238.313795) (xy 351.139288 -238.298351)
			(xy 351.094756 -238.275661) (xy 351.054323 -238.246285) (xy 351.018983 -238.210945) (xy 350.989607 -238.170512)
			(xy 350.966917 -238.12598) (xy 350.951473 -238.078448) (xy 350.943654 -238.029085) (xy 350.638636 -238.029085)
			(xy 350.630817 -238.078448) (xy 350.615373 -238.12598) (xy 350.592683 -238.170512) (xy 350.563307 -238.210945)
			(xy 350.527967 -238.246285) (xy 350.487534 -238.275661) (xy 350.443002 -238.298351) (xy 350.39547 -238.313795)
			(xy 350.346107 -238.321614) (xy 350.296129 -238.321614) (xy 350.246766 -238.313795) (xy 350.199234 -238.298351)
			(xy 350.154702 -238.275661) (xy 350.114269 -238.246285) (xy 350.078929 -238.210945) (xy 350.049553 -238.170512)
			(xy 350.026863 -238.12598) (xy 350.011419 -238.078448) (xy 350.0036 -238.029085) (xy 349.698582 -238.029085)
			(xy 349.690763 -238.078448) (xy 349.675319 -238.12598) (xy 349.652629 -238.170512) (xy 349.623253 -238.210945)
			(xy 349.587913 -238.246285) (xy 349.54748 -238.275661) (xy 349.502948 -238.298351) (xy 349.455416 -238.313795)
			(xy 349.406053 -238.321614) (xy 349.356075 -238.321614) (xy 349.306712 -238.313795) (xy 349.25918 -238.298351)
			(xy 349.214648 -238.275661) (xy 349.174215 -238.246285) (xy 349.138875 -238.210945) (xy 349.109499 -238.170512)
			(xy 349.086809 -238.12598) (xy 349.071365 -238.078448) (xy 349.063546 -238.029085) (xy 348.758528 -238.029085)
			(xy 348.750709 -238.078448) (xy 348.735265 -238.12598) (xy 348.712575 -238.170512) (xy 348.683199 -238.210945)
			(xy 348.647859 -238.246285) (xy 348.607426 -238.275661) (xy 348.562894 -238.298351) (xy 348.515362 -238.313795)
			(xy 348.465999 -238.321614) (xy 348.416021 -238.321614) (xy 348.366658 -238.313795) (xy 348.319126 -238.298351)
			(xy 348.274594 -238.275661) (xy 348.234161 -238.246285) (xy 348.198821 -238.210945) (xy 348.169445 -238.170512)
			(xy 348.146755 -238.12598) (xy 348.131311 -238.078448) (xy 348.123492 -238.029085) (xy 347.818728 -238.029085)
			(xy 347.810909 -238.078448) (xy 347.795465 -238.12598) (xy 347.772775 -238.170512) (xy 347.743399 -238.210945)
			(xy 347.708059 -238.246285) (xy 347.667626 -238.275661) (xy 347.623094 -238.298351) (xy 347.575562 -238.313795)
			(xy 347.526199 -238.321614) (xy 347.476221 -238.321614) (xy 347.426858 -238.313795) (xy 347.379326 -238.298351)
			(xy 347.334794 -238.275661) (xy 347.294361 -238.246285) (xy 347.259021 -238.210945) (xy 347.229645 -238.170512)
			(xy 347.206955 -238.12598) (xy 347.191511 -238.078448) (xy 347.183692 -238.029085) (xy 346.878674 -238.029085)
			(xy 346.870855 -238.078448) (xy 346.855411 -238.12598) (xy 346.832721 -238.170512) (xy 346.803345 -238.210945)
			(xy 346.768005 -238.246285) (xy 346.727572 -238.275661) (xy 346.68304 -238.298351) (xy 346.635508 -238.313795)
			(xy 346.586145 -238.321614) (xy 346.536167 -238.321614) (xy 346.486804 -238.313795) (xy 346.439272 -238.298351)
			(xy 346.39474 -238.275661) (xy 346.354307 -238.246285) (xy 346.318967 -238.210945) (xy 346.289591 -238.170512)
			(xy 346.266901 -238.12598) (xy 346.251457 -238.078448) (xy 346.243638 -238.029085) (xy 345.93862 -238.029085)
			(xy 345.930801 -238.078448) (xy 345.915357 -238.12598) (xy 345.892667 -238.170512) (xy 345.863291 -238.210945)
			(xy 345.827951 -238.246285) (xy 345.787518 -238.275661) (xy 345.742986 -238.298351) (xy 345.695454 -238.313795)
			(xy 345.646091 -238.321614) (xy 345.596113 -238.321614) (xy 345.54675 -238.313795) (xy 345.499218 -238.298351)
			(xy 345.454686 -238.275661) (xy 345.414253 -238.246285) (xy 345.378913 -238.210945) (xy 345.349537 -238.170512)
			(xy 345.326847 -238.12598) (xy 345.311403 -238.078448) (xy 345.303584 -238.029085) (xy 344.997981 -238.029085)
			(xy 344.997786 -238.03356) (xy 344.997532 -238.038132) (xy 344.997532 -238.839091) (xy 346.713538 -238.839091)
			(xy 346.713538 -238.789113) (xy 346.721357 -238.73975) (xy 346.736801 -238.692218) (xy 346.759491 -238.647686)
			(xy 346.788867 -238.607253) (xy 346.824207 -238.571913) (xy 346.86464 -238.542537) (xy 346.909172 -238.519847)
			(xy 346.956704 -238.504403) (xy 347.006067 -238.496584) (xy 347.056045 -238.496584) (xy 347.105408 -238.504403)
			(xy 347.15294 -238.519847) (xy 347.197472 -238.542537) (xy 347.237905 -238.571913) (xy 347.273245 -238.607253)
			(xy 347.302621 -238.647686) (xy 347.325311 -238.692218) (xy 347.340755 -238.73975) (xy 347.348574 -238.789113)
			(xy 347.349064 -238.814102) (xy 347.348574 -238.839091) (xy 349.5337 -238.839091) (xy 349.5337 -238.789113)
			(xy 349.541519 -238.73975) (xy 349.556963 -238.692218) (xy 349.579653 -238.647686) (xy 349.609029 -238.607253)
			(xy 349.644369 -238.571913) (xy 349.684802 -238.542537) (xy 349.729334 -238.519847) (xy 349.776866 -238.504403)
			(xy 349.826229 -238.496584) (xy 349.876207 -238.496584) (xy 349.92557 -238.504403) (xy 349.973102 -238.519847)
			(xy 350.017634 -238.542537) (xy 350.058067 -238.571913) (xy 350.093407 -238.607253) (xy 350.122783 -238.647686)
			(xy 350.145473 -238.692218) (xy 350.160917 -238.73975) (xy 350.168736 -238.789113) (xy 350.169226 -238.814102)
			(xy 350.168736 -238.839091) (xy 352.353608 -238.839091) (xy 352.353608 -238.789113) (xy 352.361427 -238.73975)
			(xy 352.376871 -238.692218) (xy 352.399561 -238.647686) (xy 352.428937 -238.607253) (xy 352.464277 -238.571913)
			(xy 352.50471 -238.542537) (xy 352.549242 -238.519847) (xy 352.596774 -238.504403) (xy 352.646137 -238.496584)
			(xy 352.696115 -238.496584) (xy 352.745478 -238.504403) (xy 352.79301 -238.519847) (xy 352.837542 -238.542537)
			(xy 352.877975 -238.571913) (xy 352.913315 -238.607253) (xy 352.942691 -238.647686) (xy 352.965381 -238.692218)
			(xy 352.980825 -238.73975) (xy 352.988644 -238.789113) (xy 352.989134 -238.814102) (xy 352.988644 -238.839091)
			(xy 355.173516 -238.839091) (xy 355.173516 -238.789113) (xy 355.181335 -238.73975) (xy 355.196779 -238.692218)
			(xy 355.219469 -238.647686) (xy 355.248845 -238.607253) (xy 355.284185 -238.571913) (xy 355.324618 -238.542537)
			(xy 355.36915 -238.519847) (xy 355.416682 -238.504403) (xy 355.466045 -238.496584) (xy 355.516023 -238.496584)
			(xy 355.565386 -238.504403) (xy 355.612918 -238.519847) (xy 355.65745 -238.542537) (xy 355.697883 -238.571913)
			(xy 355.733223 -238.607253) (xy 355.762599 -238.647686) (xy 355.785289 -238.692218) (xy 355.800733 -238.73975)
			(xy 355.808552 -238.789113) (xy 355.809042 -238.814102) (xy 356.114853 -238.814102) (xy 356.118948 -238.763374)
			(xy 356.131127 -238.71396) (xy 356.151075 -238.66714) (xy 356.178276 -238.624126) (xy 356.212024 -238.586032)
			(xy 356.251446 -238.553845) (xy 356.29552 -238.528399) (xy 356.343106 -238.510352) (xy 356.39297 -238.500172)
			(xy 356.443822 -238.498123) (xy 356.494343 -238.504257) (xy 356.543227 -238.518417) (xy 356.589206 -238.540234)
			(xy 356.63109 -238.569144) (xy 356.667794 -238.604399) (xy 356.698367 -238.645085) (xy 356.722018 -238.690148)
			(xy 356.738134 -238.738422) (xy 356.746298 -238.788656) (xy 356.74681 -238.814102) (xy 357.054907 -238.814102)
			(xy 357.059002 -238.763374) (xy 357.071181 -238.71396) (xy 357.091129 -238.66714) (xy 357.11833 -238.624126)
			(xy 357.152078 -238.586032) (xy 357.1915 -238.553845) (xy 357.235574 -238.528399) (xy 357.28316 -238.510352)
			(xy 357.333024 -238.500172) (xy 357.383876 -238.498123) (xy 357.434397 -238.504257) (xy 357.483281 -238.518417)
			(xy 357.52926 -238.540234) (xy 357.571144 -238.569144) (xy 357.607848 -238.604399) (xy 357.638421 -238.645085)
			(xy 357.662072 -238.690148) (xy 357.678188 -238.738422) (xy 357.686352 -238.788656) (xy 357.686864 -238.814102)
			(xy 357.686361 -238.839091) (xy 357.993678 -238.839091) (xy 357.993678 -238.789113) (xy 358.001497 -238.73975)
			(xy 358.016941 -238.692218) (xy 358.039631 -238.647686) (xy 358.069007 -238.607253) (xy 358.104347 -238.571913)
			(xy 358.14478 -238.542537) (xy 358.189312 -238.519847) (xy 358.236844 -238.504403) (xy 358.286207 -238.496584)
			(xy 358.336185 -238.496584) (xy 358.385548 -238.504403) (xy 358.43308 -238.519847) (xy 358.477612 -238.542537)
			(xy 358.518045 -238.571913) (xy 358.553385 -238.607253) (xy 358.582761 -238.647686) (xy 358.605451 -238.692218)
			(xy 358.620895 -238.73975) (xy 358.628714 -238.789113) (xy 358.629204 -238.814102) (xy 358.628714 -238.839091)
			(xy 360.807236 -238.839091) (xy 360.807236 -238.789113) (xy 360.815055 -238.73975) (xy 360.830499 -238.692218)
			(xy 360.853189 -238.647686) (xy 360.882565 -238.607253) (xy 360.917905 -238.571913) (xy 360.958338 -238.542537)
			(xy 361.00287 -238.519847) (xy 361.050402 -238.504403) (xy 361.099765 -238.496584) (xy 361.149743 -238.496584)
			(xy 361.199106 -238.504403) (xy 361.246638 -238.519847) (xy 361.29117 -238.542537) (xy 361.331603 -238.571913)
			(xy 361.366943 -238.607253) (xy 361.396319 -238.647686) (xy 361.419009 -238.692218) (xy 361.434453 -238.73975)
			(xy 361.442272 -238.789113) (xy 361.442762 -238.814102) (xy 361.748573 -238.814102) (xy 361.752668 -238.763374)
			(xy 361.764847 -238.71396) (xy 361.784795 -238.66714) (xy 361.811996 -238.624126) (xy 361.845744 -238.586032)
			(xy 361.885166 -238.553845) (xy 361.92924 -238.528399) (xy 361.976826 -238.510352) (xy 362.02669 -238.500172)
			(xy 362.077542 -238.498123) (xy 362.128063 -238.504257) (xy 362.176947 -238.518417) (xy 362.222926 -238.540234)
			(xy 362.26481 -238.569144) (xy 362.301514 -238.604399) (xy 362.332087 -238.645085) (xy 362.355738 -238.690148)
			(xy 362.371854 -238.738422) (xy 362.380018 -238.788656) (xy 362.38053 -238.814102) (xy 362.688627 -238.814102)
			(xy 362.692722 -238.763374) (xy 362.704901 -238.71396) (xy 362.724849 -238.66714) (xy 362.75205 -238.624126)
			(xy 362.785798 -238.586032) (xy 362.82522 -238.553845) (xy 362.869294 -238.528399) (xy 362.91688 -238.510352)
			(xy 362.966744 -238.500172) (xy 363.017596 -238.498123) (xy 363.068117 -238.504257) (xy 363.117001 -238.518417)
			(xy 363.16298 -238.540234) (xy 363.204864 -238.569144) (xy 363.241568 -238.604399) (xy 363.272141 -238.645085)
			(xy 363.295792 -238.690148) (xy 363.311908 -238.738422) (xy 363.320072 -238.788656) (xy 363.320584 -238.814102)
			(xy 363.320081 -238.839091) (xy 363.627398 -238.839091) (xy 363.627398 -238.789113) (xy 363.635217 -238.73975)
			(xy 363.650661 -238.692218) (xy 363.673351 -238.647686) (xy 363.702727 -238.607253) (xy 363.738067 -238.571913)
			(xy 363.7785 -238.542537) (xy 363.823032 -238.519847) (xy 363.870564 -238.504403) (xy 363.919927 -238.496584)
			(xy 363.969905 -238.496584) (xy 364.019268 -238.504403) (xy 364.0668 -238.519847) (xy 364.111332 -238.542537)
			(xy 364.151765 -238.571913) (xy 364.187105 -238.607253) (xy 364.216481 -238.647686) (xy 364.239171 -238.692218)
			(xy 364.254615 -238.73975) (xy 364.262434 -238.789113) (xy 364.262924 -238.814102) (xy 364.262434 -238.839091)
			(xy 366.447306 -238.839091) (xy 366.447306 -238.789113) (xy 366.455125 -238.73975) (xy 366.470569 -238.692218)
			(xy 366.493259 -238.647686) (xy 366.522635 -238.607253) (xy 366.557975 -238.571913) (xy 366.598408 -238.542537)
			(xy 366.64294 -238.519847) (xy 366.690472 -238.504403) (xy 366.739835 -238.496584) (xy 366.789813 -238.496584)
			(xy 366.839176 -238.504403) (xy 366.886708 -238.519847) (xy 366.93124 -238.542537) (xy 366.971673 -238.571913)
			(xy 367.007013 -238.607253) (xy 367.036389 -238.647686) (xy 367.059079 -238.692218) (xy 367.074523 -238.73975)
			(xy 367.082342 -238.789113) (xy 367.082832 -238.814102) (xy 367.082342 -238.839091) (xy 369.267214 -238.839091)
			(xy 369.267214 -238.789113) (xy 369.275033 -238.73975) (xy 369.290477 -238.692218) (xy 369.313167 -238.647686)
			(xy 369.342543 -238.607253) (xy 369.377883 -238.571913) (xy 369.418316 -238.542537) (xy 369.462848 -238.519847)
			(xy 369.51038 -238.504403) (xy 369.559743 -238.496584) (xy 369.609721 -238.496584) (xy 369.659084 -238.504403)
			(xy 369.706616 -238.519847) (xy 369.751148 -238.542537) (xy 369.791581 -238.571913) (xy 369.826921 -238.607253)
			(xy 369.856297 -238.647686) (xy 369.878987 -238.692218) (xy 369.894431 -238.73975) (xy 369.90225 -238.789113)
			(xy 369.90274 -238.814102) (xy 369.90225 -238.839091) (xy 372.087376 -238.839091) (xy 372.087376 -238.789113)
			(xy 372.095195 -238.73975) (xy 372.110639 -238.692218) (xy 372.133329 -238.647686) (xy 372.162705 -238.607253)
			(xy 372.198045 -238.571913) (xy 372.238478 -238.542537) (xy 372.28301 -238.519847) (xy 372.330542 -238.504403)
			(xy 372.379905 -238.496584) (xy 372.429883 -238.496584) (xy 372.479246 -238.504403) (xy 372.526778 -238.519847)
			(xy 372.57131 -238.542537) (xy 372.611743 -238.571913) (xy 372.647083 -238.607253) (xy 372.676459 -238.647686)
			(xy 372.699149 -238.692218) (xy 372.714593 -238.73975) (xy 372.722412 -238.789113) (xy 372.722902 -238.814102)
			(xy 372.722412 -238.839091) (xy 372.714593 -238.888454) (xy 372.699149 -238.935986) (xy 372.676459 -238.980518)
			(xy 372.647083 -239.020951) (xy 372.611743 -239.056291) (xy 372.57131 -239.085667) (xy 372.526778 -239.108357)
			(xy 372.479246 -239.123801) (xy 372.429883 -239.13162) (xy 372.379905 -239.13162) (xy 372.330542 -239.123801)
			(xy 372.28301 -239.108357) (xy 372.238478 -239.085667) (xy 372.198045 -239.056291) (xy 372.162705 -239.020951)
			(xy 372.133329 -238.980518) (xy 372.110639 -238.935986) (xy 372.095195 -238.888454) (xy 372.087376 -238.839091)
			(xy 369.90225 -238.839091) (xy 369.894431 -238.888454) (xy 369.878987 -238.935986) (xy 369.856297 -238.980518)
			(xy 369.826921 -239.020951) (xy 369.791581 -239.056291) (xy 369.751148 -239.085667) (xy 369.706616 -239.108357)
			(xy 369.659084 -239.123801) (xy 369.609721 -239.13162) (xy 369.559743 -239.13162) (xy 369.51038 -239.123801)
			(xy 369.462848 -239.108357) (xy 369.418316 -239.085667) (xy 369.377883 -239.056291) (xy 369.342543 -239.020951)
			(xy 369.313167 -238.980518) (xy 369.290477 -238.935986) (xy 369.275033 -238.888454) (xy 369.267214 -238.839091)
			(xy 367.082342 -238.839091) (xy 367.074523 -238.888454) (xy 367.059079 -238.935986) (xy 367.036389 -238.980518)
			(xy 367.007013 -239.020951) (xy 366.971673 -239.056291) (xy 366.93124 -239.085667) (xy 366.886708 -239.108357)
			(xy 366.839176 -239.123801) (xy 366.789813 -239.13162) (xy 366.739835 -239.13162) (xy 366.690472 -239.123801)
			(xy 366.64294 -239.108357) (xy 366.598408 -239.085667) (xy 366.557975 -239.056291) (xy 366.522635 -239.020951)
			(xy 366.493259 -238.980518) (xy 366.470569 -238.935986) (xy 366.455125 -238.888454) (xy 366.447306 -238.839091)
			(xy 364.262434 -238.839091) (xy 364.254615 -238.888454) (xy 364.239171 -238.935986) (xy 364.216481 -238.980518)
			(xy 364.187105 -239.020951) (xy 364.151765 -239.056291) (xy 364.111332 -239.085667) (xy 364.0668 -239.108357)
			(xy 364.019268 -239.123801) (xy 363.969905 -239.13162) (xy 363.919927 -239.13162) (xy 363.870564 -239.123801)
			(xy 363.823032 -239.108357) (xy 363.7785 -239.085667) (xy 363.738067 -239.056291) (xy 363.702727 -239.020951)
			(xy 363.673351 -238.980518) (xy 363.650661 -238.935986) (xy 363.635217 -238.888454) (xy 363.627398 -238.839091)
			(xy 363.320081 -238.839091) (xy 363.320072 -238.839548) (xy 363.311908 -238.889782) (xy 363.295792 -238.938056)
			(xy 363.272141 -238.983119) (xy 363.241568 -239.023805) (xy 363.204864 -239.05906) (xy 363.16298 -239.08797)
			(xy 363.117001 -239.109787) (xy 363.068117 -239.123947) (xy 363.017596 -239.130081) (xy 362.966744 -239.128032)
			(xy 362.91688 -239.117852) (xy 362.869294 -239.099805) (xy 362.82522 -239.074359) (xy 362.785798 -239.042172)
			(xy 362.75205 -239.004078) (xy 362.724849 -238.961064) (xy 362.704901 -238.914244) (xy 362.692722 -238.86483)
			(xy 362.688627 -238.814102) (xy 362.38053 -238.814102) (xy 362.380018 -238.839548) (xy 362.371854 -238.889782)
			(xy 362.355738 -238.938056) (xy 362.332087 -238.983119) (xy 362.301514 -239.023805) (xy 362.26481 -239.05906)
			(xy 362.222926 -239.08797) (xy 362.176947 -239.109787) (xy 362.128063 -239.123947) (xy 362.077542 -239.130081)
			(xy 362.02669 -239.128032) (xy 361.976826 -239.117852) (xy 361.92924 -239.099805) (xy 361.885166 -239.074359)
			(xy 361.845744 -239.042172) (xy 361.811996 -239.004078) (xy 361.784795 -238.961064) (xy 361.764847 -238.914244)
			(xy 361.752668 -238.86483) (xy 361.748573 -238.814102) (xy 361.442762 -238.814102) (xy 361.442272 -238.839091)
			(xy 361.434453 -238.888454) (xy 361.419009 -238.935986) (xy 361.396319 -238.980518) (xy 361.366943 -239.020951)
			(xy 361.331603 -239.056291) (xy 361.29117 -239.085667) (xy 361.246638 -239.108357) (xy 361.199106 -239.123801)
			(xy 361.149743 -239.13162) (xy 361.099765 -239.13162) (xy 361.050402 -239.123801) (xy 361.00287 -239.108357)
			(xy 360.958338 -239.085667) (xy 360.917905 -239.056291) (xy 360.882565 -239.020951) (xy 360.853189 -238.980518)
			(xy 360.830499 -238.935986) (xy 360.815055 -238.888454) (xy 360.807236 -238.839091) (xy 358.628714 -238.839091)
			(xy 358.620895 -238.888454) (xy 358.605451 -238.935986) (xy 358.582761 -238.980518) (xy 358.553385 -239.020951)
			(xy 358.518045 -239.056291) (xy 358.477612 -239.085667) (xy 358.43308 -239.108357) (xy 358.385548 -239.123801)
			(xy 358.336185 -239.13162) (xy 358.286207 -239.13162) (xy 358.236844 -239.123801) (xy 358.189312 -239.108357)
			(xy 358.14478 -239.085667) (xy 358.104347 -239.056291) (xy 358.069007 -239.020951) (xy 358.039631 -238.980518)
			(xy 358.016941 -238.935986) (xy 358.001497 -238.888454) (xy 357.993678 -238.839091) (xy 357.686361 -238.839091)
			(xy 357.686352 -238.839548) (xy 357.678188 -238.889782) (xy 357.662072 -238.938056) (xy 357.638421 -238.983119)
			(xy 357.607848 -239.023805) (xy 357.571144 -239.05906) (xy 357.52926 -239.08797) (xy 357.483281 -239.109787)
			(xy 357.434397 -239.123947) (xy 357.383876 -239.130081) (xy 357.333024 -239.128032) (xy 357.28316 -239.117852)
			(xy 357.235574 -239.099805) (xy 357.1915 -239.074359) (xy 357.152078 -239.042172) (xy 357.11833 -239.004078)
			(xy 357.091129 -238.961064) (xy 357.071181 -238.914244) (xy 357.059002 -238.86483) (xy 357.054907 -238.814102)
			(xy 356.74681 -238.814102) (xy 356.746298 -238.839548) (xy 356.738134 -238.889782) (xy 356.722018 -238.938056)
			(xy 356.698367 -238.983119) (xy 356.667794 -239.023805) (xy 356.63109 -239.05906) (xy 356.589206 -239.08797)
			(xy 356.543227 -239.109787) (xy 356.494343 -239.123947) (xy 356.443822 -239.130081) (xy 356.39297 -239.128032)
			(xy 356.343106 -239.117852) (xy 356.29552 -239.099805) (xy 356.251446 -239.074359) (xy 356.212024 -239.042172)
			(xy 356.178276 -239.004078) (xy 356.151075 -238.961064) (xy 356.131127 -238.914244) (xy 356.118948 -238.86483)
			(xy 356.114853 -238.814102) (xy 355.809042 -238.814102) (xy 355.808552 -238.839091) (xy 355.800733 -238.888454)
			(xy 355.785289 -238.935986) (xy 355.762599 -238.980518) (xy 355.733223 -239.020951) (xy 355.697883 -239.056291)
			(xy 355.65745 -239.085667) (xy 355.612918 -239.108357) (xy 355.565386 -239.123801) (xy 355.516023 -239.13162)
			(xy 355.466045 -239.13162) (xy 355.416682 -239.123801) (xy 355.36915 -239.108357) (xy 355.324618 -239.085667)
			(xy 355.284185 -239.056291) (xy 355.248845 -239.020951) (xy 355.219469 -238.980518) (xy 355.196779 -238.935986)
			(xy 355.181335 -238.888454) (xy 355.173516 -238.839091) (xy 352.988644 -238.839091) (xy 352.980825 -238.888454)
			(xy 352.965381 -238.935986) (xy 352.942691 -238.980518) (xy 352.913315 -239.020951) (xy 352.877975 -239.056291)
			(xy 352.837542 -239.085667) (xy 352.79301 -239.108357) (xy 352.745478 -239.123801) (xy 352.696115 -239.13162)
			(xy 352.646137 -239.13162) (xy 352.596774 -239.123801) (xy 352.549242 -239.108357) (xy 352.50471 -239.085667)
			(xy 352.464277 -239.056291) (xy 352.428937 -239.020951) (xy 352.399561 -238.980518) (xy 352.376871 -238.935986)
			(xy 352.361427 -238.888454) (xy 352.353608 -238.839091) (xy 350.168736 -238.839091) (xy 350.160917 -238.888454)
			(xy 350.145473 -238.935986) (xy 350.122783 -238.980518) (xy 350.093407 -239.020951) (xy 350.058067 -239.056291)
			(xy 350.017634 -239.085667) (xy 349.973102 -239.108357) (xy 349.92557 -239.123801) (xy 349.876207 -239.13162)
			(xy 349.826229 -239.13162) (xy 349.776866 -239.123801) (xy 349.729334 -239.108357) (xy 349.684802 -239.085667)
			(xy 349.644369 -239.056291) (xy 349.609029 -239.020951) (xy 349.579653 -238.980518) (xy 349.556963 -238.935986)
			(xy 349.541519 -238.888454) (xy 349.5337 -238.839091) (xy 347.348574 -238.839091) (xy 347.340755 -238.888454)
			(xy 347.325311 -238.935986) (xy 347.302621 -238.980518) (xy 347.273245 -239.020951) (xy 347.237905 -239.056291)
			(xy 347.197472 -239.085667) (xy 347.15294 -239.108357) (xy 347.105408 -239.123801) (xy 347.056045 -239.13162)
			(xy 347.006067 -239.13162) (xy 346.956704 -239.123801) (xy 346.909172 -239.108357) (xy 346.86464 -239.085667)
			(xy 346.824207 -239.056291) (xy 346.788867 -239.020951) (xy 346.759491 -238.980518) (xy 346.736801 -238.935986)
			(xy 346.721357 -238.888454) (xy 346.713538 -238.839091) (xy 344.997532 -238.839091) (xy 344.997532 -239.590072)
			(xy 344.997786 -239.594644) (xy 344.999056 -239.623854) (xy 344.999056 -239.624108) (xy 345.304867 -239.624108)
			(xy 345.308962 -239.57338) (xy 345.321141 -239.523966) (xy 345.341089 -239.477146) (xy 345.36829 -239.434132)
			(xy 345.402038 -239.396038) (xy 345.44146 -239.363851) (xy 345.485534 -239.338405) (xy 345.53312 -239.320358)
			(xy 345.582984 -239.310178) (xy 345.633836 -239.308129) (xy 345.684357 -239.314263) (xy 345.733241 -239.328423)
			(xy 345.77922 -239.35024) (xy 345.821104 -239.37915) (xy 345.857808 -239.414405) (xy 345.888381 -239.455091)
			(xy 345.912032 -239.500154) (xy 345.928148 -239.548428) (xy 345.936312 -239.598662) (xy 345.936824 -239.624108)
			(xy 346.244921 -239.624108) (xy 346.249016 -239.57338) (xy 346.261195 -239.523966) (xy 346.281143 -239.477146)
			(xy 346.308344 -239.434132) (xy 346.342092 -239.396038) (xy 346.381514 -239.363851) (xy 346.425588 -239.338405)
			(xy 346.473174 -239.320358) (xy 346.523038 -239.310178) (xy 346.57389 -239.308129) (xy 346.624411 -239.314263)
			(xy 346.673295 -239.328423) (xy 346.719274 -239.35024) (xy 346.761158 -239.37915) (xy 346.797862 -239.414405)
			(xy 346.828435 -239.455091) (xy 346.852086 -239.500154) (xy 346.868202 -239.548428) (xy 346.876366 -239.598662)
			(xy 346.876878 -239.624108) (xy 346.876375 -239.649097) (xy 347.183692 -239.649097) (xy 347.183692 -239.599119)
			(xy 347.191511 -239.549756) (xy 347.206955 -239.502224) (xy 347.229645 -239.457692) (xy 347.259021 -239.417259)
			(xy 347.294361 -239.381919) (xy 347.334794 -239.352543) (xy 347.379326 -239.329853) (xy 347.426858 -239.314409)
			(xy 347.476221 -239.30659) (xy 347.526199 -239.30659) (xy 347.575562 -239.314409) (xy 347.623094 -239.329853)
			(xy 347.667626 -239.352543) (xy 347.708059 -239.381919) (xy 347.743399 -239.417259) (xy 347.772775 -239.457692)
			(xy 347.795465 -239.502224) (xy 347.810909 -239.549756) (xy 347.818728 -239.599119) (xy 347.819218 -239.624108)
			(xy 348.124775 -239.624108) (xy 348.12887 -239.57338) (xy 348.141049 -239.523966) (xy 348.160997 -239.477146)
			(xy 348.188198 -239.434132) (xy 348.221946 -239.396038) (xy 348.261368 -239.363851) (xy 348.305442 -239.338405)
			(xy 348.353028 -239.320358) (xy 348.402892 -239.310178) (xy 348.453744 -239.308129) (xy 348.504265 -239.314263)
			(xy 348.553149 -239.328423) (xy 348.599128 -239.35024) (xy 348.641012 -239.37915) (xy 348.677716 -239.414405)
			(xy 348.708289 -239.455091) (xy 348.73194 -239.500154) (xy 348.748056 -239.548428) (xy 348.75622 -239.598662)
			(xy 348.756732 -239.624108) (xy 349.064829 -239.624108) (xy 349.068924 -239.57338) (xy 349.081103 -239.523966)
			(xy 349.101051 -239.477146) (xy 349.128252 -239.434132) (xy 349.162 -239.396038) (xy 349.201422 -239.363851)
			(xy 349.245496 -239.338405) (xy 349.293082 -239.320358) (xy 349.342946 -239.310178) (xy 349.393798 -239.308129)
			(xy 349.444319 -239.314263) (xy 349.493203 -239.328423) (xy 349.539182 -239.35024) (xy 349.581066 -239.37915)
			(xy 349.61777 -239.414405) (xy 349.648343 -239.455091) (xy 349.671994 -239.500154) (xy 349.68811 -239.548428)
			(xy 349.696274 -239.598662) (xy 349.696786 -239.624108) (xy 349.696283 -239.649097) (xy 350.0036 -239.649097)
			(xy 350.0036 -239.599119) (xy 350.011419 -239.549756) (xy 350.026863 -239.502224) (xy 350.049553 -239.457692)
			(xy 350.078929 -239.417259) (xy 350.114269 -239.381919) (xy 350.154702 -239.352543) (xy 350.199234 -239.329853)
			(xy 350.246766 -239.314409) (xy 350.296129 -239.30659) (xy 350.346107 -239.30659) (xy 350.39547 -239.314409)
			(xy 350.443002 -239.329853) (xy 350.487534 -239.352543) (xy 350.527967 -239.381919) (xy 350.563307 -239.417259)
			(xy 350.592683 -239.457692) (xy 350.615373 -239.502224) (xy 350.630817 -239.549756) (xy 350.638636 -239.599119)
			(xy 350.639126 -239.624108) (xy 350.944937 -239.624108) (xy 350.949032 -239.57338) (xy 350.961211 -239.523966)
			(xy 350.981159 -239.477146) (xy 351.00836 -239.434132) (xy 351.042108 -239.396038) (xy 351.08153 -239.363851)
			(xy 351.125604 -239.338405) (xy 351.17319 -239.320358) (xy 351.223054 -239.310178) (xy 351.273906 -239.308129)
			(xy 351.324427 -239.314263) (xy 351.373311 -239.328423) (xy 351.41929 -239.35024) (xy 351.461174 -239.37915)
			(xy 351.497878 -239.414405) (xy 351.528451 -239.455091) (xy 351.552102 -239.500154) (xy 351.568218 -239.548428)
			(xy 351.576382 -239.598662) (xy 351.576894 -239.624108) (xy 351.884991 -239.624108) (xy 351.889086 -239.57338)
			(xy 351.901265 -239.523966) (xy 351.921213 -239.477146) (xy 351.948414 -239.434132) (xy 351.982162 -239.396038)
			(xy 352.021584 -239.363851) (xy 352.065658 -239.338405) (xy 352.113244 -239.320358) (xy 352.163108 -239.310178)
			(xy 352.21396 -239.308129) (xy 352.264481 -239.314263) (xy 352.313365 -239.328423) (xy 352.359344 -239.35024)
			(xy 352.401228 -239.37915) (xy 352.437932 -239.414405) (xy 352.468505 -239.455091) (xy 352.492156 -239.500154)
			(xy 352.508272 -239.548428) (xy 352.516436 -239.598662) (xy 352.516948 -239.624108) (xy 352.516445 -239.649097)
			(xy 352.823508 -239.649097) (xy 352.823508 -239.599119) (xy 352.831327 -239.549756) (xy 352.846771 -239.502224)
			(xy 352.869461 -239.457692) (xy 352.898837 -239.417259) (xy 352.934177 -239.381919) (xy 352.97461 -239.352543)
			(xy 353.019142 -239.329853) (xy 353.066674 -239.314409) (xy 353.116037 -239.30659) (xy 353.166015 -239.30659)
			(xy 353.215378 -239.314409) (xy 353.26291 -239.329853) (xy 353.307442 -239.352543) (xy 353.347875 -239.381919)
			(xy 353.383215 -239.417259) (xy 353.412591 -239.457692) (xy 353.435281 -239.502224) (xy 353.450725 -239.549756)
			(xy 353.458544 -239.599119) (xy 353.459034 -239.624108) (xy 353.764845 -239.624108) (xy 353.76894 -239.57338)
			(xy 353.781119 -239.523966) (xy 353.801067 -239.477146) (xy 353.828268 -239.434132) (xy 353.862016 -239.396038)
			(xy 353.901438 -239.363851) (xy 353.945512 -239.338405) (xy 353.993098 -239.320358) (xy 354.042962 -239.310178)
			(xy 354.093814 -239.308129) (xy 354.144335 -239.314263) (xy 354.193219 -239.328423) (xy 354.239198 -239.35024)
			(xy 354.281082 -239.37915) (xy 354.317786 -239.414405) (xy 354.348359 -239.455091) (xy 354.37201 -239.500154)
			(xy 354.388126 -239.548428) (xy 354.39629 -239.598662) (xy 354.396802 -239.624108) (xy 354.704899 -239.624108)
			(xy 354.708994 -239.57338) (xy 354.721173 -239.523966) (xy 354.741121 -239.477146) (xy 354.768322 -239.434132)
			(xy 354.80207 -239.396038) (xy 354.841492 -239.363851) (xy 354.885566 -239.338405) (xy 354.933152 -239.320358)
			(xy 354.983016 -239.310178) (xy 355.033868 -239.308129) (xy 355.084389 -239.314263) (xy 355.133273 -239.328423)
			(xy 355.179252 -239.35024) (xy 355.221136 -239.37915) (xy 355.25784 -239.414405) (xy 355.288413 -239.455091)
			(xy 355.312064 -239.500154) (xy 355.32818 -239.548428) (xy 355.336344 -239.598662) (xy 355.336856 -239.624108)
			(xy 355.336353 -239.649097) (xy 355.64367 -239.649097) (xy 355.64367 -239.599119) (xy 355.651489 -239.549756)
			(xy 355.666933 -239.502224) (xy 355.689623 -239.457692) (xy 355.718999 -239.417259) (xy 355.754339 -239.381919)
			(xy 355.794772 -239.352543) (xy 355.839304 -239.329853) (xy 355.886836 -239.314409) (xy 355.936199 -239.30659)
			(xy 355.986177 -239.30659) (xy 356.03554 -239.314409) (xy 356.083072 -239.329853) (xy 356.127604 -239.352543)
			(xy 356.168037 -239.381919) (xy 356.203377 -239.417259) (xy 356.232753 -239.457692) (xy 356.255443 -239.502224)
			(xy 356.270887 -239.549756) (xy 356.278706 -239.599119) (xy 356.279196 -239.624108) (xy 356.278706 -239.649097)
			(xy 363.157244 -239.649097) (xy 363.157244 -239.599119) (xy 363.165063 -239.549756) (xy 363.180507 -239.502224)
			(xy 363.203197 -239.457692) (xy 363.232573 -239.417259) (xy 363.267913 -239.381919) (xy 363.308346 -239.352543)
			(xy 363.352878 -239.329853) (xy 363.40041 -239.314409) (xy 363.449773 -239.30659) (xy 363.499751 -239.30659)
			(xy 363.549114 -239.314409) (xy 363.596646 -239.329853) (xy 363.641178 -239.352543) (xy 363.681611 -239.381919)
			(xy 363.716951 -239.417259) (xy 363.746327 -239.457692) (xy 363.769017 -239.502224) (xy 363.784461 -239.549756)
			(xy 363.79228 -239.599119) (xy 363.79277 -239.624108) (xy 364.098581 -239.624108) (xy 364.102676 -239.57338)
			(xy 364.114855 -239.523966) (xy 364.134803 -239.477146) (xy 364.162004 -239.434132) (xy 364.195752 -239.396038)
			(xy 364.235174 -239.363851) (xy 364.279248 -239.338405) (xy 364.326834 -239.320358) (xy 364.376698 -239.310178)
			(xy 364.42755 -239.308129) (xy 364.478071 -239.314263) (xy 364.526955 -239.328423) (xy 364.572934 -239.35024)
			(xy 364.614818 -239.37915) (xy 364.651522 -239.414405) (xy 364.682095 -239.455091) (xy 364.705746 -239.500154)
			(xy 364.721862 -239.548428) (xy 364.730026 -239.598662) (xy 364.730538 -239.624108) (xy 365.038635 -239.624108)
			(xy 365.04273 -239.57338) (xy 365.054909 -239.523966) (xy 365.074857 -239.477146) (xy 365.102058 -239.434132)
			(xy 365.135806 -239.396038) (xy 365.175228 -239.363851) (xy 365.219302 -239.338405) (xy 365.266888 -239.320358)
			(xy 365.316752 -239.310178) (xy 365.367604 -239.308129) (xy 365.418125 -239.314263) (xy 365.467009 -239.328423)
			(xy 365.512988 -239.35024) (xy 365.554872 -239.37915) (xy 365.591576 -239.414405) (xy 365.622149 -239.455091)
			(xy 365.6458 -239.500154) (xy 365.661916 -239.548428) (xy 365.67008 -239.598662) (xy 365.670592 -239.624108)
			(xy 365.670089 -239.649097) (xy 365.977406 -239.649097) (xy 365.977406 -239.599119) (xy 365.985225 -239.549756)
			(xy 366.000669 -239.502224) (xy 366.023359 -239.457692) (xy 366.052735 -239.417259) (xy 366.088075 -239.381919)
			(xy 366.128508 -239.352543) (xy 366.17304 -239.329853) (xy 366.220572 -239.314409) (xy 366.269935 -239.30659)
			(xy 366.319913 -239.30659) (xy 366.369276 -239.314409) (xy 366.416808 -239.329853) (xy 366.46134 -239.352543)
			(xy 366.501773 -239.381919) (xy 366.537113 -239.417259) (xy 366.566489 -239.457692) (xy 366.589179 -239.502224)
			(xy 366.604623 -239.549756) (xy 366.612442 -239.599119) (xy 366.612932 -239.624108) (xy 366.918489 -239.624108)
			(xy 366.922584 -239.57338) (xy 366.934763 -239.523966) (xy 366.954711 -239.477146) (xy 366.981912 -239.434132)
			(xy 367.01566 -239.396038) (xy 367.055082 -239.363851) (xy 367.099156 -239.338405) (xy 367.146742 -239.320358)
			(xy 367.196606 -239.310178) (xy 367.247458 -239.308129) (xy 367.297979 -239.314263) (xy 367.346863 -239.328423)
			(xy 367.392842 -239.35024) (xy 367.434726 -239.37915) (xy 367.47143 -239.414405) (xy 367.502003 -239.455091)
			(xy 367.525654 -239.500154) (xy 367.54177 -239.548428) (xy 367.549934 -239.598662) (xy 367.550446 -239.624108)
			(xy 367.858543 -239.624108) (xy 367.862638 -239.57338) (xy 367.874817 -239.523966) (xy 367.894765 -239.477146)
			(xy 367.921966 -239.434132) (xy 367.955714 -239.396038) (xy 367.995136 -239.363851) (xy 368.03921 -239.338405)
			(xy 368.086796 -239.320358) (xy 368.13666 -239.310178) (xy 368.187512 -239.308129) (xy 368.238033 -239.314263)
			(xy 368.286917 -239.328423) (xy 368.332896 -239.35024) (xy 368.37478 -239.37915) (xy 368.411484 -239.414405)
			(xy 368.442057 -239.455091) (xy 368.465708 -239.500154) (xy 368.481824 -239.548428) (xy 368.489988 -239.598662)
			(xy 368.4905 -239.624108) (xy 368.489997 -239.649097) (xy 368.797314 -239.649097) (xy 368.797314 -239.599119)
			(xy 368.805133 -239.549756) (xy 368.820577 -239.502224) (xy 368.843267 -239.457692) (xy 368.872643 -239.417259)
			(xy 368.907983 -239.381919) (xy 368.948416 -239.352543) (xy 368.992948 -239.329853) (xy 369.04048 -239.314409)
			(xy 369.089843 -239.30659) (xy 369.139821 -239.30659) (xy 369.189184 -239.314409) (xy 369.236716 -239.329853)
			(xy 369.281248 -239.352543) (xy 369.321681 -239.381919) (xy 369.357021 -239.417259) (xy 369.386397 -239.457692)
			(xy 369.409087 -239.502224) (xy 369.424531 -239.549756) (xy 369.43235 -239.599119) (xy 369.43284 -239.624108)
			(xy 369.738651 -239.624108) (xy 369.742746 -239.57338) (xy 369.754925 -239.523966) (xy 369.774873 -239.477146)
			(xy 369.802074 -239.434132) (xy 369.835822 -239.396038) (xy 369.875244 -239.363851) (xy 369.919318 -239.338405)
			(xy 369.966904 -239.320358) (xy 370.016768 -239.310178) (xy 370.06762 -239.308129) (xy 370.118141 -239.314263)
			(xy 370.167025 -239.328423) (xy 370.213004 -239.35024) (xy 370.254888 -239.37915) (xy 370.291592 -239.414405)
			(xy 370.322165 -239.455091) (xy 370.345816 -239.500154) (xy 370.361932 -239.548428) (xy 370.370096 -239.598662)
			(xy 370.370608 -239.624108) (xy 370.678451 -239.624108) (xy 370.682546 -239.57338) (xy 370.694725 -239.523966)
			(xy 370.714673 -239.477146) (xy 370.741874 -239.434132) (xy 370.775622 -239.396038) (xy 370.815044 -239.363851)
			(xy 370.859118 -239.338405) (xy 370.906704 -239.320358) (xy 370.956568 -239.310178) (xy 371.00742 -239.308129)
			(xy 371.057941 -239.314263) (xy 371.106825 -239.328423) (xy 371.152804 -239.35024) (xy 371.194688 -239.37915)
			(xy 371.231392 -239.414405) (xy 371.261965 -239.455091) (xy 371.285616 -239.500154) (xy 371.301732 -239.548428)
			(xy 371.309896 -239.598662) (xy 371.310408 -239.624108) (xy 371.309905 -239.649097) (xy 371.617222 -239.649097)
			(xy 371.617222 -239.599119) (xy 371.625041 -239.549756) (xy 371.640485 -239.502224) (xy 371.663175 -239.457692)
			(xy 371.692551 -239.417259) (xy 371.727891 -239.381919) (xy 371.768324 -239.352543) (xy 371.812856 -239.329853)
			(xy 371.860388 -239.314409) (xy 371.909751 -239.30659) (xy 371.959729 -239.30659) (xy 372.009092 -239.314409)
			(xy 372.056624 -239.329853) (xy 372.101156 -239.352543) (xy 372.141589 -239.381919) (xy 372.176929 -239.417259)
			(xy 372.206305 -239.457692) (xy 372.228995 -239.502224) (xy 372.244439 -239.549756) (xy 372.252258 -239.599119)
			(xy 372.252748 -239.624108) (xy 372.558559 -239.624108) (xy 372.562654 -239.57338) (xy 372.574833 -239.523966)
			(xy 372.594781 -239.477146) (xy 372.621982 -239.434132) (xy 372.65573 -239.396038) (xy 372.695152 -239.363851)
			(xy 372.739226 -239.338405) (xy 372.786812 -239.320358) (xy 372.836676 -239.310178) (xy 372.887528 -239.308129)
			(xy 372.938049 -239.314263) (xy 372.986933 -239.328423) (xy 373.032912 -239.35024) (xy 373.074796 -239.37915)
			(xy 373.1115 -239.414405) (xy 373.142073 -239.455091) (xy 373.165724 -239.500154) (xy 373.18184 -239.548428)
			(xy 373.190004 -239.598662) (xy 373.190516 -239.624108) (xy 373.498613 -239.624108) (xy 373.502708 -239.57338)
			(xy 373.514887 -239.523966) (xy 373.534835 -239.477146) (xy 373.562036 -239.434132) (xy 373.595784 -239.396038)
			(xy 373.635206 -239.363851) (xy 373.67928 -239.338405) (xy 373.726866 -239.320358) (xy 373.77673 -239.310178)
			(xy 373.827582 -239.308129) (xy 373.878103 -239.314263) (xy 373.926987 -239.328423) (xy 373.972966 -239.35024)
			(xy 374.01485 -239.37915) (xy 374.051554 -239.414405) (xy 374.082127 -239.455091) (xy 374.105778 -239.500154)
			(xy 374.121894 -239.548428) (xy 374.130058 -239.598662) (xy 374.13057 -239.624108) (xy 374.130058 -239.649554)
			(xy 374.121894 -239.699788) (xy 374.105778 -239.748062) (xy 374.082127 -239.793125) (xy 374.051554 -239.833811)
			(xy 374.01485 -239.869066) (xy 373.972966 -239.897976) (xy 373.926987 -239.919793) (xy 373.878103 -239.933953)
			(xy 373.827582 -239.940087) (xy 373.77673 -239.938038) (xy 373.726866 -239.927858) (xy 373.67928 -239.909811)
			(xy 373.635206 -239.884365) (xy 373.595784 -239.852178) (xy 373.562036 -239.814084) (xy 373.534835 -239.77107)
			(xy 373.514887 -239.72425) (xy 373.502708 -239.674836) (xy 373.498613 -239.624108) (xy 373.190516 -239.624108)
			(xy 373.190004 -239.649554) (xy 373.18184 -239.699788) (xy 373.165724 -239.748062) (xy 373.142073 -239.793125)
			(xy 373.1115 -239.833811) (xy 373.074796 -239.869066) (xy 373.032912 -239.897976) (xy 372.986933 -239.919793)
			(xy 372.938049 -239.933953) (xy 372.887528 -239.940087) (xy 372.836676 -239.938038) (xy 372.786812 -239.927858)
			(xy 372.739226 -239.909811) (xy 372.695152 -239.884365) (xy 372.65573 -239.852178) (xy 372.621982 -239.814084)
			(xy 372.594781 -239.77107) (xy 372.574833 -239.72425) (xy 372.562654 -239.674836) (xy 372.558559 -239.624108)
			(xy 372.252748 -239.624108) (xy 372.252258 -239.649097) (xy 372.244439 -239.69846) (xy 372.228995 -239.745992)
			(xy 372.206305 -239.790524) (xy 372.176929 -239.830957) (xy 372.141589 -239.866297) (xy 372.101156 -239.895673)
			(xy 372.056624 -239.918363) (xy 372.009092 -239.933807) (xy 371.959729 -239.941626) (xy 371.909751 -239.941626)
			(xy 371.860388 -239.933807) (xy 371.812856 -239.918363) (xy 371.768324 -239.895673) (xy 371.727891 -239.866297)
			(xy 371.692551 -239.830957) (xy 371.663175 -239.790524) (xy 371.640485 -239.745992) (xy 371.625041 -239.69846)
			(xy 371.617222 -239.649097) (xy 371.309905 -239.649097) (xy 371.309896 -239.649554) (xy 371.301732 -239.699788)
			(xy 371.285616 -239.748062) (xy 371.261965 -239.793125) (xy 371.231392 -239.833811) (xy 371.194688 -239.869066)
			(xy 371.152804 -239.897976) (xy 371.106825 -239.919793) (xy 371.057941 -239.933953) (xy 371.00742 -239.940087)
			(xy 370.956568 -239.938038) (xy 370.906704 -239.927858) (xy 370.859118 -239.909811) (xy 370.815044 -239.884365)
			(xy 370.775622 -239.852178) (xy 370.741874 -239.814084) (xy 370.714673 -239.77107) (xy 370.694725 -239.72425)
			(xy 370.682546 -239.674836) (xy 370.678451 -239.624108) (xy 370.370608 -239.624108) (xy 370.370096 -239.649554)
			(xy 370.361932 -239.699788) (xy 370.345816 -239.748062) (xy 370.322165 -239.793125) (xy 370.291592 -239.833811)
			(xy 370.254888 -239.869066) (xy 370.213004 -239.897976) (xy 370.167025 -239.919793) (xy 370.118141 -239.933953)
			(xy 370.06762 -239.940087) (xy 370.016768 -239.938038) (xy 369.966904 -239.927858) (xy 369.919318 -239.909811)
			(xy 369.875244 -239.884365) (xy 369.835822 -239.852178) (xy 369.802074 -239.814084) (xy 369.774873 -239.77107)
			(xy 369.754925 -239.72425) (xy 369.742746 -239.674836) (xy 369.738651 -239.624108) (xy 369.43284 -239.624108)
			(xy 369.43235 -239.649097) (xy 369.424531 -239.69846) (xy 369.409087 -239.745992) (xy 369.386397 -239.790524)
			(xy 369.357021 -239.830957) (xy 369.321681 -239.866297) (xy 369.281248 -239.895673) (xy 369.236716 -239.918363)
			(xy 369.189184 -239.933807) (xy 369.139821 -239.941626) (xy 369.089843 -239.941626) (xy 369.04048 -239.933807)
			(xy 368.992948 -239.918363) (xy 368.948416 -239.895673) (xy 368.907983 -239.866297) (xy 368.872643 -239.830957)
			(xy 368.843267 -239.790524) (xy 368.820577 -239.745992) (xy 368.805133 -239.69846) (xy 368.797314 -239.649097)
			(xy 368.489997 -239.649097) (xy 368.489988 -239.649554) (xy 368.481824 -239.699788) (xy 368.465708 -239.748062)
			(xy 368.442057 -239.793125) (xy 368.411484 -239.833811) (xy 368.37478 -239.869066) (xy 368.332896 -239.897976)
			(xy 368.286917 -239.919793) (xy 368.238033 -239.933953) (xy 368.187512 -239.940087) (xy 368.13666 -239.938038)
			(xy 368.086796 -239.927858) (xy 368.03921 -239.909811) (xy 367.995136 -239.884365) (xy 367.955714 -239.852178)
			(xy 367.921966 -239.814084) (xy 367.894765 -239.77107) (xy 367.874817 -239.72425) (xy 367.862638 -239.674836)
			(xy 367.858543 -239.624108) (xy 367.550446 -239.624108) (xy 367.549934 -239.649554) (xy 367.54177 -239.699788)
			(xy 367.525654 -239.748062) (xy 367.502003 -239.793125) (xy 367.47143 -239.833811) (xy 367.434726 -239.869066)
			(xy 367.392842 -239.897976) (xy 367.346863 -239.919793) (xy 367.297979 -239.933953) (xy 367.247458 -239.940087)
			(xy 367.196606 -239.938038) (xy 367.146742 -239.927858) (xy 367.099156 -239.909811) (xy 367.055082 -239.884365)
			(xy 367.01566 -239.852178) (xy 366.981912 -239.814084) (xy 366.954711 -239.77107) (xy 366.934763 -239.72425)
			(xy 366.922584 -239.674836) (xy 366.918489 -239.624108) (xy 366.612932 -239.624108) (xy 366.612442 -239.649097)
			(xy 366.604623 -239.69846) (xy 366.589179 -239.745992) (xy 366.566489 -239.790524) (xy 366.537113 -239.830957)
			(xy 366.501773 -239.866297) (xy 366.46134 -239.895673) (xy 366.416808 -239.918363) (xy 366.369276 -239.933807)
			(xy 366.319913 -239.941626) (xy 366.269935 -239.941626) (xy 366.220572 -239.933807) (xy 366.17304 -239.918363)
			(xy 366.128508 -239.895673) (xy 366.088075 -239.866297) (xy 366.052735 -239.830957) (xy 366.023359 -239.790524)
			(xy 366.000669 -239.745992) (xy 365.985225 -239.69846) (xy 365.977406 -239.649097) (xy 365.670089 -239.649097)
			(xy 365.67008 -239.649554) (xy 365.661916 -239.699788) (xy 365.6458 -239.748062) (xy 365.622149 -239.793125)
			(xy 365.591576 -239.833811) (xy 365.554872 -239.869066) (xy 365.512988 -239.897976) (xy 365.467009 -239.919793)
			(xy 365.418125 -239.933953) (xy 365.367604 -239.940087) (xy 365.316752 -239.938038) (xy 365.266888 -239.927858)
			(xy 365.219302 -239.909811) (xy 365.175228 -239.884365) (xy 365.135806 -239.852178) (xy 365.102058 -239.814084)
			(xy 365.074857 -239.77107) (xy 365.054909 -239.72425) (xy 365.04273 -239.674836) (xy 365.038635 -239.624108)
			(xy 364.730538 -239.624108) (xy 364.730026 -239.649554) (xy 364.721862 -239.699788) (xy 364.705746 -239.748062)
			(xy 364.682095 -239.793125) (xy 364.651522 -239.833811) (xy 364.614818 -239.869066) (xy 364.572934 -239.897976)
			(xy 364.526955 -239.919793) (xy 364.478071 -239.933953) (xy 364.42755 -239.940087) (xy 364.376698 -239.938038)
			(xy 364.326834 -239.927858) (xy 364.279248 -239.909811) (xy 364.235174 -239.884365) (xy 364.195752 -239.852178)
			(xy 364.162004 -239.814084) (xy 364.134803 -239.77107) (xy 364.114855 -239.72425) (xy 364.102676 -239.674836)
			(xy 364.098581 -239.624108) (xy 363.79277 -239.624108) (xy 363.79228 -239.649097) (xy 363.784461 -239.69846)
			(xy 363.769017 -239.745992) (xy 363.746327 -239.790524) (xy 363.716951 -239.830957) (xy 363.681611 -239.866297)
			(xy 363.641178 -239.895673) (xy 363.596646 -239.918363) (xy 363.549114 -239.933807) (xy 363.499751 -239.941626)
			(xy 363.449773 -239.941626) (xy 363.40041 -239.933807) (xy 363.352878 -239.918363) (xy 363.308346 -239.895673)
			(xy 363.267913 -239.866297) (xy 363.232573 -239.830957) (xy 363.203197 -239.790524) (xy 363.180507 -239.745992)
			(xy 363.165063 -239.69846) (xy 363.157244 -239.649097) (xy 356.278706 -239.649097) (xy 356.270887 -239.69846)
			(xy 356.255443 -239.745992) (xy 356.232753 -239.790524) (xy 356.203377 -239.830957) (xy 356.168037 -239.866297)
			(xy 356.127604 -239.895673) (xy 356.083072 -239.918363) (xy 356.03554 -239.933807) (xy 355.986177 -239.941626)
			(xy 355.936199 -239.941626) (xy 355.886836 -239.933807) (xy 355.839304 -239.918363) (xy 355.794772 -239.895673)
			(xy 355.754339 -239.866297) (xy 355.718999 -239.830957) (xy 355.689623 -239.790524) (xy 355.666933 -239.745992)
			(xy 355.651489 -239.69846) (xy 355.64367 -239.649097) (xy 355.336353 -239.649097) (xy 355.336344 -239.649554)
			(xy 355.32818 -239.699788) (xy 355.312064 -239.748062) (xy 355.288413 -239.793125) (xy 355.25784 -239.833811)
			(xy 355.221136 -239.869066) (xy 355.179252 -239.897976) (xy 355.133273 -239.919793) (xy 355.084389 -239.933953)
			(xy 355.033868 -239.940087) (xy 354.983016 -239.938038) (xy 354.933152 -239.927858) (xy 354.885566 -239.909811)
			(xy 354.841492 -239.884365) (xy 354.80207 -239.852178) (xy 354.768322 -239.814084) (xy 354.741121 -239.77107)
			(xy 354.721173 -239.72425) (xy 354.708994 -239.674836) (xy 354.704899 -239.624108) (xy 354.396802 -239.624108)
			(xy 354.39629 -239.649554) (xy 354.388126 -239.699788) (xy 354.37201 -239.748062) (xy 354.348359 -239.793125)
			(xy 354.317786 -239.833811) (xy 354.281082 -239.869066) (xy 354.239198 -239.897976) (xy 354.193219 -239.919793)
			(xy 354.144335 -239.933953) (xy 354.093814 -239.940087) (xy 354.042962 -239.938038) (xy 353.993098 -239.927858)
			(xy 353.945512 -239.909811) (xy 353.901438 -239.884365) (xy 353.862016 -239.852178) (xy 353.828268 -239.814084)
			(xy 353.801067 -239.77107) (xy 353.781119 -239.72425) (xy 353.76894 -239.674836) (xy 353.764845 -239.624108)
			(xy 353.459034 -239.624108) (xy 353.458544 -239.649097) (xy 353.450725 -239.69846) (xy 353.435281 -239.745992)
			(xy 353.412591 -239.790524) (xy 353.383215 -239.830957) (xy 353.347875 -239.866297) (xy 353.307442 -239.895673)
			(xy 353.26291 -239.918363) (xy 353.215378 -239.933807) (xy 353.166015 -239.941626) (xy 353.116037 -239.941626)
			(xy 353.066674 -239.933807) (xy 353.019142 -239.918363) (xy 352.97461 -239.895673) (xy 352.934177 -239.866297)
			(xy 352.898837 -239.830957) (xy 352.869461 -239.790524) (xy 352.846771 -239.745992) (xy 352.831327 -239.69846)
			(xy 352.823508 -239.649097) (xy 352.516445 -239.649097) (xy 352.516436 -239.649554) (xy 352.508272 -239.699788)
			(xy 352.492156 -239.748062) (xy 352.468505 -239.793125) (xy 352.437932 -239.833811) (xy 352.401228 -239.869066)
			(xy 352.359344 -239.897976) (xy 352.313365 -239.919793) (xy 352.264481 -239.933953) (xy 352.21396 -239.940087)
			(xy 352.163108 -239.938038) (xy 352.113244 -239.927858) (xy 352.065658 -239.909811) (xy 352.021584 -239.884365)
			(xy 351.982162 -239.852178) (xy 351.948414 -239.814084) (xy 351.921213 -239.77107) (xy 351.901265 -239.72425)
			(xy 351.889086 -239.674836) (xy 351.884991 -239.624108) (xy 351.576894 -239.624108) (xy 351.576382 -239.649554)
			(xy 351.568218 -239.699788) (xy 351.552102 -239.748062) (xy 351.528451 -239.793125) (xy 351.497878 -239.833811)
			(xy 351.461174 -239.869066) (xy 351.41929 -239.897976) (xy 351.373311 -239.919793) (xy 351.324427 -239.933953)
			(xy 351.273906 -239.940087) (xy 351.223054 -239.938038) (xy 351.17319 -239.927858) (xy 351.125604 -239.909811)
			(xy 351.08153 -239.884365) (xy 351.042108 -239.852178) (xy 351.00836 -239.814084) (xy 350.981159 -239.77107)
			(xy 350.961211 -239.72425) (xy 350.949032 -239.674836) (xy 350.944937 -239.624108) (xy 350.639126 -239.624108)
			(xy 350.638636 -239.649097) (xy 350.630817 -239.69846) (xy 350.615373 -239.745992) (xy 350.592683 -239.790524)
			(xy 350.563307 -239.830957) (xy 350.527967 -239.866297) (xy 350.487534 -239.895673) (xy 350.443002 -239.918363)
			(xy 350.39547 -239.933807) (xy 350.346107 -239.941626) (xy 350.296129 -239.941626) (xy 350.246766 -239.933807)
			(xy 350.199234 -239.918363) (xy 350.154702 -239.895673) (xy 350.114269 -239.866297) (xy 350.078929 -239.830957)
			(xy 350.049553 -239.790524) (xy 350.026863 -239.745992) (xy 350.011419 -239.69846) (xy 350.0036 -239.649097)
			(xy 349.696283 -239.649097) (xy 349.696274 -239.649554) (xy 349.68811 -239.699788) (xy 349.671994 -239.748062)
			(xy 349.648343 -239.793125) (xy 349.61777 -239.833811) (xy 349.581066 -239.869066) (xy 349.539182 -239.897976)
			(xy 349.493203 -239.919793) (xy 349.444319 -239.933953) (xy 349.393798 -239.940087) (xy 349.342946 -239.938038)
			(xy 349.293082 -239.927858) (xy 349.245496 -239.909811) (xy 349.201422 -239.884365) (xy 349.162 -239.852178)
			(xy 349.128252 -239.814084) (xy 349.101051 -239.77107) (xy 349.081103 -239.72425) (xy 349.068924 -239.674836)
			(xy 349.064829 -239.624108) (xy 348.756732 -239.624108) (xy 348.75622 -239.649554) (xy 348.748056 -239.699788)
			(xy 348.73194 -239.748062) (xy 348.708289 -239.793125) (xy 348.677716 -239.833811) (xy 348.641012 -239.869066)
			(xy 348.599128 -239.897976) (xy 348.553149 -239.919793) (xy 348.504265 -239.933953) (xy 348.453744 -239.940087)
			(xy 348.402892 -239.938038) (xy 348.353028 -239.927858) (xy 348.305442 -239.909811) (xy 348.261368 -239.884365)
			(xy 348.221946 -239.852178) (xy 348.188198 -239.814084) (xy 348.160997 -239.77107) (xy 348.141049 -239.72425)
			(xy 348.12887 -239.674836) (xy 348.124775 -239.624108) (xy 347.819218 -239.624108) (xy 347.818728 -239.649097)
			(xy 347.810909 -239.69846) (xy 347.795465 -239.745992) (xy 347.772775 -239.790524) (xy 347.743399 -239.830957)
			(xy 347.708059 -239.866297) (xy 347.667626 -239.895673) (xy 347.623094 -239.918363) (xy 347.575562 -239.933807)
			(xy 347.526199 -239.941626) (xy 347.476221 -239.941626) (xy 347.426858 -239.933807) (xy 347.379326 -239.918363)
			(xy 347.334794 -239.895673) (xy 347.294361 -239.866297) (xy 347.259021 -239.830957) (xy 347.229645 -239.790524)
			(xy 347.206955 -239.745992) (xy 347.191511 -239.69846) (xy 347.183692 -239.649097) (xy 346.876375 -239.649097)
			(xy 346.876366 -239.649554) (xy 346.868202 -239.699788) (xy 346.852086 -239.748062) (xy 346.828435 -239.793125)
			(xy 346.797862 -239.833811) (xy 346.761158 -239.869066) (xy 346.719274 -239.897976) (xy 346.673295 -239.919793)
			(xy 346.624411 -239.933953) (xy 346.57389 -239.940087) (xy 346.523038 -239.938038) (xy 346.473174 -239.927858)
			(xy 346.425588 -239.909811) (xy 346.381514 -239.884365) (xy 346.342092 -239.852178) (xy 346.308344 -239.814084)
			(xy 346.281143 -239.77107) (xy 346.261195 -239.72425) (xy 346.249016 -239.674836) (xy 346.244921 -239.624108)
			(xy 345.936824 -239.624108) (xy 345.936312 -239.649554) (xy 345.928148 -239.699788) (xy 345.912032 -239.748062)
			(xy 345.888381 -239.793125) (xy 345.857808 -239.833811) (xy 345.821104 -239.869066) (xy 345.77922 -239.897976)
			(xy 345.733241 -239.919793) (xy 345.684357 -239.933953) (xy 345.633836 -239.940087) (xy 345.582984 -239.938038)
			(xy 345.53312 -239.927858) (xy 345.485534 -239.909811) (xy 345.44146 -239.884365) (xy 345.402038 -239.852178)
			(xy 345.36829 -239.814084) (xy 345.341089 -239.77107) (xy 345.321141 -239.72425) (xy 345.308962 -239.674836)
			(xy 345.304867 -239.624108) (xy 344.999056 -239.624108) (xy 344.999056 -239.624362) (xy 344.997786 -239.653572)
			(xy 344.997532 -239.658144) (xy 344.997532 -240.019586) (xy 344.998051 -240.029335) (xy 345.005502 -240.047361)
			(xy 345.01201 -240.054638) (xy 345.072462 -240.107724) (xy 345.079275 -240.112748) (xy 345.095245 -240.118331)
			(xy 345.103704 -240.118646) (xy 345.110562 -240.118646) (xy 345.113356 -240.118392) (xy 345.122781 -240.117325)
			(xy 345.141717 -240.116183) (xy 345.151202 -240.116106) (xy 345.17619 -240.116596) (xy 345.225551 -240.124415)
			(xy 345.273081 -240.139858) (xy 345.317609 -240.162547) (xy 345.358041 -240.191922) (xy 345.393379 -240.227261)
			(xy 345.422754 -240.267692) (xy 345.445442 -240.312221) (xy 345.460886 -240.359751) (xy 345.468704 -240.409112)
			(xy 345.468704 -240.459088) (xy 345.468702 -240.459103) (xy 345.773484 -240.459103) (xy 345.773484 -240.409125)
			(xy 345.781303 -240.359762) (xy 345.796747 -240.31223) (xy 345.819437 -240.267698) (xy 345.848813 -240.227265)
			(xy 345.884153 -240.191925) (xy 345.924586 -240.162549) (xy 345.969118 -240.139859) (xy 346.01665 -240.124415)
			(xy 346.066013 -240.116596) (xy 346.115991 -240.116596) (xy 346.165354 -240.124415) (xy 346.212886 -240.139859)
			(xy 346.257418 -240.162549) (xy 346.297851 -240.191925) (xy 346.333191 -240.227265) (xy 346.362567 -240.267698)
			(xy 346.385257 -240.31223) (xy 346.400701 -240.359762) (xy 346.40852 -240.409125) (xy 346.40901 -240.434114)
			(xy 346.40852 -240.459103) (xy 346.713538 -240.459103) (xy 346.713538 -240.409125) (xy 346.721357 -240.359762)
			(xy 346.736801 -240.31223) (xy 346.759491 -240.267698) (xy 346.788867 -240.227265) (xy 346.824207 -240.191925)
			(xy 346.86464 -240.162549) (xy 346.909172 -240.139859) (xy 346.956704 -240.124415) (xy 347.006067 -240.116596)
			(xy 347.056045 -240.116596) (xy 347.105408 -240.124415) (xy 347.15294 -240.139859) (xy 347.197472 -240.162549)
			(xy 347.237905 -240.191925) (xy 347.273245 -240.227265) (xy 347.302621 -240.267698) (xy 347.325311 -240.31223)
			(xy 347.340755 -240.359762) (xy 347.348574 -240.409125) (xy 347.349064 -240.434114) (xy 347.348574 -240.459103)
			(xy 347.653592 -240.459103) (xy 347.653592 -240.409125) (xy 347.661411 -240.359762) (xy 347.676855 -240.31223)
			(xy 347.699545 -240.267698) (xy 347.728921 -240.227265) (xy 347.764261 -240.191925) (xy 347.804694 -240.162549)
			(xy 347.849226 -240.139859) (xy 347.896758 -240.124415) (xy 347.946121 -240.116596) (xy 347.996099 -240.116596)
			(xy 348.045462 -240.124415) (xy 348.092994 -240.139859) (xy 348.137526 -240.162549) (xy 348.177959 -240.191925)
			(xy 348.213299 -240.227265) (xy 348.242675 -240.267698) (xy 348.265365 -240.31223) (xy 348.280809 -240.359762)
			(xy 348.288628 -240.409125) (xy 348.289118 -240.434114) (xy 348.288628 -240.459103) (xy 348.593646 -240.459103)
			(xy 348.593646 -240.409125) (xy 348.601465 -240.359762) (xy 348.616909 -240.31223) (xy 348.639599 -240.267698)
			(xy 348.668975 -240.227265) (xy 348.704315 -240.191925) (xy 348.744748 -240.162549) (xy 348.78928 -240.139859)
			(xy 348.836812 -240.124415) (xy 348.886175 -240.116596) (xy 348.936153 -240.116596) (xy 348.985516 -240.124415)
			(xy 349.033048 -240.139859) (xy 349.07758 -240.162549) (xy 349.118013 -240.191925) (xy 349.153353 -240.227265)
			(xy 349.182729 -240.267698) (xy 349.205419 -240.31223) (xy 349.220863 -240.359762) (xy 349.228682 -240.409125)
			(xy 349.229172 -240.434114) (xy 349.228682 -240.459103) (xy 349.5337 -240.459103) (xy 349.5337 -240.409125)
			(xy 349.541519 -240.359762) (xy 349.556963 -240.31223) (xy 349.579653 -240.267698) (xy 349.609029 -240.227265)
			(xy 349.644369 -240.191925) (xy 349.684802 -240.162549) (xy 349.729334 -240.139859) (xy 349.776866 -240.124415)
			(xy 349.826229 -240.116596) (xy 349.876207 -240.116596) (xy 349.92557 -240.124415) (xy 349.973102 -240.139859)
			(xy 350.017634 -240.162549) (xy 350.058067 -240.191925) (xy 350.093407 -240.227265) (xy 350.122783 -240.267698)
			(xy 350.145473 -240.31223) (xy 350.160917 -240.359762) (xy 350.168736 -240.409125) (xy 350.169226 -240.434114)
			(xy 350.168736 -240.459103) (xy 350.4735 -240.459103) (xy 350.4735 -240.409125) (xy 350.481319 -240.359762)
			(xy 350.496763 -240.31223) (xy 350.519453 -240.267698) (xy 350.548829 -240.227265) (xy 350.584169 -240.191925)
			(xy 350.624602 -240.162549) (xy 350.669134 -240.139859) (xy 350.716666 -240.124415) (xy 350.766029 -240.116596)
			(xy 350.816007 -240.116596) (xy 350.86537 -240.124415) (xy 350.912902 -240.139859) (xy 350.957434 -240.162549)
			(xy 350.997867 -240.191925) (xy 351.033207 -240.227265) (xy 351.062583 -240.267698) (xy 351.085273 -240.31223)
			(xy 351.100717 -240.359762) (xy 351.108536 -240.409125) (xy 351.109026 -240.434114) (xy 351.108536 -240.459103)
			(xy 351.413554 -240.459103) (xy 351.413554 -240.409125) (xy 351.421373 -240.359762) (xy 351.436817 -240.31223)
			(xy 351.459507 -240.267698) (xy 351.488883 -240.227265) (xy 351.524223 -240.191925) (xy 351.564656 -240.162549)
			(xy 351.609188 -240.139859) (xy 351.65672 -240.124415) (xy 351.706083 -240.116596) (xy 351.756061 -240.116596)
			(xy 351.805424 -240.124415) (xy 351.852956 -240.139859) (xy 351.897488 -240.162549) (xy 351.937921 -240.191925)
			(xy 351.973261 -240.227265) (xy 352.002637 -240.267698) (xy 352.025327 -240.31223) (xy 352.040771 -240.359762)
			(xy 352.04859 -240.409125) (xy 352.04908 -240.434114) (xy 352.04859 -240.459103) (xy 352.353608 -240.459103)
			(xy 352.353608 -240.409125) (xy 352.361427 -240.359762) (xy 352.376871 -240.31223) (xy 352.399561 -240.267698)
			(xy 352.428937 -240.227265) (xy 352.464277 -240.191925) (xy 352.50471 -240.162549) (xy 352.549242 -240.139859)
			(xy 352.596774 -240.124415) (xy 352.646137 -240.116596) (xy 352.696115 -240.116596) (xy 352.745478 -240.124415)
			(xy 352.79301 -240.139859) (xy 352.837542 -240.162549) (xy 352.877975 -240.191925) (xy 352.913315 -240.227265)
			(xy 352.942691 -240.267698) (xy 352.965381 -240.31223) (xy 352.980825 -240.359762) (xy 352.988644 -240.409125)
			(xy 352.989134 -240.434114) (xy 352.988644 -240.459103) (xy 353.293662 -240.459103) (xy 353.293662 -240.409125)
			(xy 353.301481 -240.359762) (xy 353.316925 -240.31223) (xy 353.339615 -240.267698) (xy 353.368991 -240.227265)
			(xy 353.404331 -240.191925) (xy 353.444764 -240.162549) (xy 353.489296 -240.139859) (xy 353.536828 -240.124415)
			(xy 353.586191 -240.116596) (xy 353.636169 -240.116596) (xy 353.685532 -240.124415) (xy 353.733064 -240.139859)
			(xy 353.777596 -240.162549) (xy 353.818029 -240.191925) (xy 353.853369 -240.227265) (xy 353.882745 -240.267698)
			(xy 353.905435 -240.31223) (xy 353.920879 -240.359762) (xy 353.928698 -240.409125) (xy 353.929188 -240.434114)
			(xy 353.928698 -240.459103) (xy 354.233716 -240.459103) (xy 354.233716 -240.409125) (xy 354.241535 -240.359762)
			(xy 354.256979 -240.31223) (xy 354.279669 -240.267698) (xy 354.309045 -240.227265) (xy 354.344385 -240.191925)
			(xy 354.384818 -240.162549) (xy 354.42935 -240.139859) (xy 354.476882 -240.124415) (xy 354.526245 -240.116596)
			(xy 354.576223 -240.116596) (xy 354.625586 -240.124415) (xy 354.673118 -240.139859) (xy 354.71765 -240.162549)
			(xy 354.758083 -240.191925) (xy 354.793423 -240.227265) (xy 354.822799 -240.267698) (xy 354.845489 -240.31223)
			(xy 354.860933 -240.359762) (xy 354.868752 -240.409125) (xy 354.869242 -240.434114) (xy 354.868752 -240.459103)
			(xy 355.173516 -240.459103) (xy 355.173516 -240.409125) (xy 355.181335 -240.359762) (xy 355.196779 -240.31223)
			(xy 355.219469 -240.267698) (xy 355.248845 -240.227265) (xy 355.284185 -240.191925) (xy 355.324618 -240.162549)
			(xy 355.36915 -240.139859) (xy 355.416682 -240.124415) (xy 355.466045 -240.116596) (xy 355.516023 -240.116596)
			(xy 355.565386 -240.124415) (xy 355.612918 -240.139859) (xy 355.65745 -240.162549) (xy 355.697883 -240.191925)
			(xy 355.733223 -240.227265) (xy 355.762599 -240.267698) (xy 355.785289 -240.31223) (xy 355.800733 -240.359762)
			(xy 355.808552 -240.409125) (xy 355.809042 -240.434114) (xy 356.114853 -240.434114) (xy 356.118948 -240.383386)
			(xy 356.131127 -240.333972) (xy 356.151075 -240.287152) (xy 356.178276 -240.244138) (xy 356.212024 -240.206044)
			(xy 356.251446 -240.173857) (xy 356.29552 -240.148411) (xy 356.343106 -240.130364) (xy 356.39297 -240.120184)
			(xy 356.443822 -240.118135) (xy 356.494343 -240.124269) (xy 356.543227 -240.138429) (xy 356.589206 -240.160246)
			(xy 356.63109 -240.189156) (xy 356.667794 -240.224411) (xy 356.698367 -240.265097) (xy 356.722018 -240.31016)
			(xy 356.738134 -240.358434) (xy 356.746298 -240.408668) (xy 356.74681 -240.434114) (xy 357.054907 -240.434114)
			(xy 357.059002 -240.383386) (xy 357.071181 -240.333972) (xy 357.091129 -240.287152) (xy 357.11833 -240.244138)
			(xy 357.152078 -240.206044) (xy 357.1915 -240.173857) (xy 357.235574 -240.148411) (xy 357.28316 -240.130364)
			(xy 357.333024 -240.120184) (xy 357.383876 -240.118135) (xy 357.434397 -240.124269) (xy 357.483281 -240.138429)
			(xy 357.52926 -240.160246) (xy 357.571144 -240.189156) (xy 357.607848 -240.224411) (xy 357.638421 -240.265097)
			(xy 357.662072 -240.31016) (xy 357.678188 -240.358434) (xy 357.686352 -240.408668) (xy 357.686864 -240.434114)
			(xy 357.686361 -240.459103) (xy 357.993678 -240.459103) (xy 357.993678 -240.409125) (xy 358.001497 -240.359762)
			(xy 358.016941 -240.31223) (xy 358.039631 -240.267698) (xy 358.069007 -240.227265) (xy 358.104347 -240.191925)
			(xy 358.14478 -240.162549) (xy 358.189312 -240.139859) (xy 358.236844 -240.124415) (xy 358.286207 -240.116596)
			(xy 358.336185 -240.116596) (xy 358.385548 -240.124415) (xy 358.43308 -240.139859) (xy 358.477612 -240.162549)
			(xy 358.518045 -240.191925) (xy 358.553385 -240.227265) (xy 358.582761 -240.267698) (xy 358.605451 -240.31223)
			(xy 358.620895 -240.359762) (xy 358.628714 -240.409125) (xy 358.629204 -240.434114) (xy 358.628714 -240.459103)
			(xy 360.807236 -240.459103) (xy 360.807236 -240.409125) (xy 360.815055 -240.359762) (xy 360.830499 -240.31223)
			(xy 360.853189 -240.267698) (xy 360.882565 -240.227265) (xy 360.917905 -240.191925) (xy 360.958338 -240.162549)
			(xy 361.00287 -240.139859) (xy 361.050402 -240.124415) (xy 361.099765 -240.116596) (xy 361.149743 -240.116596)
			(xy 361.199106 -240.124415) (xy 361.246638 -240.139859) (xy 361.29117 -240.162549) (xy 361.331603 -240.191925)
			(xy 361.366943 -240.227265) (xy 361.396319 -240.267698) (xy 361.419009 -240.31223) (xy 361.434453 -240.359762)
			(xy 361.442272 -240.409125) (xy 361.442762 -240.434114) (xy 361.748573 -240.434114) (xy 361.752668 -240.383386)
			(xy 361.764847 -240.333972) (xy 361.784795 -240.287152) (xy 361.811996 -240.244138) (xy 361.845744 -240.206044)
			(xy 361.885166 -240.173857) (xy 361.92924 -240.148411) (xy 361.976826 -240.130364) (xy 362.02669 -240.120184)
			(xy 362.077542 -240.118135) (xy 362.128063 -240.124269) (xy 362.176947 -240.138429) (xy 362.222926 -240.160246)
			(xy 362.26481 -240.189156) (xy 362.301514 -240.224411) (xy 362.332087 -240.265097) (xy 362.355738 -240.31016)
			(xy 362.371854 -240.358434) (xy 362.380018 -240.408668) (xy 362.38053 -240.434114) (xy 362.688627 -240.434114)
			(xy 362.692722 -240.383386) (xy 362.704901 -240.333972) (xy 362.724849 -240.287152) (xy 362.75205 -240.244138)
			(xy 362.785798 -240.206044) (xy 362.82522 -240.173857) (xy 362.869294 -240.148411) (xy 362.91688 -240.130364)
			(xy 362.966744 -240.120184) (xy 363.017596 -240.118135) (xy 363.068117 -240.124269) (xy 363.117001 -240.138429)
			(xy 363.16298 -240.160246) (xy 363.204864 -240.189156) (xy 363.241568 -240.224411) (xy 363.272141 -240.265097)
			(xy 363.295792 -240.31016) (xy 363.311908 -240.358434) (xy 363.320072 -240.408668) (xy 363.320584 -240.434114)
			(xy 363.320081 -240.459103) (xy 363.627398 -240.459103) (xy 363.627398 -240.409125) (xy 363.635217 -240.359762)
			(xy 363.650661 -240.31223) (xy 363.673351 -240.267698) (xy 363.702727 -240.227265) (xy 363.738067 -240.191925)
			(xy 363.7785 -240.162549) (xy 363.823032 -240.139859) (xy 363.870564 -240.124415) (xy 363.919927 -240.116596)
			(xy 363.969905 -240.116596) (xy 364.019268 -240.124415) (xy 364.0668 -240.139859) (xy 364.111332 -240.162549)
			(xy 364.151765 -240.191925) (xy 364.187105 -240.227265) (xy 364.216481 -240.267698) (xy 364.239171 -240.31223)
			(xy 364.254615 -240.359762) (xy 364.262434 -240.409125) (xy 364.262924 -240.434114) (xy 364.262434 -240.459103)
			(xy 364.567198 -240.459103) (xy 364.567198 -240.409125) (xy 364.575017 -240.359762) (xy 364.590461 -240.31223)
			(xy 364.613151 -240.267698) (xy 364.642527 -240.227265) (xy 364.677867 -240.191925) (xy 364.7183 -240.162549)
			(xy 364.762832 -240.139859) (xy 364.810364 -240.124415) (xy 364.859727 -240.116596) (xy 364.909705 -240.116596)
			(xy 364.959068 -240.124415) (xy 365.0066 -240.139859) (xy 365.051132 -240.162549) (xy 365.091565 -240.191925)
			(xy 365.126905 -240.227265) (xy 365.156281 -240.267698) (xy 365.178971 -240.31223) (xy 365.194415 -240.359762)
			(xy 365.202234 -240.409125) (xy 365.202724 -240.434114) (xy 365.202234 -240.459103) (xy 365.507252 -240.459103)
			(xy 365.507252 -240.409125) (xy 365.515071 -240.359762) (xy 365.530515 -240.31223) (xy 365.553205 -240.267698)
			(xy 365.582581 -240.227265) (xy 365.617921 -240.191925) (xy 365.658354 -240.162549) (xy 365.702886 -240.139859)
			(xy 365.750418 -240.124415) (xy 365.799781 -240.116596) (xy 365.849759 -240.116596) (xy 365.899122 -240.124415)
			(xy 365.946654 -240.139859) (xy 365.991186 -240.162549) (xy 366.031619 -240.191925) (xy 366.066959 -240.227265)
			(xy 366.096335 -240.267698) (xy 366.119025 -240.31223) (xy 366.134469 -240.359762) (xy 366.142288 -240.409125)
			(xy 366.142778 -240.434114) (xy 366.142288 -240.459103) (xy 366.447306 -240.459103) (xy 366.447306 -240.409125)
			(xy 366.455125 -240.359762) (xy 366.470569 -240.31223) (xy 366.493259 -240.267698) (xy 366.522635 -240.227265)
			(xy 366.557975 -240.191925) (xy 366.598408 -240.162549) (xy 366.64294 -240.139859) (xy 366.690472 -240.124415)
			(xy 366.739835 -240.116596) (xy 366.789813 -240.116596) (xy 366.839176 -240.124415) (xy 366.886708 -240.139859)
			(xy 366.93124 -240.162549) (xy 366.971673 -240.191925) (xy 367.007013 -240.227265) (xy 367.036389 -240.267698)
			(xy 367.059079 -240.31223) (xy 367.074523 -240.359762) (xy 367.082342 -240.409125) (xy 367.082832 -240.434114)
			(xy 367.082342 -240.459103) (xy 367.38736 -240.459103) (xy 367.38736 -240.409125) (xy 367.395179 -240.359762)
			(xy 367.410623 -240.31223) (xy 367.433313 -240.267698) (xy 367.462689 -240.227265) (xy 367.498029 -240.191925)
			(xy 367.538462 -240.162549) (xy 367.582994 -240.139859) (xy 367.630526 -240.124415) (xy 367.679889 -240.116596)
			(xy 367.729867 -240.116596) (xy 367.77923 -240.124415) (xy 367.826762 -240.139859) (xy 367.871294 -240.162549)
			(xy 367.911727 -240.191925) (xy 367.947067 -240.227265) (xy 367.976443 -240.267698) (xy 367.999133 -240.31223)
			(xy 368.014577 -240.359762) (xy 368.022396 -240.409125) (xy 368.022886 -240.434114) (xy 368.022396 -240.459103)
			(xy 368.32716 -240.459103) (xy 368.32716 -240.409125) (xy 368.334979 -240.359762) (xy 368.350423 -240.31223)
			(xy 368.373113 -240.267698) (xy 368.402489 -240.227265) (xy 368.437829 -240.191925) (xy 368.478262 -240.162549)
			(xy 368.522794 -240.139859) (xy 368.570326 -240.124415) (xy 368.619689 -240.116596) (xy 368.669667 -240.116596)
			(xy 368.71903 -240.124415) (xy 368.766562 -240.139859) (xy 368.811094 -240.162549) (xy 368.851527 -240.191925)
			(xy 368.886867 -240.227265) (xy 368.916243 -240.267698) (xy 368.938933 -240.31223) (xy 368.954377 -240.359762)
			(xy 368.962196 -240.409125) (xy 368.962686 -240.434114) (xy 368.962196 -240.459103) (xy 369.267214 -240.459103)
			(xy 369.267214 -240.409125) (xy 369.275033 -240.359762) (xy 369.290477 -240.31223) (xy 369.313167 -240.267698)
			(xy 369.342543 -240.227265) (xy 369.377883 -240.191925) (xy 369.418316 -240.162549) (xy 369.462848 -240.139859)
			(xy 369.51038 -240.124415) (xy 369.559743 -240.116596) (xy 369.609721 -240.116596) (xy 369.659084 -240.124415)
			(xy 369.706616 -240.139859) (xy 369.751148 -240.162549) (xy 369.791581 -240.191925) (xy 369.826921 -240.227265)
			(xy 369.856297 -240.267698) (xy 369.878987 -240.31223) (xy 369.894431 -240.359762) (xy 369.90225 -240.409125)
			(xy 369.90274 -240.434114) (xy 369.90225 -240.459103) (xy 370.207268 -240.459103) (xy 370.207268 -240.409125)
			(xy 370.215087 -240.359762) (xy 370.230531 -240.31223) (xy 370.253221 -240.267698) (xy 370.282597 -240.227265)
			(xy 370.317937 -240.191925) (xy 370.35837 -240.162549) (xy 370.402902 -240.139859) (xy 370.450434 -240.124415)
			(xy 370.499797 -240.116596) (xy 370.549775 -240.116596) (xy 370.599138 -240.124415) (xy 370.64667 -240.139859)
			(xy 370.691202 -240.162549) (xy 370.731635 -240.191925) (xy 370.766975 -240.227265) (xy 370.796351 -240.267698)
			(xy 370.819041 -240.31223) (xy 370.834485 -240.359762) (xy 370.842304 -240.409125) (xy 370.842794 -240.434114)
			(xy 370.842304 -240.459103) (xy 371.147322 -240.459103) (xy 371.147322 -240.409125) (xy 371.155141 -240.359762)
			(xy 371.170585 -240.31223) (xy 371.193275 -240.267698) (xy 371.222651 -240.227265) (xy 371.257991 -240.191925)
			(xy 371.298424 -240.162549) (xy 371.342956 -240.139859) (xy 371.390488 -240.124415) (xy 371.439851 -240.116596)
			(xy 371.489829 -240.116596) (xy 371.539192 -240.124415) (xy 371.586724 -240.139859) (xy 371.631256 -240.162549)
			(xy 371.671689 -240.191925) (xy 371.707029 -240.227265) (xy 371.736405 -240.267698) (xy 371.759095 -240.31223)
			(xy 371.774539 -240.359762) (xy 371.782358 -240.409125) (xy 371.782848 -240.434114) (xy 371.782358 -240.459103)
			(xy 372.087376 -240.459103) (xy 372.087376 -240.409125) (xy 372.095195 -240.359762) (xy 372.110639 -240.31223)
			(xy 372.133329 -240.267698) (xy 372.162705 -240.227265) (xy 372.198045 -240.191925) (xy 372.238478 -240.162549)
			(xy 372.28301 -240.139859) (xy 372.330542 -240.124415) (xy 372.379905 -240.116596) (xy 372.429883 -240.116596)
			(xy 372.479246 -240.124415) (xy 372.526778 -240.139859) (xy 372.57131 -240.162549) (xy 372.611743 -240.191925)
			(xy 372.647083 -240.227265) (xy 372.676459 -240.267698) (xy 372.699149 -240.31223) (xy 372.714593 -240.359762)
			(xy 372.722412 -240.409125) (xy 372.722902 -240.434114) (xy 372.722412 -240.459103) (xy 373.027176 -240.459103)
			(xy 373.027176 -240.409125) (xy 373.034995 -240.359762) (xy 373.050439 -240.31223) (xy 373.073129 -240.267698)
			(xy 373.102505 -240.227265) (xy 373.137845 -240.191925) (xy 373.178278 -240.162549) (xy 373.22281 -240.139859)
			(xy 373.270342 -240.124415) (xy 373.319705 -240.116596) (xy 373.369683 -240.116596) (xy 373.419046 -240.124415)
			(xy 373.466578 -240.139859) (xy 373.51111 -240.162549) (xy 373.551543 -240.191925) (xy 373.586883 -240.227265)
			(xy 373.616259 -240.267698) (xy 373.638949 -240.31223) (xy 373.654393 -240.359762) (xy 373.662212 -240.409125)
			(xy 373.662702 -240.434114) (xy 373.662212 -240.459103) (xy 373.654393 -240.508466) (xy 373.638949 -240.555998)
			(xy 373.616259 -240.60053) (xy 373.586883 -240.640963) (xy 373.551543 -240.676303) (xy 373.51111 -240.705679)
			(xy 373.466578 -240.728369) (xy 373.419046 -240.743813) (xy 373.369683 -240.751632) (xy 373.319705 -240.751632)
			(xy 373.270342 -240.743813) (xy 373.22281 -240.728369) (xy 373.178278 -240.705679) (xy 373.137845 -240.676303)
			(xy 373.102505 -240.640963) (xy 373.073129 -240.60053) (xy 373.050439 -240.555998) (xy 373.034995 -240.508466)
			(xy 373.027176 -240.459103) (xy 372.722412 -240.459103) (xy 372.714593 -240.508466) (xy 372.699149 -240.555998)
			(xy 372.676459 -240.60053) (xy 372.647083 -240.640963) (xy 372.611743 -240.676303) (xy 372.57131 -240.705679)
			(xy 372.526778 -240.728369) (xy 372.479246 -240.743813) (xy 372.429883 -240.751632) (xy 372.379905 -240.751632)
			(xy 372.330542 -240.743813) (xy 372.28301 -240.728369) (xy 372.238478 -240.705679) (xy 372.198045 -240.676303)
			(xy 372.162705 -240.640963) (xy 372.133329 -240.60053) (xy 372.110639 -240.555998) (xy 372.095195 -240.508466)
			(xy 372.087376 -240.459103) (xy 371.782358 -240.459103) (xy 371.774539 -240.508466) (xy 371.759095 -240.555998)
			(xy 371.736405 -240.60053) (xy 371.707029 -240.640963) (xy 371.671689 -240.676303) (xy 371.631256 -240.705679)
			(xy 371.586724 -240.728369) (xy 371.539192 -240.743813) (xy 371.489829 -240.751632) (xy 371.439851 -240.751632)
			(xy 371.390488 -240.743813) (xy 371.342956 -240.728369) (xy 371.298424 -240.705679) (xy 371.257991 -240.676303)
			(xy 371.222651 -240.640963) (xy 371.193275 -240.60053) (xy 371.170585 -240.555998) (xy 371.155141 -240.508466)
			(xy 371.147322 -240.459103) (xy 370.842304 -240.459103) (xy 370.834485 -240.508466) (xy 370.819041 -240.555998)
			(xy 370.796351 -240.60053) (xy 370.766975 -240.640963) (xy 370.731635 -240.676303) (xy 370.691202 -240.705679)
			(xy 370.64667 -240.728369) (xy 370.599138 -240.743813) (xy 370.549775 -240.751632) (xy 370.499797 -240.751632)
			(xy 370.450434 -240.743813) (xy 370.402902 -240.728369) (xy 370.35837 -240.705679) (xy 370.317937 -240.676303)
			(xy 370.282597 -240.640963) (xy 370.253221 -240.60053) (xy 370.230531 -240.555998) (xy 370.215087 -240.508466)
			(xy 370.207268 -240.459103) (xy 369.90225 -240.459103) (xy 369.894431 -240.508466) (xy 369.878987 -240.555998)
			(xy 369.856297 -240.60053) (xy 369.826921 -240.640963) (xy 369.791581 -240.676303) (xy 369.751148 -240.705679)
			(xy 369.706616 -240.728369) (xy 369.659084 -240.743813) (xy 369.609721 -240.751632) (xy 369.559743 -240.751632)
			(xy 369.51038 -240.743813) (xy 369.462848 -240.728369) (xy 369.418316 -240.705679) (xy 369.377883 -240.676303)
			(xy 369.342543 -240.640963) (xy 369.313167 -240.60053) (xy 369.290477 -240.555998) (xy 369.275033 -240.508466)
			(xy 369.267214 -240.459103) (xy 368.962196 -240.459103) (xy 368.954377 -240.508466) (xy 368.938933 -240.555998)
			(xy 368.916243 -240.60053) (xy 368.886867 -240.640963) (xy 368.851527 -240.676303) (xy 368.811094 -240.705679)
			(xy 368.766562 -240.728369) (xy 368.71903 -240.743813) (xy 368.669667 -240.751632) (xy 368.619689 -240.751632)
			(xy 368.570326 -240.743813) (xy 368.522794 -240.728369) (xy 368.478262 -240.705679) (xy 368.437829 -240.676303)
			(xy 368.402489 -240.640963) (xy 368.373113 -240.60053) (xy 368.350423 -240.555998) (xy 368.334979 -240.508466)
			(xy 368.32716 -240.459103) (xy 368.022396 -240.459103) (xy 368.014577 -240.508466) (xy 367.999133 -240.555998)
			(xy 367.976443 -240.60053) (xy 367.947067 -240.640963) (xy 367.911727 -240.676303) (xy 367.871294 -240.705679)
			(xy 367.826762 -240.728369) (xy 367.77923 -240.743813) (xy 367.729867 -240.751632) (xy 367.679889 -240.751632)
			(xy 367.630526 -240.743813) (xy 367.582994 -240.728369) (xy 367.538462 -240.705679) (xy 367.498029 -240.676303)
			(xy 367.462689 -240.640963) (xy 367.433313 -240.60053) (xy 367.410623 -240.555998) (xy 367.395179 -240.508466)
			(xy 367.38736 -240.459103) (xy 367.082342 -240.459103) (xy 367.074523 -240.508466) (xy 367.059079 -240.555998)
			(xy 367.036389 -240.60053) (xy 367.007013 -240.640963) (xy 366.971673 -240.676303) (xy 366.93124 -240.705679)
			(xy 366.886708 -240.728369) (xy 366.839176 -240.743813) (xy 366.789813 -240.751632) (xy 366.739835 -240.751632)
			(xy 366.690472 -240.743813) (xy 366.64294 -240.728369) (xy 366.598408 -240.705679) (xy 366.557975 -240.676303)
			(xy 366.522635 -240.640963) (xy 366.493259 -240.60053) (xy 366.470569 -240.555998) (xy 366.455125 -240.508466)
			(xy 366.447306 -240.459103) (xy 366.142288 -240.459103) (xy 366.134469 -240.508466) (xy 366.119025 -240.555998)
			(xy 366.096335 -240.60053) (xy 366.066959 -240.640963) (xy 366.031619 -240.676303) (xy 365.991186 -240.705679)
			(xy 365.946654 -240.728369) (xy 365.899122 -240.743813) (xy 365.849759 -240.751632) (xy 365.799781 -240.751632)
			(xy 365.750418 -240.743813) (xy 365.702886 -240.728369) (xy 365.658354 -240.705679) (xy 365.617921 -240.676303)
			(xy 365.582581 -240.640963) (xy 365.553205 -240.60053) (xy 365.530515 -240.555998) (xy 365.515071 -240.508466)
			(xy 365.507252 -240.459103) (xy 365.202234 -240.459103) (xy 365.194415 -240.508466) (xy 365.178971 -240.555998)
			(xy 365.156281 -240.60053) (xy 365.126905 -240.640963) (xy 365.091565 -240.676303) (xy 365.051132 -240.705679)
			(xy 365.0066 -240.728369) (xy 364.959068 -240.743813) (xy 364.909705 -240.751632) (xy 364.859727 -240.751632)
			(xy 364.810364 -240.743813) (xy 364.762832 -240.728369) (xy 364.7183 -240.705679) (xy 364.677867 -240.676303)
			(xy 364.642527 -240.640963) (xy 364.613151 -240.60053) (xy 364.590461 -240.555998) (xy 364.575017 -240.508466)
			(xy 364.567198 -240.459103) (xy 364.262434 -240.459103) (xy 364.254615 -240.508466) (xy 364.239171 -240.555998)
			(xy 364.216481 -240.60053) (xy 364.187105 -240.640963) (xy 364.151765 -240.676303) (xy 364.111332 -240.705679)
			(xy 364.0668 -240.728369) (xy 364.019268 -240.743813) (xy 363.969905 -240.751632) (xy 363.919927 -240.751632)
			(xy 363.870564 -240.743813) (xy 363.823032 -240.728369) (xy 363.7785 -240.705679) (xy 363.738067 -240.676303)
			(xy 363.702727 -240.640963) (xy 363.673351 -240.60053) (xy 363.650661 -240.555998) (xy 363.635217 -240.508466)
			(xy 363.627398 -240.459103) (xy 363.320081 -240.459103) (xy 363.320072 -240.45956) (xy 363.311908 -240.509794)
			(xy 363.295792 -240.558068) (xy 363.272141 -240.603131) (xy 363.241568 -240.643817) (xy 363.204864 -240.679072)
			(xy 363.16298 -240.707982) (xy 363.117001 -240.729799) (xy 363.068117 -240.743959) (xy 363.017596 -240.750093)
			(xy 362.966744 -240.748044) (xy 362.91688 -240.737864) (xy 362.869294 -240.719817) (xy 362.82522 -240.694371)
			(xy 362.785798 -240.662184) (xy 362.75205 -240.62409) (xy 362.724849 -240.581076) (xy 362.704901 -240.534256)
			(xy 362.692722 -240.484842) (xy 362.688627 -240.434114) (xy 362.38053 -240.434114) (xy 362.380018 -240.45956)
			(xy 362.371854 -240.509794) (xy 362.355738 -240.558068) (xy 362.332087 -240.603131) (xy 362.301514 -240.643817)
			(xy 362.26481 -240.679072) (xy 362.222926 -240.707982) (xy 362.176947 -240.729799) (xy 362.128063 -240.743959)
			(xy 362.077542 -240.750093) (xy 362.02669 -240.748044) (xy 361.976826 -240.737864) (xy 361.92924 -240.719817)
			(xy 361.885166 -240.694371) (xy 361.845744 -240.662184) (xy 361.811996 -240.62409) (xy 361.784795 -240.581076)
			(xy 361.764847 -240.534256) (xy 361.752668 -240.484842) (xy 361.748573 -240.434114) (xy 361.442762 -240.434114)
			(xy 361.442272 -240.459103) (xy 361.434453 -240.508466) (xy 361.419009 -240.555998) (xy 361.396319 -240.60053)
			(xy 361.366943 -240.640963) (xy 361.331603 -240.676303) (xy 361.29117 -240.705679) (xy 361.246638 -240.728369)
			(xy 361.199106 -240.743813) (xy 361.149743 -240.751632) (xy 361.099765 -240.751632) (xy 361.050402 -240.743813)
			(xy 361.00287 -240.728369) (xy 360.958338 -240.705679) (xy 360.917905 -240.676303) (xy 360.882565 -240.640963)
			(xy 360.853189 -240.60053) (xy 360.830499 -240.555998) (xy 360.815055 -240.508466) (xy 360.807236 -240.459103)
			(xy 358.628714 -240.459103) (xy 358.620895 -240.508466) (xy 358.605451 -240.555998) (xy 358.582761 -240.60053)
			(xy 358.553385 -240.640963) (xy 358.518045 -240.676303) (xy 358.477612 -240.705679) (xy 358.43308 -240.728369)
			(xy 358.385548 -240.743813) (xy 358.336185 -240.751632) (xy 358.286207 -240.751632) (xy 358.236844 -240.743813)
			(xy 358.189312 -240.728369) (xy 358.14478 -240.705679) (xy 358.104347 -240.676303) (xy 358.069007 -240.640963)
			(xy 358.039631 -240.60053) (xy 358.016941 -240.555998) (xy 358.001497 -240.508466) (xy 357.993678 -240.459103)
			(xy 357.686361 -240.459103) (xy 357.686352 -240.45956) (xy 357.678188 -240.509794) (xy 357.662072 -240.558068)
			(xy 357.638421 -240.603131) (xy 357.607848 -240.643817) (xy 357.571144 -240.679072) (xy 357.52926 -240.707982)
			(xy 357.483281 -240.729799) (xy 357.434397 -240.743959) (xy 357.383876 -240.750093) (xy 357.333024 -240.748044)
			(xy 357.28316 -240.737864) (xy 357.235574 -240.719817) (xy 357.1915 -240.694371) (xy 357.152078 -240.662184)
			(xy 357.11833 -240.62409) (xy 357.091129 -240.581076) (xy 357.071181 -240.534256) (xy 357.059002 -240.484842)
			(xy 357.054907 -240.434114) (xy 356.74681 -240.434114) (xy 356.746298 -240.45956) (xy 356.738134 -240.509794)
			(xy 356.722018 -240.558068) (xy 356.698367 -240.603131) (xy 356.667794 -240.643817) (xy 356.63109 -240.679072)
			(xy 356.589206 -240.707982) (xy 356.543227 -240.729799) (xy 356.494343 -240.743959) (xy 356.443822 -240.750093)
			(xy 356.39297 -240.748044) (xy 356.343106 -240.737864) (xy 356.29552 -240.719817) (xy 356.251446 -240.694371)
			(xy 356.212024 -240.662184) (xy 356.178276 -240.62409) (xy 356.151075 -240.581076) (xy 356.131127 -240.534256)
			(xy 356.118948 -240.484842) (xy 356.114853 -240.434114) (xy 355.809042 -240.434114) (xy 355.808552 -240.459103)
			(xy 355.800733 -240.508466) (xy 355.785289 -240.555998) (xy 355.762599 -240.60053) (xy 355.733223 -240.640963)
			(xy 355.697883 -240.676303) (xy 355.65745 -240.705679) (xy 355.612918 -240.728369) (xy 355.565386 -240.743813)
			(xy 355.516023 -240.751632) (xy 355.466045 -240.751632) (xy 355.416682 -240.743813) (xy 355.36915 -240.728369)
			(xy 355.324618 -240.705679) (xy 355.284185 -240.676303) (xy 355.248845 -240.640963) (xy 355.219469 -240.60053)
			(xy 355.196779 -240.555998) (xy 355.181335 -240.508466) (xy 355.173516 -240.459103) (xy 354.868752 -240.459103)
			(xy 354.860933 -240.508466) (xy 354.845489 -240.555998) (xy 354.822799 -240.60053) (xy 354.793423 -240.640963)
			(xy 354.758083 -240.676303) (xy 354.71765 -240.705679) (xy 354.673118 -240.728369) (xy 354.625586 -240.743813)
			(xy 354.576223 -240.751632) (xy 354.526245 -240.751632) (xy 354.476882 -240.743813) (xy 354.42935 -240.728369)
			(xy 354.384818 -240.705679) (xy 354.344385 -240.676303) (xy 354.309045 -240.640963) (xy 354.279669 -240.60053)
			(xy 354.256979 -240.555998) (xy 354.241535 -240.508466) (xy 354.233716 -240.459103) (xy 353.928698 -240.459103)
			(xy 353.920879 -240.508466) (xy 353.905435 -240.555998) (xy 353.882745 -240.60053) (xy 353.853369 -240.640963)
			(xy 353.818029 -240.676303) (xy 353.777596 -240.705679) (xy 353.733064 -240.728369) (xy 353.685532 -240.743813)
			(xy 353.636169 -240.751632) (xy 353.586191 -240.751632) (xy 353.536828 -240.743813) (xy 353.489296 -240.728369)
			(xy 353.444764 -240.705679) (xy 353.404331 -240.676303) (xy 353.368991 -240.640963) (xy 353.339615 -240.60053)
			(xy 353.316925 -240.555998) (xy 353.301481 -240.508466) (xy 353.293662 -240.459103) (xy 352.988644 -240.459103)
			(xy 352.980825 -240.508466) (xy 352.965381 -240.555998) (xy 352.942691 -240.60053) (xy 352.913315 -240.640963)
			(xy 352.877975 -240.676303) (xy 352.837542 -240.705679) (xy 352.79301 -240.728369) (xy 352.745478 -240.743813)
			(xy 352.696115 -240.751632) (xy 352.646137 -240.751632) (xy 352.596774 -240.743813) (xy 352.549242 -240.728369)
			(xy 352.50471 -240.705679) (xy 352.464277 -240.676303) (xy 352.428937 -240.640963) (xy 352.399561 -240.60053)
			(xy 352.376871 -240.555998) (xy 352.361427 -240.508466) (xy 352.353608 -240.459103) (xy 352.04859 -240.459103)
			(xy 352.040771 -240.508466) (xy 352.025327 -240.555998) (xy 352.002637 -240.60053) (xy 351.973261 -240.640963)
			(xy 351.937921 -240.676303) (xy 351.897488 -240.705679) (xy 351.852956 -240.728369) (xy 351.805424 -240.743813)
			(xy 351.756061 -240.751632) (xy 351.706083 -240.751632) (xy 351.65672 -240.743813) (xy 351.609188 -240.728369)
			(xy 351.564656 -240.705679) (xy 351.524223 -240.676303) (xy 351.488883 -240.640963) (xy 351.459507 -240.60053)
			(xy 351.436817 -240.555998) (xy 351.421373 -240.508466) (xy 351.413554 -240.459103) (xy 351.108536 -240.459103)
			(xy 351.100717 -240.508466) (xy 351.085273 -240.555998) (xy 351.062583 -240.60053) (xy 351.033207 -240.640963)
			(xy 350.997867 -240.676303) (xy 350.957434 -240.705679) (xy 350.912902 -240.728369) (xy 350.86537 -240.743813)
			(xy 350.816007 -240.751632) (xy 350.766029 -240.751632) (xy 350.716666 -240.743813) (xy 350.669134 -240.728369)
			(xy 350.624602 -240.705679) (xy 350.584169 -240.676303) (xy 350.548829 -240.640963) (xy 350.519453 -240.60053)
			(xy 350.496763 -240.555998) (xy 350.481319 -240.508466) (xy 350.4735 -240.459103) (xy 350.168736 -240.459103)
			(xy 350.160917 -240.508466) (xy 350.145473 -240.555998) (xy 350.122783 -240.60053) (xy 350.093407 -240.640963)
			(xy 350.058067 -240.676303) (xy 350.017634 -240.705679) (xy 349.973102 -240.728369) (xy 349.92557 -240.743813)
			(xy 349.876207 -240.751632) (xy 349.826229 -240.751632) (xy 349.776866 -240.743813) (xy 349.729334 -240.728369)
			(xy 349.684802 -240.705679) (xy 349.644369 -240.676303) (xy 349.609029 -240.640963) (xy 349.579653 -240.60053)
			(xy 349.556963 -240.555998) (xy 349.541519 -240.508466) (xy 349.5337 -240.459103) (xy 349.228682 -240.459103)
			(xy 349.220863 -240.508466) (xy 349.205419 -240.555998) (xy 349.182729 -240.60053) (xy 349.153353 -240.640963)
			(xy 349.118013 -240.676303) (xy 349.07758 -240.705679) (xy 349.033048 -240.728369) (xy 348.985516 -240.743813)
			(xy 348.936153 -240.751632) (xy 348.886175 -240.751632) (xy 348.836812 -240.743813) (xy 348.78928 -240.728369)
			(xy 348.744748 -240.705679) (xy 348.704315 -240.676303) (xy 348.668975 -240.640963) (xy 348.639599 -240.60053)
			(xy 348.616909 -240.555998) (xy 348.601465 -240.508466) (xy 348.593646 -240.459103) (xy 348.288628 -240.459103)
			(xy 348.280809 -240.508466) (xy 348.265365 -240.555998) (xy 348.242675 -240.60053) (xy 348.213299 -240.640963)
			(xy 348.177959 -240.676303) (xy 348.137526 -240.705679) (xy 348.092994 -240.728369) (xy 348.045462 -240.743813)
			(xy 347.996099 -240.751632) (xy 347.946121 -240.751632) (xy 347.896758 -240.743813) (xy 347.849226 -240.728369)
			(xy 347.804694 -240.705679) (xy 347.764261 -240.676303) (xy 347.728921 -240.640963) (xy 347.699545 -240.60053)
			(xy 347.676855 -240.555998) (xy 347.661411 -240.508466) (xy 347.653592 -240.459103) (xy 347.348574 -240.459103)
			(xy 347.340755 -240.508466) (xy 347.325311 -240.555998) (xy 347.302621 -240.60053) (xy 347.273245 -240.640963)
			(xy 347.237905 -240.676303) (xy 347.197472 -240.705679) (xy 347.15294 -240.728369) (xy 347.105408 -240.743813)
			(xy 347.056045 -240.751632) (xy 347.006067 -240.751632) (xy 346.956704 -240.743813) (xy 346.909172 -240.728369)
			(xy 346.86464 -240.705679) (xy 346.824207 -240.676303) (xy 346.788867 -240.640963) (xy 346.759491 -240.60053)
			(xy 346.736801 -240.555998) (xy 346.721357 -240.508466) (xy 346.713538 -240.459103) (xy 346.40852 -240.459103)
			(xy 346.400701 -240.508466) (xy 346.385257 -240.555998) (xy 346.362567 -240.60053) (xy 346.333191 -240.640963)
			(xy 346.297851 -240.676303) (xy 346.257418 -240.705679) (xy 346.212886 -240.728369) (xy 346.165354 -240.743813)
			(xy 346.115991 -240.751632) (xy 346.066013 -240.751632) (xy 346.01665 -240.743813) (xy 345.969118 -240.728369)
			(xy 345.924586 -240.705679) (xy 345.884153 -240.676303) (xy 345.848813 -240.640963) (xy 345.819437 -240.60053)
			(xy 345.796747 -240.555998) (xy 345.781303 -240.508466) (xy 345.773484 -240.459103) (xy 345.468702 -240.459103)
			(xy 345.460886 -240.508449) (xy 345.445442 -240.555979) (xy 345.422754 -240.600508) (xy 345.393379 -240.640939)
			(xy 345.358041 -240.676278) (xy 345.317609 -240.705653) (xy 345.273081 -240.728342) (xy 345.225551 -240.743785)
			(xy 345.17619 -240.751604) (xy 345.151202 -240.752122) (xy 345.141014 -240.752057) (xy 345.120678 -240.750787)
			(xy 345.110562 -240.749582) (xy 345.09964 -240.748312) (xy 345.089988 -240.751106) (xy 345.084905 -240.752819)
			(xy 345.07556 -240.758079) (xy 345.071446 -240.76152) (xy 345.051888 -240.778538) (xy 345.01201 -240.81359)
			(xy 345.005463 -240.820841) (xy 344.998026 -240.838884) (xy 344.997532 -240.848642) (xy 344.997532 -241.210084)
			(xy 344.997786 -241.214656) (xy 344.999056 -241.243866) (xy 344.999056 -241.24412) (xy 345.304867 -241.24412)
			(xy 345.308962 -241.193392) (xy 345.321141 -241.143978) (xy 345.341089 -241.097158) (xy 345.36829 -241.054144)
			(xy 345.402038 -241.01605) (xy 345.44146 -240.983863) (xy 345.485534 -240.958417) (xy 345.53312 -240.94037)
			(xy 345.582984 -240.93019) (xy 345.633836 -240.928141) (xy 345.684357 -240.934275) (xy 345.733241 -240.948435)
			(xy 345.77922 -240.970252) (xy 345.821104 -240.999162) (xy 345.857808 -241.034417) (xy 345.888381 -241.075103)
			(xy 345.912032 -241.120166) (xy 345.928148 -241.16844) (xy 345.936312 -241.218674) (xy 345.936824 -241.24412)
			(xy 346.244921 -241.24412) (xy 346.249016 -241.193392) (xy 346.261195 -241.143978) (xy 346.281143 -241.097158)
			(xy 346.308344 -241.054144) (xy 346.342092 -241.01605) (xy 346.381514 -240.983863) (xy 346.425588 -240.958417)
			(xy 346.473174 -240.94037) (xy 346.523038 -240.93019) (xy 346.57389 -240.928141) (xy 346.624411 -240.934275)
			(xy 346.673295 -240.948435) (xy 346.719274 -240.970252) (xy 346.761158 -240.999162) (xy 346.797862 -241.034417)
			(xy 346.828435 -241.075103) (xy 346.852086 -241.120166) (xy 346.868202 -241.16844) (xy 346.876366 -241.218674)
			(xy 346.876878 -241.24412) (xy 346.876375 -241.269109) (xy 347.183692 -241.269109) (xy 347.183692 -241.219131)
			(xy 347.191511 -241.169768) (xy 347.206955 -241.122236) (xy 347.229645 -241.077704) (xy 347.259021 -241.037271)
			(xy 347.294361 -241.001931) (xy 347.334794 -240.972555) (xy 347.379326 -240.949865) (xy 347.426858 -240.934421)
			(xy 347.476221 -240.926602) (xy 347.526199 -240.926602) (xy 347.575562 -240.934421) (xy 347.623094 -240.949865)
			(xy 347.667626 -240.972555) (xy 347.708059 -241.001931) (xy 347.743399 -241.037271) (xy 347.772775 -241.077704)
			(xy 347.795465 -241.122236) (xy 347.810909 -241.169768) (xy 347.818728 -241.219131) (xy 347.819218 -241.24412)
			(xy 348.124775 -241.24412) (xy 348.12887 -241.193392) (xy 348.141049 -241.143978) (xy 348.160997 -241.097158)
			(xy 348.188198 -241.054144) (xy 348.221946 -241.01605) (xy 348.261368 -240.983863) (xy 348.305442 -240.958417)
			(xy 348.353028 -240.94037) (xy 348.402892 -240.93019) (xy 348.453744 -240.928141) (xy 348.504265 -240.934275)
			(xy 348.553149 -240.948435) (xy 348.599128 -240.970252) (xy 348.641012 -240.999162) (xy 348.677716 -241.034417)
			(xy 348.708289 -241.075103) (xy 348.73194 -241.120166) (xy 348.748056 -241.16844) (xy 348.75622 -241.218674)
			(xy 348.756732 -241.24412) (xy 349.064829 -241.24412) (xy 349.068924 -241.193392) (xy 349.081103 -241.143978)
			(xy 349.101051 -241.097158) (xy 349.128252 -241.054144) (xy 349.162 -241.01605) (xy 349.201422 -240.983863)
			(xy 349.245496 -240.958417) (xy 349.293082 -240.94037) (xy 349.342946 -240.93019) (xy 349.393798 -240.928141)
			(xy 349.444319 -240.934275) (xy 349.493203 -240.948435) (xy 349.539182 -240.970252) (xy 349.581066 -240.999162)
			(xy 349.61777 -241.034417) (xy 349.648343 -241.075103) (xy 349.671994 -241.120166) (xy 349.68811 -241.16844)
			(xy 349.696274 -241.218674) (xy 349.696786 -241.24412) (xy 349.696283 -241.269109) (xy 350.0036 -241.269109)
			(xy 350.0036 -241.219131) (xy 350.011419 -241.169768) (xy 350.026863 -241.122236) (xy 350.049553 -241.077704)
			(xy 350.078929 -241.037271) (xy 350.114269 -241.001931) (xy 350.154702 -240.972555) (xy 350.199234 -240.949865)
			(xy 350.246766 -240.934421) (xy 350.296129 -240.926602) (xy 350.346107 -240.926602) (xy 350.39547 -240.934421)
			(xy 350.443002 -240.949865) (xy 350.487534 -240.972555) (xy 350.527967 -241.001931) (xy 350.563307 -241.037271)
			(xy 350.592683 -241.077704) (xy 350.615373 -241.122236) (xy 350.630817 -241.169768) (xy 350.638636 -241.219131)
			(xy 350.639126 -241.24412) (xy 350.944937 -241.24412) (xy 350.949032 -241.193392) (xy 350.961211 -241.143978)
			(xy 350.981159 -241.097158) (xy 351.00836 -241.054144) (xy 351.042108 -241.01605) (xy 351.08153 -240.983863)
			(xy 351.125604 -240.958417) (xy 351.17319 -240.94037) (xy 351.223054 -240.93019) (xy 351.273906 -240.928141)
			(xy 351.324427 -240.934275) (xy 351.373311 -240.948435) (xy 351.41929 -240.970252) (xy 351.461174 -240.999162)
			(xy 351.497878 -241.034417) (xy 351.528451 -241.075103) (xy 351.552102 -241.120166) (xy 351.568218 -241.16844)
			(xy 351.576382 -241.218674) (xy 351.576894 -241.24412) (xy 351.884991 -241.24412) (xy 351.889086 -241.193392)
			(xy 351.901265 -241.143978) (xy 351.921213 -241.097158) (xy 351.948414 -241.054144) (xy 351.982162 -241.01605)
			(xy 352.021584 -240.983863) (xy 352.065658 -240.958417) (xy 352.113244 -240.94037) (xy 352.163108 -240.93019)
			(xy 352.21396 -240.928141) (xy 352.264481 -240.934275) (xy 352.313365 -240.948435) (xy 352.359344 -240.970252)
			(xy 352.401228 -240.999162) (xy 352.437932 -241.034417) (xy 352.468505 -241.075103) (xy 352.492156 -241.120166)
			(xy 352.508272 -241.16844) (xy 352.516436 -241.218674) (xy 352.516948 -241.24412) (xy 352.516445 -241.269109)
			(xy 352.823508 -241.269109) (xy 352.823508 -241.219131) (xy 352.831327 -241.169768) (xy 352.846771 -241.122236)
			(xy 352.869461 -241.077704) (xy 352.898837 -241.037271) (xy 352.934177 -241.001931) (xy 352.97461 -240.972555)
			(xy 353.019142 -240.949865) (xy 353.066674 -240.934421) (xy 353.116037 -240.926602) (xy 353.166015 -240.926602)
			(xy 353.215378 -240.934421) (xy 353.26291 -240.949865) (xy 353.307442 -240.972555) (xy 353.347875 -241.001931)
			(xy 353.383215 -241.037271) (xy 353.412591 -241.077704) (xy 353.435281 -241.122236) (xy 353.450725 -241.169768)
			(xy 353.458544 -241.219131) (xy 353.459034 -241.24412) (xy 353.764845 -241.24412) (xy 353.76894 -241.193392)
			(xy 353.781119 -241.143978) (xy 353.801067 -241.097158) (xy 353.828268 -241.054144) (xy 353.862016 -241.01605)
			(xy 353.901438 -240.983863) (xy 353.945512 -240.958417) (xy 353.993098 -240.94037) (xy 354.042962 -240.93019)
			(xy 354.093814 -240.928141) (xy 354.144335 -240.934275) (xy 354.193219 -240.948435) (xy 354.239198 -240.970252)
			(xy 354.281082 -240.999162) (xy 354.317786 -241.034417) (xy 354.348359 -241.075103) (xy 354.37201 -241.120166)
			(xy 354.388126 -241.16844) (xy 354.39629 -241.218674) (xy 354.396802 -241.24412) (xy 354.704899 -241.24412)
			(xy 354.708994 -241.193392) (xy 354.721173 -241.143978) (xy 354.741121 -241.097158) (xy 354.768322 -241.054144)
			(xy 354.80207 -241.01605) (xy 354.841492 -240.983863) (xy 354.885566 -240.958417) (xy 354.933152 -240.94037)
			(xy 354.983016 -240.93019) (xy 355.033868 -240.928141) (xy 355.084389 -240.934275) (xy 355.133273 -240.948435)
			(xy 355.179252 -240.970252) (xy 355.221136 -240.999162) (xy 355.25784 -241.034417) (xy 355.288413 -241.075103)
			(xy 355.312064 -241.120166) (xy 355.32818 -241.16844) (xy 355.336344 -241.218674) (xy 355.336856 -241.24412)
			(xy 355.336353 -241.269109) (xy 355.64367 -241.269109) (xy 355.64367 -241.219131) (xy 355.651489 -241.169768)
			(xy 355.666933 -241.122236) (xy 355.689623 -241.077704) (xy 355.718999 -241.037271) (xy 355.754339 -241.001931)
			(xy 355.794772 -240.972555) (xy 355.839304 -240.949865) (xy 355.886836 -240.934421) (xy 355.936199 -240.926602)
			(xy 355.986177 -240.926602) (xy 356.03554 -240.934421) (xy 356.083072 -240.949865) (xy 356.127604 -240.972555)
			(xy 356.168037 -241.001931) (xy 356.203377 -241.037271) (xy 356.232753 -241.077704) (xy 356.255443 -241.122236)
			(xy 356.270887 -241.169768) (xy 356.278706 -241.219131) (xy 356.279196 -241.24412) (xy 356.278706 -241.269109)
			(xy 356.583724 -241.269109) (xy 356.583724 -241.219131) (xy 356.591543 -241.169768) (xy 356.606987 -241.122236)
			(xy 356.629677 -241.077704) (xy 356.659053 -241.037271) (xy 356.694393 -241.001931) (xy 356.734826 -240.972555)
			(xy 356.779358 -240.949865) (xy 356.82689 -240.934421) (xy 356.876253 -240.926602) (xy 356.926231 -240.926602)
			(xy 356.975594 -240.934421) (xy 357.023126 -240.949865) (xy 357.067658 -240.972555) (xy 357.108091 -241.001931)
			(xy 357.143431 -241.037271) (xy 357.172807 -241.077704) (xy 357.195497 -241.122236) (xy 357.210941 -241.169768)
			(xy 357.21876 -241.219131) (xy 357.21925 -241.24412) (xy 357.21876 -241.269109) (xy 357.523524 -241.269109)
			(xy 357.523524 -241.219131) (xy 357.531343 -241.169768) (xy 357.546787 -241.122236) (xy 357.569477 -241.077704)
			(xy 357.598853 -241.037271) (xy 357.634193 -241.001931) (xy 357.674626 -240.972555) (xy 357.719158 -240.949865)
			(xy 357.76669 -240.934421) (xy 357.816053 -240.926602) (xy 357.866031 -240.926602) (xy 357.915394 -240.934421)
			(xy 357.962926 -240.949865) (xy 358.007458 -240.972555) (xy 358.047891 -241.001931) (xy 358.083231 -241.037271)
			(xy 358.112607 -241.077704) (xy 358.135297 -241.122236) (xy 358.150741 -241.169768) (xy 358.15856 -241.219131)
			(xy 358.15905 -241.24412) (xy 358.15856 -241.269109) (xy 361.27739 -241.269109) (xy 361.27739 -241.219131)
			(xy 361.285209 -241.169768) (xy 361.300653 -241.122236) (xy 361.323343 -241.077704) (xy 361.352719 -241.037271)
			(xy 361.388059 -241.001931) (xy 361.428492 -240.972555) (xy 361.473024 -240.949865) (xy 361.520556 -240.934421)
			(xy 361.569919 -240.926602) (xy 361.619897 -240.926602) (xy 361.66926 -240.934421) (xy 361.716792 -240.949865)
			(xy 361.761324 -240.972555) (xy 361.801757 -241.001931) (xy 361.837097 -241.037271) (xy 361.866473 -241.077704)
			(xy 361.889163 -241.122236) (xy 361.904607 -241.169768) (xy 361.912426 -241.219131) (xy 361.912916 -241.24412)
			(xy 361.912426 -241.269109) (xy 362.21719 -241.269109) (xy 362.21719 -241.219131) (xy 362.225009 -241.169768)
			(xy 362.240453 -241.122236) (xy 362.263143 -241.077704) (xy 362.292519 -241.037271) (xy 362.327859 -241.001931)
			(xy 362.368292 -240.972555) (xy 362.412824 -240.949865) (xy 362.460356 -240.934421) (xy 362.509719 -240.926602)
			(xy 362.559697 -240.926602) (xy 362.60906 -240.934421) (xy 362.656592 -240.949865) (xy 362.701124 -240.972555)
			(xy 362.741557 -241.001931) (xy 362.776897 -241.037271) (xy 362.806273 -241.077704) (xy 362.828963 -241.122236)
			(xy 362.844407 -241.169768) (xy 362.852226 -241.219131) (xy 362.852716 -241.24412) (xy 362.852226 -241.269109)
			(xy 363.157244 -241.269109) (xy 363.157244 -241.219131) (xy 363.165063 -241.169768) (xy 363.180507 -241.122236)
			(xy 363.203197 -241.077704) (xy 363.232573 -241.037271) (xy 363.267913 -241.001931) (xy 363.308346 -240.972555)
			(xy 363.352878 -240.949865) (xy 363.40041 -240.934421) (xy 363.449773 -240.926602) (xy 363.499751 -240.926602)
			(xy 363.549114 -240.934421) (xy 363.596646 -240.949865) (xy 363.641178 -240.972555) (xy 363.681611 -241.001931)
			(xy 363.716951 -241.037271) (xy 363.746327 -241.077704) (xy 363.769017 -241.122236) (xy 363.784461 -241.169768)
			(xy 363.79228 -241.219131) (xy 363.79277 -241.24412) (xy 364.098581 -241.24412) (xy 364.102676 -241.193392)
			(xy 364.114855 -241.143978) (xy 364.134803 -241.097158) (xy 364.162004 -241.054144) (xy 364.195752 -241.01605)
			(xy 364.235174 -240.983863) (xy 364.279248 -240.958417) (xy 364.326834 -240.94037) (xy 364.376698 -240.93019)
			(xy 364.42755 -240.928141) (xy 364.478071 -240.934275) (xy 364.526955 -240.948435) (xy 364.572934 -240.970252)
			(xy 364.614818 -240.999162) (xy 364.651522 -241.034417) (xy 364.682095 -241.075103) (xy 364.705746 -241.120166)
			(xy 364.721862 -241.16844) (xy 364.730026 -241.218674) (xy 364.730538 -241.24412) (xy 365.038635 -241.24412)
			(xy 365.04273 -241.193392) (xy 365.054909 -241.143978) (xy 365.074857 -241.097158) (xy 365.102058 -241.054144)
			(xy 365.135806 -241.01605) (xy 365.175228 -240.983863) (xy 365.219302 -240.958417) (xy 365.266888 -240.94037)
			(xy 365.316752 -240.93019) (xy 365.367604 -240.928141) (xy 365.418125 -240.934275) (xy 365.467009 -240.948435)
			(xy 365.512988 -240.970252) (xy 365.554872 -240.999162) (xy 365.591576 -241.034417) (xy 365.622149 -241.075103)
			(xy 365.6458 -241.120166) (xy 365.661916 -241.16844) (xy 365.67008 -241.218674) (xy 365.670592 -241.24412)
			(xy 365.670089 -241.269109) (xy 365.977406 -241.269109) (xy 365.977406 -241.219131) (xy 365.985225 -241.169768)
			(xy 366.000669 -241.122236) (xy 366.023359 -241.077704) (xy 366.052735 -241.037271) (xy 366.088075 -241.001931)
			(xy 366.128508 -240.972555) (xy 366.17304 -240.949865) (xy 366.220572 -240.934421) (xy 366.269935 -240.926602)
			(xy 366.319913 -240.926602) (xy 366.369276 -240.934421) (xy 366.416808 -240.949865) (xy 366.46134 -240.972555)
			(xy 366.501773 -241.001931) (xy 366.537113 -241.037271) (xy 366.566489 -241.077704) (xy 366.589179 -241.122236)
			(xy 366.604623 -241.169768) (xy 366.612442 -241.219131) (xy 366.612932 -241.24412) (xy 366.918489 -241.24412)
			(xy 366.922584 -241.193392) (xy 366.934763 -241.143978) (xy 366.954711 -241.097158) (xy 366.981912 -241.054144)
			(xy 367.01566 -241.01605) (xy 367.055082 -240.983863) (xy 367.099156 -240.958417) (xy 367.146742 -240.94037)
			(xy 367.196606 -240.93019) (xy 367.247458 -240.928141) (xy 367.297979 -240.934275) (xy 367.346863 -240.948435)
			(xy 367.392842 -240.970252) (xy 367.434726 -240.999162) (xy 367.47143 -241.034417) (xy 367.502003 -241.075103)
			(xy 367.525654 -241.120166) (xy 367.54177 -241.16844) (xy 367.549934 -241.218674) (xy 367.550446 -241.24412)
			(xy 367.858543 -241.24412) (xy 367.862638 -241.193392) (xy 367.874817 -241.143978) (xy 367.894765 -241.097158)
			(xy 367.921966 -241.054144) (xy 367.955714 -241.01605) (xy 367.995136 -240.983863) (xy 368.03921 -240.958417)
			(xy 368.086796 -240.94037) (xy 368.13666 -240.93019) (xy 368.187512 -240.928141) (xy 368.238033 -240.934275)
			(xy 368.286917 -240.948435) (xy 368.332896 -240.970252) (xy 368.37478 -240.999162) (xy 368.411484 -241.034417)
			(xy 368.442057 -241.075103) (xy 368.465708 -241.120166) (xy 368.481824 -241.16844) (xy 368.489988 -241.218674)
			(xy 368.4905 -241.24412) (xy 368.489997 -241.269109) (xy 368.797314 -241.269109) (xy 368.797314 -241.219131)
			(xy 368.805133 -241.169768) (xy 368.820577 -241.122236) (xy 368.843267 -241.077704) (xy 368.872643 -241.037271)
			(xy 368.907983 -241.001931) (xy 368.948416 -240.972555) (xy 368.992948 -240.949865) (xy 369.04048 -240.934421)
			(xy 369.089843 -240.926602) (xy 369.139821 -240.926602) (xy 369.189184 -240.934421) (xy 369.236716 -240.949865)
			(xy 369.281248 -240.972555) (xy 369.321681 -241.001931) (xy 369.357021 -241.037271) (xy 369.386397 -241.077704)
			(xy 369.409087 -241.122236) (xy 369.424531 -241.169768) (xy 369.43235 -241.219131) (xy 369.43284 -241.24412)
			(xy 369.738651 -241.24412) (xy 369.742746 -241.193392) (xy 369.754925 -241.143978) (xy 369.774873 -241.097158)
			(xy 369.802074 -241.054144) (xy 369.835822 -241.01605) (xy 369.875244 -240.983863) (xy 369.919318 -240.958417)
			(xy 369.966904 -240.94037) (xy 370.016768 -240.93019) (xy 370.06762 -240.928141) (xy 370.118141 -240.934275)
			(xy 370.167025 -240.948435) (xy 370.213004 -240.970252) (xy 370.254888 -240.999162) (xy 370.291592 -241.034417)
			(xy 370.322165 -241.075103) (xy 370.345816 -241.120166) (xy 370.361932 -241.16844) (xy 370.370096 -241.218674)
			(xy 370.370608 -241.24412) (xy 370.678451 -241.24412) (xy 370.682546 -241.193392) (xy 370.694725 -241.143978)
			(xy 370.714673 -241.097158) (xy 370.741874 -241.054144) (xy 370.775622 -241.01605) (xy 370.815044 -240.983863)
			(xy 370.859118 -240.958417) (xy 370.906704 -240.94037) (xy 370.956568 -240.93019) (xy 371.00742 -240.928141)
			(xy 371.057941 -240.934275) (xy 371.106825 -240.948435) (xy 371.152804 -240.970252) (xy 371.194688 -240.999162)
			(xy 371.231392 -241.034417) (xy 371.261965 -241.075103) (xy 371.285616 -241.120166) (xy 371.301732 -241.16844)
			(xy 371.309896 -241.218674) (xy 371.310408 -241.24412) (xy 371.309905 -241.269109) (xy 371.617222 -241.269109)
			(xy 371.617222 -241.219131) (xy 371.625041 -241.169768) (xy 371.640485 -241.122236) (xy 371.663175 -241.077704)
			(xy 371.692551 -241.037271) (xy 371.727891 -241.001931) (xy 371.768324 -240.972555) (xy 371.812856 -240.949865)
			(xy 371.860388 -240.934421) (xy 371.909751 -240.926602) (xy 371.959729 -240.926602) (xy 372.009092 -240.934421)
			(xy 372.056624 -240.949865) (xy 372.101156 -240.972555) (xy 372.141589 -241.001931) (xy 372.176929 -241.037271)
			(xy 372.206305 -241.077704) (xy 372.228995 -241.122236) (xy 372.244439 -241.169768) (xy 372.252258 -241.219131)
			(xy 372.252748 -241.24412) (xy 372.558559 -241.24412) (xy 372.562654 -241.193392) (xy 372.574833 -241.143978)
			(xy 372.594781 -241.097158) (xy 372.621982 -241.054144) (xy 372.65573 -241.01605) (xy 372.695152 -240.983863)
			(xy 372.739226 -240.958417) (xy 372.786812 -240.94037) (xy 372.836676 -240.93019) (xy 372.887528 -240.928141)
			(xy 372.938049 -240.934275) (xy 372.986933 -240.948435) (xy 373.032912 -240.970252) (xy 373.074796 -240.999162)
			(xy 373.1115 -241.034417) (xy 373.142073 -241.075103) (xy 373.165724 -241.120166) (xy 373.18184 -241.16844)
			(xy 373.190004 -241.218674) (xy 373.190516 -241.24412) (xy 373.498613 -241.24412) (xy 373.502708 -241.193392)
			(xy 373.514887 -241.143978) (xy 373.534835 -241.097158) (xy 373.562036 -241.054144) (xy 373.595784 -241.01605)
			(xy 373.635206 -240.983863) (xy 373.67928 -240.958417) (xy 373.726866 -240.94037) (xy 373.77673 -240.93019)
			(xy 373.827582 -240.928141) (xy 373.878103 -240.934275) (xy 373.926987 -240.948435) (xy 373.972966 -240.970252)
			(xy 374.01485 -240.999162) (xy 374.051554 -241.034417) (xy 374.082127 -241.075103) (xy 374.105778 -241.120166)
			(xy 374.121894 -241.16844) (xy 374.130058 -241.218674) (xy 374.13057 -241.24412) (xy 374.130058 -241.269566)
			(xy 374.121894 -241.3198) (xy 374.105778 -241.368074) (xy 374.082127 -241.413137) (xy 374.051554 -241.453823)
			(xy 374.01485 -241.489078) (xy 373.972966 -241.517988) (xy 373.926987 -241.539805) (xy 373.878103 -241.553965)
			(xy 373.827582 -241.560099) (xy 373.77673 -241.55805) (xy 373.726866 -241.54787) (xy 373.67928 -241.529823)
			(xy 373.635206 -241.504377) (xy 373.595784 -241.47219) (xy 373.562036 -241.434096) (xy 373.534835 -241.391082)
			(xy 373.514887 -241.344262) (xy 373.502708 -241.294848) (xy 373.498613 -241.24412) (xy 373.190516 -241.24412)
			(xy 373.190004 -241.269566) (xy 373.18184 -241.3198) (xy 373.165724 -241.368074) (xy 373.142073 -241.413137)
			(xy 373.1115 -241.453823) (xy 373.074796 -241.489078) (xy 373.032912 -241.517988) (xy 372.986933 -241.539805)
			(xy 372.938049 -241.553965) (xy 372.887528 -241.560099) (xy 372.836676 -241.55805) (xy 372.786812 -241.54787)
			(xy 372.739226 -241.529823) (xy 372.695152 -241.504377) (xy 372.65573 -241.47219) (xy 372.621982 -241.434096)
			(xy 372.594781 -241.391082) (xy 372.574833 -241.344262) (xy 372.562654 -241.294848) (xy 372.558559 -241.24412)
			(xy 372.252748 -241.24412) (xy 372.252258 -241.269109) (xy 372.244439 -241.318472) (xy 372.228995 -241.366004)
			(xy 372.206305 -241.410536) (xy 372.176929 -241.450969) (xy 372.141589 -241.486309) (xy 372.101156 -241.515685)
			(xy 372.056624 -241.538375) (xy 372.009092 -241.553819) (xy 371.959729 -241.561638) (xy 371.909751 -241.561638)
			(xy 371.860388 -241.553819) (xy 371.812856 -241.538375) (xy 371.768324 -241.515685) (xy 371.727891 -241.486309)
			(xy 371.692551 -241.450969) (xy 371.663175 -241.410536) (xy 371.640485 -241.366004) (xy 371.625041 -241.318472)
			(xy 371.617222 -241.269109) (xy 371.309905 -241.269109) (xy 371.309896 -241.269566) (xy 371.301732 -241.3198)
			(xy 371.285616 -241.368074) (xy 371.261965 -241.413137) (xy 371.231392 -241.453823) (xy 371.194688 -241.489078)
			(xy 371.152804 -241.517988) (xy 371.106825 -241.539805) (xy 371.057941 -241.553965) (xy 371.00742 -241.560099)
			(xy 370.956568 -241.55805) (xy 370.906704 -241.54787) (xy 370.859118 -241.529823) (xy 370.815044 -241.504377)
			(xy 370.775622 -241.47219) (xy 370.741874 -241.434096) (xy 370.714673 -241.391082) (xy 370.694725 -241.344262)
			(xy 370.682546 -241.294848) (xy 370.678451 -241.24412) (xy 370.370608 -241.24412) (xy 370.370096 -241.269566)
			(xy 370.361932 -241.3198) (xy 370.345816 -241.368074) (xy 370.322165 -241.413137) (xy 370.291592 -241.453823)
			(xy 370.254888 -241.489078) (xy 370.213004 -241.517988) (xy 370.167025 -241.539805) (xy 370.118141 -241.553965)
			(xy 370.06762 -241.560099) (xy 370.016768 -241.55805) (xy 369.966904 -241.54787) (xy 369.919318 -241.529823)
			(xy 369.875244 -241.504377) (xy 369.835822 -241.47219) (xy 369.802074 -241.434096) (xy 369.774873 -241.391082)
			(xy 369.754925 -241.344262) (xy 369.742746 -241.294848) (xy 369.738651 -241.24412) (xy 369.43284 -241.24412)
			(xy 369.43235 -241.269109) (xy 369.424531 -241.318472) (xy 369.409087 -241.366004) (xy 369.386397 -241.410536)
			(xy 369.357021 -241.450969) (xy 369.321681 -241.486309) (xy 369.281248 -241.515685) (xy 369.236716 -241.538375)
			(xy 369.189184 -241.553819) (xy 369.139821 -241.561638) (xy 369.089843 -241.561638) (xy 369.04048 -241.553819)
			(xy 368.992948 -241.538375) (xy 368.948416 -241.515685) (xy 368.907983 -241.486309) (xy 368.872643 -241.450969)
			(xy 368.843267 -241.410536) (xy 368.820577 -241.366004) (xy 368.805133 -241.318472) (xy 368.797314 -241.269109)
			(xy 368.489997 -241.269109) (xy 368.489988 -241.269566) (xy 368.481824 -241.3198) (xy 368.465708 -241.368074)
			(xy 368.442057 -241.413137) (xy 368.411484 -241.453823) (xy 368.37478 -241.489078) (xy 368.332896 -241.517988)
			(xy 368.286917 -241.539805) (xy 368.238033 -241.553965) (xy 368.187512 -241.560099) (xy 368.13666 -241.55805)
			(xy 368.086796 -241.54787) (xy 368.03921 -241.529823) (xy 367.995136 -241.504377) (xy 367.955714 -241.47219)
			(xy 367.921966 -241.434096) (xy 367.894765 -241.391082) (xy 367.874817 -241.344262) (xy 367.862638 -241.294848)
			(xy 367.858543 -241.24412) (xy 367.550446 -241.24412) (xy 367.549934 -241.269566) (xy 367.54177 -241.3198)
			(xy 367.525654 -241.368074) (xy 367.502003 -241.413137) (xy 367.47143 -241.453823) (xy 367.434726 -241.489078)
			(xy 367.392842 -241.517988) (xy 367.346863 -241.539805) (xy 367.297979 -241.553965) (xy 367.247458 -241.560099)
			(xy 367.196606 -241.55805) (xy 367.146742 -241.54787) (xy 367.099156 -241.529823) (xy 367.055082 -241.504377)
			(xy 367.01566 -241.47219) (xy 366.981912 -241.434096) (xy 366.954711 -241.391082) (xy 366.934763 -241.344262)
			(xy 366.922584 -241.294848) (xy 366.918489 -241.24412) (xy 366.612932 -241.24412) (xy 366.612442 -241.269109)
			(xy 366.604623 -241.318472) (xy 366.589179 -241.366004) (xy 366.566489 -241.410536) (xy 366.537113 -241.450969)
			(xy 366.501773 -241.486309) (xy 366.46134 -241.515685) (xy 366.416808 -241.538375) (xy 366.369276 -241.553819)
			(xy 366.319913 -241.561638) (xy 366.269935 -241.561638) (xy 366.220572 -241.553819) (xy 366.17304 -241.538375)
			(xy 366.128508 -241.515685) (xy 366.088075 -241.486309) (xy 366.052735 -241.450969) (xy 366.023359 -241.410536)
			(xy 366.000669 -241.366004) (xy 365.985225 -241.318472) (xy 365.977406 -241.269109) (xy 365.670089 -241.269109)
			(xy 365.67008 -241.269566) (xy 365.661916 -241.3198) (xy 365.6458 -241.368074) (xy 365.622149 -241.413137)
			(xy 365.591576 -241.453823) (xy 365.554872 -241.489078) (xy 365.512988 -241.517988) (xy 365.467009 -241.539805)
			(xy 365.418125 -241.553965) (xy 365.367604 -241.560099) (xy 365.316752 -241.55805) (xy 365.266888 -241.54787)
			(xy 365.219302 -241.529823) (xy 365.175228 -241.504377) (xy 365.135806 -241.47219) (xy 365.102058 -241.434096)
			(xy 365.074857 -241.391082) (xy 365.054909 -241.344262) (xy 365.04273 -241.294848) (xy 365.038635 -241.24412)
			(xy 364.730538 -241.24412) (xy 364.730026 -241.269566) (xy 364.721862 -241.3198) (xy 364.705746 -241.368074)
			(xy 364.682095 -241.413137) (xy 364.651522 -241.453823) (xy 364.614818 -241.489078) (xy 364.572934 -241.517988)
			(xy 364.526955 -241.539805) (xy 364.478071 -241.553965) (xy 364.42755 -241.560099) (xy 364.376698 -241.55805)
			(xy 364.326834 -241.54787) (xy 364.279248 -241.529823) (xy 364.235174 -241.504377) (xy 364.195752 -241.47219)
			(xy 364.162004 -241.434096) (xy 364.134803 -241.391082) (xy 364.114855 -241.344262) (xy 364.102676 -241.294848)
			(xy 364.098581 -241.24412) (xy 363.79277 -241.24412) (xy 363.79228 -241.269109) (xy 363.784461 -241.318472)
			(xy 363.769017 -241.366004) (xy 363.746327 -241.410536) (xy 363.716951 -241.450969) (xy 363.681611 -241.486309)
			(xy 363.641178 -241.515685) (xy 363.596646 -241.538375) (xy 363.549114 -241.553819) (xy 363.499751 -241.561638)
			(xy 363.449773 -241.561638) (xy 363.40041 -241.553819) (xy 363.352878 -241.538375) (xy 363.308346 -241.515685)
			(xy 363.267913 -241.486309) (xy 363.232573 -241.450969) (xy 363.203197 -241.410536) (xy 363.180507 -241.366004)
			(xy 363.165063 -241.318472) (xy 363.157244 -241.269109) (xy 362.852226 -241.269109) (xy 362.844407 -241.318472)
			(xy 362.828963 -241.366004) (xy 362.806273 -241.410536) (xy 362.776897 -241.450969) (xy 362.741557 -241.486309)
			(xy 362.701124 -241.515685) (xy 362.656592 -241.538375) (xy 362.60906 -241.553819) (xy 362.559697 -241.561638)
			(xy 362.509719 -241.561638) (xy 362.460356 -241.553819) (xy 362.412824 -241.538375) (xy 362.368292 -241.515685)
			(xy 362.327859 -241.486309) (xy 362.292519 -241.450969) (xy 362.263143 -241.410536) (xy 362.240453 -241.366004)
			(xy 362.225009 -241.318472) (xy 362.21719 -241.269109) (xy 361.912426 -241.269109) (xy 361.904607 -241.318472)
			(xy 361.889163 -241.366004) (xy 361.866473 -241.410536) (xy 361.837097 -241.450969) (xy 361.801757 -241.486309)
			(xy 361.761324 -241.515685) (xy 361.716792 -241.538375) (xy 361.66926 -241.553819) (xy 361.619897 -241.561638)
			(xy 361.569919 -241.561638) (xy 361.520556 -241.553819) (xy 361.473024 -241.538375) (xy 361.428492 -241.515685)
			(xy 361.388059 -241.486309) (xy 361.352719 -241.450969) (xy 361.323343 -241.410536) (xy 361.300653 -241.366004)
			(xy 361.285209 -241.318472) (xy 361.27739 -241.269109) (xy 358.15856 -241.269109) (xy 358.150741 -241.318472)
			(xy 358.135297 -241.366004) (xy 358.112607 -241.410536) (xy 358.083231 -241.450969) (xy 358.047891 -241.486309)
			(xy 358.007458 -241.515685) (xy 357.962926 -241.538375) (xy 357.915394 -241.553819) (xy 357.866031 -241.561638)
			(xy 357.816053 -241.561638) (xy 357.76669 -241.553819) (xy 357.719158 -241.538375) (xy 357.674626 -241.515685)
			(xy 357.634193 -241.486309) (xy 357.598853 -241.450969) (xy 357.569477 -241.410536) (xy 357.546787 -241.366004)
			(xy 357.531343 -241.318472) (xy 357.523524 -241.269109) (xy 357.21876 -241.269109) (xy 357.210941 -241.318472)
			(xy 357.195497 -241.366004) (xy 357.172807 -241.410536) (xy 357.143431 -241.450969) (xy 357.108091 -241.486309)
			(xy 357.067658 -241.515685) (xy 357.023126 -241.538375) (xy 356.975594 -241.553819) (xy 356.926231 -241.561638)
			(xy 356.876253 -241.561638) (xy 356.82689 -241.553819) (xy 356.779358 -241.538375) (xy 356.734826 -241.515685)
			(xy 356.694393 -241.486309) (xy 356.659053 -241.450969) (xy 356.629677 -241.410536) (xy 356.606987 -241.366004)
			(xy 356.591543 -241.318472) (xy 356.583724 -241.269109) (xy 356.278706 -241.269109) (xy 356.270887 -241.318472)
			(xy 356.255443 -241.366004) (xy 356.232753 -241.410536) (xy 356.203377 -241.450969) (xy 356.168037 -241.486309)
			(xy 356.127604 -241.515685) (xy 356.083072 -241.538375) (xy 356.03554 -241.553819) (xy 355.986177 -241.561638)
			(xy 355.936199 -241.561638) (xy 355.886836 -241.553819) (xy 355.839304 -241.538375) (xy 355.794772 -241.515685)
			(xy 355.754339 -241.486309) (xy 355.718999 -241.450969) (xy 355.689623 -241.410536) (xy 355.666933 -241.366004)
			(xy 355.651489 -241.318472) (xy 355.64367 -241.269109) (xy 355.336353 -241.269109) (xy 355.336344 -241.269566)
			(xy 355.32818 -241.3198) (xy 355.312064 -241.368074) (xy 355.288413 -241.413137) (xy 355.25784 -241.453823)
			(xy 355.221136 -241.489078) (xy 355.179252 -241.517988) (xy 355.133273 -241.539805) (xy 355.084389 -241.553965)
			(xy 355.033868 -241.560099) (xy 354.983016 -241.55805) (xy 354.933152 -241.54787) (xy 354.885566 -241.529823)
			(xy 354.841492 -241.504377) (xy 354.80207 -241.47219) (xy 354.768322 -241.434096) (xy 354.741121 -241.391082)
			(xy 354.721173 -241.344262) (xy 354.708994 -241.294848) (xy 354.704899 -241.24412) (xy 354.396802 -241.24412)
			(xy 354.39629 -241.269566) (xy 354.388126 -241.3198) (xy 354.37201 -241.368074) (xy 354.348359 -241.413137)
			(xy 354.317786 -241.453823) (xy 354.281082 -241.489078) (xy 354.239198 -241.517988) (xy 354.193219 -241.539805)
			(xy 354.144335 -241.553965) (xy 354.093814 -241.560099) (xy 354.042962 -241.55805) (xy 353.993098 -241.54787)
			(xy 353.945512 -241.529823) (xy 353.901438 -241.504377) (xy 353.862016 -241.47219) (xy 353.828268 -241.434096)
			(xy 353.801067 -241.391082) (xy 353.781119 -241.344262) (xy 353.76894 -241.294848) (xy 353.764845 -241.24412)
			(xy 353.459034 -241.24412) (xy 353.458544 -241.269109) (xy 353.450725 -241.318472) (xy 353.435281 -241.366004)
			(xy 353.412591 -241.410536) (xy 353.383215 -241.450969) (xy 353.347875 -241.486309) (xy 353.307442 -241.515685)
			(xy 353.26291 -241.538375) (xy 353.215378 -241.553819) (xy 353.166015 -241.561638) (xy 353.116037 -241.561638)
			(xy 353.066674 -241.553819) (xy 353.019142 -241.538375) (xy 352.97461 -241.515685) (xy 352.934177 -241.486309)
			(xy 352.898837 -241.450969) (xy 352.869461 -241.410536) (xy 352.846771 -241.366004) (xy 352.831327 -241.318472)
			(xy 352.823508 -241.269109) (xy 352.516445 -241.269109) (xy 352.516436 -241.269566) (xy 352.508272 -241.3198)
			(xy 352.492156 -241.368074) (xy 352.468505 -241.413137) (xy 352.437932 -241.453823) (xy 352.401228 -241.489078)
			(xy 352.359344 -241.517988) (xy 352.313365 -241.539805) (xy 352.264481 -241.553965) (xy 352.21396 -241.560099)
			(xy 352.163108 -241.55805) (xy 352.113244 -241.54787) (xy 352.065658 -241.529823) (xy 352.021584 -241.504377)
			(xy 351.982162 -241.47219) (xy 351.948414 -241.434096) (xy 351.921213 -241.391082) (xy 351.901265 -241.344262)
			(xy 351.889086 -241.294848) (xy 351.884991 -241.24412) (xy 351.576894 -241.24412) (xy 351.576382 -241.269566)
			(xy 351.568218 -241.3198) (xy 351.552102 -241.368074) (xy 351.528451 -241.413137) (xy 351.497878 -241.453823)
			(xy 351.461174 -241.489078) (xy 351.41929 -241.517988) (xy 351.373311 -241.539805) (xy 351.324427 -241.553965)
			(xy 351.273906 -241.560099) (xy 351.223054 -241.55805) (xy 351.17319 -241.54787) (xy 351.125604 -241.529823)
			(xy 351.08153 -241.504377) (xy 351.042108 -241.47219) (xy 351.00836 -241.434096) (xy 350.981159 -241.391082)
			(xy 350.961211 -241.344262) (xy 350.949032 -241.294848) (xy 350.944937 -241.24412) (xy 350.639126 -241.24412)
			(xy 350.638636 -241.269109) (xy 350.630817 -241.318472) (xy 350.615373 -241.366004) (xy 350.592683 -241.410536)
			(xy 350.563307 -241.450969) (xy 350.527967 -241.486309) (xy 350.487534 -241.515685) (xy 350.443002 -241.538375)
			(xy 350.39547 -241.553819) (xy 350.346107 -241.561638) (xy 350.296129 -241.561638) (xy 350.246766 -241.553819)
			(xy 350.199234 -241.538375) (xy 350.154702 -241.515685) (xy 350.114269 -241.486309) (xy 350.078929 -241.450969)
			(xy 350.049553 -241.410536) (xy 350.026863 -241.366004) (xy 350.011419 -241.318472) (xy 350.0036 -241.269109)
			(xy 349.696283 -241.269109) (xy 349.696274 -241.269566) (xy 349.68811 -241.3198) (xy 349.671994 -241.368074)
			(xy 349.648343 -241.413137) (xy 349.61777 -241.453823) (xy 349.581066 -241.489078) (xy 349.539182 -241.517988)
			(xy 349.493203 -241.539805) (xy 349.444319 -241.553965) (xy 349.393798 -241.560099) (xy 349.342946 -241.55805)
			(xy 349.293082 -241.54787) (xy 349.245496 -241.529823) (xy 349.201422 -241.504377) (xy 349.162 -241.47219)
			(xy 349.128252 -241.434096) (xy 349.101051 -241.391082) (xy 349.081103 -241.344262) (xy 349.068924 -241.294848)
			(xy 349.064829 -241.24412) (xy 348.756732 -241.24412) (xy 348.75622 -241.269566) (xy 348.748056 -241.3198)
			(xy 348.73194 -241.368074) (xy 348.708289 -241.413137) (xy 348.677716 -241.453823) (xy 348.641012 -241.489078)
			(xy 348.599128 -241.517988) (xy 348.553149 -241.539805) (xy 348.504265 -241.553965) (xy 348.453744 -241.560099)
			(xy 348.402892 -241.55805) (xy 348.353028 -241.54787) (xy 348.305442 -241.529823) (xy 348.261368 -241.504377)
			(xy 348.221946 -241.47219) (xy 348.188198 -241.434096) (xy 348.160997 -241.391082) (xy 348.141049 -241.344262)
			(xy 348.12887 -241.294848) (xy 348.124775 -241.24412) (xy 347.819218 -241.24412) (xy 347.818728 -241.269109)
			(xy 347.810909 -241.318472) (xy 347.795465 -241.366004) (xy 347.772775 -241.410536) (xy 347.743399 -241.450969)
			(xy 347.708059 -241.486309) (xy 347.667626 -241.515685) (xy 347.623094 -241.538375) (xy 347.575562 -241.553819)
			(xy 347.526199 -241.561638) (xy 347.476221 -241.561638) (xy 347.426858 -241.553819) (xy 347.379326 -241.538375)
			(xy 347.334794 -241.515685) (xy 347.294361 -241.486309) (xy 347.259021 -241.450969) (xy 347.229645 -241.410536)
			(xy 347.206955 -241.366004) (xy 347.191511 -241.318472) (xy 347.183692 -241.269109) (xy 346.876375 -241.269109)
			(xy 346.876366 -241.269566) (xy 346.868202 -241.3198) (xy 346.852086 -241.368074) (xy 346.828435 -241.413137)
			(xy 346.797862 -241.453823) (xy 346.761158 -241.489078) (xy 346.719274 -241.517988) (xy 346.673295 -241.539805)
			(xy 346.624411 -241.553965) (xy 346.57389 -241.560099) (xy 346.523038 -241.55805) (xy 346.473174 -241.54787)
			(xy 346.425588 -241.529823) (xy 346.381514 -241.504377) (xy 346.342092 -241.47219) (xy 346.308344 -241.434096)
			(xy 346.281143 -241.391082) (xy 346.261195 -241.344262) (xy 346.249016 -241.294848) (xy 346.244921 -241.24412)
			(xy 345.936824 -241.24412) (xy 345.936312 -241.269566) (xy 345.928148 -241.3198) (xy 345.912032 -241.368074)
			(xy 345.888381 -241.413137) (xy 345.857808 -241.453823) (xy 345.821104 -241.489078) (xy 345.77922 -241.517988)
			(xy 345.733241 -241.539805) (xy 345.684357 -241.553965) (xy 345.633836 -241.560099) (xy 345.582984 -241.55805)
			(xy 345.53312 -241.54787) (xy 345.485534 -241.529823) (xy 345.44146 -241.504377) (xy 345.402038 -241.47219)
			(xy 345.36829 -241.434096) (xy 345.341089 -241.391082) (xy 345.321141 -241.344262) (xy 345.308962 -241.294848)
			(xy 345.304867 -241.24412) (xy 344.999056 -241.24412) (xy 344.999056 -241.244374) (xy 344.997786 -241.273584)
			(xy 344.997532 -241.278156) (xy 344.997532 -242.079115) (xy 346.713538 -242.079115) (xy 346.713538 -242.029137)
			(xy 346.721357 -241.979774) (xy 346.736801 -241.932242) (xy 346.759491 -241.88771) (xy 346.788867 -241.847277)
			(xy 346.824207 -241.811937) (xy 346.86464 -241.782561) (xy 346.909172 -241.759871) (xy 346.956704 -241.744427)
			(xy 347.006067 -241.736608) (xy 347.056045 -241.736608) (xy 347.105408 -241.744427) (xy 347.15294 -241.759871)
			(xy 347.197472 -241.782561) (xy 347.237905 -241.811937) (xy 347.273245 -241.847277) (xy 347.302621 -241.88771)
			(xy 347.325311 -241.932242) (xy 347.340755 -241.979774) (xy 347.348574 -242.029137) (xy 347.349064 -242.054126)
			(xy 347.348574 -242.079115) (xy 349.5337 -242.079115) (xy 349.5337 -242.029137) (xy 349.541519 -241.979774)
			(xy 349.556963 -241.932242) (xy 349.579653 -241.88771) (xy 349.609029 -241.847277) (xy 349.644369 -241.811937)
			(xy 349.684802 -241.782561) (xy 349.729334 -241.759871) (xy 349.776866 -241.744427) (xy 349.826229 -241.736608)
			(xy 349.876207 -241.736608) (xy 349.92557 -241.744427) (xy 349.973102 -241.759871) (xy 350.017634 -241.782561)
			(xy 350.058067 -241.811937) (xy 350.093407 -241.847277) (xy 350.122783 -241.88771) (xy 350.145473 -241.932242)
			(xy 350.160917 -241.979774) (xy 350.168736 -242.029137) (xy 350.169226 -242.054126) (xy 350.168736 -242.079115)
			(xy 352.353608 -242.079115) (xy 352.353608 -242.029137) (xy 352.361427 -241.979774) (xy 352.376871 -241.932242)
			(xy 352.399561 -241.88771) (xy 352.428937 -241.847277) (xy 352.464277 -241.811937) (xy 352.50471 -241.782561)
			(xy 352.549242 -241.759871) (xy 352.596774 -241.744427) (xy 352.646137 -241.736608) (xy 352.696115 -241.736608)
			(xy 352.745478 -241.744427) (xy 352.79301 -241.759871) (xy 352.837542 -241.782561) (xy 352.877975 -241.811937)
			(xy 352.913315 -241.847277) (xy 352.942691 -241.88771) (xy 352.965381 -241.932242) (xy 352.980825 -241.979774)
			(xy 352.988644 -242.029137) (xy 352.989134 -242.054126) (xy 352.988644 -242.079115) (xy 355.173516 -242.079115)
			(xy 355.173516 -242.029137) (xy 355.181335 -241.979774) (xy 355.196779 -241.932242) (xy 355.219469 -241.88771)
			(xy 355.248845 -241.847277) (xy 355.284185 -241.811937) (xy 355.324618 -241.782561) (xy 355.36915 -241.759871)
			(xy 355.416682 -241.744427) (xy 355.466045 -241.736608) (xy 355.516023 -241.736608) (xy 355.565386 -241.744427)
			(xy 355.612918 -241.759871) (xy 355.65745 -241.782561) (xy 355.697883 -241.811937) (xy 355.733223 -241.847277)
			(xy 355.762599 -241.88771) (xy 355.785289 -241.932242) (xy 355.800733 -241.979774) (xy 355.808552 -242.029137)
			(xy 355.809042 -242.054126) (xy 356.114853 -242.054126) (xy 356.118948 -242.003398) (xy 356.131127 -241.953984)
			(xy 356.151075 -241.907164) (xy 356.178276 -241.86415) (xy 356.212024 -241.826056) (xy 356.251446 -241.793869)
			(xy 356.29552 -241.768423) (xy 356.343106 -241.750376) (xy 356.39297 -241.740196) (xy 356.443822 -241.738147)
			(xy 356.494343 -241.744281) (xy 356.543227 -241.758441) (xy 356.589206 -241.780258) (xy 356.63109 -241.809168)
			(xy 356.667794 -241.844423) (xy 356.698367 -241.885109) (xy 356.722018 -241.930172) (xy 356.738134 -241.978446)
			(xy 356.746298 -242.02868) (xy 356.74681 -242.054126) (xy 357.054907 -242.054126) (xy 357.059002 -242.003398)
			(xy 357.071181 -241.953984) (xy 357.091129 -241.907164) (xy 357.11833 -241.86415) (xy 357.152078 -241.826056)
			(xy 357.1915 -241.793869) (xy 357.235574 -241.768423) (xy 357.28316 -241.750376) (xy 357.333024 -241.740196)
			(xy 357.383876 -241.738147) (xy 357.434397 -241.744281) (xy 357.483281 -241.758441) (xy 357.52926 -241.780258)
			(xy 357.571144 -241.809168) (xy 357.607848 -241.844423) (xy 357.638421 -241.885109) (xy 357.662072 -241.930172)
			(xy 357.678188 -241.978446) (xy 357.686352 -242.02868) (xy 357.686864 -242.054126) (xy 357.686361 -242.079115)
			(xy 357.993678 -242.079115) (xy 357.993678 -242.029137) (xy 358.001497 -241.979774) (xy 358.016941 -241.932242)
			(xy 358.039631 -241.88771) (xy 358.069007 -241.847277) (xy 358.104347 -241.811937) (xy 358.14478 -241.782561)
			(xy 358.189312 -241.759871) (xy 358.236844 -241.744427) (xy 358.286207 -241.736608) (xy 358.336185 -241.736608)
			(xy 358.385548 -241.744427) (xy 358.43308 -241.759871) (xy 358.477612 -241.782561) (xy 358.518045 -241.811937)
			(xy 358.553385 -241.847277) (xy 358.582761 -241.88771) (xy 358.605451 -241.932242) (xy 358.620895 -241.979774)
			(xy 358.628714 -242.029137) (xy 358.629204 -242.054126) (xy 358.628714 -242.079115) (xy 360.807236 -242.079115)
			(xy 360.807236 -242.029137) (xy 360.815055 -241.979774) (xy 360.830499 -241.932242) (xy 360.853189 -241.88771)
			(xy 360.882565 -241.847277) (xy 360.917905 -241.811937) (xy 360.958338 -241.782561) (xy 361.00287 -241.759871)
			(xy 361.050402 -241.744427) (xy 361.099765 -241.736608) (xy 361.149743 -241.736608) (xy 361.199106 -241.744427)
			(xy 361.246638 -241.759871) (xy 361.29117 -241.782561) (xy 361.331603 -241.811937) (xy 361.366943 -241.847277)
			(xy 361.396319 -241.88771) (xy 361.419009 -241.932242) (xy 361.434453 -241.979774) (xy 361.442272 -242.029137)
			(xy 361.442762 -242.054126) (xy 361.748573 -242.054126) (xy 361.752668 -242.003398) (xy 361.764847 -241.953984)
			(xy 361.784795 -241.907164) (xy 361.811996 -241.86415) (xy 361.845744 -241.826056) (xy 361.885166 -241.793869)
			(xy 361.92924 -241.768423) (xy 361.976826 -241.750376) (xy 362.02669 -241.740196) (xy 362.077542 -241.738147)
			(xy 362.128063 -241.744281) (xy 362.176947 -241.758441) (xy 362.222926 -241.780258) (xy 362.26481 -241.809168)
			(xy 362.301514 -241.844423) (xy 362.332087 -241.885109) (xy 362.355738 -241.930172) (xy 362.371854 -241.978446)
			(xy 362.380018 -242.02868) (xy 362.38053 -242.054126) (xy 362.688627 -242.054126) (xy 362.692722 -242.003398)
			(xy 362.704901 -241.953984) (xy 362.724849 -241.907164) (xy 362.75205 -241.86415) (xy 362.785798 -241.826056)
			(xy 362.82522 -241.793869) (xy 362.869294 -241.768423) (xy 362.91688 -241.750376) (xy 362.966744 -241.740196)
			(xy 363.017596 -241.738147) (xy 363.068117 -241.744281) (xy 363.117001 -241.758441) (xy 363.16298 -241.780258)
			(xy 363.204864 -241.809168) (xy 363.241568 -241.844423) (xy 363.272141 -241.885109) (xy 363.295792 -241.930172)
			(xy 363.311908 -241.978446) (xy 363.320072 -242.02868) (xy 363.320584 -242.054126) (xy 363.320081 -242.079115)
			(xy 363.627398 -242.079115) (xy 363.627398 -242.029137) (xy 363.635217 -241.979774) (xy 363.650661 -241.932242)
			(xy 363.673351 -241.88771) (xy 363.702727 -241.847277) (xy 363.738067 -241.811937) (xy 363.7785 -241.782561)
			(xy 363.823032 -241.759871) (xy 363.870564 -241.744427) (xy 363.919927 -241.736608) (xy 363.969905 -241.736608)
			(xy 364.019268 -241.744427) (xy 364.0668 -241.759871) (xy 364.111332 -241.782561) (xy 364.151765 -241.811937)
			(xy 364.187105 -241.847277) (xy 364.216481 -241.88771) (xy 364.239171 -241.932242) (xy 364.254615 -241.979774)
			(xy 364.262434 -242.029137) (xy 364.262924 -242.054126) (xy 364.262434 -242.079115) (xy 366.447306 -242.079115)
			(xy 366.447306 -242.029137) (xy 366.455125 -241.979774) (xy 366.470569 -241.932242) (xy 366.493259 -241.88771)
			(xy 366.522635 -241.847277) (xy 366.557975 -241.811937) (xy 366.598408 -241.782561) (xy 366.64294 -241.759871)
			(xy 366.690472 -241.744427) (xy 366.739835 -241.736608) (xy 366.789813 -241.736608) (xy 366.839176 -241.744427)
			(xy 366.886708 -241.759871) (xy 366.93124 -241.782561) (xy 366.971673 -241.811937) (xy 367.007013 -241.847277)
			(xy 367.036389 -241.88771) (xy 367.059079 -241.932242) (xy 367.074523 -241.979774) (xy 367.082342 -242.029137)
			(xy 367.082832 -242.054126) (xy 367.082342 -242.079115) (xy 369.267214 -242.079115) (xy 369.267214 -242.029137)
			(xy 369.275033 -241.979774) (xy 369.290477 -241.932242) (xy 369.313167 -241.88771) (xy 369.342543 -241.847277)
			(xy 369.377883 -241.811937) (xy 369.418316 -241.782561) (xy 369.462848 -241.759871) (xy 369.51038 -241.744427)
			(xy 369.559743 -241.736608) (xy 369.609721 -241.736608) (xy 369.659084 -241.744427) (xy 369.706616 -241.759871)
			(xy 369.751148 -241.782561) (xy 369.791581 -241.811937) (xy 369.826921 -241.847277) (xy 369.856297 -241.88771)
			(xy 369.878987 -241.932242) (xy 369.894431 -241.979774) (xy 369.90225 -242.029137) (xy 369.90274 -242.054126)
			(xy 369.90225 -242.079115) (xy 372.087376 -242.079115) (xy 372.087376 -242.029137) (xy 372.095195 -241.979774)
			(xy 372.110639 -241.932242) (xy 372.133329 -241.88771) (xy 372.162705 -241.847277) (xy 372.198045 -241.811937)
			(xy 372.238478 -241.782561) (xy 372.28301 -241.759871) (xy 372.330542 -241.744427) (xy 372.379905 -241.736608)
			(xy 372.429883 -241.736608) (xy 372.479246 -241.744427) (xy 372.526778 -241.759871) (xy 372.57131 -241.782561)
			(xy 372.611743 -241.811937) (xy 372.647083 -241.847277) (xy 372.676459 -241.88771) (xy 372.699149 -241.932242)
			(xy 372.714593 -241.979774) (xy 372.722412 -242.029137) (xy 372.722902 -242.054126) (xy 372.722412 -242.079115)
			(xy 372.714593 -242.128478) (xy 372.699149 -242.17601) (xy 372.676459 -242.220542) (xy 372.647083 -242.260975)
			(xy 372.611743 -242.296315) (xy 372.57131 -242.325691) (xy 372.526778 -242.348381) (xy 372.479246 -242.363825)
			(xy 372.429883 -242.371644) (xy 372.379905 -242.371644) (xy 372.330542 -242.363825) (xy 372.28301 -242.348381)
			(xy 372.238478 -242.325691) (xy 372.198045 -242.296315) (xy 372.162705 -242.260975) (xy 372.133329 -242.220542)
			(xy 372.110639 -242.17601) (xy 372.095195 -242.128478) (xy 372.087376 -242.079115) (xy 369.90225 -242.079115)
			(xy 369.894431 -242.128478) (xy 369.878987 -242.17601) (xy 369.856297 -242.220542) (xy 369.826921 -242.260975)
			(xy 369.791581 -242.296315) (xy 369.751148 -242.325691) (xy 369.706616 -242.348381) (xy 369.659084 -242.363825)
			(xy 369.609721 -242.371644) (xy 369.559743 -242.371644) (xy 369.51038 -242.363825) (xy 369.462848 -242.348381)
			(xy 369.418316 -242.325691) (xy 369.377883 -242.296315) (xy 369.342543 -242.260975) (xy 369.313167 -242.220542)
			(xy 369.290477 -242.17601) (xy 369.275033 -242.128478) (xy 369.267214 -242.079115) (xy 367.082342 -242.079115)
			(xy 367.074523 -242.128478) (xy 367.059079 -242.17601) (xy 367.036389 -242.220542) (xy 367.007013 -242.260975)
			(xy 366.971673 -242.296315) (xy 366.93124 -242.325691) (xy 366.886708 -242.348381) (xy 366.839176 -242.363825)
			(xy 366.789813 -242.371644) (xy 366.739835 -242.371644) (xy 366.690472 -242.363825) (xy 366.64294 -242.348381)
			(xy 366.598408 -242.325691) (xy 366.557975 -242.296315) (xy 366.522635 -242.260975) (xy 366.493259 -242.220542)
			(xy 366.470569 -242.17601) (xy 366.455125 -242.128478) (xy 366.447306 -242.079115) (xy 364.262434 -242.079115)
			(xy 364.254615 -242.128478) (xy 364.239171 -242.17601) (xy 364.216481 -242.220542) (xy 364.187105 -242.260975)
			(xy 364.151765 -242.296315) (xy 364.111332 -242.325691) (xy 364.0668 -242.348381) (xy 364.019268 -242.363825)
			(xy 363.969905 -242.371644) (xy 363.919927 -242.371644) (xy 363.870564 -242.363825) (xy 363.823032 -242.348381)
			(xy 363.7785 -242.325691) (xy 363.738067 -242.296315) (xy 363.702727 -242.260975) (xy 363.673351 -242.220542)
			(xy 363.650661 -242.17601) (xy 363.635217 -242.128478) (xy 363.627398 -242.079115) (xy 363.320081 -242.079115)
			(xy 363.320072 -242.079572) (xy 363.311908 -242.129806) (xy 363.295792 -242.17808) (xy 363.272141 -242.223143)
			(xy 363.241568 -242.263829) (xy 363.204864 -242.299084) (xy 363.16298 -242.327994) (xy 363.117001 -242.349811)
			(xy 363.068117 -242.363971) (xy 363.017596 -242.370105) (xy 362.966744 -242.368056) (xy 362.91688 -242.357876)
			(xy 362.869294 -242.339829) (xy 362.82522 -242.314383) (xy 362.785798 -242.282196) (xy 362.75205 -242.244102)
			(xy 362.724849 -242.201088) (xy 362.704901 -242.154268) (xy 362.692722 -242.104854) (xy 362.688627 -242.054126)
			(xy 362.38053 -242.054126) (xy 362.380018 -242.079572) (xy 362.371854 -242.129806) (xy 362.355738 -242.17808)
			(xy 362.332087 -242.223143) (xy 362.301514 -242.263829) (xy 362.26481 -242.299084) (xy 362.222926 -242.327994)
			(xy 362.176947 -242.349811) (xy 362.128063 -242.363971) (xy 362.077542 -242.370105) (xy 362.02669 -242.368056)
			(xy 361.976826 -242.357876) (xy 361.92924 -242.339829) (xy 361.885166 -242.314383) (xy 361.845744 -242.282196)
			(xy 361.811996 -242.244102) (xy 361.784795 -242.201088) (xy 361.764847 -242.154268) (xy 361.752668 -242.104854)
			(xy 361.748573 -242.054126) (xy 361.442762 -242.054126) (xy 361.442272 -242.079115) (xy 361.434453 -242.128478)
			(xy 361.419009 -242.17601) (xy 361.396319 -242.220542) (xy 361.366943 -242.260975) (xy 361.331603 -242.296315)
			(xy 361.29117 -242.325691) (xy 361.246638 -242.348381) (xy 361.199106 -242.363825) (xy 361.149743 -242.371644)
			(xy 361.099765 -242.371644) (xy 361.050402 -242.363825) (xy 361.00287 -242.348381) (xy 360.958338 -242.325691)
			(xy 360.917905 -242.296315) (xy 360.882565 -242.260975) (xy 360.853189 -242.220542) (xy 360.830499 -242.17601)
			(xy 360.815055 -242.128478) (xy 360.807236 -242.079115) (xy 358.628714 -242.079115) (xy 358.620895 -242.128478)
			(xy 358.605451 -242.17601) (xy 358.582761 -242.220542) (xy 358.553385 -242.260975) (xy 358.518045 -242.296315)
			(xy 358.477612 -242.325691) (xy 358.43308 -242.348381) (xy 358.385548 -242.363825) (xy 358.336185 -242.371644)
			(xy 358.286207 -242.371644) (xy 358.236844 -242.363825) (xy 358.189312 -242.348381) (xy 358.14478 -242.325691)
			(xy 358.104347 -242.296315) (xy 358.069007 -242.260975) (xy 358.039631 -242.220542) (xy 358.016941 -242.17601)
			(xy 358.001497 -242.128478) (xy 357.993678 -242.079115) (xy 357.686361 -242.079115) (xy 357.686352 -242.079572)
			(xy 357.678188 -242.129806) (xy 357.662072 -242.17808) (xy 357.638421 -242.223143) (xy 357.607848 -242.263829)
			(xy 357.571144 -242.299084) (xy 357.52926 -242.327994) (xy 357.483281 -242.349811) (xy 357.434397 -242.363971)
			(xy 357.383876 -242.370105) (xy 357.333024 -242.368056) (xy 357.28316 -242.357876) (xy 357.235574 -242.339829)
			(xy 357.1915 -242.314383) (xy 357.152078 -242.282196) (xy 357.11833 -242.244102) (xy 357.091129 -242.201088)
			(xy 357.071181 -242.154268) (xy 357.059002 -242.104854) (xy 357.054907 -242.054126) (xy 356.74681 -242.054126)
			(xy 356.746298 -242.079572) (xy 356.738134 -242.129806) (xy 356.722018 -242.17808) (xy 356.698367 -242.223143)
			(xy 356.667794 -242.263829) (xy 356.63109 -242.299084) (xy 356.589206 -242.327994) (xy 356.543227 -242.349811)
			(xy 356.494343 -242.363971) (xy 356.443822 -242.370105) (xy 356.39297 -242.368056) (xy 356.343106 -242.357876)
			(xy 356.29552 -242.339829) (xy 356.251446 -242.314383) (xy 356.212024 -242.282196) (xy 356.178276 -242.244102)
			(xy 356.151075 -242.201088) (xy 356.131127 -242.154268) (xy 356.118948 -242.104854) (xy 356.114853 -242.054126)
			(xy 355.809042 -242.054126) (xy 355.808552 -242.079115) (xy 355.800733 -242.128478) (xy 355.785289 -242.17601)
			(xy 355.762599 -242.220542) (xy 355.733223 -242.260975) (xy 355.697883 -242.296315) (xy 355.65745 -242.325691)
			(xy 355.612918 -242.348381) (xy 355.565386 -242.363825) (xy 355.516023 -242.371644) (xy 355.466045 -242.371644)
			(xy 355.416682 -242.363825) (xy 355.36915 -242.348381) (xy 355.324618 -242.325691) (xy 355.284185 -242.296315)
			(xy 355.248845 -242.260975) (xy 355.219469 -242.220542) (xy 355.196779 -242.17601) (xy 355.181335 -242.128478)
			(xy 355.173516 -242.079115) (xy 352.988644 -242.079115) (xy 352.980825 -242.128478) (xy 352.965381 -242.17601)
			(xy 352.942691 -242.220542) (xy 352.913315 -242.260975) (xy 352.877975 -242.296315) (xy 352.837542 -242.325691)
			(xy 352.79301 -242.348381) (xy 352.745478 -242.363825) (xy 352.696115 -242.371644) (xy 352.646137 -242.371644)
			(xy 352.596774 -242.363825) (xy 352.549242 -242.348381) (xy 352.50471 -242.325691) (xy 352.464277 -242.296315)
			(xy 352.428937 -242.260975) (xy 352.399561 -242.220542) (xy 352.376871 -242.17601) (xy 352.361427 -242.128478)
			(xy 352.353608 -242.079115) (xy 350.168736 -242.079115) (xy 350.160917 -242.128478) (xy 350.145473 -242.17601)
			(xy 350.122783 -242.220542) (xy 350.093407 -242.260975) (xy 350.058067 -242.296315) (xy 350.017634 -242.325691)
			(xy 349.973102 -242.348381) (xy 349.92557 -242.363825) (xy 349.876207 -242.371644) (xy 349.826229 -242.371644)
			(xy 349.776866 -242.363825) (xy 349.729334 -242.348381) (xy 349.684802 -242.325691) (xy 349.644369 -242.296315)
			(xy 349.609029 -242.260975) (xy 349.579653 -242.220542) (xy 349.556963 -242.17601) (xy 349.541519 -242.128478)
			(xy 349.5337 -242.079115) (xy 347.348574 -242.079115) (xy 347.340755 -242.128478) (xy 347.325311 -242.17601)
			(xy 347.302621 -242.220542) (xy 347.273245 -242.260975) (xy 347.237905 -242.296315) (xy 347.197472 -242.325691)
			(xy 347.15294 -242.348381) (xy 347.105408 -242.363825) (xy 347.056045 -242.371644) (xy 347.006067 -242.371644)
			(xy 346.956704 -242.363825) (xy 346.909172 -242.348381) (xy 346.86464 -242.325691) (xy 346.824207 -242.296315)
			(xy 346.788867 -242.260975) (xy 346.759491 -242.220542) (xy 346.736801 -242.17601) (xy 346.721357 -242.128478)
			(xy 346.713538 -242.079115) (xy 344.997532 -242.079115) (xy 344.997532 -242.830096) (xy 344.997786 -242.834668)
			(xy 344.999056 -242.863878) (xy 344.999056 -242.864132) (xy 345.304867 -242.864132) (xy 345.308962 -242.813404)
			(xy 345.321141 -242.76399) (xy 345.341089 -242.71717) (xy 345.36829 -242.674156) (xy 345.402038 -242.636062)
			(xy 345.44146 -242.603875) (xy 345.485534 -242.578429) (xy 345.53312 -242.560382) (xy 345.582984 -242.550202)
			(xy 345.633836 -242.548153) (xy 345.684357 -242.554287) (xy 345.733241 -242.568447) (xy 345.77922 -242.590264)
			(xy 345.821104 -242.619174) (xy 345.857808 -242.654429) (xy 345.888381 -242.695115) (xy 345.912032 -242.740178)
			(xy 345.928148 -242.788452) (xy 345.936312 -242.838686) (xy 345.936824 -242.864132) (xy 346.244921 -242.864132)
			(xy 346.249016 -242.813404) (xy 346.261195 -242.76399) (xy 346.281143 -242.71717) (xy 346.308344 -242.674156)
			(xy 346.342092 -242.636062) (xy 346.381514 -242.603875) (xy 346.425588 -242.578429) (xy 346.473174 -242.560382)
			(xy 346.523038 -242.550202) (xy 346.57389 -242.548153) (xy 346.624411 -242.554287) (xy 346.673295 -242.568447)
			(xy 346.719274 -242.590264) (xy 346.761158 -242.619174) (xy 346.797862 -242.654429) (xy 346.828435 -242.695115)
			(xy 346.852086 -242.740178) (xy 346.868202 -242.788452) (xy 346.876366 -242.838686) (xy 346.876878 -242.864132)
			(xy 346.876375 -242.889121) (xy 347.183692 -242.889121) (xy 347.183692 -242.839143) (xy 347.191511 -242.78978)
			(xy 347.206955 -242.742248) (xy 347.229645 -242.697716) (xy 347.259021 -242.657283) (xy 347.294361 -242.621943)
			(xy 347.334794 -242.592567) (xy 347.379326 -242.569877) (xy 347.426858 -242.554433) (xy 347.476221 -242.546614)
			(xy 347.526199 -242.546614) (xy 347.575562 -242.554433) (xy 347.623094 -242.569877) (xy 347.667626 -242.592567)
			(xy 347.708059 -242.621943) (xy 347.743399 -242.657283) (xy 347.772775 -242.697716) (xy 347.795465 -242.742248)
			(xy 347.810909 -242.78978) (xy 347.818728 -242.839143) (xy 347.819218 -242.864132) (xy 348.124775 -242.864132)
			(xy 348.12887 -242.813404) (xy 348.141049 -242.76399) (xy 348.160997 -242.71717) (xy 348.188198 -242.674156)
			(xy 348.221946 -242.636062) (xy 348.261368 -242.603875) (xy 348.305442 -242.578429) (xy 348.353028 -242.560382)
			(xy 348.402892 -242.550202) (xy 348.453744 -242.548153) (xy 348.504265 -242.554287) (xy 348.553149 -242.568447)
			(xy 348.599128 -242.590264) (xy 348.641012 -242.619174) (xy 348.677716 -242.654429) (xy 348.708289 -242.695115)
			(xy 348.73194 -242.740178) (xy 348.748056 -242.788452) (xy 348.75622 -242.838686) (xy 348.756732 -242.864132)
			(xy 349.064829 -242.864132) (xy 349.068924 -242.813404) (xy 349.081103 -242.76399) (xy 349.101051 -242.71717)
			(xy 349.128252 -242.674156) (xy 349.162 -242.636062) (xy 349.201422 -242.603875) (xy 349.245496 -242.578429)
			(xy 349.293082 -242.560382) (xy 349.342946 -242.550202) (xy 349.393798 -242.548153) (xy 349.444319 -242.554287)
			(xy 349.493203 -242.568447) (xy 349.539182 -242.590264) (xy 349.581066 -242.619174) (xy 349.61777 -242.654429)
			(xy 349.648343 -242.695115) (xy 349.671994 -242.740178) (xy 349.68811 -242.788452) (xy 349.696274 -242.838686)
			(xy 349.696786 -242.864132) (xy 349.696283 -242.889121) (xy 350.0036 -242.889121) (xy 350.0036 -242.839143)
			(xy 350.011419 -242.78978) (xy 350.026863 -242.742248) (xy 350.049553 -242.697716) (xy 350.078929 -242.657283)
			(xy 350.114269 -242.621943) (xy 350.154702 -242.592567) (xy 350.199234 -242.569877) (xy 350.246766 -242.554433)
			(xy 350.296129 -242.546614) (xy 350.346107 -242.546614) (xy 350.39547 -242.554433) (xy 350.443002 -242.569877)
			(xy 350.487534 -242.592567) (xy 350.527967 -242.621943) (xy 350.563307 -242.657283) (xy 350.592683 -242.697716)
			(xy 350.615373 -242.742248) (xy 350.630817 -242.78978) (xy 350.638636 -242.839143) (xy 350.639126 -242.864132)
			(xy 350.944937 -242.864132) (xy 350.949032 -242.813404) (xy 350.961211 -242.76399) (xy 350.981159 -242.71717)
			(xy 351.00836 -242.674156) (xy 351.042108 -242.636062) (xy 351.08153 -242.603875) (xy 351.125604 -242.578429)
			(xy 351.17319 -242.560382) (xy 351.223054 -242.550202) (xy 351.273906 -242.548153) (xy 351.324427 -242.554287)
			(xy 351.373311 -242.568447) (xy 351.41929 -242.590264) (xy 351.461174 -242.619174) (xy 351.497878 -242.654429)
			(xy 351.528451 -242.695115) (xy 351.552102 -242.740178) (xy 351.568218 -242.788452) (xy 351.576382 -242.838686)
			(xy 351.576894 -242.864132) (xy 351.884991 -242.864132) (xy 351.889086 -242.813404) (xy 351.901265 -242.76399)
			(xy 351.921213 -242.71717) (xy 351.948414 -242.674156) (xy 351.982162 -242.636062) (xy 352.021584 -242.603875)
			(xy 352.065658 -242.578429) (xy 352.113244 -242.560382) (xy 352.163108 -242.550202) (xy 352.21396 -242.548153)
			(xy 352.264481 -242.554287) (xy 352.313365 -242.568447) (xy 352.359344 -242.590264) (xy 352.401228 -242.619174)
			(xy 352.437932 -242.654429) (xy 352.468505 -242.695115) (xy 352.492156 -242.740178) (xy 352.508272 -242.788452)
			(xy 352.516436 -242.838686) (xy 352.516948 -242.864132) (xy 352.516445 -242.889121) (xy 352.823508 -242.889121)
			(xy 352.823508 -242.839143) (xy 352.831327 -242.78978) (xy 352.846771 -242.742248) (xy 352.869461 -242.697716)
			(xy 352.898837 -242.657283) (xy 352.934177 -242.621943) (xy 352.97461 -242.592567) (xy 353.019142 -242.569877)
			(xy 353.066674 -242.554433) (xy 353.116037 -242.546614) (xy 353.166015 -242.546614) (xy 353.215378 -242.554433)
			(xy 353.26291 -242.569877) (xy 353.307442 -242.592567) (xy 353.347875 -242.621943) (xy 353.383215 -242.657283)
			(xy 353.412591 -242.697716) (xy 353.435281 -242.742248) (xy 353.450725 -242.78978) (xy 353.458544 -242.839143)
			(xy 353.459034 -242.864132) (xy 353.764845 -242.864132) (xy 353.76894 -242.813404) (xy 353.781119 -242.76399)
			(xy 353.801067 -242.71717) (xy 353.828268 -242.674156) (xy 353.862016 -242.636062) (xy 353.901438 -242.603875)
			(xy 353.945512 -242.578429) (xy 353.993098 -242.560382) (xy 354.042962 -242.550202) (xy 354.093814 -242.548153)
			(xy 354.144335 -242.554287) (xy 354.193219 -242.568447) (xy 354.239198 -242.590264) (xy 354.281082 -242.619174)
			(xy 354.317786 -242.654429) (xy 354.348359 -242.695115) (xy 354.37201 -242.740178) (xy 354.388126 -242.788452)
			(xy 354.39629 -242.838686) (xy 354.396802 -242.864132) (xy 354.704899 -242.864132) (xy 354.708994 -242.813404)
			(xy 354.721173 -242.76399) (xy 354.741121 -242.71717) (xy 354.768322 -242.674156) (xy 354.80207 -242.636062)
			(xy 354.841492 -242.603875) (xy 354.885566 -242.578429) (xy 354.933152 -242.560382) (xy 354.983016 -242.550202)
			(xy 355.033868 -242.548153) (xy 355.084389 -242.554287) (xy 355.133273 -242.568447) (xy 355.179252 -242.590264)
			(xy 355.221136 -242.619174) (xy 355.25784 -242.654429) (xy 355.288413 -242.695115) (xy 355.312064 -242.740178)
			(xy 355.32818 -242.788452) (xy 355.336344 -242.838686) (xy 355.336856 -242.864132) (xy 355.336353 -242.889121)
			(xy 355.64367 -242.889121) (xy 355.64367 -242.839143) (xy 355.651489 -242.78978) (xy 355.666933 -242.742248)
			(xy 355.689623 -242.697716) (xy 355.718999 -242.657283) (xy 355.754339 -242.621943) (xy 355.794772 -242.592567)
			(xy 355.839304 -242.569877) (xy 355.886836 -242.554433) (xy 355.936199 -242.546614) (xy 355.986177 -242.546614)
			(xy 356.03554 -242.554433) (xy 356.083072 -242.569877) (xy 356.127604 -242.592567) (xy 356.168037 -242.621943)
			(xy 356.203377 -242.657283) (xy 356.232753 -242.697716) (xy 356.255443 -242.742248) (xy 356.270887 -242.78978)
			(xy 356.278706 -242.839143) (xy 356.279196 -242.864132) (xy 356.278706 -242.889121) (xy 363.157244 -242.889121)
			(xy 363.157244 -242.839143) (xy 363.165063 -242.78978) (xy 363.180507 -242.742248) (xy 363.203197 -242.697716)
			(xy 363.232573 -242.657283) (xy 363.267913 -242.621943) (xy 363.308346 -242.592567) (xy 363.352878 -242.569877)
			(xy 363.40041 -242.554433) (xy 363.449773 -242.546614) (xy 363.499751 -242.546614) (xy 363.549114 -242.554433)
			(xy 363.596646 -242.569877) (xy 363.641178 -242.592567) (xy 363.681611 -242.621943) (xy 363.716951 -242.657283)
			(xy 363.746327 -242.697716) (xy 363.769017 -242.742248) (xy 363.784461 -242.78978) (xy 363.79228 -242.839143)
			(xy 363.79277 -242.864132) (xy 364.098581 -242.864132) (xy 364.102676 -242.813404) (xy 364.114855 -242.76399)
			(xy 364.134803 -242.71717) (xy 364.162004 -242.674156) (xy 364.195752 -242.636062) (xy 364.235174 -242.603875)
			(xy 364.279248 -242.578429) (xy 364.326834 -242.560382) (xy 364.376698 -242.550202) (xy 364.42755 -242.548153)
			(xy 364.478071 -242.554287) (xy 364.526955 -242.568447) (xy 364.572934 -242.590264) (xy 364.614818 -242.619174)
			(xy 364.651522 -242.654429) (xy 364.682095 -242.695115) (xy 364.705746 -242.740178) (xy 364.721862 -242.788452)
			(xy 364.730026 -242.838686) (xy 364.730538 -242.864132) (xy 365.038635 -242.864132) (xy 365.04273 -242.813404)
			(xy 365.054909 -242.76399) (xy 365.074857 -242.71717) (xy 365.102058 -242.674156) (xy 365.135806 -242.636062)
			(xy 365.175228 -242.603875) (xy 365.219302 -242.578429) (xy 365.266888 -242.560382) (xy 365.316752 -242.550202)
			(xy 365.367604 -242.548153) (xy 365.418125 -242.554287) (xy 365.467009 -242.568447) (xy 365.512988 -242.590264)
			(xy 365.554872 -242.619174) (xy 365.591576 -242.654429) (xy 365.622149 -242.695115) (xy 365.6458 -242.740178)
			(xy 365.661916 -242.788452) (xy 365.67008 -242.838686) (xy 365.670592 -242.864132) (xy 365.670089 -242.889121)
			(xy 365.977406 -242.889121) (xy 365.977406 -242.839143) (xy 365.985225 -242.78978) (xy 366.000669 -242.742248)
			(xy 366.023359 -242.697716) (xy 366.052735 -242.657283) (xy 366.088075 -242.621943) (xy 366.128508 -242.592567)
			(xy 366.17304 -242.569877) (xy 366.220572 -242.554433) (xy 366.269935 -242.546614) (xy 366.319913 -242.546614)
			(xy 366.369276 -242.554433) (xy 366.416808 -242.569877) (xy 366.46134 -242.592567) (xy 366.501773 -242.621943)
			(xy 366.537113 -242.657283) (xy 366.566489 -242.697716) (xy 366.589179 -242.742248) (xy 366.604623 -242.78978)
			(xy 366.612442 -242.839143) (xy 366.612932 -242.864132) (xy 366.918489 -242.864132) (xy 366.922584 -242.813404)
			(xy 366.934763 -242.76399) (xy 366.954711 -242.71717) (xy 366.981912 -242.674156) (xy 367.01566 -242.636062)
			(xy 367.055082 -242.603875) (xy 367.099156 -242.578429) (xy 367.146742 -242.560382) (xy 367.196606 -242.550202)
			(xy 367.247458 -242.548153) (xy 367.297979 -242.554287) (xy 367.346863 -242.568447) (xy 367.392842 -242.590264)
			(xy 367.434726 -242.619174) (xy 367.47143 -242.654429) (xy 367.502003 -242.695115) (xy 367.525654 -242.740178)
			(xy 367.54177 -242.788452) (xy 367.549934 -242.838686) (xy 367.550446 -242.864132) (xy 367.858543 -242.864132)
			(xy 367.862638 -242.813404) (xy 367.874817 -242.76399) (xy 367.894765 -242.71717) (xy 367.921966 -242.674156)
			(xy 367.955714 -242.636062) (xy 367.995136 -242.603875) (xy 368.03921 -242.578429) (xy 368.086796 -242.560382)
			(xy 368.13666 -242.550202) (xy 368.187512 -242.548153) (xy 368.238033 -242.554287) (xy 368.286917 -242.568447)
			(xy 368.332896 -242.590264) (xy 368.37478 -242.619174) (xy 368.411484 -242.654429) (xy 368.442057 -242.695115)
			(xy 368.465708 -242.740178) (xy 368.481824 -242.788452) (xy 368.489988 -242.838686) (xy 368.4905 -242.864132)
			(xy 368.489997 -242.889121) (xy 368.797314 -242.889121) (xy 368.797314 -242.839143) (xy 368.805133 -242.78978)
			(xy 368.820577 -242.742248) (xy 368.843267 -242.697716) (xy 368.872643 -242.657283) (xy 368.907983 -242.621943)
			(xy 368.948416 -242.592567) (xy 368.992948 -242.569877) (xy 369.04048 -242.554433) (xy 369.089843 -242.546614)
			(xy 369.139821 -242.546614) (xy 369.189184 -242.554433) (xy 369.236716 -242.569877) (xy 369.281248 -242.592567)
			(xy 369.321681 -242.621943) (xy 369.357021 -242.657283) (xy 369.386397 -242.697716) (xy 369.409087 -242.742248)
			(xy 369.424531 -242.78978) (xy 369.43235 -242.839143) (xy 369.43284 -242.864132) (xy 369.738651 -242.864132)
			(xy 369.742746 -242.813404) (xy 369.754925 -242.76399) (xy 369.774873 -242.71717) (xy 369.802074 -242.674156)
			(xy 369.835822 -242.636062) (xy 369.875244 -242.603875) (xy 369.919318 -242.578429) (xy 369.966904 -242.560382)
			(xy 370.016768 -242.550202) (xy 370.06762 -242.548153) (xy 370.118141 -242.554287) (xy 370.167025 -242.568447)
			(xy 370.213004 -242.590264) (xy 370.254888 -242.619174) (xy 370.291592 -242.654429) (xy 370.322165 -242.695115)
			(xy 370.345816 -242.740178) (xy 370.361932 -242.788452) (xy 370.370096 -242.838686) (xy 370.370608 -242.864132)
			(xy 370.678451 -242.864132) (xy 370.682546 -242.813404) (xy 370.694725 -242.76399) (xy 370.714673 -242.71717)
			(xy 370.741874 -242.674156) (xy 370.775622 -242.636062) (xy 370.815044 -242.603875) (xy 370.859118 -242.578429)
			(xy 370.906704 -242.560382) (xy 370.956568 -242.550202) (xy 371.00742 -242.548153) (xy 371.057941 -242.554287)
			(xy 371.106825 -242.568447) (xy 371.152804 -242.590264) (xy 371.194688 -242.619174) (xy 371.231392 -242.654429)
			(xy 371.261965 -242.695115) (xy 371.285616 -242.740178) (xy 371.301732 -242.788452) (xy 371.309896 -242.838686)
			(xy 371.310408 -242.864132) (xy 371.309905 -242.889121) (xy 371.617222 -242.889121) (xy 371.617222 -242.839143)
			(xy 371.625041 -242.78978) (xy 371.640485 -242.742248) (xy 371.663175 -242.697716) (xy 371.692551 -242.657283)
			(xy 371.727891 -242.621943) (xy 371.768324 -242.592567) (xy 371.812856 -242.569877) (xy 371.860388 -242.554433)
			(xy 371.909751 -242.546614) (xy 371.959729 -242.546614) (xy 372.009092 -242.554433) (xy 372.056624 -242.569877)
			(xy 372.101156 -242.592567) (xy 372.141589 -242.621943) (xy 372.176929 -242.657283) (xy 372.206305 -242.697716)
			(xy 372.228995 -242.742248) (xy 372.244439 -242.78978) (xy 372.252258 -242.839143) (xy 372.252748 -242.864132)
			(xy 372.558559 -242.864132) (xy 372.562654 -242.813404) (xy 372.574833 -242.76399) (xy 372.594781 -242.71717)
			(xy 372.621982 -242.674156) (xy 372.65573 -242.636062) (xy 372.695152 -242.603875) (xy 372.739226 -242.578429)
			(xy 372.786812 -242.560382) (xy 372.836676 -242.550202) (xy 372.887528 -242.548153) (xy 372.938049 -242.554287)
			(xy 372.986933 -242.568447) (xy 373.032912 -242.590264) (xy 373.074796 -242.619174) (xy 373.1115 -242.654429)
			(xy 373.142073 -242.695115) (xy 373.165724 -242.740178) (xy 373.18184 -242.788452) (xy 373.190004 -242.838686)
			(xy 373.190516 -242.864132) (xy 373.498613 -242.864132) (xy 373.502708 -242.813404) (xy 373.514887 -242.76399)
			(xy 373.534835 -242.71717) (xy 373.562036 -242.674156) (xy 373.595784 -242.636062) (xy 373.635206 -242.603875)
			(xy 373.67928 -242.578429) (xy 373.726866 -242.560382) (xy 373.77673 -242.550202) (xy 373.827582 -242.548153)
			(xy 373.878103 -242.554287) (xy 373.926987 -242.568447) (xy 373.972966 -242.590264) (xy 374.01485 -242.619174)
			(xy 374.051554 -242.654429) (xy 374.082127 -242.695115) (xy 374.105778 -242.740178) (xy 374.121894 -242.788452)
			(xy 374.130058 -242.838686) (xy 374.13057 -242.864132) (xy 374.130058 -242.889578) (xy 374.121894 -242.939812)
			(xy 374.105778 -242.988086) (xy 374.082127 -243.033149) (xy 374.051554 -243.073835) (xy 374.01485 -243.10909)
			(xy 373.972966 -243.138) (xy 373.926987 -243.159817) (xy 373.878103 -243.173977) (xy 373.827582 -243.180111)
			(xy 373.77673 -243.178062) (xy 373.726866 -243.167882) (xy 373.67928 -243.149835) (xy 373.635206 -243.124389)
			(xy 373.595784 -243.092202) (xy 373.562036 -243.054108) (xy 373.534835 -243.011094) (xy 373.514887 -242.964274)
			(xy 373.502708 -242.91486) (xy 373.498613 -242.864132) (xy 373.190516 -242.864132) (xy 373.190004 -242.889578)
			(xy 373.18184 -242.939812) (xy 373.165724 -242.988086) (xy 373.142073 -243.033149) (xy 373.1115 -243.073835)
			(xy 373.074796 -243.10909) (xy 373.032912 -243.138) (xy 372.986933 -243.159817) (xy 372.938049 -243.173977)
			(xy 372.887528 -243.180111) (xy 372.836676 -243.178062) (xy 372.786812 -243.167882) (xy 372.739226 -243.149835)
			(xy 372.695152 -243.124389) (xy 372.65573 -243.092202) (xy 372.621982 -243.054108) (xy 372.594781 -243.011094)
			(xy 372.574833 -242.964274) (xy 372.562654 -242.91486) (xy 372.558559 -242.864132) (xy 372.252748 -242.864132)
			(xy 372.252258 -242.889121) (xy 372.244439 -242.938484) (xy 372.228995 -242.986016) (xy 372.206305 -243.030548)
			(xy 372.176929 -243.070981) (xy 372.141589 -243.106321) (xy 372.101156 -243.135697) (xy 372.056624 -243.158387)
			(xy 372.009092 -243.173831) (xy 371.959729 -243.18165) (xy 371.909751 -243.18165) (xy 371.860388 -243.173831)
			(xy 371.812856 -243.158387) (xy 371.768324 -243.135697) (xy 371.727891 -243.106321) (xy 371.692551 -243.070981)
			(xy 371.663175 -243.030548) (xy 371.640485 -242.986016) (xy 371.625041 -242.938484) (xy 371.617222 -242.889121)
			(xy 371.309905 -242.889121) (xy 371.309896 -242.889578) (xy 371.301732 -242.939812) (xy 371.285616 -242.988086)
			(xy 371.261965 -243.033149) (xy 371.231392 -243.073835) (xy 371.194688 -243.10909) (xy 371.152804 -243.138)
			(xy 371.106825 -243.159817) (xy 371.057941 -243.173977) (xy 371.00742 -243.180111) (xy 370.956568 -243.178062)
			(xy 370.906704 -243.167882) (xy 370.859118 -243.149835) (xy 370.815044 -243.124389) (xy 370.775622 -243.092202)
			(xy 370.741874 -243.054108) (xy 370.714673 -243.011094) (xy 370.694725 -242.964274) (xy 370.682546 -242.91486)
			(xy 370.678451 -242.864132) (xy 370.370608 -242.864132) (xy 370.370096 -242.889578) (xy 370.361932 -242.939812)
			(xy 370.345816 -242.988086) (xy 370.322165 -243.033149) (xy 370.291592 -243.073835) (xy 370.254888 -243.10909)
			(xy 370.213004 -243.138) (xy 370.167025 -243.159817) (xy 370.118141 -243.173977) (xy 370.06762 -243.180111)
			(xy 370.016768 -243.178062) (xy 369.966904 -243.167882) (xy 369.919318 -243.149835) (xy 369.875244 -243.124389)
			(xy 369.835822 -243.092202) (xy 369.802074 -243.054108) (xy 369.774873 -243.011094) (xy 369.754925 -242.964274)
			(xy 369.742746 -242.91486) (xy 369.738651 -242.864132) (xy 369.43284 -242.864132) (xy 369.43235 -242.889121)
			(xy 369.424531 -242.938484) (xy 369.409087 -242.986016) (xy 369.386397 -243.030548) (xy 369.357021 -243.070981)
			(xy 369.321681 -243.106321) (xy 369.281248 -243.135697) (xy 369.236716 -243.158387) (xy 369.189184 -243.173831)
			(xy 369.139821 -243.18165) (xy 369.089843 -243.18165) (xy 369.04048 -243.173831) (xy 368.992948 -243.158387)
			(xy 368.948416 -243.135697) (xy 368.907983 -243.106321) (xy 368.872643 -243.070981) (xy 368.843267 -243.030548)
			(xy 368.820577 -242.986016) (xy 368.805133 -242.938484) (xy 368.797314 -242.889121) (xy 368.489997 -242.889121)
			(xy 368.489988 -242.889578) (xy 368.481824 -242.939812) (xy 368.465708 -242.988086) (xy 368.442057 -243.033149)
			(xy 368.411484 -243.073835) (xy 368.37478 -243.10909) (xy 368.332896 -243.138) (xy 368.286917 -243.159817)
			(xy 368.238033 -243.173977) (xy 368.187512 -243.180111) (xy 368.13666 -243.178062) (xy 368.086796 -243.167882)
			(xy 368.03921 -243.149835) (xy 367.995136 -243.124389) (xy 367.955714 -243.092202) (xy 367.921966 -243.054108)
			(xy 367.894765 -243.011094) (xy 367.874817 -242.964274) (xy 367.862638 -242.91486) (xy 367.858543 -242.864132)
			(xy 367.550446 -242.864132) (xy 367.549934 -242.889578) (xy 367.54177 -242.939812) (xy 367.525654 -242.988086)
			(xy 367.502003 -243.033149) (xy 367.47143 -243.073835) (xy 367.434726 -243.10909) (xy 367.392842 -243.138)
			(xy 367.346863 -243.159817) (xy 367.297979 -243.173977) (xy 367.247458 -243.180111) (xy 367.196606 -243.178062)
			(xy 367.146742 -243.167882) (xy 367.099156 -243.149835) (xy 367.055082 -243.124389) (xy 367.01566 -243.092202)
			(xy 366.981912 -243.054108) (xy 366.954711 -243.011094) (xy 366.934763 -242.964274) (xy 366.922584 -242.91486)
			(xy 366.918489 -242.864132) (xy 366.612932 -242.864132) (xy 366.612442 -242.889121) (xy 366.604623 -242.938484)
			(xy 366.589179 -242.986016) (xy 366.566489 -243.030548) (xy 366.537113 -243.070981) (xy 366.501773 -243.106321)
			(xy 366.46134 -243.135697) (xy 366.416808 -243.158387) (xy 366.369276 -243.173831) (xy 366.319913 -243.18165)
			(xy 366.269935 -243.18165) (xy 366.220572 -243.173831) (xy 366.17304 -243.158387) (xy 366.128508 -243.135697)
			(xy 366.088075 -243.106321) (xy 366.052735 -243.070981) (xy 366.023359 -243.030548) (xy 366.000669 -242.986016)
			(xy 365.985225 -242.938484) (xy 365.977406 -242.889121) (xy 365.670089 -242.889121) (xy 365.67008 -242.889578)
			(xy 365.661916 -242.939812) (xy 365.6458 -242.988086) (xy 365.622149 -243.033149) (xy 365.591576 -243.073835)
			(xy 365.554872 -243.10909) (xy 365.512988 -243.138) (xy 365.467009 -243.159817) (xy 365.418125 -243.173977)
			(xy 365.367604 -243.180111) (xy 365.316752 -243.178062) (xy 365.266888 -243.167882) (xy 365.219302 -243.149835)
			(xy 365.175228 -243.124389) (xy 365.135806 -243.092202) (xy 365.102058 -243.054108) (xy 365.074857 -243.011094)
			(xy 365.054909 -242.964274) (xy 365.04273 -242.91486) (xy 365.038635 -242.864132) (xy 364.730538 -242.864132)
			(xy 364.730026 -242.889578) (xy 364.721862 -242.939812) (xy 364.705746 -242.988086) (xy 364.682095 -243.033149)
			(xy 364.651522 -243.073835) (xy 364.614818 -243.10909) (xy 364.572934 -243.138) (xy 364.526955 -243.159817)
			(xy 364.478071 -243.173977) (xy 364.42755 -243.180111) (xy 364.376698 -243.178062) (xy 364.326834 -243.167882)
			(xy 364.279248 -243.149835) (xy 364.235174 -243.124389) (xy 364.195752 -243.092202) (xy 364.162004 -243.054108)
			(xy 364.134803 -243.011094) (xy 364.114855 -242.964274) (xy 364.102676 -242.91486) (xy 364.098581 -242.864132)
			(xy 363.79277 -242.864132) (xy 363.79228 -242.889121) (xy 363.784461 -242.938484) (xy 363.769017 -242.986016)
			(xy 363.746327 -243.030548) (xy 363.716951 -243.070981) (xy 363.681611 -243.106321) (xy 363.641178 -243.135697)
			(xy 363.596646 -243.158387) (xy 363.549114 -243.173831) (xy 363.499751 -243.18165) (xy 363.449773 -243.18165)
			(xy 363.40041 -243.173831) (xy 363.352878 -243.158387) (xy 363.308346 -243.135697) (xy 363.267913 -243.106321)
			(xy 363.232573 -243.070981) (xy 363.203197 -243.030548) (xy 363.180507 -242.986016) (xy 363.165063 -242.938484)
			(xy 363.157244 -242.889121) (xy 356.278706 -242.889121) (xy 356.270887 -242.938484) (xy 356.255443 -242.986016)
			(xy 356.232753 -243.030548) (xy 356.203377 -243.070981) (xy 356.168037 -243.106321) (xy 356.127604 -243.135697)
			(xy 356.083072 -243.158387) (xy 356.03554 -243.173831) (xy 355.986177 -243.18165) (xy 355.936199 -243.18165)
			(xy 355.886836 -243.173831) (xy 355.839304 -243.158387) (xy 355.794772 -243.135697) (xy 355.754339 -243.106321)
			(xy 355.718999 -243.070981) (xy 355.689623 -243.030548) (xy 355.666933 -242.986016) (xy 355.651489 -242.938484)
			(xy 355.64367 -242.889121) (xy 355.336353 -242.889121) (xy 355.336344 -242.889578) (xy 355.32818 -242.939812)
			(xy 355.312064 -242.988086) (xy 355.288413 -243.033149) (xy 355.25784 -243.073835) (xy 355.221136 -243.10909)
			(xy 355.179252 -243.138) (xy 355.133273 -243.159817) (xy 355.084389 -243.173977) (xy 355.033868 -243.180111)
			(xy 354.983016 -243.178062) (xy 354.933152 -243.167882) (xy 354.885566 -243.149835) (xy 354.841492 -243.124389)
			(xy 354.80207 -243.092202) (xy 354.768322 -243.054108) (xy 354.741121 -243.011094) (xy 354.721173 -242.964274)
			(xy 354.708994 -242.91486) (xy 354.704899 -242.864132) (xy 354.396802 -242.864132) (xy 354.39629 -242.889578)
			(xy 354.388126 -242.939812) (xy 354.37201 -242.988086) (xy 354.348359 -243.033149) (xy 354.317786 -243.073835)
			(xy 354.281082 -243.10909) (xy 354.239198 -243.138) (xy 354.193219 -243.159817) (xy 354.144335 -243.173977)
			(xy 354.093814 -243.180111) (xy 354.042962 -243.178062) (xy 353.993098 -243.167882) (xy 353.945512 -243.149835)
			(xy 353.901438 -243.124389) (xy 353.862016 -243.092202) (xy 353.828268 -243.054108) (xy 353.801067 -243.011094)
			(xy 353.781119 -242.964274) (xy 353.76894 -242.91486) (xy 353.764845 -242.864132) (xy 353.459034 -242.864132)
			(xy 353.458544 -242.889121) (xy 353.450725 -242.938484) (xy 353.435281 -242.986016) (xy 353.412591 -243.030548)
			(xy 353.383215 -243.070981) (xy 353.347875 -243.106321) (xy 353.307442 -243.135697) (xy 353.26291 -243.158387)
			(xy 353.215378 -243.173831) (xy 353.166015 -243.18165) (xy 353.116037 -243.18165) (xy 353.066674 -243.173831)
			(xy 353.019142 -243.158387) (xy 352.97461 -243.135697) (xy 352.934177 -243.106321) (xy 352.898837 -243.070981)
			(xy 352.869461 -243.030548) (xy 352.846771 -242.986016) (xy 352.831327 -242.938484) (xy 352.823508 -242.889121)
			(xy 352.516445 -242.889121) (xy 352.516436 -242.889578) (xy 352.508272 -242.939812) (xy 352.492156 -242.988086)
			(xy 352.468505 -243.033149) (xy 352.437932 -243.073835) (xy 352.401228 -243.10909) (xy 352.359344 -243.138)
			(xy 352.313365 -243.159817) (xy 352.264481 -243.173977) (xy 352.21396 -243.180111) (xy 352.163108 -243.178062)
			(xy 352.113244 -243.167882) (xy 352.065658 -243.149835) (xy 352.021584 -243.124389) (xy 351.982162 -243.092202)
			(xy 351.948414 -243.054108) (xy 351.921213 -243.011094) (xy 351.901265 -242.964274) (xy 351.889086 -242.91486)
			(xy 351.884991 -242.864132) (xy 351.576894 -242.864132) (xy 351.576382 -242.889578) (xy 351.568218 -242.939812)
			(xy 351.552102 -242.988086) (xy 351.528451 -243.033149) (xy 351.497878 -243.073835) (xy 351.461174 -243.10909)
			(xy 351.41929 -243.138) (xy 351.373311 -243.159817) (xy 351.324427 -243.173977) (xy 351.273906 -243.180111)
			(xy 351.223054 -243.178062) (xy 351.17319 -243.167882) (xy 351.125604 -243.149835) (xy 351.08153 -243.124389)
			(xy 351.042108 -243.092202) (xy 351.00836 -243.054108) (xy 350.981159 -243.011094) (xy 350.961211 -242.964274)
			(xy 350.949032 -242.91486) (xy 350.944937 -242.864132) (xy 350.639126 -242.864132) (xy 350.638636 -242.889121)
			(xy 350.630817 -242.938484) (xy 350.615373 -242.986016) (xy 350.592683 -243.030548) (xy 350.563307 -243.070981)
			(xy 350.527967 -243.106321) (xy 350.487534 -243.135697) (xy 350.443002 -243.158387) (xy 350.39547 -243.173831)
			(xy 350.346107 -243.18165) (xy 350.296129 -243.18165) (xy 350.246766 -243.173831) (xy 350.199234 -243.158387)
			(xy 350.154702 -243.135697) (xy 350.114269 -243.106321) (xy 350.078929 -243.070981) (xy 350.049553 -243.030548)
			(xy 350.026863 -242.986016) (xy 350.011419 -242.938484) (xy 350.0036 -242.889121) (xy 349.696283 -242.889121)
			(xy 349.696274 -242.889578) (xy 349.68811 -242.939812) (xy 349.671994 -242.988086) (xy 349.648343 -243.033149)
			(xy 349.61777 -243.073835) (xy 349.581066 -243.10909) (xy 349.539182 -243.138) (xy 349.493203 -243.159817)
			(xy 349.444319 -243.173977) (xy 349.393798 -243.180111) (xy 349.342946 -243.178062) (xy 349.293082 -243.167882)
			(xy 349.245496 -243.149835) (xy 349.201422 -243.124389) (xy 349.162 -243.092202) (xy 349.128252 -243.054108)
			(xy 349.101051 -243.011094) (xy 349.081103 -242.964274) (xy 349.068924 -242.91486) (xy 349.064829 -242.864132)
			(xy 348.756732 -242.864132) (xy 348.75622 -242.889578) (xy 348.748056 -242.939812) (xy 348.73194 -242.988086)
			(xy 348.708289 -243.033149) (xy 348.677716 -243.073835) (xy 348.641012 -243.10909) (xy 348.599128 -243.138)
			(xy 348.553149 -243.159817) (xy 348.504265 -243.173977) (xy 348.453744 -243.180111) (xy 348.402892 -243.178062)
			(xy 348.353028 -243.167882) (xy 348.305442 -243.149835) (xy 348.261368 -243.124389) (xy 348.221946 -243.092202)
			(xy 348.188198 -243.054108) (xy 348.160997 -243.011094) (xy 348.141049 -242.964274) (xy 348.12887 -242.91486)
			(xy 348.124775 -242.864132) (xy 347.819218 -242.864132) (xy 347.818728 -242.889121) (xy 347.810909 -242.938484)
			(xy 347.795465 -242.986016) (xy 347.772775 -243.030548) (xy 347.743399 -243.070981) (xy 347.708059 -243.106321)
			(xy 347.667626 -243.135697) (xy 347.623094 -243.158387) (xy 347.575562 -243.173831) (xy 347.526199 -243.18165)
			(xy 347.476221 -243.18165) (xy 347.426858 -243.173831) (xy 347.379326 -243.158387) (xy 347.334794 -243.135697)
			(xy 347.294361 -243.106321) (xy 347.259021 -243.070981) (xy 347.229645 -243.030548) (xy 347.206955 -242.986016)
			(xy 347.191511 -242.938484) (xy 347.183692 -242.889121) (xy 346.876375 -242.889121) (xy 346.876366 -242.889578)
			(xy 346.868202 -242.939812) (xy 346.852086 -242.988086) (xy 346.828435 -243.033149) (xy 346.797862 -243.073835)
			(xy 346.761158 -243.10909) (xy 346.719274 -243.138) (xy 346.673295 -243.159817) (xy 346.624411 -243.173977)
			(xy 346.57389 -243.180111) (xy 346.523038 -243.178062) (xy 346.473174 -243.167882) (xy 346.425588 -243.149835)
			(xy 346.381514 -243.124389) (xy 346.342092 -243.092202) (xy 346.308344 -243.054108) (xy 346.281143 -243.011094)
			(xy 346.261195 -242.964274) (xy 346.249016 -242.91486) (xy 346.244921 -242.864132) (xy 345.936824 -242.864132)
			(xy 345.936312 -242.889578) (xy 345.928148 -242.939812) (xy 345.912032 -242.988086) (xy 345.888381 -243.033149)
			(xy 345.857808 -243.073835) (xy 345.821104 -243.10909) (xy 345.77922 -243.138) (xy 345.733241 -243.159817)
			(xy 345.684357 -243.173977) (xy 345.633836 -243.180111) (xy 345.582984 -243.178062) (xy 345.53312 -243.167882)
			(xy 345.485534 -243.149835) (xy 345.44146 -243.124389) (xy 345.402038 -243.092202) (xy 345.36829 -243.054108)
			(xy 345.341089 -243.011094) (xy 345.321141 -242.964274) (xy 345.308962 -242.91486) (xy 345.304867 -242.864132)
			(xy 344.999056 -242.864132) (xy 344.999056 -242.864386) (xy 344.997786 -242.893596) (xy 344.997532 -242.898168)
			(xy 344.997532 -243.25961) (xy 344.998037 -243.269365) (xy 345.005469 -243.28741) (xy 345.01201 -243.294662)
			(xy 345.072462 -243.347748) (xy 345.079276 -243.35277) (xy 345.095245 -243.35835) (xy 345.103704 -243.35867)
			(xy 345.110562 -243.35867) (xy 345.113356 -243.358416) (xy 345.122781 -243.357349) (xy 345.141717 -243.356207)
			(xy 345.151202 -243.35613) (xy 345.176188 -243.35662) (xy 345.225545 -243.364438) (xy 345.273071 -243.379881)
			(xy 345.317597 -243.402568) (xy 345.358025 -243.431941) (xy 345.393361 -243.467276) (xy 345.422733 -243.507705)
			(xy 345.44542 -243.552231) (xy 345.460862 -243.599757) (xy 345.46868 -243.649114) (xy 345.46868 -243.699086)
			(xy 345.468674 -243.699127) (xy 345.773484 -243.699127) (xy 345.773484 -243.649149) (xy 345.781303 -243.599786)
			(xy 345.796747 -243.552254) (xy 345.819437 -243.507722) (xy 345.848813 -243.467289) (xy 345.884153 -243.431949)
			(xy 345.924586 -243.402573) (xy 345.969118 -243.379883) (xy 346.01665 -243.364439) (xy 346.066013 -243.35662)
			(xy 346.115991 -243.35662) (xy 346.165354 -243.364439) (xy 346.212886 -243.379883) (xy 346.257418 -243.402573)
			(xy 346.297851 -243.431949) (xy 346.333191 -243.467289) (xy 346.362567 -243.507722) (xy 346.385257 -243.552254)
			(xy 346.400701 -243.599786) (xy 346.40852 -243.649149) (xy 346.40901 -243.674138) (xy 346.40852 -243.699127)
			(xy 346.713538 -243.699127) (xy 346.713538 -243.649149) (xy 346.721357 -243.599786) (xy 346.736801 -243.552254)
			(xy 346.759491 -243.507722) (xy 346.788867 -243.467289) (xy 346.824207 -243.431949) (xy 346.86464 -243.402573)
			(xy 346.909172 -243.379883) (xy 346.956704 -243.364439) (xy 347.006067 -243.35662) (xy 347.056045 -243.35662)
			(xy 347.105408 -243.364439) (xy 347.15294 -243.379883) (xy 347.197472 -243.402573) (xy 347.237905 -243.431949)
			(xy 347.273245 -243.467289) (xy 347.302621 -243.507722) (xy 347.325311 -243.552254) (xy 347.340755 -243.599786)
			(xy 347.348574 -243.649149) (xy 347.349064 -243.674138) (xy 347.348574 -243.699127) (xy 347.653592 -243.699127)
			(xy 347.653592 -243.649149) (xy 347.661411 -243.599786) (xy 347.676855 -243.552254) (xy 347.699545 -243.507722)
			(xy 347.728921 -243.467289) (xy 347.764261 -243.431949) (xy 347.804694 -243.402573) (xy 347.849226 -243.379883)
			(xy 347.896758 -243.364439) (xy 347.946121 -243.35662) (xy 347.996099 -243.35662) (xy 348.045462 -243.364439)
			(xy 348.092994 -243.379883) (xy 348.137526 -243.402573) (xy 348.177959 -243.431949) (xy 348.213299 -243.467289)
			(xy 348.242675 -243.507722) (xy 348.265365 -243.552254) (xy 348.280809 -243.599786) (xy 348.288628 -243.649149)
			(xy 348.289118 -243.674138) (xy 348.288628 -243.699127) (xy 348.593646 -243.699127) (xy 348.593646 -243.649149)
			(xy 348.601465 -243.599786) (xy 348.616909 -243.552254) (xy 348.639599 -243.507722) (xy 348.668975 -243.467289)
			(xy 348.704315 -243.431949) (xy 348.744748 -243.402573) (xy 348.78928 -243.379883) (xy 348.836812 -243.364439)
			(xy 348.886175 -243.35662) (xy 348.936153 -243.35662) (xy 348.985516 -243.364439) (xy 349.033048 -243.379883)
			(xy 349.07758 -243.402573) (xy 349.118013 -243.431949) (xy 349.153353 -243.467289) (xy 349.182729 -243.507722)
			(xy 349.205419 -243.552254) (xy 349.220863 -243.599786) (xy 349.228682 -243.649149) (xy 349.229172 -243.674138)
			(xy 349.228682 -243.699127) (xy 349.5337 -243.699127) (xy 349.5337 -243.649149) (xy 349.541519 -243.599786)
			(xy 349.556963 -243.552254) (xy 349.579653 -243.507722) (xy 349.609029 -243.467289) (xy 349.644369 -243.431949)
			(xy 349.684802 -243.402573) (xy 349.729334 -243.379883) (xy 349.776866 -243.364439) (xy 349.826229 -243.35662)
			(xy 349.876207 -243.35662) (xy 349.92557 -243.364439) (xy 349.973102 -243.379883) (xy 350.017634 -243.402573)
			(xy 350.058067 -243.431949) (xy 350.093407 -243.467289) (xy 350.122783 -243.507722) (xy 350.145473 -243.552254)
			(xy 350.160917 -243.599786) (xy 350.168736 -243.649149) (xy 350.169226 -243.674138) (xy 350.168736 -243.699127)
			(xy 350.4735 -243.699127) (xy 350.4735 -243.649149) (xy 350.481319 -243.599786) (xy 350.496763 -243.552254)
			(xy 350.519453 -243.507722) (xy 350.548829 -243.467289) (xy 350.584169 -243.431949) (xy 350.624602 -243.402573)
			(xy 350.669134 -243.379883) (xy 350.716666 -243.364439) (xy 350.766029 -243.35662) (xy 350.816007 -243.35662)
			(xy 350.86537 -243.364439) (xy 350.912902 -243.379883) (xy 350.957434 -243.402573) (xy 350.997867 -243.431949)
			(xy 351.033207 -243.467289) (xy 351.062583 -243.507722) (xy 351.085273 -243.552254) (xy 351.100717 -243.599786)
			(xy 351.108536 -243.649149) (xy 351.109026 -243.674138) (xy 351.108536 -243.699127) (xy 351.413554 -243.699127)
			(xy 351.413554 -243.649149) (xy 351.421373 -243.599786) (xy 351.436817 -243.552254) (xy 351.459507 -243.507722)
			(xy 351.488883 -243.467289) (xy 351.524223 -243.431949) (xy 351.564656 -243.402573) (xy 351.609188 -243.379883)
			(xy 351.65672 -243.364439) (xy 351.706083 -243.35662) (xy 351.756061 -243.35662) (xy 351.805424 -243.364439)
			(xy 351.852956 -243.379883) (xy 351.897488 -243.402573) (xy 351.937921 -243.431949) (xy 351.973261 -243.467289)
			(xy 352.002637 -243.507722) (xy 352.025327 -243.552254) (xy 352.040771 -243.599786) (xy 352.04859 -243.649149)
			(xy 352.04908 -243.674138) (xy 352.04859 -243.699127) (xy 352.353608 -243.699127) (xy 352.353608 -243.649149)
			(xy 352.361427 -243.599786) (xy 352.376871 -243.552254) (xy 352.399561 -243.507722) (xy 352.428937 -243.467289)
			(xy 352.464277 -243.431949) (xy 352.50471 -243.402573) (xy 352.549242 -243.379883) (xy 352.596774 -243.364439)
			(xy 352.646137 -243.35662) (xy 352.696115 -243.35662) (xy 352.745478 -243.364439) (xy 352.79301 -243.379883)
			(xy 352.837542 -243.402573) (xy 352.877975 -243.431949) (xy 352.913315 -243.467289) (xy 352.942691 -243.507722)
			(xy 352.965381 -243.552254) (xy 352.980825 -243.599786) (xy 352.988644 -243.649149) (xy 352.989134 -243.674138)
			(xy 352.988644 -243.699127) (xy 353.293662 -243.699127) (xy 353.293662 -243.649149) (xy 353.301481 -243.599786)
			(xy 353.316925 -243.552254) (xy 353.339615 -243.507722) (xy 353.368991 -243.467289) (xy 353.404331 -243.431949)
			(xy 353.444764 -243.402573) (xy 353.489296 -243.379883) (xy 353.536828 -243.364439) (xy 353.586191 -243.35662)
			(xy 353.636169 -243.35662) (xy 353.685532 -243.364439) (xy 353.733064 -243.379883) (xy 353.777596 -243.402573)
			(xy 353.818029 -243.431949) (xy 353.853369 -243.467289) (xy 353.882745 -243.507722) (xy 353.905435 -243.552254)
			(xy 353.920879 -243.599786) (xy 353.928698 -243.649149) (xy 353.929188 -243.674138) (xy 353.928698 -243.699127)
			(xy 354.233716 -243.699127) (xy 354.233716 -243.649149) (xy 354.241535 -243.599786) (xy 354.256979 -243.552254)
			(xy 354.279669 -243.507722) (xy 354.309045 -243.467289) (xy 354.344385 -243.431949) (xy 354.384818 -243.402573)
			(xy 354.42935 -243.379883) (xy 354.476882 -243.364439) (xy 354.526245 -243.35662) (xy 354.576223 -243.35662)
			(xy 354.625586 -243.364439) (xy 354.673118 -243.379883) (xy 354.71765 -243.402573) (xy 354.758083 -243.431949)
			(xy 354.793423 -243.467289) (xy 354.822799 -243.507722) (xy 354.845489 -243.552254) (xy 354.860933 -243.599786)
			(xy 354.868752 -243.649149) (xy 354.869242 -243.674138) (xy 354.868752 -243.699127) (xy 355.173516 -243.699127)
			(xy 355.173516 -243.649149) (xy 355.181335 -243.599786) (xy 355.196779 -243.552254) (xy 355.219469 -243.507722)
			(xy 355.248845 -243.467289) (xy 355.284185 -243.431949) (xy 355.324618 -243.402573) (xy 355.36915 -243.379883)
			(xy 355.416682 -243.364439) (xy 355.466045 -243.35662) (xy 355.516023 -243.35662) (xy 355.565386 -243.364439)
			(xy 355.612918 -243.379883) (xy 355.65745 -243.402573) (xy 355.697883 -243.431949) (xy 355.733223 -243.467289)
			(xy 355.762599 -243.507722) (xy 355.785289 -243.552254) (xy 355.800733 -243.599786) (xy 355.808552 -243.649149)
			(xy 355.809042 -243.674138) (xy 356.114853 -243.674138) (xy 356.118948 -243.62341) (xy 356.131127 -243.573996)
			(xy 356.151075 -243.527176) (xy 356.178276 -243.484162) (xy 356.212024 -243.446068) (xy 356.251446 -243.413881)
			(xy 356.29552 -243.388435) (xy 356.343106 -243.370388) (xy 356.39297 -243.360208) (xy 356.443822 -243.358159)
			(xy 356.494343 -243.364293) (xy 356.543227 -243.378453) (xy 356.589206 -243.40027) (xy 356.63109 -243.42918)
			(xy 356.667794 -243.464435) (xy 356.698367 -243.505121) (xy 356.722018 -243.550184) (xy 356.738134 -243.598458)
			(xy 356.746298 -243.648692) (xy 356.74681 -243.674138) (xy 357.054907 -243.674138) (xy 357.059002 -243.62341)
			(xy 357.071181 -243.573996) (xy 357.091129 -243.527176) (xy 357.11833 -243.484162) (xy 357.152078 -243.446068)
			(xy 357.1915 -243.413881) (xy 357.235574 -243.388435) (xy 357.28316 -243.370388) (xy 357.333024 -243.360208)
			(xy 357.383876 -243.358159) (xy 357.434397 -243.364293) (xy 357.483281 -243.378453) (xy 357.52926 -243.40027)
			(xy 357.571144 -243.42918) (xy 357.607848 -243.464435) (xy 357.638421 -243.505121) (xy 357.662072 -243.550184)
			(xy 357.678188 -243.598458) (xy 357.686352 -243.648692) (xy 357.686864 -243.674138) (xy 357.686361 -243.699127)
			(xy 357.993678 -243.699127) (xy 357.993678 -243.649149) (xy 358.001497 -243.599786) (xy 358.016941 -243.552254)
			(xy 358.039631 -243.507722) (xy 358.069007 -243.467289) (xy 358.104347 -243.431949) (xy 358.14478 -243.402573)
			(xy 358.189312 -243.379883) (xy 358.236844 -243.364439) (xy 358.286207 -243.35662) (xy 358.336185 -243.35662)
			(xy 358.385548 -243.364439) (xy 358.43308 -243.379883) (xy 358.477612 -243.402573) (xy 358.518045 -243.431949)
			(xy 358.553385 -243.467289) (xy 358.582761 -243.507722) (xy 358.605451 -243.552254) (xy 358.620895 -243.599786)
			(xy 358.628714 -243.649149) (xy 358.629204 -243.674138) (xy 358.628714 -243.699127) (xy 360.807236 -243.699127)
			(xy 360.807236 -243.649149) (xy 360.815055 -243.599786) (xy 360.830499 -243.552254) (xy 360.853189 -243.507722)
			(xy 360.882565 -243.467289) (xy 360.917905 -243.431949) (xy 360.958338 -243.402573) (xy 361.00287 -243.379883)
			(xy 361.050402 -243.364439) (xy 361.099765 -243.35662) (xy 361.149743 -243.35662) (xy 361.199106 -243.364439)
			(xy 361.246638 -243.379883) (xy 361.29117 -243.402573) (xy 361.331603 -243.431949) (xy 361.366943 -243.467289)
			(xy 361.396319 -243.507722) (xy 361.419009 -243.552254) (xy 361.434453 -243.599786) (xy 361.442272 -243.649149)
			(xy 361.442762 -243.674138) (xy 361.748573 -243.674138) (xy 361.752668 -243.62341) (xy 361.764847 -243.573996)
			(xy 361.784795 -243.527176) (xy 361.811996 -243.484162) (xy 361.845744 -243.446068) (xy 361.885166 -243.413881)
			(xy 361.92924 -243.388435) (xy 361.976826 -243.370388) (xy 362.02669 -243.360208) (xy 362.077542 -243.358159)
			(xy 362.128063 -243.364293) (xy 362.176947 -243.378453) (xy 362.222926 -243.40027) (xy 362.26481 -243.42918)
			(xy 362.301514 -243.464435) (xy 362.332087 -243.505121) (xy 362.355738 -243.550184) (xy 362.371854 -243.598458)
			(xy 362.380018 -243.648692) (xy 362.38053 -243.674138) (xy 362.688627 -243.674138) (xy 362.692722 -243.62341)
			(xy 362.704901 -243.573996) (xy 362.724849 -243.527176) (xy 362.75205 -243.484162) (xy 362.785798 -243.446068)
			(xy 362.82522 -243.413881) (xy 362.869294 -243.388435) (xy 362.91688 -243.370388) (xy 362.966744 -243.360208)
			(xy 363.017596 -243.358159) (xy 363.068117 -243.364293) (xy 363.117001 -243.378453) (xy 363.16298 -243.40027)
			(xy 363.204864 -243.42918) (xy 363.241568 -243.464435) (xy 363.272141 -243.505121) (xy 363.295792 -243.550184)
			(xy 363.311908 -243.598458) (xy 363.320072 -243.648692) (xy 363.320584 -243.674138) (xy 363.320081 -243.699127)
			(xy 363.627398 -243.699127) (xy 363.627398 -243.649149) (xy 363.635217 -243.599786) (xy 363.650661 -243.552254)
			(xy 363.673351 -243.507722) (xy 363.702727 -243.467289) (xy 363.738067 -243.431949) (xy 363.7785 -243.402573)
			(xy 363.823032 -243.379883) (xy 363.870564 -243.364439) (xy 363.919927 -243.35662) (xy 363.969905 -243.35662)
			(xy 364.019268 -243.364439) (xy 364.0668 -243.379883) (xy 364.111332 -243.402573) (xy 364.151765 -243.431949)
			(xy 364.187105 -243.467289) (xy 364.216481 -243.507722) (xy 364.239171 -243.552254) (xy 364.254615 -243.599786)
			(xy 364.262434 -243.649149) (xy 364.262924 -243.674138) (xy 364.262434 -243.699127) (xy 364.567198 -243.699127)
			(xy 364.567198 -243.649149) (xy 364.575017 -243.599786) (xy 364.590461 -243.552254) (xy 364.613151 -243.507722)
			(xy 364.642527 -243.467289) (xy 364.677867 -243.431949) (xy 364.7183 -243.402573) (xy 364.762832 -243.379883)
			(xy 364.810364 -243.364439) (xy 364.859727 -243.35662) (xy 364.909705 -243.35662) (xy 364.959068 -243.364439)
			(xy 365.0066 -243.379883) (xy 365.051132 -243.402573) (xy 365.091565 -243.431949) (xy 365.126905 -243.467289)
			(xy 365.156281 -243.507722) (xy 365.178971 -243.552254) (xy 365.194415 -243.599786) (xy 365.202234 -243.649149)
			(xy 365.202724 -243.674138) (xy 365.202234 -243.699127) (xy 365.507252 -243.699127) (xy 365.507252 -243.649149)
			(xy 365.515071 -243.599786) (xy 365.530515 -243.552254) (xy 365.553205 -243.507722) (xy 365.582581 -243.467289)
			(xy 365.617921 -243.431949) (xy 365.658354 -243.402573) (xy 365.702886 -243.379883) (xy 365.750418 -243.364439)
			(xy 365.799781 -243.35662) (xy 365.849759 -243.35662) (xy 365.899122 -243.364439) (xy 365.946654 -243.379883)
			(xy 365.991186 -243.402573) (xy 366.031619 -243.431949) (xy 366.066959 -243.467289) (xy 366.096335 -243.507722)
			(xy 366.119025 -243.552254) (xy 366.134469 -243.599786) (xy 366.142288 -243.649149) (xy 366.142778 -243.674138)
			(xy 366.142288 -243.699127) (xy 366.447306 -243.699127) (xy 366.447306 -243.649149) (xy 366.455125 -243.599786)
			(xy 366.470569 -243.552254) (xy 366.493259 -243.507722) (xy 366.522635 -243.467289) (xy 366.557975 -243.431949)
			(xy 366.598408 -243.402573) (xy 366.64294 -243.379883) (xy 366.690472 -243.364439) (xy 366.739835 -243.35662)
			(xy 366.789813 -243.35662) (xy 366.839176 -243.364439) (xy 366.886708 -243.379883) (xy 366.93124 -243.402573)
			(xy 366.971673 -243.431949) (xy 367.007013 -243.467289) (xy 367.036389 -243.507722) (xy 367.059079 -243.552254)
			(xy 367.074523 -243.599786) (xy 367.082342 -243.649149) (xy 367.082832 -243.674138) (xy 367.082342 -243.699127)
			(xy 367.38736 -243.699127) (xy 367.38736 -243.649149) (xy 367.395179 -243.599786) (xy 367.410623 -243.552254)
			(xy 367.433313 -243.507722) (xy 367.462689 -243.467289) (xy 367.498029 -243.431949) (xy 367.538462 -243.402573)
			(xy 367.582994 -243.379883) (xy 367.630526 -243.364439) (xy 367.679889 -243.35662) (xy 367.729867 -243.35662)
			(xy 367.77923 -243.364439) (xy 367.826762 -243.379883) (xy 367.871294 -243.402573) (xy 367.911727 -243.431949)
			(xy 367.947067 -243.467289) (xy 367.976443 -243.507722) (xy 367.999133 -243.552254) (xy 368.014577 -243.599786)
			(xy 368.022396 -243.649149) (xy 368.022886 -243.674138) (xy 368.022396 -243.699127) (xy 368.32716 -243.699127)
			(xy 368.32716 -243.649149) (xy 368.334979 -243.599786) (xy 368.350423 -243.552254) (xy 368.373113 -243.507722)
			(xy 368.402489 -243.467289) (xy 368.437829 -243.431949) (xy 368.478262 -243.402573) (xy 368.522794 -243.379883)
			(xy 368.570326 -243.364439) (xy 368.619689 -243.35662) (xy 368.669667 -243.35662) (xy 368.71903 -243.364439)
			(xy 368.766562 -243.379883) (xy 368.811094 -243.402573) (xy 368.851527 -243.431949) (xy 368.886867 -243.467289)
			(xy 368.916243 -243.507722) (xy 368.938933 -243.552254) (xy 368.954377 -243.599786) (xy 368.962196 -243.649149)
			(xy 368.962686 -243.674138) (xy 368.962196 -243.699127) (xy 369.267214 -243.699127) (xy 369.267214 -243.649149)
			(xy 369.275033 -243.599786) (xy 369.290477 -243.552254) (xy 369.313167 -243.507722) (xy 369.342543 -243.467289)
			(xy 369.377883 -243.431949) (xy 369.418316 -243.402573) (xy 369.462848 -243.379883) (xy 369.51038 -243.364439)
			(xy 369.559743 -243.35662) (xy 369.609721 -243.35662) (xy 369.659084 -243.364439) (xy 369.706616 -243.379883)
			(xy 369.751148 -243.402573) (xy 369.791581 -243.431949) (xy 369.826921 -243.467289) (xy 369.856297 -243.507722)
			(xy 369.878987 -243.552254) (xy 369.894431 -243.599786) (xy 369.90225 -243.649149) (xy 369.90274 -243.674138)
			(xy 369.90225 -243.699127) (xy 370.207268 -243.699127) (xy 370.207268 -243.649149) (xy 370.215087 -243.599786)
			(xy 370.230531 -243.552254) (xy 370.253221 -243.507722) (xy 370.282597 -243.467289) (xy 370.317937 -243.431949)
			(xy 370.35837 -243.402573) (xy 370.402902 -243.379883) (xy 370.450434 -243.364439) (xy 370.499797 -243.35662)
			(xy 370.549775 -243.35662) (xy 370.599138 -243.364439) (xy 370.64667 -243.379883) (xy 370.691202 -243.402573)
			(xy 370.731635 -243.431949) (xy 370.766975 -243.467289) (xy 370.796351 -243.507722) (xy 370.819041 -243.552254)
			(xy 370.834485 -243.599786) (xy 370.842304 -243.649149) (xy 370.842794 -243.674138) (xy 370.842304 -243.699127)
			(xy 371.147322 -243.699127) (xy 371.147322 -243.649149) (xy 371.155141 -243.599786) (xy 371.170585 -243.552254)
			(xy 371.193275 -243.507722) (xy 371.222651 -243.467289) (xy 371.257991 -243.431949) (xy 371.298424 -243.402573)
			(xy 371.342956 -243.379883) (xy 371.390488 -243.364439) (xy 371.439851 -243.35662) (xy 371.489829 -243.35662)
			(xy 371.539192 -243.364439) (xy 371.586724 -243.379883) (xy 371.631256 -243.402573) (xy 371.671689 -243.431949)
			(xy 371.707029 -243.467289) (xy 371.736405 -243.507722) (xy 371.759095 -243.552254) (xy 371.774539 -243.599786)
			(xy 371.782358 -243.649149) (xy 371.782848 -243.674138) (xy 371.782358 -243.699127) (xy 372.087376 -243.699127)
			(xy 372.087376 -243.649149) (xy 372.095195 -243.599786) (xy 372.110639 -243.552254) (xy 372.133329 -243.507722)
			(xy 372.162705 -243.467289) (xy 372.198045 -243.431949) (xy 372.238478 -243.402573) (xy 372.28301 -243.379883)
			(xy 372.330542 -243.364439) (xy 372.379905 -243.35662) (xy 372.429883 -243.35662) (xy 372.479246 -243.364439)
			(xy 372.526778 -243.379883) (xy 372.57131 -243.402573) (xy 372.611743 -243.431949) (xy 372.647083 -243.467289)
			(xy 372.676459 -243.507722) (xy 372.699149 -243.552254) (xy 372.714593 -243.599786) (xy 372.722412 -243.649149)
			(xy 372.722902 -243.674138) (xy 372.722412 -243.699127) (xy 373.027176 -243.699127) (xy 373.027176 -243.649149)
			(xy 373.034995 -243.599786) (xy 373.050439 -243.552254) (xy 373.073129 -243.507722) (xy 373.102505 -243.467289)
			(xy 373.137845 -243.431949) (xy 373.178278 -243.402573) (xy 373.22281 -243.379883) (xy 373.270342 -243.364439)
			(xy 373.319705 -243.35662) (xy 373.369683 -243.35662) (xy 373.419046 -243.364439) (xy 373.466578 -243.379883)
			(xy 373.51111 -243.402573) (xy 373.551543 -243.431949) (xy 373.586883 -243.467289) (xy 373.616259 -243.507722)
			(xy 373.638949 -243.552254) (xy 373.654393 -243.599786) (xy 373.662212 -243.649149) (xy 373.662702 -243.674138)
			(xy 373.662212 -243.699127) (xy 373.654393 -243.74849) (xy 373.638949 -243.796022) (xy 373.616259 -243.840554)
			(xy 373.586883 -243.880987) (xy 373.551543 -243.916327) (xy 373.51111 -243.945703) (xy 373.466578 -243.968393)
			(xy 373.419046 -243.983837) (xy 373.369683 -243.991656) (xy 373.319705 -243.991656) (xy 373.270342 -243.983837)
			(xy 373.22281 -243.968393) (xy 373.178278 -243.945703) (xy 373.137845 -243.916327) (xy 373.102505 -243.880987)
			(xy 373.073129 -243.840554) (xy 373.050439 -243.796022) (xy 373.034995 -243.74849) (xy 373.027176 -243.699127)
			(xy 372.722412 -243.699127) (xy 372.714593 -243.74849) (xy 372.699149 -243.796022) (xy 372.676459 -243.840554)
			(xy 372.647083 -243.880987) (xy 372.611743 -243.916327) (xy 372.57131 -243.945703) (xy 372.526778 -243.968393)
			(xy 372.479246 -243.983837) (xy 372.429883 -243.991656) (xy 372.379905 -243.991656) (xy 372.330542 -243.983837)
			(xy 372.28301 -243.968393) (xy 372.238478 -243.945703) (xy 372.198045 -243.916327) (xy 372.162705 -243.880987)
			(xy 372.133329 -243.840554) (xy 372.110639 -243.796022) (xy 372.095195 -243.74849) (xy 372.087376 -243.699127)
			(xy 371.782358 -243.699127) (xy 371.774539 -243.74849) (xy 371.759095 -243.796022) (xy 371.736405 -243.840554)
			(xy 371.707029 -243.880987) (xy 371.671689 -243.916327) (xy 371.631256 -243.945703) (xy 371.586724 -243.968393)
			(xy 371.539192 -243.983837) (xy 371.489829 -243.991656) (xy 371.439851 -243.991656) (xy 371.390488 -243.983837)
			(xy 371.342956 -243.968393) (xy 371.298424 -243.945703) (xy 371.257991 -243.916327) (xy 371.222651 -243.880987)
			(xy 371.193275 -243.840554) (xy 371.170585 -243.796022) (xy 371.155141 -243.74849) (xy 371.147322 -243.699127)
			(xy 370.842304 -243.699127) (xy 370.834485 -243.74849) (xy 370.819041 -243.796022) (xy 370.796351 -243.840554)
			(xy 370.766975 -243.880987) (xy 370.731635 -243.916327) (xy 370.691202 -243.945703) (xy 370.64667 -243.968393)
			(xy 370.599138 -243.983837) (xy 370.549775 -243.991656) (xy 370.499797 -243.991656) (xy 370.450434 -243.983837)
			(xy 370.402902 -243.968393) (xy 370.35837 -243.945703) (xy 370.317937 -243.916327) (xy 370.282597 -243.880987)
			(xy 370.253221 -243.840554) (xy 370.230531 -243.796022) (xy 370.215087 -243.74849) (xy 370.207268 -243.699127)
			(xy 369.90225 -243.699127) (xy 369.894431 -243.74849) (xy 369.878987 -243.796022) (xy 369.856297 -243.840554)
			(xy 369.826921 -243.880987) (xy 369.791581 -243.916327) (xy 369.751148 -243.945703) (xy 369.706616 -243.968393)
			(xy 369.659084 -243.983837) (xy 369.609721 -243.991656) (xy 369.559743 -243.991656) (xy 369.51038 -243.983837)
			(xy 369.462848 -243.968393) (xy 369.418316 -243.945703) (xy 369.377883 -243.916327) (xy 369.342543 -243.880987)
			(xy 369.313167 -243.840554) (xy 369.290477 -243.796022) (xy 369.275033 -243.74849) (xy 369.267214 -243.699127)
			(xy 368.962196 -243.699127) (xy 368.954377 -243.74849) (xy 368.938933 -243.796022) (xy 368.916243 -243.840554)
			(xy 368.886867 -243.880987) (xy 368.851527 -243.916327) (xy 368.811094 -243.945703) (xy 368.766562 -243.968393)
			(xy 368.71903 -243.983837) (xy 368.669667 -243.991656) (xy 368.619689 -243.991656) (xy 368.570326 -243.983837)
			(xy 368.522794 -243.968393) (xy 368.478262 -243.945703) (xy 368.437829 -243.916327) (xy 368.402489 -243.880987)
			(xy 368.373113 -243.840554) (xy 368.350423 -243.796022) (xy 368.334979 -243.74849) (xy 368.32716 -243.699127)
			(xy 368.022396 -243.699127) (xy 368.014577 -243.74849) (xy 367.999133 -243.796022) (xy 367.976443 -243.840554)
			(xy 367.947067 -243.880987) (xy 367.911727 -243.916327) (xy 367.871294 -243.945703) (xy 367.826762 -243.968393)
			(xy 367.77923 -243.983837) (xy 367.729867 -243.991656) (xy 367.679889 -243.991656) (xy 367.630526 -243.983837)
			(xy 367.582994 -243.968393) (xy 367.538462 -243.945703) (xy 367.498029 -243.916327) (xy 367.462689 -243.880987)
			(xy 367.433313 -243.840554) (xy 367.410623 -243.796022) (xy 367.395179 -243.74849) (xy 367.38736 -243.699127)
			(xy 367.082342 -243.699127) (xy 367.074523 -243.74849) (xy 367.059079 -243.796022) (xy 367.036389 -243.840554)
			(xy 367.007013 -243.880987) (xy 366.971673 -243.916327) (xy 366.93124 -243.945703) (xy 366.886708 -243.968393)
			(xy 366.839176 -243.983837) (xy 366.789813 -243.991656) (xy 366.739835 -243.991656) (xy 366.690472 -243.983837)
			(xy 366.64294 -243.968393) (xy 366.598408 -243.945703) (xy 366.557975 -243.916327) (xy 366.522635 -243.880987)
			(xy 366.493259 -243.840554) (xy 366.470569 -243.796022) (xy 366.455125 -243.74849) (xy 366.447306 -243.699127)
			(xy 366.142288 -243.699127) (xy 366.134469 -243.74849) (xy 366.119025 -243.796022) (xy 366.096335 -243.840554)
			(xy 366.066959 -243.880987) (xy 366.031619 -243.916327) (xy 365.991186 -243.945703) (xy 365.946654 -243.968393)
			(xy 365.899122 -243.983837) (xy 365.849759 -243.991656) (xy 365.799781 -243.991656) (xy 365.750418 -243.983837)
			(xy 365.702886 -243.968393) (xy 365.658354 -243.945703) (xy 365.617921 -243.916327) (xy 365.582581 -243.880987)
			(xy 365.553205 -243.840554) (xy 365.530515 -243.796022) (xy 365.515071 -243.74849) (xy 365.507252 -243.699127)
			(xy 365.202234 -243.699127) (xy 365.194415 -243.74849) (xy 365.178971 -243.796022) (xy 365.156281 -243.840554)
			(xy 365.126905 -243.880987) (xy 365.091565 -243.916327) (xy 365.051132 -243.945703) (xy 365.0066 -243.968393)
			(xy 364.959068 -243.983837) (xy 364.909705 -243.991656) (xy 364.859727 -243.991656) (xy 364.810364 -243.983837)
			(xy 364.762832 -243.968393) (xy 364.7183 -243.945703) (xy 364.677867 -243.916327) (xy 364.642527 -243.880987)
			(xy 364.613151 -243.840554) (xy 364.590461 -243.796022) (xy 364.575017 -243.74849) (xy 364.567198 -243.699127)
			(xy 364.262434 -243.699127) (xy 364.254615 -243.74849) (xy 364.239171 -243.796022) (xy 364.216481 -243.840554)
			(xy 364.187105 -243.880987) (xy 364.151765 -243.916327) (xy 364.111332 -243.945703) (xy 364.0668 -243.968393)
			(xy 364.019268 -243.983837) (xy 363.969905 -243.991656) (xy 363.919927 -243.991656) (xy 363.870564 -243.983837)
			(xy 363.823032 -243.968393) (xy 363.7785 -243.945703) (xy 363.738067 -243.916327) (xy 363.702727 -243.880987)
			(xy 363.673351 -243.840554) (xy 363.650661 -243.796022) (xy 363.635217 -243.74849) (xy 363.627398 -243.699127)
			(xy 363.320081 -243.699127) (xy 363.320072 -243.699584) (xy 363.311908 -243.749818) (xy 363.295792 -243.798092)
			(xy 363.272141 -243.843155) (xy 363.241568 -243.883841) (xy 363.204864 -243.919096) (xy 363.16298 -243.948006)
			(xy 363.117001 -243.969823) (xy 363.068117 -243.983983) (xy 363.017596 -243.990117) (xy 362.966744 -243.988068)
			(xy 362.91688 -243.977888) (xy 362.869294 -243.959841) (xy 362.82522 -243.934395) (xy 362.785798 -243.902208)
			(xy 362.75205 -243.864114) (xy 362.724849 -243.8211) (xy 362.704901 -243.77428) (xy 362.692722 -243.724866)
			(xy 362.688627 -243.674138) (xy 362.38053 -243.674138) (xy 362.380018 -243.699584) (xy 362.371854 -243.749818)
			(xy 362.355738 -243.798092) (xy 362.332087 -243.843155) (xy 362.301514 -243.883841) (xy 362.26481 -243.919096)
			(xy 362.222926 -243.948006) (xy 362.176947 -243.969823) (xy 362.128063 -243.983983) (xy 362.077542 -243.990117)
			(xy 362.02669 -243.988068) (xy 361.976826 -243.977888) (xy 361.92924 -243.959841) (xy 361.885166 -243.934395)
			(xy 361.845744 -243.902208) (xy 361.811996 -243.864114) (xy 361.784795 -243.8211) (xy 361.764847 -243.77428)
			(xy 361.752668 -243.724866) (xy 361.748573 -243.674138) (xy 361.442762 -243.674138) (xy 361.442272 -243.699127)
			(xy 361.434453 -243.74849) (xy 361.419009 -243.796022) (xy 361.396319 -243.840554) (xy 361.366943 -243.880987)
			(xy 361.331603 -243.916327) (xy 361.29117 -243.945703) (xy 361.246638 -243.968393) (xy 361.199106 -243.983837)
			(xy 361.149743 -243.991656) (xy 361.099765 -243.991656) (xy 361.050402 -243.983837) (xy 361.00287 -243.968393)
			(xy 360.958338 -243.945703) (xy 360.917905 -243.916327) (xy 360.882565 -243.880987) (xy 360.853189 -243.840554)
			(xy 360.830499 -243.796022) (xy 360.815055 -243.74849) (xy 360.807236 -243.699127) (xy 358.628714 -243.699127)
			(xy 358.620895 -243.74849) (xy 358.605451 -243.796022) (xy 358.582761 -243.840554) (xy 358.553385 -243.880987)
			(xy 358.518045 -243.916327) (xy 358.477612 -243.945703) (xy 358.43308 -243.968393) (xy 358.385548 -243.983837)
			(xy 358.336185 -243.991656) (xy 358.286207 -243.991656) (xy 358.236844 -243.983837) (xy 358.189312 -243.968393)
			(xy 358.14478 -243.945703) (xy 358.104347 -243.916327) (xy 358.069007 -243.880987) (xy 358.039631 -243.840554)
			(xy 358.016941 -243.796022) (xy 358.001497 -243.74849) (xy 357.993678 -243.699127) (xy 357.686361 -243.699127)
			(xy 357.686352 -243.699584) (xy 357.678188 -243.749818) (xy 357.662072 -243.798092) (xy 357.638421 -243.843155)
			(xy 357.607848 -243.883841) (xy 357.571144 -243.919096) (xy 357.52926 -243.948006) (xy 357.483281 -243.969823)
			(xy 357.434397 -243.983983) (xy 357.383876 -243.990117) (xy 357.333024 -243.988068) (xy 357.28316 -243.977888)
			(xy 357.235574 -243.959841) (xy 357.1915 -243.934395) (xy 357.152078 -243.902208) (xy 357.11833 -243.864114)
			(xy 357.091129 -243.8211) (xy 357.071181 -243.77428) (xy 357.059002 -243.724866) (xy 357.054907 -243.674138)
			(xy 356.74681 -243.674138) (xy 356.746298 -243.699584) (xy 356.738134 -243.749818) (xy 356.722018 -243.798092)
			(xy 356.698367 -243.843155) (xy 356.667794 -243.883841) (xy 356.63109 -243.919096) (xy 356.589206 -243.948006)
			(xy 356.543227 -243.969823) (xy 356.494343 -243.983983) (xy 356.443822 -243.990117) (xy 356.39297 -243.988068)
			(xy 356.343106 -243.977888) (xy 356.29552 -243.959841) (xy 356.251446 -243.934395) (xy 356.212024 -243.902208)
			(xy 356.178276 -243.864114) (xy 356.151075 -243.8211) (xy 356.131127 -243.77428) (xy 356.118948 -243.724866)
			(xy 356.114853 -243.674138) (xy 355.809042 -243.674138) (xy 355.808552 -243.699127) (xy 355.800733 -243.74849)
			(xy 355.785289 -243.796022) (xy 355.762599 -243.840554) (xy 355.733223 -243.880987) (xy 355.697883 -243.916327)
			(xy 355.65745 -243.945703) (xy 355.612918 -243.968393) (xy 355.565386 -243.983837) (xy 355.516023 -243.991656)
			(xy 355.466045 -243.991656) (xy 355.416682 -243.983837) (xy 355.36915 -243.968393) (xy 355.324618 -243.945703)
			(xy 355.284185 -243.916327) (xy 355.248845 -243.880987) (xy 355.219469 -243.840554) (xy 355.196779 -243.796022)
			(xy 355.181335 -243.74849) (xy 355.173516 -243.699127) (xy 354.868752 -243.699127) (xy 354.860933 -243.74849)
			(xy 354.845489 -243.796022) (xy 354.822799 -243.840554) (xy 354.793423 -243.880987) (xy 354.758083 -243.916327)
			(xy 354.71765 -243.945703) (xy 354.673118 -243.968393) (xy 354.625586 -243.983837) (xy 354.576223 -243.991656)
			(xy 354.526245 -243.991656) (xy 354.476882 -243.983837) (xy 354.42935 -243.968393) (xy 354.384818 -243.945703)
			(xy 354.344385 -243.916327) (xy 354.309045 -243.880987) (xy 354.279669 -243.840554) (xy 354.256979 -243.796022)
			(xy 354.241535 -243.74849) (xy 354.233716 -243.699127) (xy 353.928698 -243.699127) (xy 353.920879 -243.74849)
			(xy 353.905435 -243.796022) (xy 353.882745 -243.840554) (xy 353.853369 -243.880987) (xy 353.818029 -243.916327)
			(xy 353.777596 -243.945703) (xy 353.733064 -243.968393) (xy 353.685532 -243.983837) (xy 353.636169 -243.991656)
			(xy 353.586191 -243.991656) (xy 353.536828 -243.983837) (xy 353.489296 -243.968393) (xy 353.444764 -243.945703)
			(xy 353.404331 -243.916327) (xy 353.368991 -243.880987) (xy 353.339615 -243.840554) (xy 353.316925 -243.796022)
			(xy 353.301481 -243.74849) (xy 353.293662 -243.699127) (xy 352.988644 -243.699127) (xy 352.980825 -243.74849)
			(xy 352.965381 -243.796022) (xy 352.942691 -243.840554) (xy 352.913315 -243.880987) (xy 352.877975 -243.916327)
			(xy 352.837542 -243.945703) (xy 352.79301 -243.968393) (xy 352.745478 -243.983837) (xy 352.696115 -243.991656)
			(xy 352.646137 -243.991656) (xy 352.596774 -243.983837) (xy 352.549242 -243.968393) (xy 352.50471 -243.945703)
			(xy 352.464277 -243.916327) (xy 352.428937 -243.880987) (xy 352.399561 -243.840554) (xy 352.376871 -243.796022)
			(xy 352.361427 -243.74849) (xy 352.353608 -243.699127) (xy 352.04859 -243.699127) (xy 352.040771 -243.74849)
			(xy 352.025327 -243.796022) (xy 352.002637 -243.840554) (xy 351.973261 -243.880987) (xy 351.937921 -243.916327)
			(xy 351.897488 -243.945703) (xy 351.852956 -243.968393) (xy 351.805424 -243.983837) (xy 351.756061 -243.991656)
			(xy 351.706083 -243.991656) (xy 351.65672 -243.983837) (xy 351.609188 -243.968393) (xy 351.564656 -243.945703)
			(xy 351.524223 -243.916327) (xy 351.488883 -243.880987) (xy 351.459507 -243.840554) (xy 351.436817 -243.796022)
			(xy 351.421373 -243.74849) (xy 351.413554 -243.699127) (xy 351.108536 -243.699127) (xy 351.100717 -243.74849)
			(xy 351.085273 -243.796022) (xy 351.062583 -243.840554) (xy 351.033207 -243.880987) (xy 350.997867 -243.916327)
			(xy 350.957434 -243.945703) (xy 350.912902 -243.968393) (xy 350.86537 -243.983837) (xy 350.816007 -243.991656)
			(xy 350.766029 -243.991656) (xy 350.716666 -243.983837) (xy 350.669134 -243.968393) (xy 350.624602 -243.945703)
			(xy 350.584169 -243.916327) (xy 350.548829 -243.880987) (xy 350.519453 -243.840554) (xy 350.496763 -243.796022)
			(xy 350.481319 -243.74849) (xy 350.4735 -243.699127) (xy 350.168736 -243.699127) (xy 350.160917 -243.74849)
			(xy 350.145473 -243.796022) (xy 350.122783 -243.840554) (xy 350.093407 -243.880987) (xy 350.058067 -243.916327)
			(xy 350.017634 -243.945703) (xy 349.973102 -243.968393) (xy 349.92557 -243.983837) (xy 349.876207 -243.991656)
			(xy 349.826229 -243.991656) (xy 349.776866 -243.983837) (xy 349.729334 -243.968393) (xy 349.684802 -243.945703)
			(xy 349.644369 -243.916327) (xy 349.609029 -243.880987) (xy 349.579653 -243.840554) (xy 349.556963 -243.796022)
			(xy 349.541519 -243.74849) (xy 349.5337 -243.699127) (xy 349.228682 -243.699127) (xy 349.220863 -243.74849)
			(xy 349.205419 -243.796022) (xy 349.182729 -243.840554) (xy 349.153353 -243.880987) (xy 349.118013 -243.916327)
			(xy 349.07758 -243.945703) (xy 349.033048 -243.968393) (xy 348.985516 -243.983837) (xy 348.936153 -243.991656)
			(xy 348.886175 -243.991656) (xy 348.836812 -243.983837) (xy 348.78928 -243.968393) (xy 348.744748 -243.945703)
			(xy 348.704315 -243.916327) (xy 348.668975 -243.880987) (xy 348.639599 -243.840554) (xy 348.616909 -243.796022)
			(xy 348.601465 -243.74849) (xy 348.593646 -243.699127) (xy 348.288628 -243.699127) (xy 348.280809 -243.74849)
			(xy 348.265365 -243.796022) (xy 348.242675 -243.840554) (xy 348.213299 -243.880987) (xy 348.177959 -243.916327)
			(xy 348.137526 -243.945703) (xy 348.092994 -243.968393) (xy 348.045462 -243.983837) (xy 347.996099 -243.991656)
			(xy 347.946121 -243.991656) (xy 347.896758 -243.983837) (xy 347.849226 -243.968393) (xy 347.804694 -243.945703)
			(xy 347.764261 -243.916327) (xy 347.728921 -243.880987) (xy 347.699545 -243.840554) (xy 347.676855 -243.796022)
			(xy 347.661411 -243.74849) (xy 347.653592 -243.699127) (xy 347.348574 -243.699127) (xy 347.340755 -243.74849)
			(xy 347.325311 -243.796022) (xy 347.302621 -243.840554) (xy 347.273245 -243.880987) (xy 347.237905 -243.916327)
			(xy 347.197472 -243.945703) (xy 347.15294 -243.968393) (xy 347.105408 -243.983837) (xy 347.056045 -243.991656)
			(xy 347.006067 -243.991656) (xy 346.956704 -243.983837) (xy 346.909172 -243.968393) (xy 346.86464 -243.945703)
			(xy 346.824207 -243.916327) (xy 346.788867 -243.880987) (xy 346.759491 -243.840554) (xy 346.736801 -243.796022)
			(xy 346.721357 -243.74849) (xy 346.713538 -243.699127) (xy 346.40852 -243.699127) (xy 346.400701 -243.74849)
			(xy 346.385257 -243.796022) (xy 346.362567 -243.840554) (xy 346.333191 -243.880987) (xy 346.297851 -243.916327)
			(xy 346.257418 -243.945703) (xy 346.212886 -243.968393) (xy 346.165354 -243.983837) (xy 346.115991 -243.991656)
			(xy 346.066013 -243.991656) (xy 346.01665 -243.983837) (xy 345.969118 -243.968393) (xy 345.924586 -243.945703)
			(xy 345.884153 -243.916327) (xy 345.848813 -243.880987) (xy 345.819437 -243.840554) (xy 345.796747 -243.796022)
			(xy 345.781303 -243.74849) (xy 345.773484 -243.699127) (xy 345.468674 -243.699127) (xy 345.460862 -243.748443)
			(xy 345.44542 -243.795969) (xy 345.422733 -243.840495) (xy 345.393361 -243.880924) (xy 345.358025 -243.916259)
			(xy 345.317597 -243.945632) (xy 345.273071 -243.968319) (xy 345.225545 -243.983762) (xy 345.176188 -243.99158)
			(xy 345.151202 -243.992146) (xy 345.141014 -243.992081) (xy 345.120678 -243.990811) (xy 345.110562 -243.989606)
			(xy 345.09964 -243.988336) (xy 345.089988 -243.99113) (xy 345.084906 -243.992844) (xy 345.075563 -243.998105)
			(xy 345.071446 -244.001544) (xy 345.051888 -244.018562) (xy 345.01201 -244.053614) (xy 345.005451 -244.060861)
			(xy 344.997986 -244.078903) (xy 344.997532 -244.088666) (xy 344.997532 -244.450108) (xy 344.997786 -244.45468)
			(xy 344.999056 -244.48389) (xy 344.999056 -244.484144) (xy 345.304867 -244.484144) (xy 345.308962 -244.433416)
			(xy 345.321141 -244.384002) (xy 345.341089 -244.337182) (xy 345.36829 -244.294168) (xy 345.402038 -244.256074)
			(xy 345.44146 -244.223887) (xy 345.485534 -244.198441) (xy 345.53312 -244.180394) (xy 345.582984 -244.170214)
			(xy 345.633836 -244.168165) (xy 345.684357 -244.174299) (xy 345.733241 -244.188459) (xy 345.77922 -244.210276)
			(xy 345.821104 -244.239186) (xy 345.857808 -244.274441) (xy 345.888381 -244.315127) (xy 345.912032 -244.36019)
			(xy 345.928148 -244.408464) (xy 345.936312 -244.458698) (xy 345.936824 -244.484144) (xy 346.244921 -244.484144)
			(xy 346.249016 -244.433416) (xy 346.261195 -244.384002) (xy 346.281143 -244.337182) (xy 346.308344 -244.294168)
			(xy 346.342092 -244.256074) (xy 346.381514 -244.223887) (xy 346.425588 -244.198441) (xy 346.473174 -244.180394)
			(xy 346.523038 -244.170214) (xy 346.57389 -244.168165) (xy 346.624411 -244.174299) (xy 346.673295 -244.188459)
			(xy 346.719274 -244.210276) (xy 346.761158 -244.239186) (xy 346.797862 -244.274441) (xy 346.828435 -244.315127)
			(xy 346.852086 -244.36019) (xy 346.868202 -244.408464) (xy 346.876366 -244.458698) (xy 346.876878 -244.484144)
			(xy 346.876375 -244.509133) (xy 347.183692 -244.509133) (xy 347.183692 -244.459155) (xy 347.191511 -244.409792)
			(xy 347.206955 -244.36226) (xy 347.229645 -244.317728) (xy 347.259021 -244.277295) (xy 347.294361 -244.241955)
			(xy 347.334794 -244.212579) (xy 347.379326 -244.189889) (xy 347.426858 -244.174445) (xy 347.476221 -244.166626)
			(xy 347.526199 -244.166626) (xy 347.575562 -244.174445) (xy 347.623094 -244.189889) (xy 347.667626 -244.212579)
			(xy 347.708059 -244.241955) (xy 347.743399 -244.277295) (xy 347.772775 -244.317728) (xy 347.795465 -244.36226)
			(xy 347.810909 -244.409792) (xy 347.818728 -244.459155) (xy 347.819218 -244.484144) (xy 348.124775 -244.484144)
			(xy 348.12887 -244.433416) (xy 348.141049 -244.384002) (xy 348.160997 -244.337182) (xy 348.188198 -244.294168)
			(xy 348.221946 -244.256074) (xy 348.261368 -244.223887) (xy 348.305442 -244.198441) (xy 348.353028 -244.180394)
			(xy 348.402892 -244.170214) (xy 348.453744 -244.168165) (xy 348.504265 -244.174299) (xy 348.553149 -244.188459)
			(xy 348.599128 -244.210276) (xy 348.641012 -244.239186) (xy 348.677716 -244.274441) (xy 348.708289 -244.315127)
			(xy 348.73194 -244.36019) (xy 348.748056 -244.408464) (xy 348.75622 -244.458698) (xy 348.756732 -244.484144)
			(xy 349.064829 -244.484144) (xy 349.068924 -244.433416) (xy 349.081103 -244.384002) (xy 349.101051 -244.337182)
			(xy 349.128252 -244.294168) (xy 349.162 -244.256074) (xy 349.201422 -244.223887) (xy 349.245496 -244.198441)
			(xy 349.293082 -244.180394) (xy 349.342946 -244.170214) (xy 349.393798 -244.168165) (xy 349.444319 -244.174299)
			(xy 349.493203 -244.188459) (xy 349.539182 -244.210276) (xy 349.581066 -244.239186) (xy 349.61777 -244.274441)
			(xy 349.648343 -244.315127) (xy 349.671994 -244.36019) (xy 349.68811 -244.408464) (xy 349.696274 -244.458698)
			(xy 349.696786 -244.484144) (xy 349.696283 -244.509133) (xy 350.0036 -244.509133) (xy 350.0036 -244.459155)
			(xy 350.011419 -244.409792) (xy 350.026863 -244.36226) (xy 350.049553 -244.317728) (xy 350.078929 -244.277295)
			(xy 350.114269 -244.241955) (xy 350.154702 -244.212579) (xy 350.199234 -244.189889) (xy 350.246766 -244.174445)
			(xy 350.296129 -244.166626) (xy 350.346107 -244.166626) (xy 350.39547 -244.174445) (xy 350.443002 -244.189889)
			(xy 350.487534 -244.212579) (xy 350.527967 -244.241955) (xy 350.563307 -244.277295) (xy 350.592683 -244.317728)
			(xy 350.615373 -244.36226) (xy 350.630817 -244.409792) (xy 350.638636 -244.459155) (xy 350.639126 -244.484144)
			(xy 350.944937 -244.484144) (xy 350.949032 -244.433416) (xy 350.961211 -244.384002) (xy 350.981159 -244.337182)
			(xy 351.00836 -244.294168) (xy 351.042108 -244.256074) (xy 351.08153 -244.223887) (xy 351.125604 -244.198441)
			(xy 351.17319 -244.180394) (xy 351.223054 -244.170214) (xy 351.273906 -244.168165) (xy 351.324427 -244.174299)
			(xy 351.373311 -244.188459) (xy 351.41929 -244.210276) (xy 351.461174 -244.239186) (xy 351.497878 -244.274441)
			(xy 351.528451 -244.315127) (xy 351.552102 -244.36019) (xy 351.568218 -244.408464) (xy 351.576382 -244.458698)
			(xy 351.576894 -244.484144) (xy 351.884991 -244.484144) (xy 351.889086 -244.433416) (xy 351.901265 -244.384002)
			(xy 351.921213 -244.337182) (xy 351.948414 -244.294168) (xy 351.982162 -244.256074) (xy 352.021584 -244.223887)
			(xy 352.065658 -244.198441) (xy 352.113244 -244.180394) (xy 352.163108 -244.170214) (xy 352.21396 -244.168165)
			(xy 352.264481 -244.174299) (xy 352.313365 -244.188459) (xy 352.359344 -244.210276) (xy 352.401228 -244.239186)
			(xy 352.437932 -244.274441) (xy 352.468505 -244.315127) (xy 352.492156 -244.36019) (xy 352.508272 -244.408464)
			(xy 352.516436 -244.458698) (xy 352.516948 -244.484144) (xy 352.516445 -244.509133) (xy 352.823508 -244.509133)
			(xy 352.823508 -244.459155) (xy 352.831327 -244.409792) (xy 352.846771 -244.36226) (xy 352.869461 -244.317728)
			(xy 352.898837 -244.277295) (xy 352.934177 -244.241955) (xy 352.97461 -244.212579) (xy 353.019142 -244.189889)
			(xy 353.066674 -244.174445) (xy 353.116037 -244.166626) (xy 353.166015 -244.166626) (xy 353.215378 -244.174445)
			(xy 353.26291 -244.189889) (xy 353.307442 -244.212579) (xy 353.347875 -244.241955) (xy 353.383215 -244.277295)
			(xy 353.412591 -244.317728) (xy 353.435281 -244.36226) (xy 353.450725 -244.409792) (xy 353.458544 -244.459155)
			(xy 353.459034 -244.484144) (xy 353.764845 -244.484144) (xy 353.76894 -244.433416) (xy 353.781119 -244.384002)
			(xy 353.801067 -244.337182) (xy 353.828268 -244.294168) (xy 353.862016 -244.256074) (xy 353.901438 -244.223887)
			(xy 353.945512 -244.198441) (xy 353.993098 -244.180394) (xy 354.042962 -244.170214) (xy 354.093814 -244.168165)
			(xy 354.144335 -244.174299) (xy 354.193219 -244.188459) (xy 354.239198 -244.210276) (xy 354.281082 -244.239186)
			(xy 354.317786 -244.274441) (xy 354.348359 -244.315127) (xy 354.37201 -244.36019) (xy 354.388126 -244.408464)
			(xy 354.39629 -244.458698) (xy 354.396802 -244.484144) (xy 354.704899 -244.484144) (xy 354.708994 -244.433416)
			(xy 354.721173 -244.384002) (xy 354.741121 -244.337182) (xy 354.768322 -244.294168) (xy 354.80207 -244.256074)
			(xy 354.841492 -244.223887) (xy 354.885566 -244.198441) (xy 354.933152 -244.180394) (xy 354.983016 -244.170214)
			(xy 355.033868 -244.168165) (xy 355.084389 -244.174299) (xy 355.133273 -244.188459) (xy 355.179252 -244.210276)
			(xy 355.221136 -244.239186) (xy 355.25784 -244.274441) (xy 355.288413 -244.315127) (xy 355.312064 -244.36019)
			(xy 355.32818 -244.408464) (xy 355.336344 -244.458698) (xy 355.336856 -244.484144) (xy 355.336353 -244.509133)
			(xy 355.64367 -244.509133) (xy 355.64367 -244.459155) (xy 355.651489 -244.409792) (xy 355.666933 -244.36226)
			(xy 355.689623 -244.317728) (xy 355.718999 -244.277295) (xy 355.754339 -244.241955) (xy 355.794772 -244.212579)
			(xy 355.839304 -244.189889) (xy 355.886836 -244.174445) (xy 355.936199 -244.166626) (xy 355.986177 -244.166626)
			(xy 356.03554 -244.174445) (xy 356.083072 -244.189889) (xy 356.127604 -244.212579) (xy 356.168037 -244.241955)
			(xy 356.203377 -244.277295) (xy 356.232753 -244.317728) (xy 356.255443 -244.36226) (xy 356.270887 -244.409792)
			(xy 356.278706 -244.459155) (xy 356.279196 -244.484144) (xy 356.278706 -244.509133) (xy 356.583724 -244.509133)
			(xy 356.583724 -244.459155) (xy 356.591543 -244.409792) (xy 356.606987 -244.36226) (xy 356.629677 -244.317728)
			(xy 356.659053 -244.277295) (xy 356.694393 -244.241955) (xy 356.734826 -244.212579) (xy 356.779358 -244.189889)
			(xy 356.82689 -244.174445) (xy 356.876253 -244.166626) (xy 356.926231 -244.166626) (xy 356.975594 -244.174445)
			(xy 357.023126 -244.189889) (xy 357.067658 -244.212579) (xy 357.108091 -244.241955) (xy 357.143431 -244.277295)
			(xy 357.172807 -244.317728) (xy 357.195497 -244.36226) (xy 357.210941 -244.409792) (xy 357.21876 -244.459155)
			(xy 357.21925 -244.484144) (xy 357.21876 -244.509133) (xy 357.523524 -244.509133) (xy 357.523524 -244.459155)
			(xy 357.531343 -244.409792) (xy 357.546787 -244.36226) (xy 357.569477 -244.317728) (xy 357.598853 -244.277295)
			(xy 357.634193 -244.241955) (xy 357.674626 -244.212579) (xy 357.719158 -244.189889) (xy 357.76669 -244.174445)
			(xy 357.816053 -244.166626) (xy 357.866031 -244.166626) (xy 357.915394 -244.174445) (xy 357.962926 -244.189889)
			(xy 358.007458 -244.212579) (xy 358.047891 -244.241955) (xy 358.083231 -244.277295) (xy 358.112607 -244.317728)
			(xy 358.135297 -244.36226) (xy 358.150741 -244.409792) (xy 358.15856 -244.459155) (xy 358.15905 -244.484144)
			(xy 358.15856 -244.509133) (xy 361.27739 -244.509133) (xy 361.27739 -244.459155) (xy 361.285209 -244.409792)
			(xy 361.300653 -244.36226) (xy 361.323343 -244.317728) (xy 361.352719 -244.277295) (xy 361.388059 -244.241955)
			(xy 361.428492 -244.212579) (xy 361.473024 -244.189889) (xy 361.520556 -244.174445) (xy 361.569919 -244.166626)
			(xy 361.619897 -244.166626) (xy 361.66926 -244.174445) (xy 361.716792 -244.189889) (xy 361.761324 -244.212579)
			(xy 361.801757 -244.241955) (xy 361.837097 -244.277295) (xy 361.866473 -244.317728) (xy 361.889163 -244.36226)
			(xy 361.904607 -244.409792) (xy 361.912426 -244.459155) (xy 361.912916 -244.484144) (xy 361.912426 -244.509133)
			(xy 362.21719 -244.509133) (xy 362.21719 -244.459155) (xy 362.225009 -244.409792) (xy 362.240453 -244.36226)
			(xy 362.263143 -244.317728) (xy 362.292519 -244.277295) (xy 362.327859 -244.241955) (xy 362.368292 -244.212579)
			(xy 362.412824 -244.189889) (xy 362.460356 -244.174445) (xy 362.509719 -244.166626) (xy 362.559697 -244.166626)
			(xy 362.60906 -244.174445) (xy 362.656592 -244.189889) (xy 362.701124 -244.212579) (xy 362.741557 -244.241955)
			(xy 362.776897 -244.277295) (xy 362.806273 -244.317728) (xy 362.828963 -244.36226) (xy 362.844407 -244.409792)
			(xy 362.852226 -244.459155) (xy 362.852716 -244.484144) (xy 362.852226 -244.509133) (xy 363.157244 -244.509133)
			(xy 363.157244 -244.459155) (xy 363.165063 -244.409792) (xy 363.180507 -244.36226) (xy 363.203197 -244.317728)
			(xy 363.232573 -244.277295) (xy 363.267913 -244.241955) (xy 363.308346 -244.212579) (xy 363.352878 -244.189889)
			(xy 363.40041 -244.174445) (xy 363.449773 -244.166626) (xy 363.499751 -244.166626) (xy 363.549114 -244.174445)
			(xy 363.596646 -244.189889) (xy 363.641178 -244.212579) (xy 363.681611 -244.241955) (xy 363.716951 -244.277295)
			(xy 363.746327 -244.317728) (xy 363.769017 -244.36226) (xy 363.784461 -244.409792) (xy 363.79228 -244.459155)
			(xy 363.79277 -244.484144) (xy 364.098581 -244.484144) (xy 364.102676 -244.433416) (xy 364.114855 -244.384002)
			(xy 364.134803 -244.337182) (xy 364.162004 -244.294168) (xy 364.195752 -244.256074) (xy 364.235174 -244.223887)
			(xy 364.279248 -244.198441) (xy 364.326834 -244.180394) (xy 364.376698 -244.170214) (xy 364.42755 -244.168165)
			(xy 364.478071 -244.174299) (xy 364.526955 -244.188459) (xy 364.572934 -244.210276) (xy 364.614818 -244.239186)
			(xy 364.651522 -244.274441) (xy 364.682095 -244.315127) (xy 364.705746 -244.36019) (xy 364.721862 -244.408464)
			(xy 364.730026 -244.458698) (xy 364.730538 -244.484144) (xy 365.038635 -244.484144) (xy 365.04273 -244.433416)
			(xy 365.054909 -244.384002) (xy 365.074857 -244.337182) (xy 365.102058 -244.294168) (xy 365.135806 -244.256074)
			(xy 365.175228 -244.223887) (xy 365.219302 -244.198441) (xy 365.266888 -244.180394) (xy 365.316752 -244.170214)
			(xy 365.367604 -244.168165) (xy 365.418125 -244.174299) (xy 365.467009 -244.188459) (xy 365.512988 -244.210276)
			(xy 365.554872 -244.239186) (xy 365.591576 -244.274441) (xy 365.622149 -244.315127) (xy 365.6458 -244.36019)
			(xy 365.661916 -244.408464) (xy 365.67008 -244.458698) (xy 365.670592 -244.484144) (xy 365.670089 -244.509133)
			(xy 365.977406 -244.509133) (xy 365.977406 -244.459155) (xy 365.985225 -244.409792) (xy 366.000669 -244.36226)
			(xy 366.023359 -244.317728) (xy 366.052735 -244.277295) (xy 366.088075 -244.241955) (xy 366.128508 -244.212579)
			(xy 366.17304 -244.189889) (xy 366.220572 -244.174445) (xy 366.269935 -244.166626) (xy 366.319913 -244.166626)
			(xy 366.369276 -244.174445) (xy 366.416808 -244.189889) (xy 366.46134 -244.212579) (xy 366.501773 -244.241955)
			(xy 366.537113 -244.277295) (xy 366.566489 -244.317728) (xy 366.589179 -244.36226) (xy 366.604623 -244.409792)
			(xy 366.612442 -244.459155) (xy 366.612932 -244.484144) (xy 366.918489 -244.484144) (xy 366.922584 -244.433416)
			(xy 366.934763 -244.384002) (xy 366.954711 -244.337182) (xy 366.981912 -244.294168) (xy 367.01566 -244.256074)
			(xy 367.055082 -244.223887) (xy 367.099156 -244.198441) (xy 367.146742 -244.180394) (xy 367.196606 -244.170214)
			(xy 367.247458 -244.168165) (xy 367.297979 -244.174299) (xy 367.346863 -244.188459) (xy 367.392842 -244.210276)
			(xy 367.434726 -244.239186) (xy 367.47143 -244.274441) (xy 367.502003 -244.315127) (xy 367.525654 -244.36019)
			(xy 367.54177 -244.408464) (xy 367.549934 -244.458698) (xy 367.550446 -244.484144) (xy 367.858543 -244.484144)
			(xy 367.862638 -244.433416) (xy 367.874817 -244.384002) (xy 367.894765 -244.337182) (xy 367.921966 -244.294168)
			(xy 367.955714 -244.256074) (xy 367.995136 -244.223887) (xy 368.03921 -244.198441) (xy 368.086796 -244.180394)
			(xy 368.13666 -244.170214) (xy 368.187512 -244.168165) (xy 368.238033 -244.174299) (xy 368.286917 -244.188459)
			(xy 368.332896 -244.210276) (xy 368.37478 -244.239186) (xy 368.411484 -244.274441) (xy 368.442057 -244.315127)
			(xy 368.465708 -244.36019) (xy 368.481824 -244.408464) (xy 368.489988 -244.458698) (xy 368.4905 -244.484144)
			(xy 368.489997 -244.509133) (xy 368.797314 -244.509133) (xy 368.797314 -244.459155) (xy 368.805133 -244.409792)
			(xy 368.820577 -244.36226) (xy 368.843267 -244.317728) (xy 368.872643 -244.277295) (xy 368.907983 -244.241955)
			(xy 368.948416 -244.212579) (xy 368.992948 -244.189889) (xy 369.04048 -244.174445) (xy 369.089843 -244.166626)
			(xy 369.139821 -244.166626) (xy 369.189184 -244.174445) (xy 369.236716 -244.189889) (xy 369.281248 -244.212579)
			(xy 369.321681 -244.241955) (xy 369.357021 -244.277295) (xy 369.386397 -244.317728) (xy 369.409087 -244.36226)
			(xy 369.424531 -244.409792) (xy 369.43235 -244.459155) (xy 369.43284 -244.484144) (xy 369.738651 -244.484144)
			(xy 369.742746 -244.433416) (xy 369.754925 -244.384002) (xy 369.774873 -244.337182) (xy 369.802074 -244.294168)
			(xy 369.835822 -244.256074) (xy 369.875244 -244.223887) (xy 369.919318 -244.198441) (xy 369.966904 -244.180394)
			(xy 370.016768 -244.170214) (xy 370.06762 -244.168165) (xy 370.118141 -244.174299) (xy 370.167025 -244.188459)
			(xy 370.213004 -244.210276) (xy 370.254888 -244.239186) (xy 370.291592 -244.274441) (xy 370.322165 -244.315127)
			(xy 370.345816 -244.36019) (xy 370.361932 -244.408464) (xy 370.370096 -244.458698) (xy 370.370608 -244.484144)
			(xy 370.678451 -244.484144) (xy 370.682546 -244.433416) (xy 370.694725 -244.384002) (xy 370.714673 -244.337182)
			(xy 370.741874 -244.294168) (xy 370.775622 -244.256074) (xy 370.815044 -244.223887) (xy 370.859118 -244.198441)
			(xy 370.906704 -244.180394) (xy 370.956568 -244.170214) (xy 371.00742 -244.168165) (xy 371.057941 -244.174299)
			(xy 371.106825 -244.188459) (xy 371.152804 -244.210276) (xy 371.194688 -244.239186) (xy 371.231392 -244.274441)
			(xy 371.261965 -244.315127) (xy 371.285616 -244.36019) (xy 371.301732 -244.408464) (xy 371.309896 -244.458698)
			(xy 371.310408 -244.484144) (xy 371.309905 -244.509133) (xy 371.617222 -244.509133) (xy 371.617222 -244.459155)
			(xy 371.625041 -244.409792) (xy 371.640485 -244.36226) (xy 371.663175 -244.317728) (xy 371.692551 -244.277295)
			(xy 371.727891 -244.241955) (xy 371.768324 -244.212579) (xy 371.812856 -244.189889) (xy 371.860388 -244.174445)
			(xy 371.909751 -244.166626) (xy 371.959729 -244.166626) (xy 372.009092 -244.174445) (xy 372.056624 -244.189889)
			(xy 372.101156 -244.212579) (xy 372.141589 -244.241955) (xy 372.176929 -244.277295) (xy 372.206305 -244.317728)
			(xy 372.228995 -244.36226) (xy 372.244439 -244.409792) (xy 372.252258 -244.459155) (xy 372.252748 -244.484144)
			(xy 372.558559 -244.484144) (xy 372.562654 -244.433416) (xy 372.574833 -244.384002) (xy 372.594781 -244.337182)
			(xy 372.621982 -244.294168) (xy 372.65573 -244.256074) (xy 372.695152 -244.223887) (xy 372.739226 -244.198441)
			(xy 372.786812 -244.180394) (xy 372.836676 -244.170214) (xy 372.887528 -244.168165) (xy 372.938049 -244.174299)
			(xy 372.986933 -244.188459) (xy 373.032912 -244.210276) (xy 373.074796 -244.239186) (xy 373.1115 -244.274441)
			(xy 373.142073 -244.315127) (xy 373.165724 -244.36019) (xy 373.18184 -244.408464) (xy 373.190004 -244.458698)
			(xy 373.190516 -244.484144) (xy 373.498613 -244.484144) (xy 373.502708 -244.433416) (xy 373.514887 -244.384002)
			(xy 373.534835 -244.337182) (xy 373.562036 -244.294168) (xy 373.595784 -244.256074) (xy 373.635206 -244.223887)
			(xy 373.67928 -244.198441) (xy 373.726866 -244.180394) (xy 373.77673 -244.170214) (xy 373.827582 -244.168165)
			(xy 373.878103 -244.174299) (xy 373.926987 -244.188459) (xy 373.972966 -244.210276) (xy 374.01485 -244.239186)
			(xy 374.051554 -244.274441) (xy 374.082127 -244.315127) (xy 374.105778 -244.36019) (xy 374.121894 -244.408464)
			(xy 374.130058 -244.458698) (xy 374.13057 -244.484144) (xy 374.130058 -244.50959) (xy 374.121894 -244.559824)
			(xy 374.105778 -244.608098) (xy 374.082127 -244.653161) (xy 374.051554 -244.693847) (xy 374.01485 -244.729102)
			(xy 373.972966 -244.758012) (xy 373.926987 -244.779829) (xy 373.878103 -244.793989) (xy 373.827582 -244.800123)
			(xy 373.77673 -244.798074) (xy 373.726866 -244.787894) (xy 373.67928 -244.769847) (xy 373.635206 -244.744401)
			(xy 373.595784 -244.712214) (xy 373.562036 -244.67412) (xy 373.534835 -244.631106) (xy 373.514887 -244.584286)
			(xy 373.502708 -244.534872) (xy 373.498613 -244.484144) (xy 373.190516 -244.484144) (xy 373.190004 -244.50959)
			(xy 373.18184 -244.559824) (xy 373.165724 -244.608098) (xy 373.142073 -244.653161) (xy 373.1115 -244.693847)
			(xy 373.074796 -244.729102) (xy 373.032912 -244.758012) (xy 372.986933 -244.779829) (xy 372.938049 -244.793989)
			(xy 372.887528 -244.800123) (xy 372.836676 -244.798074) (xy 372.786812 -244.787894) (xy 372.739226 -244.769847)
			(xy 372.695152 -244.744401) (xy 372.65573 -244.712214) (xy 372.621982 -244.67412) (xy 372.594781 -244.631106)
			(xy 372.574833 -244.584286) (xy 372.562654 -244.534872) (xy 372.558559 -244.484144) (xy 372.252748 -244.484144)
			(xy 372.252258 -244.509133) (xy 372.244439 -244.558496) (xy 372.228995 -244.606028) (xy 372.206305 -244.65056)
			(xy 372.176929 -244.690993) (xy 372.141589 -244.726333) (xy 372.101156 -244.755709) (xy 372.056624 -244.778399)
			(xy 372.009092 -244.793843) (xy 371.959729 -244.801662) (xy 371.909751 -244.801662) (xy 371.860388 -244.793843)
			(xy 371.812856 -244.778399) (xy 371.768324 -244.755709) (xy 371.727891 -244.726333) (xy 371.692551 -244.690993)
			(xy 371.663175 -244.65056) (xy 371.640485 -244.606028) (xy 371.625041 -244.558496) (xy 371.617222 -244.509133)
			(xy 371.309905 -244.509133) (xy 371.309896 -244.50959) (xy 371.301732 -244.559824) (xy 371.285616 -244.608098)
			(xy 371.261965 -244.653161) (xy 371.231392 -244.693847) (xy 371.194688 -244.729102) (xy 371.152804 -244.758012)
			(xy 371.106825 -244.779829) (xy 371.057941 -244.793989) (xy 371.00742 -244.800123) (xy 370.956568 -244.798074)
			(xy 370.906704 -244.787894) (xy 370.859118 -244.769847) (xy 370.815044 -244.744401) (xy 370.775622 -244.712214)
			(xy 370.741874 -244.67412) (xy 370.714673 -244.631106) (xy 370.694725 -244.584286) (xy 370.682546 -244.534872)
			(xy 370.678451 -244.484144) (xy 370.370608 -244.484144) (xy 370.370096 -244.50959) (xy 370.361932 -244.559824)
			(xy 370.345816 -244.608098) (xy 370.322165 -244.653161) (xy 370.291592 -244.693847) (xy 370.254888 -244.729102)
			(xy 370.213004 -244.758012) (xy 370.167025 -244.779829) (xy 370.118141 -244.793989) (xy 370.06762 -244.800123)
			(xy 370.016768 -244.798074) (xy 369.966904 -244.787894) (xy 369.919318 -244.769847) (xy 369.875244 -244.744401)
			(xy 369.835822 -244.712214) (xy 369.802074 -244.67412) (xy 369.774873 -244.631106) (xy 369.754925 -244.584286)
			(xy 369.742746 -244.534872) (xy 369.738651 -244.484144) (xy 369.43284 -244.484144) (xy 369.43235 -244.509133)
			(xy 369.424531 -244.558496) (xy 369.409087 -244.606028) (xy 369.386397 -244.65056) (xy 369.357021 -244.690993)
			(xy 369.321681 -244.726333) (xy 369.281248 -244.755709) (xy 369.236716 -244.778399) (xy 369.189184 -244.793843)
			(xy 369.139821 -244.801662) (xy 369.089843 -244.801662) (xy 369.04048 -244.793843) (xy 368.992948 -244.778399)
			(xy 368.948416 -244.755709) (xy 368.907983 -244.726333) (xy 368.872643 -244.690993) (xy 368.843267 -244.65056)
			(xy 368.820577 -244.606028) (xy 368.805133 -244.558496) (xy 368.797314 -244.509133) (xy 368.489997 -244.509133)
			(xy 368.489988 -244.50959) (xy 368.481824 -244.559824) (xy 368.465708 -244.608098) (xy 368.442057 -244.653161)
			(xy 368.411484 -244.693847) (xy 368.37478 -244.729102) (xy 368.332896 -244.758012) (xy 368.286917 -244.779829)
			(xy 368.238033 -244.793989) (xy 368.187512 -244.800123) (xy 368.13666 -244.798074) (xy 368.086796 -244.787894)
			(xy 368.03921 -244.769847) (xy 367.995136 -244.744401) (xy 367.955714 -244.712214) (xy 367.921966 -244.67412)
			(xy 367.894765 -244.631106) (xy 367.874817 -244.584286) (xy 367.862638 -244.534872) (xy 367.858543 -244.484144)
			(xy 367.550446 -244.484144) (xy 367.549934 -244.50959) (xy 367.54177 -244.559824) (xy 367.525654 -244.608098)
			(xy 367.502003 -244.653161) (xy 367.47143 -244.693847) (xy 367.434726 -244.729102) (xy 367.392842 -244.758012)
			(xy 367.346863 -244.779829) (xy 367.297979 -244.793989) (xy 367.247458 -244.800123) (xy 367.196606 -244.798074)
			(xy 367.146742 -244.787894) (xy 367.099156 -244.769847) (xy 367.055082 -244.744401) (xy 367.01566 -244.712214)
			(xy 366.981912 -244.67412) (xy 366.954711 -244.631106) (xy 366.934763 -244.584286) (xy 366.922584 -244.534872)
			(xy 366.918489 -244.484144) (xy 366.612932 -244.484144) (xy 366.612442 -244.509133) (xy 366.604623 -244.558496)
			(xy 366.589179 -244.606028) (xy 366.566489 -244.65056) (xy 366.537113 -244.690993) (xy 366.501773 -244.726333)
			(xy 366.46134 -244.755709) (xy 366.416808 -244.778399) (xy 366.369276 -244.793843) (xy 366.319913 -244.801662)
			(xy 366.269935 -244.801662) (xy 366.220572 -244.793843) (xy 366.17304 -244.778399) (xy 366.128508 -244.755709)
			(xy 366.088075 -244.726333) (xy 366.052735 -244.690993) (xy 366.023359 -244.65056) (xy 366.000669 -244.606028)
			(xy 365.985225 -244.558496) (xy 365.977406 -244.509133) (xy 365.670089 -244.509133) (xy 365.67008 -244.50959)
			(xy 365.661916 -244.559824) (xy 365.6458 -244.608098) (xy 365.622149 -244.653161) (xy 365.591576 -244.693847)
			(xy 365.554872 -244.729102) (xy 365.512988 -244.758012) (xy 365.467009 -244.779829) (xy 365.418125 -244.793989)
			(xy 365.367604 -244.800123) (xy 365.316752 -244.798074) (xy 365.266888 -244.787894) (xy 365.219302 -244.769847)
			(xy 365.175228 -244.744401) (xy 365.135806 -244.712214) (xy 365.102058 -244.67412) (xy 365.074857 -244.631106)
			(xy 365.054909 -244.584286) (xy 365.04273 -244.534872) (xy 365.038635 -244.484144) (xy 364.730538 -244.484144)
			(xy 364.730026 -244.50959) (xy 364.721862 -244.559824) (xy 364.705746 -244.608098) (xy 364.682095 -244.653161)
			(xy 364.651522 -244.693847) (xy 364.614818 -244.729102) (xy 364.572934 -244.758012) (xy 364.526955 -244.779829)
			(xy 364.478071 -244.793989) (xy 364.42755 -244.800123) (xy 364.376698 -244.798074) (xy 364.326834 -244.787894)
			(xy 364.279248 -244.769847) (xy 364.235174 -244.744401) (xy 364.195752 -244.712214) (xy 364.162004 -244.67412)
			(xy 364.134803 -244.631106) (xy 364.114855 -244.584286) (xy 364.102676 -244.534872) (xy 364.098581 -244.484144)
			(xy 363.79277 -244.484144) (xy 363.79228 -244.509133) (xy 363.784461 -244.558496) (xy 363.769017 -244.606028)
			(xy 363.746327 -244.65056) (xy 363.716951 -244.690993) (xy 363.681611 -244.726333) (xy 363.641178 -244.755709)
			(xy 363.596646 -244.778399) (xy 363.549114 -244.793843) (xy 363.499751 -244.801662) (xy 363.449773 -244.801662)
			(xy 363.40041 -244.793843) (xy 363.352878 -244.778399) (xy 363.308346 -244.755709) (xy 363.267913 -244.726333)
			(xy 363.232573 -244.690993) (xy 363.203197 -244.65056) (xy 363.180507 -244.606028) (xy 363.165063 -244.558496)
			(xy 363.157244 -244.509133) (xy 362.852226 -244.509133) (xy 362.844407 -244.558496) (xy 362.828963 -244.606028)
			(xy 362.806273 -244.65056) (xy 362.776897 -244.690993) (xy 362.741557 -244.726333) (xy 362.701124 -244.755709)
			(xy 362.656592 -244.778399) (xy 362.60906 -244.793843) (xy 362.559697 -244.801662) (xy 362.509719 -244.801662)
			(xy 362.460356 -244.793843) (xy 362.412824 -244.778399) (xy 362.368292 -244.755709) (xy 362.327859 -244.726333)
			(xy 362.292519 -244.690993) (xy 362.263143 -244.65056) (xy 362.240453 -244.606028) (xy 362.225009 -244.558496)
			(xy 362.21719 -244.509133) (xy 361.912426 -244.509133) (xy 361.904607 -244.558496) (xy 361.889163 -244.606028)
			(xy 361.866473 -244.65056) (xy 361.837097 -244.690993) (xy 361.801757 -244.726333) (xy 361.761324 -244.755709)
			(xy 361.716792 -244.778399) (xy 361.66926 -244.793843) (xy 361.619897 -244.801662) (xy 361.569919 -244.801662)
			(xy 361.520556 -244.793843) (xy 361.473024 -244.778399) (xy 361.428492 -244.755709) (xy 361.388059 -244.726333)
			(xy 361.352719 -244.690993) (xy 361.323343 -244.65056) (xy 361.300653 -244.606028) (xy 361.285209 -244.558496)
			(xy 361.27739 -244.509133) (xy 358.15856 -244.509133) (xy 358.150741 -244.558496) (xy 358.135297 -244.606028)
			(xy 358.112607 -244.65056) (xy 358.083231 -244.690993) (xy 358.047891 -244.726333) (xy 358.007458 -244.755709)
			(xy 357.962926 -244.778399) (xy 357.915394 -244.793843) (xy 357.866031 -244.801662) (xy 357.816053 -244.801662)
			(xy 357.76669 -244.793843) (xy 357.719158 -244.778399) (xy 357.674626 -244.755709) (xy 357.634193 -244.726333)
			(xy 357.598853 -244.690993) (xy 357.569477 -244.65056) (xy 357.546787 -244.606028) (xy 357.531343 -244.558496)
			(xy 357.523524 -244.509133) (xy 357.21876 -244.509133) (xy 357.210941 -244.558496) (xy 357.195497 -244.606028)
			(xy 357.172807 -244.65056) (xy 357.143431 -244.690993) (xy 357.108091 -244.726333) (xy 357.067658 -244.755709)
			(xy 357.023126 -244.778399) (xy 356.975594 -244.793843) (xy 356.926231 -244.801662) (xy 356.876253 -244.801662)
			(xy 356.82689 -244.793843) (xy 356.779358 -244.778399) (xy 356.734826 -244.755709) (xy 356.694393 -244.726333)
			(xy 356.659053 -244.690993) (xy 356.629677 -244.65056) (xy 356.606987 -244.606028) (xy 356.591543 -244.558496)
			(xy 356.583724 -244.509133) (xy 356.278706 -244.509133) (xy 356.270887 -244.558496) (xy 356.255443 -244.606028)
			(xy 356.232753 -244.65056) (xy 356.203377 -244.690993) (xy 356.168037 -244.726333) (xy 356.127604 -244.755709)
			(xy 356.083072 -244.778399) (xy 356.03554 -244.793843) (xy 355.986177 -244.801662) (xy 355.936199 -244.801662)
			(xy 355.886836 -244.793843) (xy 355.839304 -244.778399) (xy 355.794772 -244.755709) (xy 355.754339 -244.726333)
			(xy 355.718999 -244.690993) (xy 355.689623 -244.65056) (xy 355.666933 -244.606028) (xy 355.651489 -244.558496)
			(xy 355.64367 -244.509133) (xy 355.336353 -244.509133) (xy 355.336344 -244.50959) (xy 355.32818 -244.559824)
			(xy 355.312064 -244.608098) (xy 355.288413 -244.653161) (xy 355.25784 -244.693847) (xy 355.221136 -244.729102)
			(xy 355.179252 -244.758012) (xy 355.133273 -244.779829) (xy 355.084389 -244.793989) (xy 355.033868 -244.800123)
			(xy 354.983016 -244.798074) (xy 354.933152 -244.787894) (xy 354.885566 -244.769847) (xy 354.841492 -244.744401)
			(xy 354.80207 -244.712214) (xy 354.768322 -244.67412) (xy 354.741121 -244.631106) (xy 354.721173 -244.584286)
			(xy 354.708994 -244.534872) (xy 354.704899 -244.484144) (xy 354.396802 -244.484144) (xy 354.39629 -244.50959)
			(xy 354.388126 -244.559824) (xy 354.37201 -244.608098) (xy 354.348359 -244.653161) (xy 354.317786 -244.693847)
			(xy 354.281082 -244.729102) (xy 354.239198 -244.758012) (xy 354.193219 -244.779829) (xy 354.144335 -244.793989)
			(xy 354.093814 -244.800123) (xy 354.042962 -244.798074) (xy 353.993098 -244.787894) (xy 353.945512 -244.769847)
			(xy 353.901438 -244.744401) (xy 353.862016 -244.712214) (xy 353.828268 -244.67412) (xy 353.801067 -244.631106)
			(xy 353.781119 -244.584286) (xy 353.76894 -244.534872) (xy 353.764845 -244.484144) (xy 353.459034 -244.484144)
			(xy 353.458544 -244.509133) (xy 353.450725 -244.558496) (xy 353.435281 -244.606028) (xy 353.412591 -244.65056)
			(xy 353.383215 -244.690993) (xy 353.347875 -244.726333) (xy 353.307442 -244.755709) (xy 353.26291 -244.778399)
			(xy 353.215378 -244.793843) (xy 353.166015 -244.801662) (xy 353.116037 -244.801662) (xy 353.066674 -244.793843)
			(xy 353.019142 -244.778399) (xy 352.97461 -244.755709) (xy 352.934177 -244.726333) (xy 352.898837 -244.690993)
			(xy 352.869461 -244.65056) (xy 352.846771 -244.606028) (xy 352.831327 -244.558496) (xy 352.823508 -244.509133)
			(xy 352.516445 -244.509133) (xy 352.516436 -244.50959) (xy 352.508272 -244.559824) (xy 352.492156 -244.608098)
			(xy 352.468505 -244.653161) (xy 352.437932 -244.693847) (xy 352.401228 -244.729102) (xy 352.359344 -244.758012)
			(xy 352.313365 -244.779829) (xy 352.264481 -244.793989) (xy 352.21396 -244.800123) (xy 352.163108 -244.798074)
			(xy 352.113244 -244.787894) (xy 352.065658 -244.769847) (xy 352.021584 -244.744401) (xy 351.982162 -244.712214)
			(xy 351.948414 -244.67412) (xy 351.921213 -244.631106) (xy 351.901265 -244.584286) (xy 351.889086 -244.534872)
			(xy 351.884991 -244.484144) (xy 351.576894 -244.484144) (xy 351.576382 -244.50959) (xy 351.568218 -244.559824)
			(xy 351.552102 -244.608098) (xy 351.528451 -244.653161) (xy 351.497878 -244.693847) (xy 351.461174 -244.729102)
			(xy 351.41929 -244.758012) (xy 351.373311 -244.779829) (xy 351.324427 -244.793989) (xy 351.273906 -244.800123)
			(xy 351.223054 -244.798074) (xy 351.17319 -244.787894) (xy 351.125604 -244.769847) (xy 351.08153 -244.744401)
			(xy 351.042108 -244.712214) (xy 351.00836 -244.67412) (xy 350.981159 -244.631106) (xy 350.961211 -244.584286)
			(xy 350.949032 -244.534872) (xy 350.944937 -244.484144) (xy 350.639126 -244.484144) (xy 350.638636 -244.509133)
			(xy 350.630817 -244.558496) (xy 350.615373 -244.606028) (xy 350.592683 -244.65056) (xy 350.563307 -244.690993)
			(xy 350.527967 -244.726333) (xy 350.487534 -244.755709) (xy 350.443002 -244.778399) (xy 350.39547 -244.793843)
			(xy 350.346107 -244.801662) (xy 350.296129 -244.801662) (xy 350.246766 -244.793843) (xy 350.199234 -244.778399)
			(xy 350.154702 -244.755709) (xy 350.114269 -244.726333) (xy 350.078929 -244.690993) (xy 350.049553 -244.65056)
			(xy 350.026863 -244.606028) (xy 350.011419 -244.558496) (xy 350.0036 -244.509133) (xy 349.696283 -244.509133)
			(xy 349.696274 -244.50959) (xy 349.68811 -244.559824) (xy 349.671994 -244.608098) (xy 349.648343 -244.653161)
			(xy 349.61777 -244.693847) (xy 349.581066 -244.729102) (xy 349.539182 -244.758012) (xy 349.493203 -244.779829)
			(xy 349.444319 -244.793989) (xy 349.393798 -244.800123) (xy 349.342946 -244.798074) (xy 349.293082 -244.787894)
			(xy 349.245496 -244.769847) (xy 349.201422 -244.744401) (xy 349.162 -244.712214) (xy 349.128252 -244.67412)
			(xy 349.101051 -244.631106) (xy 349.081103 -244.584286) (xy 349.068924 -244.534872) (xy 349.064829 -244.484144)
			(xy 348.756732 -244.484144) (xy 348.75622 -244.50959) (xy 348.748056 -244.559824) (xy 348.73194 -244.608098)
			(xy 348.708289 -244.653161) (xy 348.677716 -244.693847) (xy 348.641012 -244.729102) (xy 348.599128 -244.758012)
			(xy 348.553149 -244.779829) (xy 348.504265 -244.793989) (xy 348.453744 -244.800123) (xy 348.402892 -244.798074)
			(xy 348.353028 -244.787894) (xy 348.305442 -244.769847) (xy 348.261368 -244.744401) (xy 348.221946 -244.712214)
			(xy 348.188198 -244.67412) (xy 348.160997 -244.631106) (xy 348.141049 -244.584286) (xy 348.12887 -244.534872)
			(xy 348.124775 -244.484144) (xy 347.819218 -244.484144) (xy 347.818728 -244.509133) (xy 347.810909 -244.558496)
			(xy 347.795465 -244.606028) (xy 347.772775 -244.65056) (xy 347.743399 -244.690993) (xy 347.708059 -244.726333)
			(xy 347.667626 -244.755709) (xy 347.623094 -244.778399) (xy 347.575562 -244.793843) (xy 347.526199 -244.801662)
			(xy 347.476221 -244.801662) (xy 347.426858 -244.793843) (xy 347.379326 -244.778399) (xy 347.334794 -244.755709)
			(xy 347.294361 -244.726333) (xy 347.259021 -244.690993) (xy 347.229645 -244.65056) (xy 347.206955 -244.606028)
			(xy 347.191511 -244.558496) (xy 347.183692 -244.509133) (xy 346.876375 -244.509133) (xy 346.876366 -244.50959)
			(xy 346.868202 -244.559824) (xy 346.852086 -244.608098) (xy 346.828435 -244.653161) (xy 346.797862 -244.693847)
			(xy 346.761158 -244.729102) (xy 346.719274 -244.758012) (xy 346.673295 -244.779829) (xy 346.624411 -244.793989)
			(xy 346.57389 -244.800123) (xy 346.523038 -244.798074) (xy 346.473174 -244.787894) (xy 346.425588 -244.769847)
			(xy 346.381514 -244.744401) (xy 346.342092 -244.712214) (xy 346.308344 -244.67412) (xy 346.281143 -244.631106)
			(xy 346.261195 -244.584286) (xy 346.249016 -244.534872) (xy 346.244921 -244.484144) (xy 345.936824 -244.484144)
			(xy 345.936312 -244.50959) (xy 345.928148 -244.559824) (xy 345.912032 -244.608098) (xy 345.888381 -244.653161)
			(xy 345.857808 -244.693847) (xy 345.821104 -244.729102) (xy 345.77922 -244.758012) (xy 345.733241 -244.779829)
			(xy 345.684357 -244.793989) (xy 345.633836 -244.800123) (xy 345.582984 -244.798074) (xy 345.53312 -244.787894)
			(xy 345.485534 -244.769847) (xy 345.44146 -244.744401) (xy 345.402038 -244.712214) (xy 345.36829 -244.67412)
			(xy 345.341089 -244.631106) (xy 345.321141 -244.584286) (xy 345.308962 -244.534872) (xy 345.304867 -244.484144)
			(xy 344.999056 -244.484144) (xy 344.999056 -244.484398) (xy 344.997786 -244.513608) (xy 344.997532 -244.51818)
			(xy 344.997532 -245.319139) (xy 346.713538 -245.319139) (xy 346.713538 -245.269161) (xy 346.721357 -245.219798)
			(xy 346.736801 -245.172266) (xy 346.759491 -245.127734) (xy 346.788867 -245.087301) (xy 346.824207 -245.051961)
			(xy 346.86464 -245.022585) (xy 346.909172 -244.999895) (xy 346.956704 -244.984451) (xy 347.006067 -244.976632)
			(xy 347.056045 -244.976632) (xy 347.105408 -244.984451) (xy 347.15294 -244.999895) (xy 347.197472 -245.022585)
			(xy 347.237905 -245.051961) (xy 347.273245 -245.087301) (xy 347.302621 -245.127734) (xy 347.325311 -245.172266)
			(xy 347.340755 -245.219798) (xy 347.348574 -245.269161) (xy 347.349064 -245.29415) (xy 347.348574 -245.319139)
			(xy 347.340755 -245.368502) (xy 347.325311 -245.416034) (xy 347.302621 -245.460566) (xy 347.273245 -245.500999)
			(xy 347.237905 -245.536339) (xy 347.197472 -245.565715) (xy 347.15294 -245.588405) (xy 347.105408 -245.603849)
			(xy 347.056045 -245.611668) (xy 347.006067 -245.611668) (xy 346.956704 -245.603849) (xy 346.909172 -245.588405)
			(xy 346.86464 -245.565715) (xy 346.824207 -245.536339) (xy 346.788867 -245.500999) (xy 346.759491 -245.460566)
			(xy 346.736801 -245.416034) (xy 346.721357 -245.368502) (xy 346.713538 -245.319139) (xy 344.997532 -245.319139)
			(xy 344.997532 -246.07012) (xy 344.997786 -246.074692) (xy 344.999056 -246.103902) (xy 344.999056 -246.104156)
			(xy 345.304867 -246.104156) (xy 345.308962 -246.053428) (xy 345.321141 -246.004014) (xy 345.341089 -245.957194)
			(xy 345.36829 -245.91418) (xy 345.402038 -245.876086) (xy 345.44146 -245.843899) (xy 345.485534 -245.818453)
			(xy 345.53312 -245.800406) (xy 345.582984 -245.790226) (xy 345.633836 -245.788177) (xy 345.684357 -245.794311)
			(xy 345.733241 -245.808471) (xy 345.77922 -245.830288) (xy 345.821104 -245.859198) (xy 345.857808 -245.894453)
			(xy 345.888381 -245.935139) (xy 345.912032 -245.980202) (xy 345.928148 -246.028476) (xy 345.936312 -246.07871)
			(xy 345.936824 -246.104156) (xy 346.244921 -246.104156) (xy 346.249016 -246.053428) (xy 346.261195 -246.004014)
			(xy 346.281143 -245.957194) (xy 346.308344 -245.91418) (xy 346.342092 -245.876086) (xy 346.381514 -245.843899)
			(xy 346.425588 -245.818453) (xy 346.473174 -245.800406) (xy 346.523038 -245.790226) (xy 346.57389 -245.788177)
			(xy 346.624411 -245.794311) (xy 346.673295 -245.808471) (xy 346.719274 -245.830288) (xy 346.761158 -245.859198)
			(xy 346.797862 -245.894453) (xy 346.828435 -245.935139) (xy 346.852086 -245.980202) (xy 346.868202 -246.028476)
			(xy 346.876366 -246.07871) (xy 346.876878 -246.104156) (xy 346.876868 -246.104664) (xy 347.119956 -246.104664)
			(xy 347.119956 -246.104156) (xy 347.120436 -246.076917) (xy 347.128191 -246.022993) (xy 347.143537 -245.970721)
			(xy 347.166162 -245.921163) (xy 347.195606 -245.875326) (xy 347.23127 -245.834144) (xy 347.272429 -245.798454)
			(xy 347.318246 -245.76898) (xy 347.36779 -245.746323) (xy 347.420052 -245.730943) (xy 347.473971 -245.723154)
			(xy 347.50121 -245.722648) (xy 347.531188 -245.723235) (xy 347.590403 -245.732627) (xy 347.647421 -245.751163)
			(xy 347.700839 -245.778386) (xy 347.749344 -245.813627) (xy 347.770958 -245.834408) (xy 347.800676 -245.864126)
			(xy 347.808087 -245.870952) (xy 347.826678 -245.878679) (xy 347.836744 -245.879112) (xy 348.19971 -245.879112)
			(xy 348.208811 -245.878719) (xy 348.225861 -245.872343) (xy 348.232984 -245.866666) (xy 348.254725 -245.848537)
			(xy 348.303299 -245.819483) (xy 348.356272 -245.799547) (xy 348.411949 -245.789367) (xy 348.440248 -245.788688)
			(xy 348.44101 -245.788688) (xy 348.465796 -245.789263) (xy 348.514756 -245.797019) (xy 348.561901 -245.812339)
			(xy 348.606069 -245.834845) (xy 348.646172 -245.863983) (xy 348.681224 -245.899035) (xy 348.710361 -245.93914)
			(xy 348.732865 -245.983308) (xy 348.748183 -246.030453) (xy 348.755938 -246.079414) (xy 348.755938 -246.107936)
			(xy 349.064978 -246.107936) (xy 349.068443 -246.057381) (xy 349.079943 -246.00803) (xy 349.099183 -245.961152)
			(xy 349.125667 -245.91795) (xy 349.158716 -245.879537) (xy 349.197479 -245.846899) (xy 349.240959 -245.820876)
			(xy 349.28804 -245.802137) (xy 349.337511 -245.791163) (xy 349.362776 -245.789196) (xy 349.371942 -245.788243)
			(xy 349.388733 -245.780676) (xy 349.395542 -245.774464) (xy 349.417386 -245.752874) (xy 349.424228 -245.745475)
			(xy 349.431947 -245.726875) (xy 349.432372 -245.716806) (xy 349.432372 -245.233952) (xy 349.432848 -245.223945)
			(xy 349.440518 -245.205457) (xy 349.454674 -245.191307) (xy 349.473165 -245.183644) (xy 349.483172 -245.183152)
			(xy 349.53448 -245.183152) (xy 349.559118 -245.167912) (xy 349.565468 -245.154704) (xy 349.577054 -245.132116)
			(xy 349.606266 -245.090604) (xy 349.641705 -245.054261) (xy 349.68247 -245.024013) (xy 349.727524 -245.000629)
			(xy 349.775721 -244.984701) (xy 349.825837 -244.976637) (xy 349.851218 -244.976142) (xy 349.876212 -244.97654)
			(xy 349.925585 -244.984363) (xy 349.973125 -244.999814) (xy 350.017663 -245.022512) (xy 350.058102 -245.051899)
			(xy 350.093446 -245.08725) (xy 350.122823 -245.127695) (xy 350.145512 -245.172238) (xy 350.160953 -245.219782)
			(xy 350.168765 -245.269156) (xy 350.169226 -245.29415) (xy 352.353118 -245.29415) (xy 352.353603 -245.269159)
			(xy 352.361415 -245.219791) (xy 352.376856 -245.172254) (xy 352.399543 -245.127717) (xy 352.428919 -245.087279)
			(xy 352.464261 -245.051935) (xy 352.504697 -245.022556) (xy 352.549231 -244.999865) (xy 352.596768 -244.984421)
			(xy 352.646135 -244.976605) (xy 352.671126 -244.976142) (xy 352.697737 -244.976687) (xy 352.750219 -244.985523)
			(xy 352.800497 -245.002977) (xy 352.847165 -245.028562) (xy 352.888921 -245.061562) (xy 352.924596 -245.101056)
			(xy 352.93935 -245.123208) (xy 352.956876 -245.123208) (xy 352.956876 -245.15445) (xy 352.961378 -245.162851)
			(xy 352.975344 -245.1758) (xy 352.993073 -245.182756) (xy 353.002596 -245.183152) (xy 353.170744 -245.183152)
			(xy 353.180749 -245.183651) (xy 353.199232 -245.191316) (xy 353.213382 -245.205465) (xy 353.221048 -245.223948)
			(xy 353.221544 -245.233952) (xy 353.221544 -245.759478) (xy 353.221997 -245.769753) (xy 353.230048 -245.78866)
			(xy 353.244869 -245.802894) (xy 353.25431 -245.806976) (xy 353.276575 -245.81593) (xy 353.318334 -245.839579)
			(xy 353.356066 -245.869231) (xy 353.388917 -245.904214) (xy 353.416141 -245.943734) (xy 353.437121 -245.986895)
			(xy 353.451379 -246.032717) (xy 353.458594 -246.080161) (xy 353.459034 -246.104156) (xy 353.764845 -246.104156)
			(xy 353.76894 -246.053428) (xy 353.781119 -246.004014) (xy 353.801067 -245.957194) (xy 353.828268 -245.91418)
			(xy 353.862016 -245.876086) (xy 353.901438 -245.843899) (xy 353.945512 -245.818453) (xy 353.993098 -245.800406)
			(xy 354.042962 -245.790226) (xy 354.093814 -245.788177) (xy 354.144335 -245.794311) (xy 354.193219 -245.808471)
			(xy 354.239198 -245.830288) (xy 354.281082 -245.859198) (xy 354.317786 -245.894453) (xy 354.348359 -245.935139)
			(xy 354.37201 -245.980202) (xy 354.388126 -246.028476) (xy 354.39629 -246.07871) (xy 354.396802 -246.104156)
			(xy 354.705412 -246.104156) (xy 354.705907 -246.079071) (xy 354.713826 -246.02953) (xy 354.729488 -245.981868)
			(xy 354.752499 -245.937286) (xy 354.782278 -245.896911) (xy 354.818074 -245.861759) (xy 354.858983 -245.832717)
			(xy 354.903975 -245.81052) (xy 354.951914 -245.795725) (xy 354.976684 -245.791736) (xy 354.976938 -245.791736)
			(xy 354.985866 -245.790033) (xy 355.001782 -245.781286) (xy 355.013654 -245.767542) (xy 355.019995 -245.750524)
			(xy 355.020372 -245.741444) (xy 355.020372 -245.233952) (xy 355.020848 -245.223945) (xy 355.028518 -245.205457)
			(xy 355.042674 -245.191307) (xy 355.061165 -245.183644) (xy 355.071172 -245.183152) (xy 355.174296 -245.183152)
			(xy 355.198934 -245.167912) (xy 355.205284 -245.154704) (xy 355.216857 -245.13211) (xy 355.246072 -245.090597)
			(xy 355.281513 -245.054255) (xy 355.32228 -245.024007) (xy 355.367335 -245.000624) (xy 355.415535 -244.984698)
			(xy 355.465653 -244.976636) (xy 355.491034 -244.976142) (xy 355.516029 -244.976525) (xy 355.565402 -244.984351)
			(xy 355.612943 -244.999804) (xy 355.657481 -245.022504) (xy 355.697919 -245.051892) (xy 355.733262 -245.087245)
			(xy 355.76264 -245.127691) (xy 355.785328 -245.172235) (xy 355.800769 -245.21978) (xy 355.808581 -245.269155)
			(xy 355.809042 -245.29415) (xy 356.114853 -245.29415) (xy 356.118948 -245.243422) (xy 356.131127 -245.194008)
			(xy 356.151075 -245.147188) (xy 356.178276 -245.104174) (xy 356.212024 -245.06608) (xy 356.251446 -245.033893)
			(xy 356.29552 -245.008447) (xy 356.343106 -244.9904) (xy 356.39297 -244.98022) (xy 356.443822 -244.978171)
			(xy 356.494343 -244.984305) (xy 356.543227 -244.998465) (xy 356.589206 -245.020282) (xy 356.63109 -245.049192)
			(xy 356.667794 -245.084447) (xy 356.698367 -245.125133) (xy 356.722018 -245.170196) (xy 356.738134 -245.21847)
			(xy 356.746298 -245.268704) (xy 356.74681 -245.29415) (xy 357.054907 -245.29415) (xy 357.059002 -245.243422)
			(xy 357.071181 -245.194008) (xy 357.091129 -245.147188) (xy 357.11833 -245.104174) (xy 357.152078 -245.06608)
			(xy 357.1915 -245.033893) (xy 357.235574 -245.008447) (xy 357.28316 -244.9904) (xy 357.333024 -244.98022)
			(xy 357.383876 -244.978171) (xy 357.434397 -244.984305) (xy 357.483281 -244.998465) (xy 357.52926 -245.020282)
			(xy 357.571144 -245.049192) (xy 357.607848 -245.084447) (xy 357.638421 -245.125133) (xy 357.662072 -245.170196)
			(xy 357.678188 -245.21847) (xy 357.686352 -245.268704) (xy 357.686864 -245.29415) (xy 357.686361 -245.319139)
			(xy 357.993678 -245.319139) (xy 357.993678 -245.269161) (xy 358.001497 -245.219798) (xy 358.016941 -245.172266)
			(xy 358.039631 -245.127734) (xy 358.069007 -245.087301) (xy 358.104347 -245.051961) (xy 358.14478 -245.022585)
			(xy 358.189312 -244.999895) (xy 358.236844 -244.984451) (xy 358.286207 -244.976632) (xy 358.336185 -244.976632)
			(xy 358.385548 -244.984451) (xy 358.43308 -244.999895) (xy 358.477612 -245.022585) (xy 358.518045 -245.051961)
			(xy 358.553385 -245.087301) (xy 358.582761 -245.127734) (xy 358.605451 -245.172266) (xy 358.620895 -245.219798)
			(xy 358.628714 -245.269161) (xy 358.629204 -245.29415) (xy 358.628714 -245.319139) (xy 358.620895 -245.368502)
			(xy 358.605451 -245.416034) (xy 358.582761 -245.460566) (xy 358.553385 -245.500999) (xy 358.518045 -245.536339)
			(xy 358.477612 -245.565715) (xy 358.43308 -245.588405) (xy 358.385548 -245.603849) (xy 358.336185 -245.611668)
			(xy 358.286207 -245.611668) (xy 358.236844 -245.603849) (xy 358.189312 -245.588405) (xy 358.14478 -245.565715)
			(xy 358.104347 -245.536339) (xy 358.069007 -245.500999) (xy 358.039631 -245.460566) (xy 358.016941 -245.416034)
			(xy 358.001497 -245.368502) (xy 357.993678 -245.319139) (xy 357.686361 -245.319139) (xy 357.686352 -245.319596)
			(xy 357.678188 -245.36983) (xy 357.662072 -245.418104) (xy 357.638421 -245.463167) (xy 357.607848 -245.503853)
			(xy 357.571144 -245.539108) (xy 357.52926 -245.568018) (xy 357.483281 -245.589835) (xy 357.434397 -245.603995)
			(xy 357.383876 -245.610129) (xy 357.333024 -245.60808) (xy 357.28316 -245.5979) (xy 357.235574 -245.579853)
			(xy 357.1915 -245.554407) (xy 357.152078 -245.52222) (xy 357.11833 -245.484126) (xy 357.091129 -245.441112)
			(xy 357.071181 -245.394292) (xy 357.059002 -245.344878) (xy 357.054907 -245.29415) (xy 356.74681 -245.29415)
			(xy 356.746298 -245.319596) (xy 356.738134 -245.36983) (xy 356.722018 -245.418104) (xy 356.698367 -245.463167)
			(xy 356.667794 -245.503853) (xy 356.63109 -245.539108) (xy 356.589206 -245.568018) (xy 356.543227 -245.589835)
			(xy 356.494343 -245.603995) (xy 356.443822 -245.610129) (xy 356.39297 -245.60808) (xy 356.343106 -245.5979)
			(xy 356.29552 -245.579853) (xy 356.251446 -245.554407) (xy 356.212024 -245.52222) (xy 356.178276 -245.484126)
			(xy 356.151075 -245.441112) (xy 356.131127 -245.394292) (xy 356.118948 -245.344878) (xy 356.114853 -245.29415)
			(xy 355.809042 -245.29415) (xy 355.809042 -245.294404) (xy 355.808682 -245.316527) (xy 355.802545 -245.360346)
			(xy 355.790377 -245.402886) (xy 355.772414 -245.443321) (xy 355.761036 -245.462298) (xy 355.757513 -245.468396)
			(xy 355.753642 -245.48193) (xy 355.753416 -245.488968) (xy 355.753416 -245.637812) (xy 355.753226 -245.651551)
			(xy 355.749791 -245.678813) (xy 355.746558 -245.692168) (xy 355.745796 -245.69547) (xy 355.744277 -245.705641)
			(xy 355.748704 -245.725712) (xy 355.760624 -245.742456) (xy 355.778141 -245.753209) (xy 355.798467 -245.756261)
			(xy 355.808534 -245.754144) (xy 355.815138 -245.751858) (xy 355.838362 -245.742609) (xy 355.886634 -245.729613)
			(xy 355.936193 -245.723051) (xy 355.961188 -245.722648) (xy 355.991165 -245.723249) (xy 356.050379 -245.732637)
			(xy 356.074349 -245.740428) (xy 359.375964 -245.740428) (xy 359.375964 -245.536212) (xy 359.376424 -245.51689)
			(xy 359.383396 -245.47888) (xy 359.397078 -245.442739) (xy 359.406698 -245.425976) (xy 359.410254 -245.418864)
			(xy 359.420586 -245.394523) (xy 359.447391 -245.348943) (xy 359.480643 -245.307829) (xy 359.51961 -245.272085)
			(xy 359.563435 -245.242498) (xy 359.611155 -245.219719) (xy 359.661719 -245.204249) (xy 359.714015 -245.196428)
			(xy 359.766893 -245.196428) (xy 359.819189 -245.204249) (xy 359.869753 -245.219719) (xy 359.917473 -245.242498)
			(xy 359.961298 -245.272085) (xy 360.000265 -245.307829) (xy 360.009412 -245.319139) (xy 360.807236 -245.319139)
			(xy 360.807236 -245.269161) (xy 360.815055 -245.219798) (xy 360.830499 -245.172266) (xy 360.853189 -245.127734)
			(xy 360.882565 -245.087301) (xy 360.917905 -245.051961) (xy 360.958338 -245.022585) (xy 361.00287 -244.999895)
			(xy 361.050402 -244.984451) (xy 361.099765 -244.976632) (xy 361.149743 -244.976632) (xy 361.199106 -244.984451)
			(xy 361.246638 -244.999895) (xy 361.29117 -245.022585) (xy 361.331603 -245.051961) (xy 361.366943 -245.087301)
			(xy 361.396319 -245.127734) (xy 361.419009 -245.172266) (xy 361.434453 -245.219798) (xy 361.442272 -245.269161)
			(xy 361.442762 -245.29415) (xy 361.748573 -245.29415) (xy 361.752668 -245.243422) (xy 361.764847 -245.194008)
			(xy 361.784795 -245.147188) (xy 361.811996 -245.104174) (xy 361.845744 -245.06608) (xy 361.885166 -245.033893)
			(xy 361.92924 -245.008447) (xy 361.976826 -244.9904) (xy 362.02669 -244.98022) (xy 362.077542 -244.978171)
			(xy 362.128063 -244.984305) (xy 362.176947 -244.998465) (xy 362.222926 -245.020282) (xy 362.26481 -245.049192)
			(xy 362.301514 -245.084447) (xy 362.332087 -245.125133) (xy 362.355738 -245.170196) (xy 362.371854 -245.21847)
			(xy 362.380018 -245.268704) (xy 362.38053 -245.29415) (xy 362.688627 -245.29415) (xy 362.692722 -245.243422)
			(xy 362.704901 -245.194008) (xy 362.724849 -245.147188) (xy 362.75205 -245.104174) (xy 362.785798 -245.06608)
			(xy 362.82522 -245.033893) (xy 362.869294 -245.008447) (xy 362.91688 -244.9904) (xy 362.966744 -244.98022)
			(xy 363.017596 -244.978171) (xy 363.068117 -244.984305) (xy 363.117001 -244.998465) (xy 363.16298 -245.020282)
			(xy 363.204864 -245.049192) (xy 363.241568 -245.084447) (xy 363.272141 -245.125133) (xy 363.295792 -245.170196)
			(xy 363.311908 -245.21847) (xy 363.320072 -245.268704) (xy 363.320584 -245.29415) (xy 363.320072 -245.319596)
			(xy 363.311908 -245.36983) (xy 363.295792 -245.418104) (xy 363.272141 -245.463167) (xy 363.241568 -245.503853)
			(xy 363.204864 -245.539108) (xy 363.16298 -245.568018) (xy 363.117001 -245.589835) (xy 363.068117 -245.603995)
			(xy 363.017596 -245.610129) (xy 362.966744 -245.60808) (xy 362.91688 -245.5979) (xy 362.869294 -245.579853)
			(xy 362.82522 -245.554407) (xy 362.785798 -245.52222) (xy 362.75205 -245.484126) (xy 362.724849 -245.441112)
			(xy 362.704901 -245.394292) (xy 362.692722 -245.344878) (xy 362.688627 -245.29415) (xy 362.38053 -245.29415)
			(xy 362.380018 -245.319596) (xy 362.371854 -245.36983) (xy 362.355738 -245.418104) (xy 362.332087 -245.463167)
			(xy 362.301514 -245.503853) (xy 362.26481 -245.539108) (xy 362.222926 -245.568018) (xy 362.176947 -245.589835)
			(xy 362.128063 -245.603995) (xy 362.077542 -245.610129) (xy 362.02669 -245.60808) (xy 361.976826 -245.5979)
			(xy 361.92924 -245.579853) (xy 361.885166 -245.554407) (xy 361.845744 -245.52222) (xy 361.811996 -245.484126)
			(xy 361.784795 -245.441112) (xy 361.764847 -245.394292) (xy 361.752668 -245.344878) (xy 361.748573 -245.29415)
			(xy 361.442762 -245.29415) (xy 361.442272 -245.319139) (xy 361.434453 -245.368502) (xy 361.419009 -245.416034)
			(xy 361.396319 -245.460566) (xy 361.366943 -245.500999) (xy 361.331603 -245.536339) (xy 361.29117 -245.565715)
			(xy 361.246638 -245.588405) (xy 361.199106 -245.603849) (xy 361.149743 -245.611668) (xy 361.099765 -245.611668)
			(xy 361.050402 -245.603849) (xy 361.00287 -245.588405) (xy 360.958338 -245.565715) (xy 360.917905 -245.536339)
			(xy 360.882565 -245.500999) (xy 360.853189 -245.460566) (xy 360.830499 -245.416034) (xy 360.815055 -245.368502)
			(xy 360.807236 -245.319139) (xy 360.009412 -245.319139) (xy 360.033517 -245.348943) (xy 360.060322 -245.394523)
			(xy 360.070654 -245.418864) (xy 360.07421 -245.425976) (xy 360.083864 -245.442724) (xy 360.097573 -245.478864)
			(xy 360.104532 -245.516885) (xy 360.104944 -245.536212) (xy 360.104944 -245.791228) (xy 360.0958 -245.791228)
			(xy 360.085775 -245.79162) (xy 360.067253 -245.799295) (xy 360.05308 -245.813476) (xy 360.045415 -245.832003)
			(xy 360.045 -245.842028) (xy 360.045 -246.005096) (xy 360.044577 -246.015117) (xy 360.036909 -246.033634)
			(xy 360.022737 -246.047806) (xy 360.004221 -246.055476) (xy 359.9942 -246.055896) (xy 359.486708 -246.055896)
			(xy 359.476687 -246.055474) (xy 359.458169 -246.047806) (xy 359.443996 -246.033634) (xy 359.436327 -246.015117)
			(xy 359.435908 -246.005096) (xy 359.435908 -245.791228) (xy 359.426764 -245.791228) (xy 359.416757 -245.790742)
			(xy 359.39827 -245.783076) (xy 359.38412 -245.768923) (xy 359.376456 -245.750435) (xy 359.375964 -245.740428)
			(xy 356.074349 -245.740428) (xy 356.107398 -245.75117) (xy 356.160816 -245.77839) (xy 356.209322 -245.813629)
			(xy 356.230936 -245.834408) (xy 356.276656 -245.880128) (xy 356.29797 -245.902341) (xy 356.333928 -245.952304)
			(xy 356.361408 -246.007387) (xy 356.371144 -246.036592) (xy 356.382066 -246.072152) (xy 356.396544 -246.072152)
			(xy 356.396544 -246.527828) (xy 356.396992 -246.537556) (xy 356.404316 -246.555584) (xy 356.410768 -246.56288)
			(xy 356.43185 -246.584978) (xy 356.438336 -246.591168) (xy 356.454467 -246.598973) (xy 356.463346 -246.600218)
			(xy 356.488915 -246.603354) (xy 356.538618 -246.616887) (xy 356.585463 -246.638314) (xy 356.628206 -246.667064)
			(xy 356.665711 -246.702375) (xy 356.696984 -246.743309) (xy 356.721192 -246.788778) (xy 356.737694 -246.837576)
			(xy 356.74605 -246.888406) (xy 356.746556 -246.914162) (xy 357.054907 -246.914162) (xy 357.059002 -246.863434)
			(xy 357.071181 -246.81402) (xy 357.091129 -246.7672) (xy 357.11833 -246.724186) (xy 357.152078 -246.686092)
			(xy 357.1915 -246.653905) (xy 357.235574 -246.628459) (xy 357.28316 -246.610412) (xy 357.333024 -246.600232)
			(xy 357.383876 -246.598183) (xy 357.434397 -246.604317) (xy 357.483281 -246.618477) (xy 357.494514 -246.623807)
			(xy 357.848875 -246.623807) (xy 357.854024 -246.604499) (xy 357.866168 -246.588629) (xy 357.87457 -246.5832)
			(xy 358.314498 -246.3292) (xy 358.323371 -246.324537) (xy 358.343228 -246.321909) (xy 358.362578 -246.327086)
			(xy 358.37847 -246.339278) (xy 358.38384 -246.347742) (xy 358.491028 -246.533416) (xy 358.499156 -246.528844)
			(xy 358.508081 -246.524316) (xy 358.527891 -246.521685) (xy 358.547201 -246.526835) (xy 358.56307 -246.538982)
			(xy 358.568498 -246.547386) (xy 358.670098 -246.723662) (xy 358.680028 -246.741888) (xy 358.693466 -246.781151)
			(xy 358.699074 -246.822269) (xy 358.699074 -246.822272) (xy 360.781829 -246.822272) (xy 360.787433 -246.781149)
			(xy 360.800861 -246.741879) (xy 360.81081 -246.723662) (xy 360.93781 -246.503444) (xy 360.945938 -246.508016)
			(xy 360.954793 -246.512716) (xy 360.97466 -246.515332) (xy 360.994015 -246.510144) (xy 361.009909 -246.497942)
			(xy 361.01528 -246.489474) (xy 361.097068 -246.347742) (xy 361.10244 -246.33928) (xy 361.118331 -246.327092)
			(xy 361.137679 -246.321918) (xy 361.157533 -246.324548) (xy 361.16641 -246.3292) (xy 361.606338 -246.5832)
			(xy 361.614786 -246.588576) (xy 361.626945 -246.604468) (xy 361.6321 -246.623802) (xy 361.629468 -246.643638)
			(xy 361.62488 -246.652542) (xy 361.517692 -246.837708) (xy 361.525566 -246.84228) (xy 361.534044 -246.847661)
			(xy 361.546357 -246.863491) (xy 361.55162 -246.882845) (xy 361.54902 -246.902731) (xy 361.544362 -246.911622)
			(xy 361.542895 -246.914162) (xy 361.748573 -246.914162) (xy 361.752668 -246.863434) (xy 361.764847 -246.81402)
			(xy 361.784795 -246.7672) (xy 361.811996 -246.724186) (xy 361.845744 -246.686092) (xy 361.885166 -246.653905)
			(xy 361.92924 -246.628459) (xy 361.976826 -246.610412) (xy 362.02669 -246.600232) (xy 362.077542 -246.598183)
			(xy 362.128063 -246.604317) (xy 362.176947 -246.618477) (xy 362.222926 -246.640294) (xy 362.26481 -246.669204)
			(xy 362.301514 -246.704459) (xy 362.332087 -246.745145) (xy 362.355738 -246.790208) (xy 362.371854 -246.838482)
			(xy 362.380018 -246.888716) (xy 362.38053 -246.914162) (xy 362.68914 -246.914162) (xy 362.689649 -246.88922)
			(xy 362.697499 -246.839957) (xy 362.712998 -246.792541) (xy 362.735761 -246.748152) (xy 362.765221 -246.707896)
			(xy 362.800645 -246.672772) (xy 362.841151 -246.643656) (xy 362.885732 -246.621273) (xy 362.933278 -246.606178)
			(xy 362.957872 -246.601996) (xy 362.966393 -246.600434) (xy 362.981717 -246.592374) (xy 362.987844 -246.586248)
			(xy 363.008164 -246.563896) (xy 363.014158 -246.556613) (xy 363.020934 -246.539028) (xy 363.021372 -246.529606)
			(xy 363.021372 -246.098568) (xy 363.022066 -246.086307) (xy 363.033336 -246.064535) (xy 363.042962 -246.056912)
			(xy 363.046518 -246.054372) (xy 363.052106 -246.038624) (xy 363.062043 -246.012478) (xy 363.08848 -245.963187)
			(xy 363.121831 -245.918284) (xy 363.14126 -245.898162) (xy 363.205014 -245.834408) (xy 363.226588 -245.813581)
			(xy 363.275096 -245.77833) (xy 363.328523 -245.751104) (xy 363.385553 -245.732576) (xy 363.44478 -245.723201)
			(xy 363.474762 -245.722648) (xy 363.50756 -245.72332) (xy 363.572185 -245.734565) (xy 363.603286 -245.745)
			(xy 363.613713 -245.748208) (xy 363.635432 -245.746396) (xy 363.654442 -245.735738) (xy 363.667319 -245.718154)
			(xy 363.671743 -245.696813) (xy 363.669834 -245.686072) (xy 363.667303 -245.674169) (xy 363.66463 -245.64998)
			(xy 363.6645 -245.637812) (xy 363.6645 -245.450614) (xy 363.66196 -245.439438) (xy 363.65942 -245.434358)
			(xy 363.649196 -245.412456) (xy 363.634731 -245.36634) (xy 363.627384 -245.318569) (xy 363.626908 -245.294404)
			(xy 363.626908 -245.29415) (xy 363.627403 -245.269159) (xy 363.635215 -245.219793) (xy 363.650655 -245.172256)
			(xy 363.673341 -245.12772) (xy 363.702717 -245.087282) (xy 363.738057 -245.051939) (xy 363.778491 -245.022559)
			(xy 363.823024 -244.999868) (xy 363.870559 -244.984423) (xy 363.919925 -244.976606) (xy 363.944916 -244.976142)
			(xy 363.970293 -244.976674) (xy 364.020402 -244.984751) (xy 364.068592 -245.000682) (xy 364.113642 -245.024062)
			(xy 364.154407 -245.054299) (xy 364.189855 -245.090624) (xy 364.219086 -245.132117) (xy 364.230666 -245.154704)
			(xy 364.235261 -245.163006) (xy 364.249244 -245.175808) (xy 364.266908 -245.182696) (xy 364.276386 -245.183152)
			(xy 364.346744 -245.183152) (xy 364.356749 -245.183651) (xy 364.375232 -245.191316) (xy 364.389382 -245.205465)
			(xy 364.397048 -245.223948) (xy 364.397544 -245.233952) (xy 364.397544 -245.7196) (xy 364.39786 -245.729045)
			(xy 364.404658 -245.746666) (xy 364.410752 -245.75389) (xy 364.431072 -245.775988) (xy 364.437191 -245.78216)
			(xy 364.452511 -245.790343) (xy 364.461044 -245.79199) (xy 364.485679 -245.796095) (xy 364.533304 -245.81113)
			(xy 364.577967 -245.833475) (xy 364.618556 -245.862574) (xy 364.654056 -245.897701) (xy 364.683583 -245.93798)
			(xy 364.706399 -245.982404) (xy 364.721936 -246.029868) (xy 364.729806 -246.079185) (xy 364.730284 -246.104156)
			(xy 365.038635 -246.104156) (xy 365.04273 -246.053428) (xy 365.054909 -246.004014) (xy 365.074857 -245.957194)
			(xy 365.102058 -245.91418) (xy 365.135806 -245.876086) (xy 365.175228 -245.843899) (xy 365.219302 -245.818453)
			(xy 365.266888 -245.800406) (xy 365.316752 -245.790226) (xy 365.367604 -245.788177) (xy 365.418125 -245.794311)
			(xy 365.467009 -245.808471) (xy 365.512988 -245.830288) (xy 365.554872 -245.859198) (xy 365.591576 -245.894453)
			(xy 365.622149 -245.935139) (xy 365.6458 -245.980202) (xy 365.661916 -246.028476) (xy 365.67008 -246.07871)
			(xy 365.670592 -246.104156) (xy 365.976916 -246.104156) (xy 365.977472 -246.078454) (xy 365.985754 -246.027722)
			(xy 366.002081 -245.97898) (xy 366.026026 -245.933495) (xy 366.05697 -245.892448) (xy 366.094106 -245.856906)
			(xy 366.136471 -245.827793) (xy 366.182963 -245.805865) (xy 366.232375 -245.791693) (xy 366.25784 -245.78818)
			(xy 366.266596 -245.786774) (xy 366.282445 -245.778844) (xy 366.288828 -245.772686) (xy 366.309402 -245.750842)
			(xy 366.315743 -245.743493) (xy 366.322936 -245.725485) (xy 366.323372 -245.71579) (xy 366.323372 -245.233952)
			(xy 366.323848 -245.223945) (xy 366.331518 -245.205457) (xy 366.345674 -245.191307) (xy 366.364165 -245.183644)
			(xy 366.374172 -245.183152) (xy 366.448086 -245.183152) (xy 366.472724 -245.167912) (xy 366.479074 -245.154704)
			(xy 366.490655 -245.132114) (xy 366.519868 -245.090601) (xy 366.555308 -245.054259) (xy 366.596074 -245.024011)
			(xy 366.641128 -245.000627) (xy 366.689326 -244.9847) (xy 366.739443 -244.976636) (xy 366.764824 -244.976142)
			(xy 366.789818 -244.976534) (xy 366.839191 -244.984359) (xy 366.886732 -244.99981) (xy 366.93127 -245.022509)
			(xy 366.971709 -245.051896) (xy 367.007052 -245.087248) (xy 367.03643 -245.127693) (xy 367.059118 -245.172237)
			(xy 367.074559 -245.219781) (xy 367.082371 -245.269156) (xy 367.082832 -245.29415) (xy 369.266724 -245.29415)
			(xy 369.267203 -245.269159) (xy 369.275016 -245.21979) (xy 369.290456 -245.172252) (xy 369.313144 -245.127715)
			(xy 369.342521 -245.087277) (xy 369.377863 -245.051933) (xy 369.4183 -245.022554) (xy 369.462836 -244.999863)
			(xy 369.510373 -244.98442) (xy 369.559741 -244.976605) (xy 369.584732 -244.976142) (xy 369.61011 -244.976661)
			(xy 369.660219 -244.984741) (xy 369.708409 -245.000674) (xy 369.753459 -245.024056) (xy 369.794225 -245.054295)
			(xy 369.829672 -245.090622) (xy 369.858902 -245.132116) (xy 369.870482 -245.154704) (xy 369.87502 -245.163048)
			(xy 369.889024 -245.175864) (xy 369.906711 -245.182755) (xy 369.916202 -245.183152) (xy 370.061744 -245.183152)
			(xy 370.071749 -245.183651) (xy 370.090232 -245.191316) (xy 370.104382 -245.205465) (xy 370.112048 -245.223948)
			(xy 370.112544 -245.233952) (xy 370.112544 -245.319139) (xy 372.087376 -245.319139) (xy 372.087376 -245.269161)
			(xy 372.095195 -245.219798) (xy 372.110639 -245.172266) (xy 372.133329 -245.127734) (xy 372.162705 -245.087301)
			(xy 372.198045 -245.051961) (xy 372.238478 -245.022585) (xy 372.28301 -244.999895) (xy 372.330542 -244.984451)
			(xy 372.379905 -244.976632) (xy 372.429883 -244.976632) (xy 372.479246 -244.984451) (xy 372.526778 -244.999895)
			(xy 372.57131 -245.022585) (xy 372.611743 -245.051961) (xy 372.647083 -245.087301) (xy 372.676459 -245.127734)
			(xy 372.699149 -245.172266) (xy 372.714593 -245.219798) (xy 372.722412 -245.269161) (xy 372.722902 -245.29415)
			(xy 372.722412 -245.319139) (xy 372.714593 -245.368502) (xy 372.699149 -245.416034) (xy 372.676459 -245.460566)
			(xy 372.647083 -245.500999) (xy 372.611743 -245.536339) (xy 372.57131 -245.565715) (xy 372.526778 -245.588405)
			(xy 372.479246 -245.603849) (xy 372.429883 -245.611668) (xy 372.379905 -245.611668) (xy 372.330542 -245.603849)
			(xy 372.28301 -245.588405) (xy 372.238478 -245.565715) (xy 372.198045 -245.536339) (xy 372.162705 -245.500999)
			(xy 372.133329 -245.460566) (xy 372.110639 -245.416034) (xy 372.095195 -245.368502) (xy 372.087376 -245.319139)
			(xy 370.112544 -245.319139) (xy 370.112544 -245.770908) (xy 370.132356 -245.797832) (xy 370.148358 -245.802658)
			(xy 370.172162 -245.81056) (xy 370.217126 -245.832776) (xy 370.258009 -245.861825) (xy 370.293782 -245.896976)
			(xy 370.323543 -245.937344) (xy 370.346544 -245.981912) (xy 370.362204 -246.029557) (xy 370.370129 -246.07908)
			(xy 370.370608 -246.104156) (xy 370.370121 -246.128966) (xy 370.370117 -246.128992) (xy 370.679674 -246.128992)
			(xy 370.679674 -246.079408) (xy 370.687431 -246.030433) (xy 370.702753 -245.983275) (xy 370.725263 -245.939095)
			(xy 370.754408 -245.898979) (xy 370.789469 -245.863917) (xy 370.829583 -245.83477) (xy 370.873762 -245.812258)
			(xy 370.92092 -245.796934) (xy 370.969894 -245.789175) (xy 370.994686 -245.788688) (xy 371.021315 -245.78924)
			(xy 371.073817 -245.798173) (xy 371.124076 -245.81579) (xy 371.170667 -245.841589) (xy 371.212269 -245.87484)
			(xy 371.230398 -245.894352) (xy 371.237216 -245.901383) (xy 371.254718 -245.910136) (xy 371.264434 -245.91137)
			(xy 371.317774 -245.915434) (xy 371.325394 -245.908576) (xy 371.342412 -245.89359) (xy 371.342412 -245.879112)
			(xy 371.353588 -245.879112) (xy 371.367558 -245.874794) (xy 371.373908 -245.87073) (xy 371.374416 -245.870222)
			(xy 371.400818 -245.852769) (xy 371.457293 -245.824198) (xy 371.517022 -245.803264) (xy 371.547898 -245.796308)
			(xy 371.555264 -245.794784) (xy 371.567964 -245.787926) (xy 371.59311 -245.762526) (xy 371.615865 -245.740549)
			(xy 371.666056 -245.702043) (xy 371.720842 -245.670415) (xy 371.779287 -245.646206) (xy 371.840391 -245.629831)
			(xy 371.90311 -245.621569) (xy 371.93474 -245.621048) (xy 371.96637 -245.621571) (xy 372.029088 -245.629833)
			(xy 372.090191 -245.646209) (xy 372.148634 -245.67042) (xy 372.203418 -245.702051) (xy 372.253605 -245.740561)
			(xy 372.298336 -245.785292) (xy 372.336847 -245.835479) (xy 372.368479 -245.890262) (xy 372.39269 -245.948705)
			(xy 372.409066 -246.009808) (xy 372.417328 -246.072526) (xy 372.417848 -246.104156) (xy 372.558559 -246.104156)
			(xy 372.562654 -246.053428) (xy 372.574833 -246.004014) (xy 372.594781 -245.957194) (xy 372.621982 -245.91418)
			(xy 372.65573 -245.876086) (xy 372.695152 -245.843899) (xy 372.739226 -245.818453) (xy 372.786812 -245.800406)
			(xy 372.836676 -245.790226) (xy 372.887528 -245.788177) (xy 372.938049 -245.794311) (xy 372.986933 -245.808471)
			(xy 373.032912 -245.830288) (xy 373.074796 -245.859198) (xy 373.1115 -245.894453) (xy 373.142073 -245.935139)
			(xy 373.165724 -245.980202) (xy 373.18184 -246.028476) (xy 373.190004 -246.07871) (xy 373.190516 -246.104156)
			(xy 373.498613 -246.104156) (xy 373.502708 -246.053428) (xy 373.514887 -246.004014) (xy 373.534835 -245.957194)
			(xy 373.562036 -245.91418) (xy 373.595784 -245.876086) (xy 373.635206 -245.843899) (xy 373.67928 -245.818453)
			(xy 373.726866 -245.800406) (xy 373.77673 -245.790226) (xy 373.827582 -245.788177) (xy 373.878103 -245.794311)
			(xy 373.926987 -245.808471) (xy 373.972966 -245.830288) (xy 374.01485 -245.859198) (xy 374.051554 -245.894453)
			(xy 374.082127 -245.935139) (xy 374.105778 -245.980202) (xy 374.121894 -246.028476) (xy 374.130058 -246.07871)
			(xy 374.13057 -246.104156) (xy 374.130058 -246.129602) (xy 374.121894 -246.179836) (xy 374.105778 -246.22811)
			(xy 374.082127 -246.273173) (xy 374.051554 -246.313859) (xy 374.01485 -246.349114) (xy 373.972966 -246.378024)
			(xy 373.926987 -246.399841) (xy 373.878103 -246.414001) (xy 373.827582 -246.420135) (xy 373.77673 -246.418086)
			(xy 373.726866 -246.407906) (xy 373.67928 -246.389859) (xy 373.635206 -246.364413) (xy 373.595784 -246.332226)
			(xy 373.562036 -246.294132) (xy 373.534835 -246.251118) (xy 373.514887 -246.204298) (xy 373.502708 -246.154884)
			(xy 373.498613 -246.104156) (xy 373.190516 -246.104156) (xy 373.190004 -246.129602) (xy 373.18184 -246.179836)
			(xy 373.165724 -246.22811) (xy 373.142073 -246.273173) (xy 373.1115 -246.313859) (xy 373.074796 -246.349114)
			(xy 373.032912 -246.378024) (xy 372.986933 -246.399841) (xy 372.938049 -246.414001) (xy 372.887528 -246.420135)
			(xy 372.836676 -246.418086) (xy 372.786812 -246.407906) (xy 372.739226 -246.389859) (xy 372.695152 -246.364413)
			(xy 372.65573 -246.332226) (xy 372.621982 -246.294132) (xy 372.594781 -246.251118) (xy 372.574833 -246.204298)
			(xy 372.562654 -246.154884) (xy 372.558559 -246.104156) (xy 372.417848 -246.104156) (xy 372.417337 -246.135789)
			(xy 372.409094 -246.198516) (xy 372.392731 -246.259629) (xy 372.368529 -246.318082) (xy 372.3369 -246.372875)
			(xy 372.298388 -246.423068) (xy 372.27637 -246.445786) (xy 372.111524 -246.610632) (xy 372.090738 -246.63075)
			(xy 372.045224 -246.666452) (xy 371.995766 -246.696454) (xy 371.943073 -246.720324) (xy 371.887904 -246.737719)
			(xy 371.859556 -246.743474) (xy 371.859302 -246.743474) (xy 371.849823 -246.745848) (xy 371.833492 -246.756544)
			(xy 371.827552 -246.764302) (xy 371.780816 -246.831358) (xy 371.776498 -246.850408) (xy 371.778276 -246.860568)
			(xy 371.78041 -246.873864) (xy 371.782696 -246.900697) (xy 371.782848 -246.914162) (xy 371.782358 -246.939151)
			(xy 372.087376 -246.939151) (xy 372.087376 -246.889173) (xy 372.095195 -246.83981) (xy 372.110639 -246.792278)
			(xy 372.133329 -246.747746) (xy 372.162705 -246.707313) (xy 372.198045 -246.671973) (xy 372.238478 -246.642597)
			(xy 372.28301 -246.619907) (xy 372.330542 -246.604463) (xy 372.379905 -246.596644) (xy 372.429883 -246.596644)
			(xy 372.479246 -246.604463) (xy 372.526778 -246.619907) (xy 372.57131 -246.642597) (xy 372.611743 -246.671973)
			(xy 372.647083 -246.707313) (xy 372.676459 -246.747746) (xy 372.699149 -246.792278) (xy 372.714593 -246.83981)
			(xy 372.722412 -246.889173) (xy 372.722902 -246.914162) (xy 372.722412 -246.939151) (xy 373.027176 -246.939151)
			(xy 373.027176 -246.889173) (xy 373.034995 -246.83981) (xy 373.050439 -246.792278) (xy 373.073129 -246.747746)
			(xy 373.102505 -246.707313) (xy 373.137845 -246.671973) (xy 373.178278 -246.642597) (xy 373.22281 -246.619907)
			(xy 373.270342 -246.604463) (xy 373.319705 -246.596644) (xy 373.369683 -246.596644) (xy 373.419046 -246.604463)
			(xy 373.466578 -246.619907) (xy 373.51111 -246.642597) (xy 373.551543 -246.671973) (xy 373.586883 -246.707313)
			(xy 373.616259 -246.747746) (xy 373.638949 -246.792278) (xy 373.654393 -246.83981) (xy 373.662212 -246.889173)
			(xy 373.662702 -246.914162) (xy 373.662212 -246.939151) (xy 373.654393 -246.988514) (xy 373.638949 -247.036046)
			(xy 373.616259 -247.080578) (xy 373.586883 -247.121011) (xy 373.551543 -247.156351) (xy 373.51111 -247.185727)
			(xy 373.466578 -247.208417) (xy 373.419046 -247.223861) (xy 373.369683 -247.23168) (xy 373.319705 -247.23168)
			(xy 373.270342 -247.223861) (xy 373.22281 -247.208417) (xy 373.178278 -247.185727) (xy 373.137845 -247.156351)
			(xy 373.102505 -247.121011) (xy 373.073129 -247.080578) (xy 373.050439 -247.036046) (xy 373.034995 -246.988514)
			(xy 373.027176 -246.939151) (xy 372.722412 -246.939151) (xy 372.714593 -246.988514) (xy 372.699149 -247.036046)
			(xy 372.676459 -247.080578) (xy 372.647083 -247.121011) (xy 372.611743 -247.156351) (xy 372.57131 -247.185727)
			(xy 372.526778 -247.208417) (xy 372.479246 -247.223861) (xy 372.429883 -247.23168) (xy 372.379905 -247.23168)
			(xy 372.330542 -247.223861) (xy 372.28301 -247.208417) (xy 372.238478 -247.185727) (xy 372.198045 -247.156351)
			(xy 372.162705 -247.121011) (xy 372.133329 -247.080578) (xy 372.110639 -247.036046) (xy 372.095195 -246.988514)
			(xy 372.087376 -246.939151) (xy 371.782358 -246.939151) (xy 371.774539 -246.988514) (xy 371.759095 -247.036046)
			(xy 371.736405 -247.080578) (xy 371.707029 -247.121011) (xy 371.671689 -247.156351) (xy 371.631256 -247.185727)
			(xy 371.586724 -247.208417) (xy 371.539192 -247.223861) (xy 371.489829 -247.23168) (xy 371.439851 -247.23168)
			(xy 371.390488 -247.223861) (xy 371.342956 -247.208417) (xy 371.298424 -247.185727) (xy 371.257991 -247.156351)
			(xy 371.222651 -247.121011) (xy 371.193275 -247.080578) (xy 371.170585 -247.036046) (xy 371.155141 -246.988514)
			(xy 371.147322 -246.939151) (xy 371.146832 -246.914162) (xy 371.147335 -246.888597) (xy 371.155514 -246.838127)
			(xy 371.171672 -246.789618) (xy 371.19539 -246.744323) (xy 371.226057 -246.703412) (xy 371.244114 -246.685308)
			(xy 371.250452 -246.678673) (xy 371.258392 -246.662145) (xy 371.259608 -246.65305) (xy 371.266212 -246.577358)
			(xy 371.261386 -246.559832) (xy 371.255798 -246.552466) (xy 371.241053 -246.531472) (xy 371.215599 -246.486928)
			(xy 371.204998 -246.463566) (xy 371.204998 -246.463312) (xy 371.200886 -246.45517) (xy 371.187991 -246.442286)
			(xy 371.179852 -246.438166) (xy 371.110256 -246.405654) (xy 371.092476 -246.404384) (xy 371.083332 -246.406924)
			(xy 371.061652 -246.412856) (xy 371.017159 -246.419228) (xy 370.994686 -246.419624) (xy 370.969894 -246.419225)
			(xy 370.92092 -246.411466) (xy 370.873762 -246.396142) (xy 370.829583 -246.37363) (xy 370.789469 -246.344483)
			(xy 370.754408 -246.309421) (xy 370.725263 -246.269305) (xy 370.702753 -246.225125) (xy 370.687431 -246.177967)
			(xy 370.679674 -246.128992) (xy 370.370117 -246.128992) (xy 370.362359 -246.177974) (xy 370.347026 -246.225164)
			(xy 370.324499 -246.269375) (xy 370.295334 -246.309518) (xy 370.260248 -246.344604) (xy 370.220105 -246.373769)
			(xy 370.175894 -246.396296) (xy 370.128704 -246.411629) (xy 370.079696 -246.419391) (xy 370.030076 -246.419391)
			(xy 369.981068 -246.411629) (xy 369.933878 -246.396296) (xy 369.889667 -246.373769) (xy 369.849524 -246.344604)
			(xy 369.814438 -246.309518) (xy 369.785273 -246.269375) (xy 369.762746 -246.225164) (xy 369.747413 -246.177974)
			(xy 369.739651 -246.128966) (xy 369.739164 -246.104156) (xy 369.739885 -246.075092) (xy 369.750619 -246.01796)
			(xy 369.7605 -245.990618) (xy 369.764186 -245.978862) (xy 369.761264 -245.954439) (xy 369.754912 -245.943882)
			(xy 369.707668 -245.874794) (xy 369.700166 -245.864876) (xy 369.678181 -245.853304) (xy 369.665758 -245.852696)
			(xy 369.59286 -245.852696) (xy 369.571814 -245.852213) (xy 369.530539 -245.843964) (xy 369.491678 -245.827795)
			(xy 369.456734 -245.80433) (xy 369.42706 -245.774479) (xy 369.403804 -245.739395) (xy 369.387867 -245.700438)
			(xy 369.379865 -245.659114) (xy 369.3795 -245.638066) (xy 369.3795 -245.637558) (xy 369.3795 -245.559834)
			(xy 369.379056 -245.549584) (xy 369.37106 -245.530709) (xy 369.364006 -245.523258) (xy 369.345936 -245.505136)
			(xy 369.315274 -245.464163) (xy 369.291561 -245.418813) (xy 369.275408 -245.370255) (xy 369.26723 -245.319738)
			(xy 369.266724 -245.29415) (xy 367.082832 -245.29415) (xy 367.08216 -245.324499) (xy 367.070647 -245.384096)
			(xy 367.059972 -245.412514) (xy 367.056416 -245.421658) (xy 367.056416 -245.638574) (xy 367.056287 -245.648218)
			(xy 367.05451 -245.667425) (xy 367.05286 -245.676928) (xy 367.05286 -245.677182) (xy 367.051306 -245.689542)
			(xy 367.058888 -245.713242) (xy 367.067338 -245.722394) (xy 367.13668 -245.790212) (xy 367.160302 -245.797324)
			(xy 367.172748 -245.794784) (xy 367.187957 -245.791947) (xy 367.218746 -245.788891) (xy 367.234216 -245.788688)
			(xy 367.234724 -245.788688) (xy 367.259514 -245.789219) (xy 367.308483 -245.796979) (xy 367.355635 -245.812304)
			(xy 367.39981 -245.834816) (xy 367.439918 -245.863962) (xy 367.474974 -245.899023) (xy 367.504112 -245.939137)
			(xy 367.526617 -245.983315) (xy 367.541934 -246.03047) (xy 367.549685 -246.079441) (xy 367.549683 -246.104156)
			(xy 367.858543 -246.104156) (xy 367.862638 -246.053428) (xy 367.874817 -246.004014) (xy 367.894765 -245.957194)
			(xy 367.921966 -245.91418) (xy 367.955714 -245.876086) (xy 367.995136 -245.843899) (xy 368.03921 -245.818453)
			(xy 368.086796 -245.800406) (xy 368.13666 -245.790226) (xy 368.187512 -245.788177) (xy 368.238033 -245.794311)
			(xy 368.286917 -245.808471) (xy 368.332896 -245.830288) (xy 368.37478 -245.859198) (xy 368.411484 -245.894453)
			(xy 368.442057 -245.935139) (xy 368.465708 -245.980202) (xy 368.481824 -246.028476) (xy 368.489988 -246.07871)
			(xy 368.4905 -246.104156) (xy 368.489997 -246.129145) (xy 368.797314 -246.129145) (xy 368.797314 -246.079167)
			(xy 368.805133 -246.029804) (xy 368.820577 -245.982272) (xy 368.843267 -245.93774) (xy 368.872643 -245.897307)
			(xy 368.907983 -245.861967) (xy 368.948416 -245.832591) (xy 368.992948 -245.809901) (xy 369.04048 -245.794457)
			(xy 369.089843 -245.786638) (xy 369.139821 -245.786638) (xy 369.189184 -245.794457) (xy 369.236716 -245.809901)
			(xy 369.281248 -245.832591) (xy 369.321681 -245.861967) (xy 369.357021 -245.897307) (xy 369.386397 -245.93774)
			(xy 369.409087 -245.982272) (xy 369.424531 -246.029804) (xy 369.43235 -246.079167) (xy 369.43284 -246.104156)
			(xy 369.43235 -246.129145) (xy 369.424531 -246.178508) (xy 369.409087 -246.22604) (xy 369.386397 -246.270572)
			(xy 369.357021 -246.311005) (xy 369.321681 -246.346345) (xy 369.281248 -246.375721) (xy 369.236716 -246.398411)
			(xy 369.189184 -246.413855) (xy 369.139821 -246.421674) (xy 369.089843 -246.421674) (xy 369.04048 -246.413855)
			(xy 368.992948 -246.398411) (xy 368.948416 -246.375721) (xy 368.907983 -246.346345) (xy 368.872643 -246.311005)
			(xy 368.843267 -246.270572) (xy 368.820577 -246.22604) (xy 368.805133 -246.178508) (xy 368.797314 -246.129145)
			(xy 368.489997 -246.129145) (xy 368.489988 -246.129602) (xy 368.481824 -246.179836) (xy 368.465708 -246.22811)
			(xy 368.442057 -246.273173) (xy 368.411484 -246.313859) (xy 368.37478 -246.349114) (xy 368.332896 -246.378024)
			(xy 368.286917 -246.399841) (xy 368.238033 -246.414001) (xy 368.187512 -246.420135) (xy 368.13666 -246.418086)
			(xy 368.086796 -246.407906) (xy 368.03921 -246.389859) (xy 367.995136 -246.364413) (xy 367.955714 -246.332226)
			(xy 367.921966 -246.294132) (xy 367.894765 -246.251118) (xy 367.874817 -246.204298) (xy 367.862638 -246.154884)
			(xy 367.858543 -246.104156) (xy 367.549683 -246.104156) (xy 367.549681 -246.129021) (xy 367.54192 -246.17799)
			(xy 367.526594 -246.225141) (xy 367.50408 -246.269315) (xy 367.474934 -246.309423) (xy 367.439872 -246.344478)
			(xy 367.399757 -246.373616) (xy 367.355579 -246.39612) (xy 367.308423 -246.411436) (xy 367.259453 -246.419186)
			(xy 367.209873 -246.41918) (xy 367.160904 -246.411418) (xy 367.113752 -246.396091) (xy 367.069579 -246.373577)
			(xy 367.029472 -246.344429) (xy 366.994418 -246.309366) (xy 366.965281 -246.269251) (xy 366.942778 -246.225072)
			(xy 366.927463 -246.177917) (xy 366.919714 -246.128946) (xy 366.919256 -246.104156) (xy 366.919256 -246.103902)
			(xy 366.919935 -246.074912) (xy 366.930542 -246.017911) (xy 366.940338 -245.990618) (xy 366.94491 -245.978934)
			(xy 366.941862 -245.954042) (xy 366.886744 -245.874286) (xy 366.87921 -245.864428) (xy 366.85723 -245.85298)
			(xy 366.844834 -245.852442) (xy 366.84458 -245.852442) (xy 366.843056 -245.852696) (xy 366.686846 -245.852696)
			(xy 366.674425 -245.853286) (xy 366.652458 -245.86489) (xy 366.644936 -245.874794) (xy 366.590326 -245.954042)
			(xy 366.587278 -245.978426) (xy 366.59185 -245.990364) (xy 366.601669 -246.017783) (xy 366.612281 -246.07504)
			(xy 366.612932 -246.104156) (xy 366.612442 -246.129145) (xy 366.604623 -246.178508) (xy 366.589179 -246.22604)
			(xy 366.566489 -246.270572) (xy 366.537113 -246.311005) (xy 366.501773 -246.346345) (xy 366.46134 -246.375721)
			(xy 366.416808 -246.398411) (xy 366.369276 -246.413855) (xy 366.319913 -246.421674) (xy 366.269935 -246.421674)
			(xy 366.220572 -246.413855) (xy 366.17304 -246.398411) (xy 366.128508 -246.375721) (xy 366.088075 -246.346345)
			(xy 366.052735 -246.311005) (xy 366.023359 -246.270572) (xy 366.000669 -246.22604) (xy 365.985225 -246.178508)
			(xy 365.977406 -246.129145) (xy 365.976916 -246.104156) (xy 365.670592 -246.104156) (xy 365.67008 -246.129602)
			(xy 365.661916 -246.179836) (xy 365.6458 -246.22811) (xy 365.622149 -246.273173) (xy 365.591576 -246.313859)
			(xy 365.554872 -246.349114) (xy 365.512988 -246.378024) (xy 365.467009 -246.399841) (xy 365.418125 -246.414001)
			(xy 365.367604 -246.420135) (xy 365.316752 -246.418086) (xy 365.266888 -246.407906) (xy 365.219302 -246.389859)
			(xy 365.175228 -246.364413) (xy 365.135806 -246.332226) (xy 365.102058 -246.294132) (xy 365.074857 -246.251118)
			(xy 365.054909 -246.204298) (xy 365.04273 -246.154884) (xy 365.038635 -246.104156) (xy 364.730284 -246.104156)
			(xy 364.729798 -246.128946) (xy 364.722042 -246.177914) (xy 364.706721 -246.225067) (xy 364.684212 -246.269242)
			(xy 364.65507 -246.309353) (xy 364.620013 -246.34441) (xy 364.579902 -246.373552) (xy 364.535727 -246.396061)
			(xy 364.488574 -246.411382) (xy 364.439606 -246.419138) (xy 364.390026 -246.419138) (xy 364.341058 -246.411382)
			(xy 364.293905 -246.396061) (xy 364.24973 -246.373552) (xy 364.209619 -246.34441) (xy 364.174562 -246.309353)
			(xy 364.14542 -246.269242) (xy 364.122911 -246.225067) (xy 364.10759 -246.177914) (xy 364.099834 -246.128946)
			(xy 364.099348 -246.104156) (xy 364.099348 -246.103902) (xy 364.100028 -246.074913) (xy 364.110634 -246.017911)
			(xy 364.12043 -245.990618) (xy 364.124111 -245.978861) (xy 364.12119 -245.95444) (xy 364.114842 -245.943882)
			(xy 364.067598 -245.874794) (xy 364.060082 -245.864889) (xy 364.038107 -245.853311) (xy 364.025688 -245.852696)
			(xy 363.87786 -245.852696) (xy 363.861096 -245.851934) (xy 363.850196 -245.851628) (xy 363.829702 -245.85899)
			(xy 363.814106 -245.874188) (xy 363.806218 -245.894486) (xy 363.807459 -245.916227) (xy 363.812074 -245.926102)
			(xy 363.825933 -245.953711) (xy 363.845524 -246.012296) (xy 363.855435 -246.073269) (xy 363.856016 -246.104156)
			(xy 363.855611 -246.13039) (xy 363.848449 -246.182367) (xy 363.834227 -246.232871) (xy 363.813213 -246.280947)
			(xy 363.799882 -246.303546) (xy 363.79648 -246.309613) (xy 363.792751 -246.323009) (xy 363.792516 -246.329962)
			(xy 363.792516 -246.376952) (xy 363.791998 -246.404448) (xy 363.784026 -246.45886) (xy 363.768326 -246.511564)
			(xy 363.75721 -246.536718) (xy 363.755607 -246.540427) (xy 363.753439 -246.548209) (xy 363.752892 -246.552212)
			(xy 363.75086 -246.565674) (xy 363.749468 -246.576558) (xy 363.754988 -246.597773) (xy 363.768836 -246.614767)
			(xy 363.788499 -246.624457) (xy 363.810411 -246.625087) (xy 363.82071 -246.6213) (xy 363.840361 -246.613373)
			(xy 363.88123 -246.602186) (xy 363.923222 -246.596523) (xy 363.944408 -246.596154) (xy 363.944916 -246.596154)
			(xy 363.969906 -246.596674) (xy 364.019271 -246.604495) (xy 364.066805 -246.619942) (xy 364.111337 -246.642636)
			(xy 364.15177 -246.672016) (xy 364.18711 -246.70736) (xy 364.216485 -246.747797) (xy 364.239173 -246.792332)
			(xy 364.254614 -246.839867) (xy 364.262429 -246.889233) (xy 364.262426 -246.939151) (xy 364.567198 -246.939151)
			(xy 364.567198 -246.889173) (xy 364.575017 -246.83981) (xy 364.590461 -246.792278) (xy 364.613151 -246.747746)
			(xy 364.642527 -246.707313) (xy 364.677867 -246.671973) (xy 364.7183 -246.642597) (xy 364.762832 -246.619907)
			(xy 364.810364 -246.604463) (xy 364.859727 -246.596644) (xy 364.909705 -246.596644) (xy 364.959068 -246.604463)
			(xy 365.0066 -246.619907) (xy 365.051132 -246.642597) (xy 365.091565 -246.671973) (xy 365.126905 -246.707313)
			(xy 365.156281 -246.747746) (xy 365.178971 -246.792278) (xy 365.194415 -246.83981) (xy 365.202234 -246.889173)
			(xy 365.202724 -246.914162) (xy 365.202234 -246.939151) (xy 365.507252 -246.939151) (xy 365.507252 -246.889173)
			(xy 365.515071 -246.83981) (xy 365.530515 -246.792278) (xy 365.553205 -246.747746) (xy 365.582581 -246.707313)
			(xy 365.617921 -246.671973) (xy 365.658354 -246.642597) (xy 365.702886 -246.619907) (xy 365.750418 -246.604463)
			(xy 365.799781 -246.596644) (xy 365.849759 -246.596644) (xy 365.899122 -246.604463) (xy 365.946654 -246.619907)
			(xy 365.991186 -246.642597) (xy 366.031619 -246.671973) (xy 366.066959 -246.707313) (xy 366.096335 -246.747746)
			(xy 366.119025 -246.792278) (xy 366.134469 -246.83981) (xy 366.142288 -246.889173) (xy 366.142778 -246.914162)
			(xy 366.142288 -246.939151) (xy 366.447306 -246.939151) (xy 366.447306 -246.889173) (xy 366.455125 -246.83981)
			(xy 366.470569 -246.792278) (xy 366.493259 -246.747746) (xy 366.522635 -246.707313) (xy 366.557975 -246.671973)
			(xy 366.598408 -246.642597) (xy 366.64294 -246.619907) (xy 366.690472 -246.604463) (xy 366.739835 -246.596644)
			(xy 366.789813 -246.596644) (xy 366.839176 -246.604463) (xy 366.886708 -246.619907) (xy 366.93124 -246.642597)
			(xy 366.971673 -246.671973) (xy 367.007013 -246.707313) (xy 367.036389 -246.747746) (xy 367.059079 -246.792278)
			(xy 367.074523 -246.83981) (xy 367.082342 -246.889173) (xy 367.082832 -246.914162) (xy 367.082342 -246.939151)
			(xy 367.38736 -246.939151) (xy 367.38736 -246.889173) (xy 367.395179 -246.83981) (xy 367.410623 -246.792278)
			(xy 367.433313 -246.747746) (xy 367.462689 -246.707313) (xy 367.498029 -246.671973) (xy 367.538462 -246.642597)
			(xy 367.582994 -246.619907) (xy 367.630526 -246.604463) (xy 367.679889 -246.596644) (xy 367.729867 -246.596644)
			(xy 367.77923 -246.604463) (xy 367.826762 -246.619907) (xy 367.871294 -246.642597) (xy 367.911727 -246.671973)
			(xy 367.947067 -246.707313) (xy 367.976443 -246.747746) (xy 367.999133 -246.792278) (xy 368.014577 -246.83981)
			(xy 368.022396 -246.889173) (xy 368.022886 -246.914162) (xy 368.022396 -246.939151) (xy 368.32716 -246.939151)
			(xy 368.32716 -246.889173) (xy 368.334979 -246.83981) (xy 368.350423 -246.792278) (xy 368.373113 -246.747746)
			(xy 368.402489 -246.707313) (xy 368.437829 -246.671973) (xy 368.478262 -246.642597) (xy 368.522794 -246.619907)
			(xy 368.570326 -246.604463) (xy 368.619689 -246.596644) (xy 368.669667 -246.596644) (xy 368.71903 -246.604463)
			(xy 368.766562 -246.619907) (xy 368.811094 -246.642597) (xy 368.851527 -246.671973) (xy 368.886867 -246.707313)
			(xy 368.916243 -246.747746) (xy 368.938933 -246.792278) (xy 368.954377 -246.83981) (xy 368.962196 -246.889173)
			(xy 368.962686 -246.914162) (xy 368.962196 -246.939151) (xy 369.267214 -246.939151) (xy 369.267214 -246.889173)
			(xy 369.275033 -246.83981) (xy 369.290477 -246.792278) (xy 369.313167 -246.747746) (xy 369.342543 -246.707313)
			(xy 369.377883 -246.671973) (xy 369.418316 -246.642597) (xy 369.462848 -246.619907) (xy 369.51038 -246.604463)
			(xy 369.559743 -246.596644) (xy 369.609721 -246.596644) (xy 369.659084 -246.604463) (xy 369.706616 -246.619907)
			(xy 369.751148 -246.642597) (xy 369.791581 -246.671973) (xy 369.826921 -246.707313) (xy 369.856297 -246.747746)
			(xy 369.878987 -246.792278) (xy 369.894431 -246.83981) (xy 369.90225 -246.889173) (xy 369.90274 -246.914162)
			(xy 369.90225 -246.939151) (xy 370.207268 -246.939151) (xy 370.207268 -246.889173) (xy 370.215087 -246.83981)
			(xy 370.230531 -246.792278) (xy 370.253221 -246.747746) (xy 370.282597 -246.707313) (xy 370.317937 -246.671973)
			(xy 370.35837 -246.642597) (xy 370.402902 -246.619907) (xy 370.450434 -246.604463) (xy 370.499797 -246.596644)
			(xy 370.549775 -246.596644) (xy 370.599138 -246.604463) (xy 370.64667 -246.619907) (xy 370.691202 -246.642597)
			(xy 370.731635 -246.671973) (xy 370.766975 -246.707313) (xy 370.796351 -246.747746) (xy 370.819041 -246.792278)
			(xy 370.834485 -246.83981) (xy 370.842304 -246.889173) (xy 370.842794 -246.914162) (xy 370.842304 -246.939151)
			(xy 370.834485 -246.988514) (xy 370.819041 -247.036046) (xy 370.796351 -247.080578) (xy 370.766975 -247.121011)
			(xy 370.731635 -247.156351) (xy 370.691202 -247.185727) (xy 370.64667 -247.208417) (xy 370.599138 -247.223861)
			(xy 370.549775 -247.23168) (xy 370.499797 -247.23168) (xy 370.450434 -247.223861) (xy 370.402902 -247.208417)
			(xy 370.35837 -247.185727) (xy 370.317937 -247.156351) (xy 370.282597 -247.121011) (xy 370.253221 -247.080578)
			(xy 370.230531 -247.036046) (xy 370.215087 -246.988514) (xy 370.207268 -246.939151) (xy 369.90225 -246.939151)
			(xy 369.894431 -246.988514) (xy 369.878987 -247.036046) (xy 369.856297 -247.080578) (xy 369.826921 -247.121011)
			(xy 369.791581 -247.156351) (xy 369.751148 -247.185727) (xy 369.706616 -247.208417) (xy 369.659084 -247.223861)
			(xy 369.609721 -247.23168) (xy 369.559743 -247.23168) (xy 369.51038 -247.223861) (xy 369.462848 -247.208417)
			(xy 369.418316 -247.185727) (xy 369.377883 -247.156351) (xy 369.342543 -247.121011) (xy 369.313167 -247.080578)
			(xy 369.290477 -247.036046) (xy 369.275033 -246.988514) (xy 369.267214 -246.939151) (xy 368.962196 -246.939151)
			(xy 368.954377 -246.988514) (xy 368.938933 -247.036046) (xy 368.916243 -247.080578) (xy 368.886867 -247.121011)
			(xy 368.851527 -247.156351) (xy 368.811094 -247.185727) (xy 368.766562 -247.208417) (xy 368.71903 -247.223861)
			(xy 368.669667 -247.23168) (xy 368.619689 -247.23168) (xy 368.570326 -247.223861) (xy 368.522794 -247.208417)
			(xy 368.478262 -247.185727) (xy 368.437829 -247.156351) (xy 368.402489 -247.121011) (xy 368.373113 -247.080578)
			(xy 368.350423 -247.036046) (xy 368.334979 -246.988514) (xy 368.32716 -246.939151) (xy 368.022396 -246.939151)
			(xy 368.014577 -246.988514) (xy 367.999133 -247.036046) (xy 367.976443 -247.080578) (xy 367.947067 -247.121011)
			(xy 367.911727 -247.156351) (xy 367.871294 -247.185727) (xy 367.826762 -247.208417) (xy 367.77923 -247.223861)
			(xy 367.729867 -247.23168) (xy 367.679889 -247.23168) (xy 367.630526 -247.223861) (xy 367.582994 -247.208417)
			(xy 367.538462 -247.185727) (xy 367.498029 -247.156351) (xy 367.462689 -247.121011) (xy 367.433313 -247.080578)
			(xy 367.410623 -247.036046) (xy 367.395179 -246.988514) (xy 367.38736 -246.939151) (xy 367.082342 -246.939151)
			(xy 367.074523 -246.988514) (xy 367.059079 -247.036046) (xy 367.036389 -247.080578) (xy 367.007013 -247.121011)
			(xy 366.971673 -247.156351) (xy 366.93124 -247.185727) (xy 366.886708 -247.208417) (xy 366.839176 -247.223861)
			(xy 366.789813 -247.23168) (xy 366.739835 -247.23168) (xy 366.690472 -247.223861) (xy 366.64294 -247.208417)
			(xy 366.598408 -247.185727) (xy 366.557975 -247.156351) (xy 366.522635 -247.121011) (xy 366.493259 -247.080578)
			(xy 366.470569 -247.036046) (xy 366.455125 -246.988514) (xy 366.447306 -246.939151) (xy 366.142288 -246.939151)
			(xy 366.134469 -246.988514) (xy 366.119025 -247.036046) (xy 366.096335 -247.080578) (xy 366.066959 -247.121011)
			(xy 366.031619 -247.156351) (xy 365.991186 -247.185727) (xy 365.946654 -247.208417) (xy 365.899122 -247.223861)
			(xy 365.849759 -247.23168) (xy 365.799781 -247.23168) (xy 365.750418 -247.223861) (xy 365.702886 -247.208417)
			(xy 365.658354 -247.185727) (xy 365.617921 -247.156351) (xy 365.582581 -247.121011) (xy 365.553205 -247.080578)
			(xy 365.530515 -247.036046) (xy 365.515071 -246.988514) (xy 365.507252 -246.939151) (xy 365.202234 -246.939151)
			(xy 365.194415 -246.988514) (xy 365.178971 -247.036046) (xy 365.156281 -247.080578) (xy 365.126905 -247.121011)
			(xy 365.091565 -247.156351) (xy 365.051132 -247.185727) (xy 365.0066 -247.208417) (xy 364.959068 -247.223861)
			(xy 364.909705 -247.23168) (xy 364.859727 -247.23168) (xy 364.810364 -247.223861) (xy 364.762832 -247.208417)
			(xy 364.7183 -247.185727) (xy 364.677867 -247.156351) (xy 364.642527 -247.121011) (xy 364.613151 -247.080578)
			(xy 364.590461 -247.036046) (xy 364.575017 -246.988514) (xy 364.567198 -246.939151) (xy 364.262426 -246.939151)
			(xy 364.262426 -246.939214) (xy 364.254603 -246.988578) (xy 364.239155 -247.036112) (xy 364.21646 -247.080643)
			(xy 364.187079 -247.121076) (xy 364.151735 -247.156414) (xy 364.111297 -247.185789) (xy 364.066762 -247.208475)
			(xy 364.019226 -247.223916) (xy 363.96986 -247.23173) (xy 363.919879 -247.231725) (xy 363.870514 -247.223902)
			(xy 363.822982 -247.208452) (xy 363.778451 -247.185757) (xy 363.738019 -247.156374) (xy 363.702681 -247.121029)
			(xy 363.673307 -247.08059) (xy 363.650622 -247.036055) (xy 363.635182 -246.988519) (xy 363.627369 -246.939152)
			(xy 363.626908 -246.914162) (xy 363.626908 -246.913654) (xy 363.627537 -246.885487) (xy 363.637501 -246.830041)
			(xy 363.64672 -246.803418) (xy 363.650038 -246.79297) (xy 363.648442 -246.771131) (xy 363.637877 -246.751951)
			(xy 363.620272 -246.738931) (xy 363.598839 -246.734446) (xy 363.588046 -246.736362) (xy 363.576452 -246.738819)
			(xy 363.552905 -246.741497) (xy 363.541056 -246.741696) (xy 363.523022 -246.741696) (xy 363.516164 -246.743474)
			(xy 363.491846 -246.750032) (xy 363.442024 -246.757417) (xy 363.41685 -246.758206) (xy 363.406209 -246.758992)
			(xy 363.386915 -246.768047) (xy 363.379512 -246.775732) (xy 363.322616 -246.841264) (xy 363.316266 -246.862346)
			(xy 363.31779 -246.873014) (xy 363.319078 -246.883253) (xy 363.320476 -246.903843) (xy 363.320584 -246.914162)
			(xy 363.320097 -246.938972) (xy 363.312335 -246.98798) (xy 363.297002 -247.03517) (xy 363.274475 -247.079381)
			(xy 363.24531 -247.119524) (xy 363.210224 -247.15461) (xy 363.170081 -247.183775) (xy 363.12587 -247.206302)
			(xy 363.07868 -247.221635) (xy 363.029672 -247.229397) (xy 362.980052 -247.229397) (xy 362.931044 -247.221635)
			(xy 362.883854 -247.206302) (xy 362.839643 -247.183775) (xy 362.7995 -247.15461) (xy 362.764414 -247.119524)
			(xy 362.735249 -247.079381) (xy 362.712722 -247.03517) (xy 362.697389 -246.98798) (xy 362.689627 -246.938972)
			(xy 362.68914 -246.914162) (xy 362.38053 -246.914162) (xy 362.380018 -246.939608) (xy 362.371854 -246.989842)
			(xy 362.355738 -247.038116) (xy 362.332087 -247.083179) (xy 362.301514 -247.123865) (xy 362.26481 -247.15912)
			(xy 362.222926 -247.18803) (xy 362.176947 -247.209847) (xy 362.128063 -247.224007) (xy 362.077542 -247.230141)
			(xy 362.02669 -247.228092) (xy 361.976826 -247.217912) (xy 361.92924 -247.199865) (xy 361.885166 -247.174419)
			(xy 361.845744 -247.142232) (xy 361.811996 -247.104138) (xy 361.784795 -247.061124) (xy 361.764847 -247.014304)
			(xy 361.752668 -246.96489) (xy 361.748573 -246.914162) (xy 361.542895 -246.914162) (xy 361.442254 -247.088406)
			(xy 361.431988 -247.1053) (xy 361.40629 -247.135334) (xy 361.375515 -247.160141) (xy 361.340711 -247.178878)
			(xy 361.303058 -247.190908) (xy 361.283504 -247.193816) (xy 361.279218 -247.194397) (xy 361.270914 -247.196815)
			(xy 361.266994 -247.198642) (xy 361.244821 -247.209179) (xy 361.198054 -247.224104) (xy 361.149553 -247.231687)
			(xy 361.125008 -247.23217) (xy 361.124754 -247.23217) (xy 361.098442 -247.231725) (xy 361.046536 -247.223064)
			(xy 360.996766 -247.205969) (xy 360.950493 -247.180908) (xy 360.908981 -247.148565) (xy 360.873366 -247.109826)
			(xy 360.844619 -247.065747) (xy 360.823528 -247.017535) (xy 360.810668 -246.966507) (xy 360.808016 -246.940324)
			(xy 360.807527 -246.935776) (xy 360.805096 -246.926957) (xy 360.80319 -246.922798) (xy 360.794634 -246.903888)
			(xy 360.78426 -246.863703) (xy 360.781829 -246.822272) (xy 358.699074 -246.822272) (xy 358.696643 -246.863697)
			(xy 358.686262 -246.903876) (xy 358.668323 -246.941297) (xy 358.643499 -246.974553) (xy 358.628442 -246.988838)
			(xy 358.623551 -246.993493) (xy 358.616213 -247.004823) (xy 358.613964 -247.01119) (xy 358.605884 -247.034928)
			(xy 358.5833 -247.079696) (xy 358.553965 -247.120362) (xy 358.518608 -247.155916) (xy 358.478106 -247.185477)
			(xy 358.433464 -247.208309) (xy 358.38579 -247.223848) (xy 358.336267 -247.231706) (xy 358.311196 -247.23217)
			(xy 358.310942 -247.23217) (xy 358.28579 -247.231717) (xy 358.236113 -247.223801) (xy 358.188302 -247.20816)
			(xy 358.143551 -247.185185) (xy 358.122982 -247.170702) (xy 358.118156 -247.1674) (xy 358.101911 -247.157706)
			(xy 358.072831 -247.133514) (xy 358.048458 -247.104585) (xy 358.038654 -247.088406) (xy 357.911146 -246.86768)
			(xy 357.91902 -246.863108) (xy 357.927511 -246.857704) (xy 357.939799 -246.841788) (xy 357.94505 -246.822378)
			(xy 357.942464 -246.802437) (xy 357.937816 -246.793512) (xy 357.856028 -246.652542) (xy 357.851505 -246.643616)
			(xy 357.848875 -246.623807) (xy 357.494514 -246.623807) (xy 357.52926 -246.640294) (xy 357.571144 -246.669204)
			(xy 357.607848 -246.704459) (xy 357.638421 -246.745145) (xy 357.662072 -246.790208) (xy 357.678188 -246.838482)
			(xy 357.686352 -246.888716) (xy 357.686864 -246.914162) (xy 357.686352 -246.939608) (xy 357.678188 -246.989842)
			(xy 357.662072 -247.038116) (xy 357.638421 -247.083179) (xy 357.607848 -247.123865) (xy 357.571144 -247.15912)
			(xy 357.52926 -247.18803) (xy 357.483281 -247.209847) (xy 357.434397 -247.224007) (xy 357.383876 -247.230141)
			(xy 357.333024 -247.228092) (xy 357.28316 -247.217912) (xy 357.235574 -247.199865) (xy 357.1915 -247.174419)
			(xy 357.152078 -247.142232) (xy 357.11833 -247.104138) (xy 357.091129 -247.061124) (xy 357.071181 -247.014304)
			(xy 357.059002 -246.96489) (xy 357.054907 -246.914162) (xy 356.746556 -246.914162) (xy 356.74607 -246.938952)
			(xy 356.738314 -246.98792) (xy 356.722993 -247.035073) (xy 356.700484 -247.079248) (xy 356.671342 -247.119359)
			(xy 356.636285 -247.154416) (xy 356.596174 -247.183558) (xy 356.551999 -247.206067) (xy 356.504846 -247.221388)
			(xy 356.455878 -247.229144) (xy 356.406298 -247.229144) (xy 356.35733 -247.221388) (xy 356.310177 -247.206067)
			(xy 356.266002 -247.183558) (xy 356.225891 -247.154416) (xy 356.190834 -247.119359) (xy 356.161692 -247.079248)
			(xy 356.139183 -247.035073) (xy 356.123862 -246.98792) (xy 356.116106 -246.938952) (xy 356.11562 -246.914162)
			(xy 356.115665 -246.903847) (xy 356.116939 -246.883257) (xy 356.11816 -246.873014) (xy 356.119684 -246.862092)
			(xy 356.11308 -246.840756) (xy 356.054152 -246.775224) (xy 356.046463 -246.767336) (xy 356.026302 -246.758515)
			(xy 356.01529 -246.758206) (xy 356.007416 -246.75846) (xy 356.0064 -246.75846) (xy 355.979876 -246.757926)
			(xy 355.927361 -246.750402) (xy 355.901752 -246.743474) (xy 355.894894 -246.741696) (xy 355.87686 -246.741696)
			(xy 355.869081 -246.741549) (xy 355.853571 -246.740278) (xy 355.845872 -246.739156) (xy 355.837744 -246.738648)
			(xy 355.828006 -246.739222) (xy 355.809968 -246.746582) (xy 355.795979 -246.760141) (xy 355.788059 -246.77794)
			(xy 355.787352 -246.797409) (xy 355.790246 -246.80672) (xy 355.798995 -246.832716) (xy 355.808446 -246.88674)
			(xy 355.809042 -246.914162) (xy 355.808584 -246.939157) (xy 355.80077 -246.988534) (xy 355.785327 -247.036079)
			(xy 355.762636 -247.080624) (xy 355.733255 -247.12107) (xy 355.697909 -247.156421) (xy 355.657468 -247.185808)
			(xy 355.612927 -247.208507) (xy 355.565384 -247.223957) (xy 355.516009 -247.23178) (xy 355.466019 -247.231782)
			(xy 355.416643 -247.223964) (xy 355.369098 -247.208517) (xy 355.324556 -247.185823) (xy 355.284112 -247.15644)
			(xy 355.248763 -247.121091) (xy 355.219379 -247.080648) (xy 355.196684 -247.036105) (xy 355.181237 -246.988561)
			(xy 355.173418 -246.939185) (xy 355.173419 -246.889195) (xy 355.181242 -246.83982) (xy 355.196692 -246.792276)
			(xy 355.21939 -246.747735) (xy 355.248776 -246.707294) (xy 355.284127 -246.671947) (xy 355.324573 -246.642567)
			(xy 355.369117 -246.619875) (xy 355.416662 -246.604431) (xy 355.466039 -246.596616) (xy 355.491034 -246.596154)
			(xy 355.518456 -246.596743) (xy 355.57248 -246.606201) (xy 355.598476 -246.61495) (xy 355.608142 -246.61804)
			(xy 355.628399 -246.617084) (xy 355.646705 -246.608358) (xy 355.660202 -246.593223) (xy 355.666784 -246.574043)
			(xy 355.666548 -246.563896) (xy 355.66604 -246.559324) (xy 355.665024 -246.552212) (xy 355.664489 -246.548268)
			(xy 355.662317 -246.540612) (xy 355.660706 -246.536972) (xy 355.649576 -246.511778) (xy 355.633861 -246.45899)
			(xy 355.625902 -246.40449) (xy 355.6254 -246.376952) (xy 355.6254 -246.291354) (xy 355.62286 -246.280178)
			(xy 355.620066 -246.274844) (xy 355.607353 -246.248204) (xy 355.589378 -246.191983) (xy 355.580255 -246.133668)
			(xy 355.57968 -246.104156) (xy 355.580328 -246.072921) (xy 355.590566 -246.011294) (xy 355.610697 -245.952155)
			(xy 355.624892 -245.924324) (xy 355.629027 -245.915835) (xy 355.631381 -245.897114) (xy 355.62679 -245.878813)
			(xy 355.61588 -245.86342) (xy 355.600133 -245.853026) (xy 355.58169 -245.849045) (xy 355.572314 -245.850156)
			(xy 355.564301 -245.85133) (xy 355.548154 -245.852602) (xy 355.540056 -245.852696) (xy 355.410262 -245.852696)
			(xy 355.397842 -245.853296) (xy 355.375875 -245.864892) (xy 355.368352 -245.874794) (xy 355.313996 -245.954296)
			(xy 355.310948 -245.97868) (xy 355.31552 -245.990364) (xy 355.31552 -245.990872) (xy 355.325397 -246.01815)
			(xy 355.33613 -246.075154) (xy 355.336856 -246.104156) (xy 355.336369 -246.128966) (xy 355.328607 -246.177974)
			(xy 355.313274 -246.225164) (xy 355.290747 -246.269375) (xy 355.261582 -246.309518) (xy 355.226496 -246.344604)
			(xy 355.186353 -246.373769) (xy 355.142142 -246.396296) (xy 355.094952 -246.411629) (xy 355.045944 -246.419391)
			(xy 354.996324 -246.419391) (xy 354.947316 -246.411629) (xy 354.900126 -246.396296) (xy 354.855915 -246.373769)
			(xy 354.815772 -246.344604) (xy 354.780686 -246.309518) (xy 354.751521 -246.269375) (xy 354.728994 -246.225164)
			(xy 354.713661 -246.177974) (xy 354.705899 -246.128966) (xy 354.705412 -246.104156) (xy 354.396802 -246.104156)
			(xy 354.39629 -246.129602) (xy 354.388126 -246.179836) (xy 354.37201 -246.22811) (xy 354.348359 -246.273173)
			(xy 354.317786 -246.313859) (xy 354.281082 -246.349114) (xy 354.239198 -246.378024) (xy 354.193219 -246.399841)
			(xy 354.144335 -246.414001) (xy 354.093814 -246.420135) (xy 354.042962 -246.418086) (xy 353.993098 -246.407906)
			(xy 353.945512 -246.389859) (xy 353.901438 -246.364413) (xy 353.862016 -246.332226) (xy 353.828268 -246.294132)
			(xy 353.801067 -246.251118) (xy 353.781119 -246.204298) (xy 353.76894 -246.154884) (xy 353.764845 -246.104156)
			(xy 353.459034 -246.104156) (xy 353.458544 -246.129145) (xy 353.450725 -246.178508) (xy 353.435281 -246.22604)
			(xy 353.412591 -246.270572) (xy 353.383215 -246.311005) (xy 353.347875 -246.346345) (xy 353.307442 -246.375721)
			(xy 353.26291 -246.398411) (xy 353.215378 -246.413855) (xy 353.166015 -246.421674) (xy 353.116037 -246.421674)
			(xy 353.066674 -246.413855) (xy 353.019142 -246.398411) (xy 352.97461 -246.375721) (xy 352.934177 -246.346345)
			(xy 352.898837 -246.311005) (xy 352.869461 -246.270572) (xy 352.846771 -246.22604) (xy 352.831327 -246.178508)
			(xy 352.823508 -246.129145) (xy 352.823018 -246.104156) (xy 352.823669 -246.07504) (xy 352.834286 -246.017784)
			(xy 352.8441 -245.990364) (xy 352.847754 -245.978601) (xy 352.844853 -245.954185) (xy 352.838512 -245.943628)
			(xy 352.791014 -245.874794) (xy 352.78349 -245.864897) (xy 352.761521 -245.853314) (xy 352.749104 -245.852696)
			(xy 352.70186 -245.852696) (xy 352.680814 -245.852213) (xy 352.639539 -245.843964) (xy 352.600678 -245.827795)
			(xy 352.565734 -245.80433) (xy 352.53606 -245.774479) (xy 352.512804 -245.739395) (xy 352.496867 -245.700438)
			(xy 352.488865 -245.659114) (xy 352.4885 -245.638066) (xy 352.4885 -245.637558) (xy 352.4885 -245.579646)
			(xy 352.487935 -245.568345) (xy 352.478318 -245.547899) (xy 352.469958 -245.540276) (xy 352.452054 -245.52509)
			(xy 352.42047 -245.490359) (xy 352.394327 -245.451366) (xy 352.374194 -245.408957) (xy 352.360507 -245.364051)
			(xy 352.353563 -245.317622) (xy 352.353118 -245.29415) (xy 350.169226 -245.29415) (xy 350.169139 -245.305748)
			(xy 350.167487 -245.328885) (xy 350.165924 -245.340378) (xy 350.165416 -245.344188) (xy 350.165416 -245.637812)
			(xy 350.165356 -245.646551) (xy 350.163955 -245.663973) (xy 350.162622 -245.67261) (xy 350.161342 -245.684526)
			(xy 350.168649 -245.707321) (xy 350.176592 -245.716298) (xy 350.233742 -245.774464) (xy 350.242591 -245.782536)
			(xy 350.265243 -245.790224) (xy 350.277176 -245.789196) (xy 350.288105 -245.787765) (xy 350.310096 -245.786241)
			(xy 350.321118 -245.786148) (xy 350.346108 -245.786676) (xy 350.395473 -245.794498) (xy 350.443006 -245.809946)
			(xy 350.487537 -245.832639) (xy 350.52797 -245.86202) (xy 350.563309 -245.897364) (xy 350.592684 -245.937801)
			(xy 350.615371 -245.982335) (xy 350.630813 -246.029871) (xy 350.638627 -246.079236) (xy 350.638625 -246.104156)
			(xy 350.944937 -246.104156) (xy 350.949032 -246.053428) (xy 350.961211 -246.004014) (xy 350.981159 -245.957194)
			(xy 351.00836 -245.91418) (xy 351.042108 -245.876086) (xy 351.08153 -245.843899) (xy 351.125604 -245.818453)
			(xy 351.17319 -245.800406) (xy 351.223054 -245.790226) (xy 351.273906 -245.788177) (xy 351.324427 -245.794311)
			(xy 351.373311 -245.808471) (xy 351.41929 -245.830288) (xy 351.461174 -245.859198) (xy 351.497878 -245.894453)
			(xy 351.528451 -245.935139) (xy 351.552102 -245.980202) (xy 351.568218 -246.028476) (xy 351.576382 -246.07871)
			(xy 351.576894 -246.104156) (xy 351.884991 -246.104156) (xy 351.889086 -246.053428) (xy 351.901265 -246.004014)
			(xy 351.921213 -245.957194) (xy 351.948414 -245.91418) (xy 351.982162 -245.876086) (xy 352.021584 -245.843899)
			(xy 352.065658 -245.818453) (xy 352.113244 -245.800406) (xy 352.163108 -245.790226) (xy 352.21396 -245.788177)
			(xy 352.264481 -245.794311) (xy 352.313365 -245.808471) (xy 352.359344 -245.830288) (xy 352.401228 -245.859198)
			(xy 352.437932 -245.894453) (xy 352.468505 -245.935139) (xy 352.492156 -245.980202) (xy 352.508272 -246.028476)
			(xy 352.516436 -246.07871) (xy 352.516948 -246.104156) (xy 352.516436 -246.129602) (xy 352.508272 -246.179836)
			(xy 352.492156 -246.22811) (xy 352.468505 -246.273173) (xy 352.437932 -246.313859) (xy 352.401228 -246.349114)
			(xy 352.359344 -246.378024) (xy 352.313365 -246.399841) (xy 352.264481 -246.414001) (xy 352.21396 -246.420135)
			(xy 352.163108 -246.418086) (xy 352.113244 -246.407906) (xy 352.065658 -246.389859) (xy 352.021584 -246.364413)
			(xy 351.982162 -246.332226) (xy 351.948414 -246.294132) (xy 351.921213 -246.251118) (xy 351.901265 -246.204298)
			(xy 351.889086 -246.154884) (xy 351.884991 -246.104156) (xy 351.576894 -246.104156) (xy 351.576382 -246.129602)
			(xy 351.568218 -246.179836) (xy 351.552102 -246.22811) (xy 351.528451 -246.273173) (xy 351.497878 -246.313859)
			(xy 351.461174 -246.349114) (xy 351.41929 -246.378024) (xy 351.373311 -246.399841) (xy 351.324427 -246.414001)
			(xy 351.273906 -246.420135) (xy 351.223054 -246.418086) (xy 351.17319 -246.407906) (xy 351.125604 -246.389859)
			(xy 351.08153 -246.364413) (xy 351.042108 -246.332226) (xy 351.00836 -246.294132) (xy 350.981159 -246.251118)
			(xy 350.961211 -246.204298) (xy 350.949032 -246.154884) (xy 350.944937 -246.104156) (xy 350.638625 -246.104156)
			(xy 350.638623 -246.129217) (xy 350.6308 -246.178581) (xy 350.615351 -246.226114) (xy 350.592656 -246.270645)
			(xy 350.563275 -246.311077) (xy 350.52793 -246.346415) (xy 350.487492 -246.375789) (xy 350.442957 -246.398475)
			(xy 350.395421 -246.413915) (xy 350.346055 -246.421728) (xy 350.296075 -246.421722) (xy 350.24671 -246.413898)
			(xy 350.199178 -246.398448) (xy 350.154648 -246.375752) (xy 350.114216 -246.346369) (xy 350.078879 -246.311023)
			(xy 350.049507 -246.270584) (xy 350.026822 -246.226049) (xy 350.011383 -246.178512) (xy 350.003571 -246.129146)
			(xy 350.00311 -246.104156) (xy 350.00311 -246.103648) (xy 350.003552 -246.079738) (xy 350.01074 -246.03246)
			(xy 350.024931 -245.986792) (xy 350.045804 -245.943767) (xy 350.05899 -245.923816) (xy 350.06444 -245.915076)
			(xy 350.068482 -245.894896) (xy 350.06428 -245.874749) (xy 350.05251 -245.857867) (xy 350.035058 -245.846958)
			(xy 350.014726 -245.843773) (xy 350.004634 -245.845838) (xy 349.991716 -245.848986) (xy 349.96535 -245.852429)
			(xy 349.952056 -245.852696) (xy 349.770192 -245.852696) (xy 349.757775 -245.853314) (xy 349.735807 -245.864898)
			(xy 349.728282 -245.874794) (xy 349.673926 -245.954296) (xy 349.670878 -245.97868) (xy 349.67545 -245.990364)
			(xy 349.67545 -245.990872) (xy 349.685265 -246.018093) (xy 349.695865 -246.074973) (xy 349.696532 -246.103902)
			(xy 349.696532 -246.104156) (xy 349.69603 -246.129493) (xy 349.687938 -246.179516) (xy 349.671956 -246.227602)
			(xy 349.648494 -246.272517) (xy 349.618155 -246.313104) (xy 349.58172 -246.348321) (xy 349.540124 -246.377262)
			(xy 349.494438 -246.399184) (xy 349.445836 -246.413522) (xy 349.395567 -246.419908) (xy 349.344923 -246.418178)
			(xy 349.295207 -246.408376) (xy 349.247696 -246.390755) (xy 349.203613 -246.365767) (xy 349.164089 -246.334055)
			(xy 349.130142 -246.296434) (xy 349.102643 -246.253871) (xy 349.082301 -246.20746) (xy 349.069638 -246.158394)
			(xy 349.064978 -246.107936) (xy 348.755938 -246.107936) (xy 348.755938 -246.128986) (xy 348.748183 -246.177947)
			(xy 348.732865 -246.225092) (xy 348.710361 -246.26926) (xy 348.681224 -246.309365) (xy 348.646172 -246.344417)
			(xy 348.606069 -246.373555) (xy 348.561901 -246.396061) (xy 348.514756 -246.411381) (xy 348.465796 -246.419137)
			(xy 348.44101 -246.419624) (xy 348.440756 -246.419624) (xy 348.422293 -246.419356) (xy 348.385621 -246.415029)
			(xy 348.367604 -246.410988) (xy 348.36735 -246.410988) (xy 348.358377 -246.409291) (xy 348.34028 -246.411618)
			(xy 348.332044 -246.41556) (xy 348.264226 -246.451628) (xy 348.252034 -246.465598) (xy 348.248986 -246.47398)
			(xy 348.240392 -246.495041) (xy 348.215661 -246.533209) (xy 348.199964 -246.549672) (xy 348.192852 -246.556784)
			(xy 348.185232 -246.575072) (xy 348.184724 -246.656352) (xy 348.185055 -246.666372) (xy 348.1925 -246.684966)
			(xy 348.199202 -246.69242) (xy 348.21598 -246.71031) (xy 348.244363 -246.750306) (xy 348.266258 -246.794192)
			(xy 348.281146 -246.840922) (xy 348.28867 -246.889386) (xy 348.289118 -246.913908) (xy 348.289118 -246.914162)
			(xy 348.288628 -246.939151) (xy 348.593646 -246.939151) (xy 348.593646 -246.889173) (xy 348.601465 -246.83981)
			(xy 348.616909 -246.792278) (xy 348.639599 -246.747746) (xy 348.668975 -246.707313) (xy 348.704315 -246.671973)
			(xy 348.744748 -246.642597) (xy 348.78928 -246.619907) (xy 348.836812 -246.604463) (xy 348.886175 -246.596644)
			(xy 348.936153 -246.596644) (xy 348.985516 -246.604463) (xy 349.033048 -246.619907) (xy 349.07758 -246.642597)
			(xy 349.118013 -246.671973) (xy 349.153353 -246.707313) (xy 349.182729 -246.747746) (xy 349.205419 -246.792278)
			(xy 349.220863 -246.83981) (xy 349.228682 -246.889173) (xy 349.229172 -246.914162) (xy 349.228682 -246.939151)
			(xy 349.5337 -246.939151) (xy 349.5337 -246.889173) (xy 349.541519 -246.83981) (xy 349.556963 -246.792278)
			(xy 349.579653 -246.747746) (xy 349.609029 -246.707313) (xy 349.644369 -246.671973) (xy 349.684802 -246.642597)
			(xy 349.729334 -246.619907) (xy 349.776866 -246.604463) (xy 349.826229 -246.596644) (xy 349.876207 -246.596644)
			(xy 349.92557 -246.604463) (xy 349.973102 -246.619907) (xy 350.017634 -246.642597) (xy 350.058067 -246.671973)
			(xy 350.093407 -246.707313) (xy 350.122783 -246.747746) (xy 350.145473 -246.792278) (xy 350.160917 -246.83981)
			(xy 350.168736 -246.889173) (xy 350.169226 -246.914162) (xy 350.168736 -246.939151) (xy 350.4735 -246.939151)
			(xy 350.4735 -246.889173) (xy 350.481319 -246.83981) (xy 350.496763 -246.792278) (xy 350.519453 -246.747746)
			(xy 350.548829 -246.707313) (xy 350.584169 -246.671973) (xy 350.624602 -246.642597) (xy 350.669134 -246.619907)
			(xy 350.716666 -246.604463) (xy 350.766029 -246.596644) (xy 350.816007 -246.596644) (xy 350.86537 -246.604463)
			(xy 350.912902 -246.619907) (xy 350.957434 -246.642597) (xy 350.997867 -246.671973) (xy 351.033207 -246.707313)
			(xy 351.062583 -246.747746) (xy 351.085273 -246.792278) (xy 351.100717 -246.83981) (xy 351.108536 -246.889173)
			(xy 351.109026 -246.914162) (xy 351.108536 -246.939151) (xy 351.413554 -246.939151) (xy 351.413554 -246.889173)
			(xy 351.421373 -246.83981) (xy 351.436817 -246.792278) (xy 351.459507 -246.747746) (xy 351.488883 -246.707313)
			(xy 351.524223 -246.671973) (xy 351.564656 -246.642597) (xy 351.609188 -246.619907) (xy 351.65672 -246.604463)
			(xy 351.706083 -246.596644) (xy 351.756061 -246.596644) (xy 351.805424 -246.604463) (xy 351.852956 -246.619907)
			(xy 351.897488 -246.642597) (xy 351.937921 -246.671973) (xy 351.973261 -246.707313) (xy 352.002637 -246.747746)
			(xy 352.025327 -246.792278) (xy 352.040771 -246.83981) (xy 352.04859 -246.889173) (xy 352.04908 -246.914162)
			(xy 352.04859 -246.939151) (xy 352.353608 -246.939151) (xy 352.353608 -246.889173) (xy 352.361427 -246.83981)
			(xy 352.376871 -246.792278) (xy 352.399561 -246.747746) (xy 352.428937 -246.707313) (xy 352.464277 -246.671973)
			(xy 352.50471 -246.642597) (xy 352.549242 -246.619907) (xy 352.596774 -246.604463) (xy 352.646137 -246.596644)
			(xy 352.696115 -246.596644) (xy 352.745478 -246.604463) (xy 352.79301 -246.619907) (xy 352.837542 -246.642597)
			(xy 352.877975 -246.671973) (xy 352.913315 -246.707313) (xy 352.942691 -246.747746) (xy 352.965381 -246.792278)
			(xy 352.980825 -246.83981) (xy 352.988644 -246.889173) (xy 352.989134 -246.914162) (xy 352.988644 -246.939151)
			(xy 353.293662 -246.939151) (xy 353.293662 -246.889173) (xy 353.301481 -246.83981) (xy 353.316925 -246.792278)
			(xy 353.339615 -246.747746) (xy 353.368991 -246.707313) (xy 353.404331 -246.671973) (xy 353.444764 -246.642597)
			(xy 353.489296 -246.619907) (xy 353.536828 -246.604463) (xy 353.586191 -246.596644) (xy 353.636169 -246.596644)
			(xy 353.685532 -246.604463) (xy 353.733064 -246.619907) (xy 353.777596 -246.642597) (xy 353.818029 -246.671973)
			(xy 353.853369 -246.707313) (xy 353.882745 -246.747746) (xy 353.905435 -246.792278) (xy 353.920879 -246.83981)
			(xy 353.928698 -246.889173) (xy 353.929188 -246.914162) (xy 353.928698 -246.939151) (xy 354.233716 -246.939151)
			(xy 354.233716 -246.889173) (xy 354.241535 -246.83981) (xy 354.256979 -246.792278) (xy 354.279669 -246.747746)
			(xy 354.309045 -246.707313) (xy 354.344385 -246.671973) (xy 354.384818 -246.642597) (xy 354.42935 -246.619907)
			(xy 354.476882 -246.604463) (xy 354.526245 -246.596644) (xy 354.576223 -246.596644) (xy 354.625586 -246.604463)
			(xy 354.673118 -246.619907) (xy 354.71765 -246.642597) (xy 354.758083 -246.671973) (xy 354.793423 -246.707313)
			(xy 354.822799 -246.747746) (xy 354.845489 -246.792278) (xy 354.860933 -246.83981) (xy 354.868752 -246.889173)
			(xy 354.869242 -246.914162) (xy 354.868752 -246.939151) (xy 354.860933 -246.988514) (xy 354.845489 -247.036046)
			(xy 354.822799 -247.080578) (xy 354.793423 -247.121011) (xy 354.758083 -247.156351) (xy 354.71765 -247.185727)
			(xy 354.673118 -247.208417) (xy 354.625586 -247.223861) (xy 354.576223 -247.23168) (xy 354.526245 -247.23168)
			(xy 354.476882 -247.223861) (xy 354.42935 -247.208417) (xy 354.384818 -247.185727) (xy 354.344385 -247.156351)
			(xy 354.309045 -247.121011) (xy 354.279669 -247.080578) (xy 354.256979 -247.036046) (xy 354.241535 -246.988514)
			(xy 354.233716 -246.939151) (xy 353.928698 -246.939151) (xy 353.920879 -246.988514) (xy 353.905435 -247.036046)
			(xy 353.882745 -247.080578) (xy 353.853369 -247.121011) (xy 353.818029 -247.156351) (xy 353.777596 -247.185727)
			(xy 353.733064 -247.208417) (xy 353.685532 -247.223861) (xy 353.636169 -247.23168) (xy 353.586191 -247.23168)
			(xy 353.536828 -247.223861) (xy 353.489296 -247.208417) (xy 353.444764 -247.185727) (xy 353.404331 -247.156351)
			(xy 353.368991 -247.121011) (xy 353.339615 -247.080578) (xy 353.316925 -247.036046) (xy 353.301481 -246.988514)
			(xy 353.293662 -246.939151) (xy 352.988644 -246.939151) (xy 352.980825 -246.988514) (xy 352.965381 -247.036046)
			(xy 352.942691 -247.080578) (xy 352.913315 -247.121011) (xy 352.877975 -247.156351) (xy 352.837542 -247.185727)
			(xy 352.79301 -247.208417) (xy 352.745478 -247.223861) (xy 352.696115 -247.23168) (xy 352.646137 -247.23168)
			(xy 352.596774 -247.223861) (xy 352.549242 -247.208417) (xy 352.50471 -247.185727) (xy 352.464277 -247.156351)
			(xy 352.428937 -247.121011) (xy 352.399561 -247.080578) (xy 352.376871 -247.036046) (xy 352.361427 -246.988514)
			(xy 352.353608 -246.939151) (xy 352.04859 -246.939151) (xy 352.040771 -246.988514) (xy 352.025327 -247.036046)
			(xy 352.002637 -247.080578) (xy 351.973261 -247.121011) (xy 351.937921 -247.156351) (xy 351.897488 -247.185727)
			(xy 351.852956 -247.208417) (xy 351.805424 -247.223861) (xy 351.756061 -247.23168) (xy 351.706083 -247.23168)
			(xy 351.65672 -247.223861) (xy 351.609188 -247.208417) (xy 351.564656 -247.185727) (xy 351.524223 -247.156351)
			(xy 351.488883 -247.121011) (xy 351.459507 -247.080578) (xy 351.436817 -247.036046) (xy 351.421373 -246.988514)
			(xy 351.413554 -246.939151) (xy 351.108536 -246.939151) (xy 351.100717 -246.988514) (xy 351.085273 -247.036046)
			(xy 351.062583 -247.080578) (xy 351.033207 -247.121011) (xy 350.997867 -247.156351) (xy 350.957434 -247.185727)
			(xy 350.912902 -247.208417) (xy 350.86537 -247.223861) (xy 350.816007 -247.23168) (xy 350.766029 -247.23168)
			(xy 350.716666 -247.223861) (xy 350.669134 -247.208417) (xy 350.624602 -247.185727) (xy 350.584169 -247.156351)
			(xy 350.548829 -247.121011) (xy 350.519453 -247.080578) (xy 350.496763 -247.036046) (xy 350.481319 -246.988514)
			(xy 350.4735 -246.939151) (xy 350.168736 -246.939151) (xy 350.160917 -246.988514) (xy 350.145473 -247.036046)
			(xy 350.122783 -247.080578) (xy 350.093407 -247.121011) (xy 350.058067 -247.156351) (xy 350.017634 -247.185727)
			(xy 349.973102 -247.208417) (xy 349.92557 -247.223861) (xy 349.876207 -247.23168) (xy 349.826229 -247.23168)
			(xy 349.776866 -247.223861) (xy 349.729334 -247.208417) (xy 349.684802 -247.185727) (xy 349.644369 -247.156351)
			(xy 349.609029 -247.121011) (xy 349.579653 -247.080578) (xy 349.556963 -247.036046) (xy 349.541519 -246.988514)
			(xy 349.5337 -246.939151) (xy 349.228682 -246.939151) (xy 349.220863 -246.988514) (xy 349.205419 -247.036046)
			(xy 349.182729 -247.080578) (xy 349.153353 -247.121011) (xy 349.118013 -247.156351) (xy 349.07758 -247.185727)
			(xy 349.033048 -247.208417) (xy 348.985516 -247.223861) (xy 348.936153 -247.23168) (xy 348.886175 -247.23168)
			(xy 348.836812 -247.223861) (xy 348.78928 -247.208417) (xy 348.744748 -247.185727) (xy 348.704315 -247.156351)
			(xy 348.668975 -247.121011) (xy 348.639599 -247.080578) (xy 348.616909 -247.036046) (xy 348.601465 -246.988514)
			(xy 348.593646 -246.939151) (xy 348.288628 -246.939151) (xy 348.280809 -246.988514) (xy 348.265365 -247.036046)
			(xy 348.242675 -247.080578) (xy 348.213299 -247.121011) (xy 348.177959 -247.156351) (xy 348.137526 -247.185727)
			(xy 348.092994 -247.208417) (xy 348.045462 -247.223861) (xy 347.996099 -247.23168) (xy 347.946121 -247.23168)
			(xy 347.896758 -247.223861) (xy 347.849226 -247.208417) (xy 347.804694 -247.185727) (xy 347.764261 -247.156351)
			(xy 347.728921 -247.121011) (xy 347.699545 -247.080578) (xy 347.676855 -247.036046) (xy 347.661411 -246.988514)
			(xy 347.653592 -246.939151) (xy 347.653102 -246.914162) (xy 347.65354 -246.889673) (xy 347.661049 -246.841276)
			(xy 347.675899 -246.794604) (xy 347.697737 -246.750765) (xy 347.711522 -246.73052) (xy 347.716094 -246.723916)
			(xy 347.72092 -246.709184) (xy 347.72092 -246.701056) (xy 347.720448 -246.691048) (xy 347.712778 -246.672559)
			(xy 347.698621 -246.658408) (xy 347.680128 -246.650747) (xy 347.67012 -246.650256) (xy 347.665548 -246.650256)
			(xy 347.635629 -246.649658) (xy 347.576529 -246.640295) (xy 347.51962 -246.621806) (xy 347.466301 -246.594647)
			(xy 347.417884 -246.559485) (xy 347.396308 -246.53875) (xy 347.231462 -246.373904) (xy 347.210767 -246.352294)
			(xy 347.175622 -246.303874) (xy 347.148465 -246.250563) (xy 347.129962 -246.193666) (xy 347.120567 -246.134578)
			(xy 347.119956 -246.104664) (xy 346.876868 -246.104664) (xy 346.876366 -246.129602) (xy 346.868202 -246.179836)
			(xy 346.852086 -246.22811) (xy 346.828435 -246.273173) (xy 346.797862 -246.313859) (xy 346.761158 -246.349114)
			(xy 346.719274 -246.378024) (xy 346.673295 -246.399841) (xy 346.624411 -246.414001) (xy 346.57389 -246.420135)
			(xy 346.523038 -246.418086) (xy 346.473174 -246.407906) (xy 346.425588 -246.389859) (xy 346.381514 -246.364413)
			(xy 346.342092 -246.332226) (xy 346.308344 -246.294132) (xy 346.281143 -246.251118) (xy 346.261195 -246.204298)
			(xy 346.249016 -246.154884) (xy 346.244921 -246.104156) (xy 345.936824 -246.104156) (xy 345.936312 -246.129602)
			(xy 345.928148 -246.179836) (xy 345.912032 -246.22811) (xy 345.888381 -246.273173) (xy 345.857808 -246.313859)
			(xy 345.821104 -246.349114) (xy 345.77922 -246.378024) (xy 345.733241 -246.399841) (xy 345.684357 -246.414001)
			(xy 345.633836 -246.420135) (xy 345.582984 -246.418086) (xy 345.53312 -246.407906) (xy 345.485534 -246.389859)
			(xy 345.44146 -246.364413) (xy 345.402038 -246.332226) (xy 345.36829 -246.294132) (xy 345.341089 -246.251118)
			(xy 345.321141 -246.204298) (xy 345.308962 -246.154884) (xy 345.304867 -246.104156) (xy 344.999056 -246.104156)
			(xy 344.999056 -246.10441) (xy 344.997786 -246.13362) (xy 344.997532 -246.138192) (xy 344.997532 -246.499634)
			(xy 344.998042 -246.509387) (xy 345.005479 -246.527426) (xy 345.01201 -246.534686) (xy 345.072462 -246.587772)
			(xy 345.079277 -246.592792) (xy 345.095246 -246.59837) (xy 345.103704 -246.598694) (xy 345.110562 -246.598694)
			(xy 345.113356 -246.59844) (xy 345.122781 -246.597372) (xy 345.141717 -246.596231) (xy 345.151202 -246.596154)
			(xy 345.176194 -246.596645) (xy 345.225563 -246.604464) (xy 345.2731 -246.61991) (xy 345.317636 -246.642603)
			(xy 345.358074 -246.671983) (xy 345.393418 -246.707327) (xy 345.422798 -246.747765) (xy 345.44549 -246.792301)
			(xy 345.460936 -246.839839) (xy 345.468756 -246.889208) (xy 345.468756 -246.939151) (xy 345.773484 -246.939151)
			(xy 345.773484 -246.889173) (xy 345.781303 -246.83981) (xy 345.796747 -246.792278) (xy 345.819437 -246.747746)
			(xy 345.848813 -246.707313) (xy 345.884153 -246.671973) (xy 345.924586 -246.642597) (xy 345.969118 -246.619907)
			(xy 346.01665 -246.604463) (xy 346.066013 -246.596644) (xy 346.115991 -246.596644) (xy 346.165354 -246.604463)
			(xy 346.212886 -246.619907) (xy 346.257418 -246.642597) (xy 346.297851 -246.671973) (xy 346.333191 -246.707313)
			(xy 346.362567 -246.747746) (xy 346.385257 -246.792278) (xy 346.400701 -246.83981) (xy 346.40852 -246.889173)
			(xy 346.40901 -246.914162) (xy 346.40852 -246.939151) (xy 346.713538 -246.939151) (xy 346.713538 -246.889173)
			(xy 346.721357 -246.83981) (xy 346.736801 -246.792278) (xy 346.759491 -246.747746) (xy 346.788867 -246.707313)
			(xy 346.824207 -246.671973) (xy 346.86464 -246.642597) (xy 346.909172 -246.619907) (xy 346.956704 -246.604463)
			(xy 347.006067 -246.596644) (xy 347.056045 -246.596644) (xy 347.105408 -246.604463) (xy 347.15294 -246.619907)
			(xy 347.197472 -246.642597) (xy 347.237905 -246.671973) (xy 347.273245 -246.707313) (xy 347.302621 -246.747746)
			(xy 347.325311 -246.792278) (xy 347.340755 -246.83981) (xy 347.348574 -246.889173) (xy 347.349064 -246.914162)
			(xy 347.348574 -246.939151) (xy 347.340755 -246.988514) (xy 347.325311 -247.036046) (xy 347.302621 -247.080578)
			(xy 347.273245 -247.121011) (xy 347.237905 -247.156351) (xy 347.197472 -247.185727) (xy 347.15294 -247.208417)
			(xy 347.105408 -247.223861) (xy 347.056045 -247.23168) (xy 347.006067 -247.23168) (xy 346.956704 -247.223861)
			(xy 346.909172 -247.208417) (xy 346.86464 -247.185727) (xy 346.824207 -247.156351) (xy 346.788867 -247.121011)
			(xy 346.759491 -247.080578) (xy 346.736801 -247.036046) (xy 346.721357 -246.988514) (xy 346.713538 -246.939151)
			(xy 346.40852 -246.939151) (xy 346.400701 -246.988514) (xy 346.385257 -247.036046) (xy 346.362567 -247.080578)
			(xy 346.333191 -247.121011) (xy 346.297851 -247.156351) (xy 346.257418 -247.185727) (xy 346.212886 -247.208417)
			(xy 346.165354 -247.223861) (xy 346.115991 -247.23168) (xy 346.066013 -247.23168) (xy 346.01665 -247.223861)
			(xy 345.969118 -247.208417) (xy 345.924586 -247.185727) (xy 345.884153 -247.156351) (xy 345.848813 -247.121011)
			(xy 345.819437 -247.080578) (xy 345.796747 -247.036046) (xy 345.781303 -246.988514) (xy 345.773484 -246.939151)
			(xy 345.468756 -246.939151) (xy 345.468756 -246.939192) (xy 345.460936 -246.988561) (xy 345.44549 -247.036099)
			(xy 345.422798 -247.080635) (xy 345.393418 -247.121073) (xy 345.358074 -247.156417) (xy 345.317636 -247.185797)
			(xy 345.2731 -247.20849) (xy 345.225563 -247.223936) (xy 345.176194 -247.231755) (xy 345.151202 -247.23217)
			(xy 345.141014 -247.232105) (xy 345.120678 -247.230835) (xy 345.110562 -247.22963) (xy 345.09964 -247.22836)
			(xy 345.089988 -247.231154) (xy 345.084904 -247.232866) (xy 345.075556 -247.238121) (xy 345.071446 -247.241568)
			(xy 345.051888 -247.258586) (xy 345.01201 -247.293638) (xy 345.005455 -247.300886) (xy 344.997999 -247.318929)
			(xy 344.997532 -247.32869) (xy 344.997532 -247.690132) (xy 344.997786 -247.694704) (xy 344.999056 -247.723914)
			(xy 344.999056 -247.724168) (xy 345.304867 -247.724168) (xy 345.308962 -247.67344) (xy 345.321141 -247.624026)
			(xy 345.341089 -247.577206) (xy 345.36829 -247.534192) (xy 345.402038 -247.496098) (xy 345.44146 -247.463911)
			(xy 345.485534 -247.438465) (xy 345.53312 -247.420418) (xy 345.582984 -247.410238) (xy 345.633836 -247.408189)
			(xy 345.684357 -247.414323) (xy 345.733241 -247.428483) (xy 345.77922 -247.4503) (xy 345.821104 -247.47921)
			(xy 345.857808 -247.514465) (xy 345.888381 -247.555151) (xy 345.912032 -247.600214) (xy 345.928148 -247.648488)
			(xy 345.936312 -247.698722) (xy 345.936824 -247.724168) (xy 346.244921 -247.724168) (xy 346.249016 -247.67344)
			(xy 346.261195 -247.624026) (xy 346.281143 -247.577206) (xy 346.308344 -247.534192) (xy 346.342092 -247.496098)
			(xy 346.381514 -247.463911) (xy 346.425588 -247.438465) (xy 346.473174 -247.420418) (xy 346.523038 -247.410238)
			(xy 346.57389 -247.408189) (xy 346.624411 -247.414323) (xy 346.673295 -247.428483) (xy 346.719274 -247.4503)
			(xy 346.761158 -247.47921) (xy 346.797862 -247.514465) (xy 346.828435 -247.555151) (xy 346.852086 -247.600214)
			(xy 346.868202 -247.648488) (xy 346.876366 -247.698722) (xy 346.876878 -247.724168) (xy 346.876375 -247.749157)
			(xy 347.183692 -247.749157) (xy 347.183692 -247.699179) (xy 347.191511 -247.649816) (xy 347.206955 -247.602284)
			(xy 347.229645 -247.557752) (xy 347.259021 -247.517319) (xy 347.294361 -247.481979) (xy 347.334794 -247.452603)
			(xy 347.379326 -247.429913) (xy 347.426858 -247.414469) (xy 347.476221 -247.40665) (xy 347.526199 -247.40665)
			(xy 347.575562 -247.414469) (xy 347.623094 -247.429913) (xy 347.667626 -247.452603) (xy 347.708059 -247.481979)
			(xy 347.743399 -247.517319) (xy 347.772775 -247.557752) (xy 347.795465 -247.602284) (xy 347.810909 -247.649816)
			(xy 347.818728 -247.699179) (xy 347.819218 -247.724168) (xy 348.124775 -247.724168) (xy 348.12887 -247.67344)
			(xy 348.141049 -247.624026) (xy 348.160997 -247.577206) (xy 348.188198 -247.534192) (xy 348.221946 -247.496098)
			(xy 348.261368 -247.463911) (xy 348.305442 -247.438465) (xy 348.353028 -247.420418) (xy 348.402892 -247.410238)
			(xy 348.453744 -247.408189) (xy 348.504265 -247.414323) (xy 348.553149 -247.428483) (xy 348.599128 -247.4503)
			(xy 348.641012 -247.47921) (xy 348.677716 -247.514465) (xy 348.708289 -247.555151) (xy 348.73194 -247.600214)
			(xy 348.748056 -247.648488) (xy 348.75622 -247.698722) (xy 348.756732 -247.724168) (xy 349.064829 -247.724168)
			(xy 349.068924 -247.67344) (xy 349.081103 -247.624026) (xy 349.101051 -247.577206) (xy 349.128252 -247.534192)
			(xy 349.162 -247.496098) (xy 349.201422 -247.463911) (xy 349.245496 -247.438465) (xy 349.293082 -247.420418)
			(xy 349.342946 -247.410238) (xy 349.393798 -247.408189) (xy 349.444319 -247.414323) (xy 349.493203 -247.428483)
			(xy 349.539182 -247.4503) (xy 349.581066 -247.47921) (xy 349.61777 -247.514465) (xy 349.648343 -247.555151)
			(xy 349.671994 -247.600214) (xy 349.68811 -247.648488) (xy 349.696274 -247.698722) (xy 349.696786 -247.724168)
			(xy 349.696283 -247.749157) (xy 350.0036 -247.749157) (xy 350.0036 -247.699179) (xy 350.011419 -247.649816)
			(xy 350.026863 -247.602284) (xy 350.049553 -247.557752) (xy 350.078929 -247.517319) (xy 350.114269 -247.481979)
			(xy 350.154702 -247.452603) (xy 350.199234 -247.429913) (xy 350.246766 -247.414469) (xy 350.296129 -247.40665)
			(xy 350.346107 -247.40665) (xy 350.39547 -247.414469) (xy 350.443002 -247.429913) (xy 350.487534 -247.452603)
			(xy 350.527967 -247.481979) (xy 350.563307 -247.517319) (xy 350.592683 -247.557752) (xy 350.615373 -247.602284)
			(xy 350.630817 -247.649816) (xy 350.638636 -247.699179) (xy 350.639126 -247.724168) (xy 350.944937 -247.724168)
			(xy 350.949032 -247.67344) (xy 350.961211 -247.624026) (xy 350.981159 -247.577206) (xy 351.00836 -247.534192)
			(xy 351.042108 -247.496098) (xy 351.08153 -247.463911) (xy 351.125604 -247.438465) (xy 351.17319 -247.420418)
			(xy 351.223054 -247.410238) (xy 351.273906 -247.408189) (xy 351.324427 -247.414323) (xy 351.373311 -247.428483)
			(xy 351.41929 -247.4503) (xy 351.461174 -247.47921) (xy 351.497878 -247.514465) (xy 351.528451 -247.555151)
			(xy 351.552102 -247.600214) (xy 351.568218 -247.648488) (xy 351.576382 -247.698722) (xy 351.576894 -247.724168)
			(xy 351.884991 -247.724168) (xy 351.889086 -247.67344) (xy 351.901265 -247.624026) (xy 351.921213 -247.577206)
			(xy 351.948414 -247.534192) (xy 351.982162 -247.496098) (xy 352.021584 -247.463911) (xy 352.065658 -247.438465)
			(xy 352.113244 -247.420418) (xy 352.163108 -247.410238) (xy 352.21396 -247.408189) (xy 352.264481 -247.414323)
			(xy 352.313365 -247.428483) (xy 352.359344 -247.4503) (xy 352.401228 -247.47921) (xy 352.437932 -247.514465)
			(xy 352.468505 -247.555151) (xy 352.492156 -247.600214) (xy 352.508272 -247.648488) (xy 352.516436 -247.698722)
			(xy 352.516948 -247.724168) (xy 352.516445 -247.749157) (xy 352.823508 -247.749157) (xy 352.823508 -247.699179)
			(xy 352.831327 -247.649816) (xy 352.846771 -247.602284) (xy 352.869461 -247.557752) (xy 352.898837 -247.517319)
			(xy 352.934177 -247.481979) (xy 352.97461 -247.452603) (xy 353.019142 -247.429913) (xy 353.066674 -247.414469)
			(xy 353.116037 -247.40665) (xy 353.166015 -247.40665) (xy 353.215378 -247.414469) (xy 353.26291 -247.429913)
			(xy 353.307442 -247.452603) (xy 353.347875 -247.481979) (xy 353.383215 -247.517319) (xy 353.412591 -247.557752)
			(xy 353.435281 -247.602284) (xy 353.450725 -247.649816) (xy 353.458544 -247.699179) (xy 353.459034 -247.724168)
			(xy 353.764845 -247.724168) (xy 353.76894 -247.67344) (xy 353.781119 -247.624026) (xy 353.801067 -247.577206)
			(xy 353.828268 -247.534192) (xy 353.862016 -247.496098) (xy 353.901438 -247.463911) (xy 353.945512 -247.438465)
			(xy 353.993098 -247.420418) (xy 354.042962 -247.410238) (xy 354.093814 -247.408189) (xy 354.144335 -247.414323)
			(xy 354.193219 -247.428483) (xy 354.239198 -247.4503) (xy 354.281082 -247.47921) (xy 354.317786 -247.514465)
			(xy 354.348359 -247.555151) (xy 354.37201 -247.600214) (xy 354.388126 -247.648488) (xy 354.39629 -247.698722)
			(xy 354.396802 -247.724168) (xy 354.704899 -247.724168) (xy 354.708994 -247.67344) (xy 354.721173 -247.624026)
			(xy 354.741121 -247.577206) (xy 354.768322 -247.534192) (xy 354.80207 -247.496098) (xy 354.841492 -247.463911)
			(xy 354.885566 -247.438465) (xy 354.933152 -247.420418) (xy 354.983016 -247.410238) (xy 355.033868 -247.408189)
			(xy 355.084389 -247.414323) (xy 355.133273 -247.428483) (xy 355.179252 -247.4503) (xy 355.221136 -247.47921)
			(xy 355.25784 -247.514465) (xy 355.288413 -247.555151) (xy 355.312064 -247.600214) (xy 355.32818 -247.648488)
			(xy 355.336344 -247.698722) (xy 355.336856 -247.724168) (xy 355.336353 -247.749157) (xy 355.64367 -247.749157)
			(xy 355.64367 -247.699179) (xy 355.651489 -247.649816) (xy 355.666933 -247.602284) (xy 355.689623 -247.557752)
			(xy 355.718999 -247.517319) (xy 355.754339 -247.481979) (xy 355.794772 -247.452603) (xy 355.839304 -247.429913)
			(xy 355.886836 -247.414469) (xy 355.936199 -247.40665) (xy 355.986177 -247.40665) (xy 356.03554 -247.414469)
			(xy 356.083072 -247.429913) (xy 356.127604 -247.452603) (xy 356.168037 -247.481979) (xy 356.203377 -247.517319)
			(xy 356.232753 -247.557752) (xy 356.255443 -247.602284) (xy 356.270887 -247.649816) (xy 356.278706 -247.699179)
			(xy 356.279196 -247.724168) (xy 356.278706 -247.749157) (xy 356.583724 -247.749157) (xy 356.583724 -247.699179)
			(xy 356.591543 -247.649816) (xy 356.606987 -247.602284) (xy 356.629677 -247.557752) (xy 356.659053 -247.517319)
			(xy 356.694393 -247.481979) (xy 356.734826 -247.452603) (xy 356.779358 -247.429913) (xy 356.82689 -247.414469)
			(xy 356.876253 -247.40665) (xy 356.926231 -247.40665) (xy 356.975594 -247.414469) (xy 357.023126 -247.429913)
			(xy 357.067658 -247.452603) (xy 357.108091 -247.481979) (xy 357.143431 -247.517319) (xy 357.172807 -247.557752)
			(xy 357.195497 -247.602284) (xy 357.210941 -247.649816) (xy 357.21876 -247.699179) (xy 357.21925 -247.724168)
			(xy 357.21876 -247.749157) (xy 357.523524 -247.749157) (xy 357.523524 -247.699179) (xy 357.531343 -247.649816)
			(xy 357.546787 -247.602284) (xy 357.569477 -247.557752) (xy 357.598853 -247.517319) (xy 357.634193 -247.481979)
			(xy 357.674626 -247.452603) (xy 357.719158 -247.429913) (xy 357.76669 -247.414469) (xy 357.816053 -247.40665)
			(xy 357.866031 -247.40665) (xy 357.915394 -247.414469) (xy 357.962926 -247.429913) (xy 358.007458 -247.452603)
			(xy 358.047891 -247.481979) (xy 358.083231 -247.517319) (xy 358.112607 -247.557752) (xy 358.135297 -247.602284)
			(xy 358.149315 -247.645428) (xy 359.375964 -247.645428) (xy 359.375964 -247.441212) (xy 359.376424 -247.42189)
			(xy 359.383396 -247.38388) (xy 359.397078 -247.347739) (xy 359.406698 -247.330976) (xy 359.410254 -247.323864)
			(xy 359.420586 -247.299523) (xy 359.447391 -247.253943) (xy 359.480643 -247.212829) (xy 359.51961 -247.177085)
			(xy 359.563435 -247.147498) (xy 359.611155 -247.124719) (xy 359.661719 -247.109249) (xy 359.714015 -247.101428)
			(xy 359.766893 -247.101428) (xy 359.819189 -247.109249) (xy 359.869753 -247.124719) (xy 359.917473 -247.147498)
			(xy 359.961298 -247.177085) (xy 360.000265 -247.212829) (xy 360.033517 -247.253943) (xy 360.060322 -247.299523)
			(xy 360.070654 -247.323864) (xy 360.07421 -247.330976) (xy 360.083864 -247.347724) (xy 360.097573 -247.383864)
			(xy 360.104532 -247.421885) (xy 360.104944 -247.441212) (xy 360.104944 -247.696228) (xy 360.0958 -247.696228)
			(xy 360.085775 -247.69662) (xy 360.067253 -247.704295) (xy 360.05308 -247.718476) (xy 360.045415 -247.737003)
			(xy 360.045 -247.747028) (xy 360.045 -247.749157) (xy 361.27739 -247.749157) (xy 361.27739 -247.699179)
			(xy 361.285209 -247.649816) (xy 361.300653 -247.602284) (xy 361.323343 -247.557752) (xy 361.352719 -247.517319)
			(xy 361.388059 -247.481979) (xy 361.428492 -247.452603) (xy 361.473024 -247.429913) (xy 361.520556 -247.414469)
			(xy 361.569919 -247.40665) (xy 361.619897 -247.40665) (xy 361.66926 -247.414469) (xy 361.716792 -247.429913)
			(xy 361.761324 -247.452603) (xy 361.801757 -247.481979) (xy 361.837097 -247.517319) (xy 361.866473 -247.557752)
			(xy 361.889163 -247.602284) (xy 361.904607 -247.649816) (xy 361.912426 -247.699179) (xy 361.912916 -247.724168)
			(xy 361.912426 -247.749157) (xy 362.21719 -247.749157) (xy 362.21719 -247.699179) (xy 362.225009 -247.649816)
			(xy 362.240453 -247.602284) (xy 362.263143 -247.557752) (xy 362.292519 -247.517319) (xy 362.327859 -247.481979)
			(xy 362.368292 -247.452603) (xy 362.412824 -247.429913) (xy 362.460356 -247.414469) (xy 362.509719 -247.40665)
			(xy 362.559697 -247.40665) (xy 362.60906 -247.414469) (xy 362.656592 -247.429913) (xy 362.701124 -247.452603)
			(xy 362.741557 -247.481979) (xy 362.776897 -247.517319) (xy 362.806273 -247.557752) (xy 362.828963 -247.602284)
			(xy 362.844407 -247.649816) (xy 362.852226 -247.699179) (xy 362.852716 -247.724168) (xy 362.852226 -247.749157)
			(xy 363.157244 -247.749157) (xy 363.157244 -247.699179) (xy 363.165063 -247.649816) (xy 363.180507 -247.602284)
			(xy 363.203197 -247.557752) (xy 363.232573 -247.517319) (xy 363.267913 -247.481979) (xy 363.308346 -247.452603)
			(xy 363.352878 -247.429913) (xy 363.40041 -247.414469) (xy 363.449773 -247.40665) (xy 363.499751 -247.40665)
			(xy 363.549114 -247.414469) (xy 363.596646 -247.429913) (xy 363.641178 -247.452603) (xy 363.681611 -247.481979)
			(xy 363.716951 -247.517319) (xy 363.746327 -247.557752) (xy 363.769017 -247.602284) (xy 363.784461 -247.649816)
			(xy 363.79228 -247.699179) (xy 363.79277 -247.724168) (xy 364.098581 -247.724168) (xy 364.102676 -247.67344)
			(xy 364.114855 -247.624026) (xy 364.134803 -247.577206) (xy 364.162004 -247.534192) (xy 364.195752 -247.496098)
			(xy 364.235174 -247.463911) (xy 364.279248 -247.438465) (xy 364.326834 -247.420418) (xy 364.376698 -247.410238)
			(xy 364.42755 -247.408189) (xy 364.478071 -247.414323) (xy 364.526955 -247.428483) (xy 364.572934 -247.4503)
			(xy 364.614818 -247.47921) (xy 364.651522 -247.514465) (xy 364.682095 -247.555151) (xy 364.705746 -247.600214)
			(xy 364.721862 -247.648488) (xy 364.730026 -247.698722) (xy 364.730538 -247.724168) (xy 365.038635 -247.724168)
			(xy 365.04273 -247.67344) (xy 365.054909 -247.624026) (xy 365.074857 -247.577206) (xy 365.102058 -247.534192)
			(xy 365.135806 -247.496098) (xy 365.175228 -247.463911) (xy 365.219302 -247.438465) (xy 365.266888 -247.420418)
			(xy 365.316752 -247.410238) (xy 365.367604 -247.408189) (xy 365.418125 -247.414323) (xy 365.467009 -247.428483)
			(xy 365.512988 -247.4503) (xy 365.554872 -247.47921) (xy 365.591576 -247.514465) (xy 365.622149 -247.555151)
			(xy 365.6458 -247.600214) (xy 365.661916 -247.648488) (xy 365.67008 -247.698722) (xy 365.670592 -247.724168)
			(xy 365.670089 -247.749157) (xy 365.977406 -247.749157) (xy 365.977406 -247.699179) (xy 365.985225 -247.649816)
			(xy 366.000669 -247.602284) (xy 366.023359 -247.557752) (xy 366.052735 -247.517319) (xy 366.088075 -247.481979)
			(xy 366.128508 -247.452603) (xy 366.17304 -247.429913) (xy 366.220572 -247.414469) (xy 366.269935 -247.40665)
			(xy 366.319913 -247.40665) (xy 366.369276 -247.414469) (xy 366.416808 -247.429913) (xy 366.46134 -247.452603)
			(xy 366.501773 -247.481979) (xy 366.537113 -247.517319) (xy 366.566489 -247.557752) (xy 366.589179 -247.602284)
			(xy 366.604623 -247.649816) (xy 366.612442 -247.699179) (xy 366.612932 -247.724168) (xy 366.918489 -247.724168)
			(xy 366.922584 -247.67344) (xy 366.934763 -247.624026) (xy 366.954711 -247.577206) (xy 366.981912 -247.534192)
			(xy 367.01566 -247.496098) (xy 367.055082 -247.463911) (xy 367.099156 -247.438465) (xy 367.146742 -247.420418)
			(xy 367.196606 -247.410238) (xy 367.247458 -247.408189) (xy 367.297979 -247.414323) (xy 367.346863 -247.428483)
			(xy 367.392842 -247.4503) (xy 367.434726 -247.47921) (xy 367.47143 -247.514465) (xy 367.502003 -247.555151)
			(xy 367.525654 -247.600214) (xy 367.54177 -247.648488) (xy 367.549934 -247.698722) (xy 367.550446 -247.724168)
			(xy 367.858543 -247.724168) (xy 367.862638 -247.67344) (xy 367.874817 -247.624026) (xy 367.894765 -247.577206)
			(xy 367.921966 -247.534192) (xy 367.955714 -247.496098) (xy 367.995136 -247.463911) (xy 368.03921 -247.438465)
			(xy 368.086796 -247.420418) (xy 368.13666 -247.410238) (xy 368.187512 -247.408189) (xy 368.238033 -247.414323)
			(xy 368.286917 -247.428483) (xy 368.332896 -247.4503) (xy 368.37478 -247.47921) (xy 368.411484 -247.514465)
			(xy 368.442057 -247.555151) (xy 368.465708 -247.600214) (xy 368.481824 -247.648488) (xy 368.489988 -247.698722)
			(xy 368.4905 -247.724168) (xy 368.489997 -247.749157) (xy 368.797314 -247.749157) (xy 368.797314 -247.699179)
			(xy 368.805133 -247.649816) (xy 368.820577 -247.602284) (xy 368.843267 -247.557752) (xy 368.872643 -247.517319)
			(xy 368.907983 -247.481979) (xy 368.948416 -247.452603) (xy 368.992948 -247.429913) (xy 369.04048 -247.414469)
			(xy 369.089843 -247.40665) (xy 369.139821 -247.40665) (xy 369.189184 -247.414469) (xy 369.236716 -247.429913)
			(xy 369.281248 -247.452603) (xy 369.321681 -247.481979) (xy 369.357021 -247.517319) (xy 369.386397 -247.557752)
			(xy 369.409087 -247.602284) (xy 369.424531 -247.649816) (xy 369.43235 -247.699179) (xy 369.43284 -247.724168)
			(xy 369.738651 -247.724168) (xy 369.742746 -247.67344) (xy 369.754925 -247.624026) (xy 369.774873 -247.577206)
			(xy 369.802074 -247.534192) (xy 369.835822 -247.496098) (xy 369.875244 -247.463911) (xy 369.919318 -247.438465)
			(xy 369.966904 -247.420418) (xy 370.016768 -247.410238) (xy 370.06762 -247.408189) (xy 370.118141 -247.414323)
			(xy 370.167025 -247.428483) (xy 370.213004 -247.4503) (xy 370.254888 -247.47921) (xy 370.291592 -247.514465)
			(xy 370.322165 -247.555151) (xy 370.345816 -247.600214) (xy 370.361932 -247.648488) (xy 370.370096 -247.698722)
			(xy 370.370608 -247.724168) (xy 370.678451 -247.724168) (xy 370.682546 -247.67344) (xy 370.694725 -247.624026)
			(xy 370.714673 -247.577206) (xy 370.741874 -247.534192) (xy 370.775622 -247.496098) (xy 370.815044 -247.463911)
			(xy 370.859118 -247.438465) (xy 370.906704 -247.420418) (xy 370.956568 -247.410238) (xy 371.00742 -247.408189)
			(xy 371.057941 -247.414323) (xy 371.106825 -247.428483) (xy 371.152804 -247.4503) (xy 371.194688 -247.47921)
			(xy 371.231392 -247.514465) (xy 371.261965 -247.555151) (xy 371.285616 -247.600214) (xy 371.301732 -247.648488)
			(xy 371.309896 -247.698722) (xy 371.310408 -247.724168) (xy 371.309905 -247.749157) (xy 371.617222 -247.749157)
			(xy 371.617222 -247.699179) (xy 371.625041 -247.649816) (xy 371.640485 -247.602284) (xy 371.663175 -247.557752)
			(xy 371.692551 -247.517319) (xy 371.727891 -247.481979) (xy 371.768324 -247.452603) (xy 371.812856 -247.429913)
			(xy 371.860388 -247.414469) (xy 371.909751 -247.40665) (xy 371.959729 -247.40665) (xy 372.009092 -247.414469)
			(xy 372.056624 -247.429913) (xy 372.101156 -247.452603) (xy 372.141589 -247.481979) (xy 372.176929 -247.517319)
			(xy 372.206305 -247.557752) (xy 372.228995 -247.602284) (xy 372.244439 -247.649816) (xy 372.252258 -247.699179)
			(xy 372.252748 -247.724168) (xy 372.558559 -247.724168) (xy 372.562654 -247.67344) (xy 372.574833 -247.624026)
			(xy 372.594781 -247.577206) (xy 372.621982 -247.534192) (xy 372.65573 -247.496098) (xy 372.695152 -247.463911)
			(xy 372.739226 -247.438465) (xy 372.786812 -247.420418) (xy 372.836676 -247.410238) (xy 372.887528 -247.408189)
			(xy 372.938049 -247.414323) (xy 372.986933 -247.428483) (xy 373.032912 -247.4503) (xy 373.074796 -247.47921)
			(xy 373.1115 -247.514465) (xy 373.142073 -247.555151) (xy 373.165724 -247.600214) (xy 373.18184 -247.648488)
			(xy 373.190004 -247.698722) (xy 373.190516 -247.724168) (xy 373.498613 -247.724168) (xy 373.502708 -247.67344)
			(xy 373.514887 -247.624026) (xy 373.534835 -247.577206) (xy 373.562036 -247.534192) (xy 373.595784 -247.496098)
			(xy 373.635206 -247.463911) (xy 373.67928 -247.438465) (xy 373.726866 -247.420418) (xy 373.77673 -247.410238)
			(xy 373.827582 -247.408189) (xy 373.878103 -247.414323) (xy 373.926987 -247.428483) (xy 373.972966 -247.4503)
			(xy 374.01485 -247.47921) (xy 374.051554 -247.514465) (xy 374.082127 -247.555151) (xy 374.105778 -247.600214)
			(xy 374.121894 -247.648488) (xy 374.130058 -247.698722) (xy 374.13057 -247.724168) (xy 374.130058 -247.749614)
			(xy 374.121894 -247.799848) (xy 374.105778 -247.848122) (xy 374.082127 -247.893185) (xy 374.051554 -247.933871)
			(xy 374.01485 -247.969126) (xy 373.972966 -247.998036) (xy 373.926987 -248.019853) (xy 373.878103 -248.034013)
			(xy 373.827582 -248.040147) (xy 373.77673 -248.038098) (xy 373.726866 -248.027918) (xy 373.67928 -248.009871)
			(xy 373.635206 -247.984425) (xy 373.595784 -247.952238) (xy 373.562036 -247.914144) (xy 373.534835 -247.87113)
			(xy 373.514887 -247.82431) (xy 373.502708 -247.774896) (xy 373.498613 -247.724168) (xy 373.190516 -247.724168)
			(xy 373.190004 -247.749614) (xy 373.18184 -247.799848) (xy 373.165724 -247.848122) (xy 373.142073 -247.893185)
			(xy 373.1115 -247.933871) (xy 373.074796 -247.969126) (xy 373.032912 -247.998036) (xy 372.986933 -248.019853)
			(xy 372.938049 -248.034013) (xy 372.887528 -248.040147) (xy 372.836676 -248.038098) (xy 372.786812 -248.027918)
			(xy 372.739226 -248.009871) (xy 372.695152 -247.984425) (xy 372.65573 -247.952238) (xy 372.621982 -247.914144)
			(xy 372.594781 -247.87113) (xy 372.574833 -247.82431) (xy 372.562654 -247.774896) (xy 372.558559 -247.724168)
			(xy 372.252748 -247.724168) (xy 372.252258 -247.749157) (xy 372.244439 -247.79852) (xy 372.228995 -247.846052)
			(xy 372.206305 -247.890584) (xy 372.176929 -247.931017) (xy 372.141589 -247.966357) (xy 372.101156 -247.995733)
			(xy 372.056624 -248.018423) (xy 372.009092 -248.033867) (xy 371.959729 -248.041686) (xy 371.909751 -248.041686)
			(xy 371.860388 -248.033867) (xy 371.812856 -248.018423) (xy 371.768324 -247.995733) (xy 371.727891 -247.966357)
			(xy 371.692551 -247.931017) (xy 371.663175 -247.890584) (xy 371.640485 -247.846052) (xy 371.625041 -247.79852)
			(xy 371.617222 -247.749157) (xy 371.309905 -247.749157) (xy 371.309896 -247.749614) (xy 371.301732 -247.799848)
			(xy 371.285616 -247.848122) (xy 371.261965 -247.893185) (xy 371.231392 -247.933871) (xy 371.194688 -247.969126)
			(xy 371.152804 -247.998036) (xy 371.106825 -248.019853) (xy 371.057941 -248.034013) (xy 371.00742 -248.040147)
			(xy 370.956568 -248.038098) (xy 370.906704 -248.027918) (xy 370.859118 -248.009871) (xy 370.815044 -247.984425)
			(xy 370.775622 -247.952238) (xy 370.741874 -247.914144) (xy 370.714673 -247.87113) (xy 370.694725 -247.82431)
			(xy 370.682546 -247.774896) (xy 370.678451 -247.724168) (xy 370.370608 -247.724168) (xy 370.370096 -247.749614)
			(xy 370.361932 -247.799848) (xy 370.345816 -247.848122) (xy 370.322165 -247.893185) (xy 370.291592 -247.933871)
			(xy 370.254888 -247.969126) (xy 370.213004 -247.998036) (xy 370.167025 -248.019853) (xy 370.118141 -248.034013)
			(xy 370.06762 -248.040147) (xy 370.016768 -248.038098) (xy 369.966904 -248.027918) (xy 369.919318 -248.009871)
			(xy 369.875244 -247.984425) (xy 369.835822 -247.952238) (xy 369.802074 -247.914144) (xy 369.774873 -247.87113)
			(xy 369.754925 -247.82431) (xy 369.742746 -247.774896) (xy 369.738651 -247.724168) (xy 369.43284 -247.724168)
			(xy 369.43235 -247.749157) (xy 369.424531 -247.79852) (xy 369.409087 -247.846052) (xy 369.386397 -247.890584)
			(xy 369.357021 -247.931017) (xy 369.321681 -247.966357) (xy 369.281248 -247.995733) (xy 369.236716 -248.018423)
			(xy 369.189184 -248.033867) (xy 369.139821 -248.041686) (xy 369.089843 -248.041686) (xy 369.04048 -248.033867)
			(xy 368.992948 -248.018423) (xy 368.948416 -247.995733) (xy 368.907983 -247.966357) (xy 368.872643 -247.931017)
			(xy 368.843267 -247.890584) (xy 368.820577 -247.846052) (xy 368.805133 -247.79852) (xy 368.797314 -247.749157)
			(xy 368.489997 -247.749157) (xy 368.489988 -247.749614) (xy 368.481824 -247.799848) (xy 368.465708 -247.848122)
			(xy 368.442057 -247.893185) (xy 368.411484 -247.933871) (xy 368.37478 -247.969126) (xy 368.332896 -247.998036)
			(xy 368.286917 -248.019853) (xy 368.238033 -248.034013) (xy 368.187512 -248.040147) (xy 368.13666 -248.038098)
			(xy 368.086796 -248.027918) (xy 368.03921 -248.009871) (xy 367.995136 -247.984425) (xy 367.955714 -247.952238)
			(xy 367.921966 -247.914144) (xy 367.894765 -247.87113) (xy 367.874817 -247.82431) (xy 367.862638 -247.774896)
			(xy 367.858543 -247.724168) (xy 367.550446 -247.724168) (xy 367.549934 -247.749614) (xy 367.54177 -247.799848)
			(xy 367.525654 -247.848122) (xy 367.502003 -247.893185) (xy 367.47143 -247.933871) (xy 367.434726 -247.969126)
			(xy 367.392842 -247.998036) (xy 367.346863 -248.019853) (xy 367.297979 -248.034013) (xy 367.247458 -248.040147)
			(xy 367.196606 -248.038098) (xy 367.146742 -248.027918) (xy 367.099156 -248.009871) (xy 367.055082 -247.984425)
			(xy 367.01566 -247.952238) (xy 366.981912 -247.914144) (xy 366.954711 -247.87113) (xy 366.934763 -247.82431)
			(xy 366.922584 -247.774896) (xy 366.918489 -247.724168) (xy 366.612932 -247.724168) (xy 366.612442 -247.749157)
			(xy 366.604623 -247.79852) (xy 366.589179 -247.846052) (xy 366.566489 -247.890584) (xy 366.537113 -247.931017)
			(xy 366.501773 -247.966357) (xy 366.46134 -247.995733) (xy 366.416808 -248.018423) (xy 366.369276 -248.033867)
			(xy 366.319913 -248.041686) (xy 366.269935 -248.041686) (xy 366.220572 -248.033867) (xy 366.17304 -248.018423)
			(xy 366.128508 -247.995733) (xy 366.088075 -247.966357) (xy 366.052735 -247.931017) (xy 366.023359 -247.890584)
			(xy 366.000669 -247.846052) (xy 365.985225 -247.79852) (xy 365.977406 -247.749157) (xy 365.670089 -247.749157)
			(xy 365.67008 -247.749614) (xy 365.661916 -247.799848) (xy 365.6458 -247.848122) (xy 365.622149 -247.893185)
			(xy 365.591576 -247.933871) (xy 365.554872 -247.969126) (xy 365.512988 -247.998036) (xy 365.467009 -248.019853)
			(xy 365.418125 -248.034013) (xy 365.367604 -248.040147) (xy 365.316752 -248.038098) (xy 365.266888 -248.027918)
			(xy 365.219302 -248.009871) (xy 365.175228 -247.984425) (xy 365.135806 -247.952238) (xy 365.102058 -247.914144)
			(xy 365.074857 -247.87113) (xy 365.054909 -247.82431) (xy 365.04273 -247.774896) (xy 365.038635 -247.724168)
			(xy 364.730538 -247.724168) (xy 364.730026 -247.749614) (xy 364.721862 -247.799848) (xy 364.705746 -247.848122)
			(xy 364.682095 -247.893185) (xy 364.651522 -247.933871) (xy 364.614818 -247.969126) (xy 364.572934 -247.998036)
			(xy 364.526955 -248.019853) (xy 364.478071 -248.034013) (xy 364.42755 -248.040147) (xy 364.376698 -248.038098)
			(xy 364.326834 -248.027918) (xy 364.279248 -248.009871) (xy 364.235174 -247.984425) (xy 364.195752 -247.952238)
			(xy 364.162004 -247.914144) (xy 364.134803 -247.87113) (xy 364.114855 -247.82431) (xy 364.102676 -247.774896)
			(xy 364.098581 -247.724168) (xy 363.79277 -247.724168) (xy 363.79228 -247.749157) (xy 363.784461 -247.79852)
			(xy 363.769017 -247.846052) (xy 363.746327 -247.890584) (xy 363.716951 -247.931017) (xy 363.681611 -247.966357)
			(xy 363.641178 -247.995733) (xy 363.596646 -248.018423) (xy 363.549114 -248.033867) (xy 363.499751 -248.041686)
			(xy 363.449773 -248.041686) (xy 363.40041 -248.033867) (xy 363.352878 -248.018423) (xy 363.308346 -247.995733)
			(xy 363.267913 -247.966357) (xy 363.232573 -247.931017) (xy 363.203197 -247.890584) (xy 363.180507 -247.846052)
			(xy 363.165063 -247.79852) (xy 363.157244 -247.749157) (xy 362.852226 -247.749157) (xy 362.844407 -247.79852)
			(xy 362.828963 -247.846052) (xy 362.806273 -247.890584) (xy 362.776897 -247.931017) (xy 362.741557 -247.966357)
			(xy 362.701124 -247.995733) (xy 362.656592 -248.018423) (xy 362.60906 -248.033867) (xy 362.559697 -248.041686)
			(xy 362.509719 -248.041686) (xy 362.460356 -248.033867) (xy 362.412824 -248.018423) (xy 362.368292 -247.995733)
			(xy 362.327859 -247.966357) (xy 362.292519 -247.931017) (xy 362.263143 -247.890584) (xy 362.240453 -247.846052)
			(xy 362.225009 -247.79852) (xy 362.21719 -247.749157) (xy 361.912426 -247.749157) (xy 361.904607 -247.79852)
			(xy 361.889163 -247.846052) (xy 361.866473 -247.890584) (xy 361.837097 -247.931017) (xy 361.801757 -247.966357)
			(xy 361.761324 -247.995733) (xy 361.716792 -248.018423) (xy 361.66926 -248.033867) (xy 361.619897 -248.041686)
			(xy 361.569919 -248.041686) (xy 361.520556 -248.033867) (xy 361.473024 -248.018423) (xy 361.428492 -247.995733)
			(xy 361.388059 -247.966357) (xy 361.352719 -247.931017) (xy 361.323343 -247.890584) (xy 361.300653 -247.846052)
			(xy 361.285209 -247.79852) (xy 361.27739 -247.749157) (xy 360.045 -247.749157) (xy 360.045 -247.910096)
			(xy 360.044577 -247.920117) (xy 360.036909 -247.938634) (xy 360.022737 -247.952806) (xy 360.004221 -247.960476)
			(xy 359.9942 -247.960896) (xy 359.486708 -247.960896) (xy 359.476687 -247.960474) (xy 359.458169 -247.952806)
			(xy 359.443996 -247.938634) (xy 359.436327 -247.920117) (xy 359.435908 -247.910096) (xy 359.435908 -247.696228)
			(xy 359.426764 -247.696228) (xy 359.416757 -247.695742) (xy 359.39827 -247.688076) (xy 359.38412 -247.673923)
			(xy 359.376456 -247.655435) (xy 359.375964 -247.645428) (xy 358.149315 -247.645428) (xy 358.150741 -247.649816)
			(xy 358.15856 -247.699179) (xy 358.15905 -247.724168) (xy 358.15856 -247.749157) (xy 358.150741 -247.79852)
			(xy 358.135297 -247.846052) (xy 358.112607 -247.890584) (xy 358.083231 -247.931017) (xy 358.047891 -247.966357)
			(xy 358.007458 -247.995733) (xy 357.962926 -248.018423) (xy 357.915394 -248.033867) (xy 357.866031 -248.041686)
			(xy 357.816053 -248.041686) (xy 357.76669 -248.033867) (xy 357.719158 -248.018423) (xy 357.674626 -247.995733)
			(xy 357.634193 -247.966357) (xy 357.598853 -247.931017) (xy 357.569477 -247.890584) (xy 357.546787 -247.846052)
			(xy 357.531343 -247.79852) (xy 357.523524 -247.749157) (xy 357.21876 -247.749157) (xy 357.210941 -247.79852)
			(xy 357.195497 -247.846052) (xy 357.172807 -247.890584) (xy 357.143431 -247.931017) (xy 357.108091 -247.966357)
			(xy 357.067658 -247.995733) (xy 357.023126 -248.018423) (xy 356.975594 -248.033867) (xy 356.926231 -248.041686)
			(xy 356.876253 -248.041686) (xy 356.82689 -248.033867) (xy 356.779358 -248.018423) (xy 356.734826 -247.995733)
			(xy 356.694393 -247.966357) (xy 356.659053 -247.931017) (xy 356.629677 -247.890584) (xy 356.606987 -247.846052)
			(xy 356.591543 -247.79852) (xy 356.583724 -247.749157) (xy 356.278706 -247.749157) (xy 356.270887 -247.79852)
			(xy 356.255443 -247.846052) (xy 356.232753 -247.890584) (xy 356.203377 -247.931017) (xy 356.168037 -247.966357)
			(xy 356.127604 -247.995733) (xy 356.083072 -248.018423) (xy 356.03554 -248.033867) (xy 355.986177 -248.041686)
			(xy 355.936199 -248.041686) (xy 355.886836 -248.033867) (xy 355.839304 -248.018423) (xy 355.794772 -247.995733)
			(xy 355.754339 -247.966357) (xy 355.718999 -247.931017) (xy 355.689623 -247.890584) (xy 355.666933 -247.846052)
			(xy 355.651489 -247.79852) (xy 355.64367 -247.749157) (xy 355.336353 -247.749157) (xy 355.336344 -247.749614)
			(xy 355.32818 -247.799848) (xy 355.312064 -247.848122) (xy 355.288413 -247.893185) (xy 355.25784 -247.933871)
			(xy 355.221136 -247.969126) (xy 355.179252 -247.998036) (xy 355.133273 -248.019853) (xy 355.084389 -248.034013)
			(xy 355.033868 -248.040147) (xy 354.983016 -248.038098) (xy 354.933152 -248.027918) (xy 354.885566 -248.009871)
			(xy 354.841492 -247.984425) (xy 354.80207 -247.952238) (xy 354.768322 -247.914144) (xy 354.741121 -247.87113)
			(xy 354.721173 -247.82431) (xy 354.708994 -247.774896) (xy 354.704899 -247.724168) (xy 354.396802 -247.724168)
			(xy 354.39629 -247.749614) (xy 354.388126 -247.799848) (xy 354.37201 -247.848122) (xy 354.348359 -247.893185)
			(xy 354.317786 -247.933871) (xy 354.281082 -247.969126) (xy 354.239198 -247.998036) (xy 354.193219 -248.019853)
			(xy 354.144335 -248.034013) (xy 354.093814 -248.040147) (xy 354.042962 -248.038098) (xy 353.993098 -248.027918)
			(xy 353.945512 -248.009871) (xy 353.901438 -247.984425) (xy 353.862016 -247.952238) (xy 353.828268 -247.914144)
			(xy 353.801067 -247.87113) (xy 353.781119 -247.82431) (xy 353.76894 -247.774896) (xy 353.764845 -247.724168)
			(xy 353.459034 -247.724168) (xy 353.458544 -247.749157) (xy 353.450725 -247.79852) (xy 353.435281 -247.846052)
			(xy 353.412591 -247.890584) (xy 353.383215 -247.931017) (xy 353.347875 -247.966357) (xy 353.307442 -247.995733)
			(xy 353.26291 -248.018423) (xy 353.215378 -248.033867) (xy 353.166015 -248.041686) (xy 353.116037 -248.041686)
			(xy 353.066674 -248.033867) (xy 353.019142 -248.018423) (xy 352.97461 -247.995733) (xy 352.934177 -247.966357)
			(xy 352.898837 -247.931017) (xy 352.869461 -247.890584) (xy 352.846771 -247.846052) (xy 352.831327 -247.79852)
			(xy 352.823508 -247.749157) (xy 352.516445 -247.749157) (xy 352.516436 -247.749614) (xy 352.508272 -247.799848)
			(xy 352.492156 -247.848122) (xy 352.468505 -247.893185) (xy 352.437932 -247.933871) (xy 352.401228 -247.969126)
			(xy 352.359344 -247.998036) (xy 352.313365 -248.019853) (xy 352.264481 -248.034013) (xy 352.21396 -248.040147)
			(xy 352.163108 -248.038098) (xy 352.113244 -248.027918) (xy 352.065658 -248.009871) (xy 352.021584 -247.984425)
			(xy 351.982162 -247.952238) (xy 351.948414 -247.914144) (xy 351.921213 -247.87113) (xy 351.901265 -247.82431)
			(xy 351.889086 -247.774896) (xy 351.884991 -247.724168) (xy 351.576894 -247.724168) (xy 351.576382 -247.749614)
			(xy 351.568218 -247.799848) (xy 351.552102 -247.848122) (xy 351.528451 -247.893185) (xy 351.497878 -247.933871)
			(xy 351.461174 -247.969126) (xy 351.41929 -247.998036) (xy 351.373311 -248.019853) (xy 351.324427 -248.034013)
			(xy 351.273906 -248.040147) (xy 351.223054 -248.038098) (xy 351.17319 -248.027918) (xy 351.125604 -248.009871)
			(xy 351.08153 -247.984425) (xy 351.042108 -247.952238) (xy 351.00836 -247.914144) (xy 350.981159 -247.87113)
			(xy 350.961211 -247.82431) (xy 350.949032 -247.774896) (xy 350.944937 -247.724168) (xy 350.639126 -247.724168)
			(xy 350.638636 -247.749157) (xy 350.630817 -247.79852) (xy 350.615373 -247.846052) (xy 350.592683 -247.890584)
			(xy 350.563307 -247.931017) (xy 350.527967 -247.966357) (xy 350.487534 -247.995733) (xy 350.443002 -248.018423)
			(xy 350.39547 -248.033867) (xy 350.346107 -248.041686) (xy 350.296129 -248.041686) (xy 350.246766 -248.033867)
			(xy 350.199234 -248.018423) (xy 350.154702 -247.995733) (xy 350.114269 -247.966357) (xy 350.078929 -247.931017)
			(xy 350.049553 -247.890584) (xy 350.026863 -247.846052) (xy 350.011419 -247.79852) (xy 350.0036 -247.749157)
			(xy 349.696283 -247.749157) (xy 349.696274 -247.749614) (xy 349.68811 -247.799848) (xy 349.671994 -247.848122)
			(xy 349.648343 -247.893185) (xy 349.61777 -247.933871) (xy 349.581066 -247.969126) (xy 349.539182 -247.998036)
			(xy 349.493203 -248.019853) (xy 349.444319 -248.034013) (xy 349.393798 -248.040147) (xy 349.342946 -248.038098)
			(xy 349.293082 -248.027918) (xy 349.245496 -248.009871) (xy 349.201422 -247.984425) (xy 349.162 -247.952238)
			(xy 349.128252 -247.914144) (xy 349.101051 -247.87113) (xy 349.081103 -247.82431) (xy 349.068924 -247.774896)
			(xy 349.064829 -247.724168) (xy 348.756732 -247.724168) (xy 348.75622 -247.749614) (xy 348.748056 -247.799848)
			(xy 348.73194 -247.848122) (xy 348.708289 -247.893185) (xy 348.677716 -247.933871) (xy 348.641012 -247.969126)
			(xy 348.599128 -247.998036) (xy 348.553149 -248.019853) (xy 348.504265 -248.034013) (xy 348.453744 -248.040147)
			(xy 348.402892 -248.038098) (xy 348.353028 -248.027918) (xy 348.305442 -248.009871) (xy 348.261368 -247.984425)
			(xy 348.221946 -247.952238) (xy 348.188198 -247.914144) (xy 348.160997 -247.87113) (xy 348.141049 -247.82431)
			(xy 348.12887 -247.774896) (xy 348.124775 -247.724168) (xy 347.819218 -247.724168) (xy 347.818728 -247.749157)
			(xy 347.810909 -247.79852) (xy 347.795465 -247.846052) (xy 347.772775 -247.890584) (xy 347.743399 -247.931017)
			(xy 347.708059 -247.966357) (xy 347.667626 -247.995733) (xy 347.623094 -248.018423) (xy 347.575562 -248.033867)
			(xy 347.526199 -248.041686) (xy 347.476221 -248.041686) (xy 347.426858 -248.033867) (xy 347.379326 -248.018423)
			(xy 347.334794 -247.995733) (xy 347.294361 -247.966357) (xy 347.259021 -247.931017) (xy 347.229645 -247.890584)
			(xy 347.206955 -247.846052) (xy 347.191511 -247.79852) (xy 347.183692 -247.749157) (xy 346.876375 -247.749157)
			(xy 346.876366 -247.749614) (xy 346.868202 -247.799848) (xy 346.852086 -247.848122) (xy 346.828435 -247.893185)
			(xy 346.797862 -247.933871) (xy 346.761158 -247.969126) (xy 346.719274 -247.998036) (xy 346.673295 -248.019853)
			(xy 346.624411 -248.034013) (xy 346.57389 -248.040147) (xy 346.523038 -248.038098) (xy 346.473174 -248.027918)
			(xy 346.425588 -248.009871) (xy 346.381514 -247.984425) (xy 346.342092 -247.952238) (xy 346.308344 -247.914144)
			(xy 346.281143 -247.87113) (xy 346.261195 -247.82431) (xy 346.249016 -247.774896) (xy 346.244921 -247.724168)
			(xy 345.936824 -247.724168) (xy 345.936312 -247.749614) (xy 345.928148 -247.799848) (xy 345.912032 -247.848122)
			(xy 345.888381 -247.893185) (xy 345.857808 -247.933871) (xy 345.821104 -247.969126) (xy 345.77922 -247.998036)
			(xy 345.733241 -248.019853) (xy 345.684357 -248.034013) (xy 345.633836 -248.040147) (xy 345.582984 -248.038098)
			(xy 345.53312 -248.027918) (xy 345.485534 -248.009871) (xy 345.44146 -247.984425) (xy 345.402038 -247.952238)
			(xy 345.36829 -247.914144) (xy 345.341089 -247.87113) (xy 345.321141 -247.82431) (xy 345.308962 -247.774896)
			(xy 345.304867 -247.724168) (xy 344.999056 -247.724168) (xy 344.999056 -247.724422) (xy 344.997786 -247.753632)
			(xy 344.997532 -247.758204) (xy 344.997532 -248.585736) (xy 344.998294 -248.594372) (xy 345.001342 -248.60504)
			(xy 345.005152 -248.61393) (xy 345.2368 -248.845578) (xy 345.239866 -248.848469) (xy 345.246763 -248.853312)
			(xy 345.250516 -248.85523) (xy 345.252548 -248.855992) (xy 345.257388 -248.857995) (xy 345.267632 -248.860172)
			(xy 345.272868 -248.86031) (xy 346.41028 -248.86031) (xy 346.420152 -248.8599) (xy 346.438393 -248.852347)
			(xy 346.452352 -248.838386) (xy 346.459901 -248.820144) (xy 346.460318 -248.810272) (xy 346.460318 -248.20372)
			(xy 346.489274 -248.174764) (xy 346.675456 -248.174764) (xy 346.685839 -248.174176) (xy 346.704839 -248.16577)
			(xy 346.712286 -248.158508) (xy 346.717713 -248.152085) (xy 346.72434 -248.136642) (xy 346.72524 -248.128282)
			(xy 346.72524 -248.11482) (xy 346.976446 -248.11482) (xy 346.979494 -248.114566) (xy 347.001204 -248.115029)
			(xy 347.04375 -248.123682) (xy 347.083678 -248.140737) (xy 347.119347 -248.165492) (xy 347.134688 -248.18086)
			(xy 347.136212 -248.182384) (xy 347.146008 -248.193266) (xy 347.16284 -248.217223) (xy 347.16974 -248.230136)
			(xy 347.171518 -248.233692) (xy 347.179392 -248.244614) (xy 347.180408 -248.245884) (xy 347.189298 -248.25579)
			(xy 347.193616 -248.260616) (xy 347.199712 -248.264426) (xy 347.222166 -248.279141) (xy 347.262242 -248.314858)
			(xy 347.295757 -248.356792) (xy 347.321764 -248.403754) (xy 347.339523 -248.454413) (xy 347.348533 -248.507333)
			(xy 347.349064 -248.534174) (xy 347.348646 -248.556822) (xy 347.342189 -248.601657) (xy 347.329444 -248.645125)
			(xy 347.310668 -248.686347) (xy 347.298772 -248.705624) (xy 347.295216 -248.710958) (xy 347.291152 -248.717816)
			(xy 347.290644 -248.73077) (xy 347.29059 -248.733056) (xy 349.330772 -248.733056) (xy 349.330772 -248.225564)
			(xy 349.331258 -248.215557) (xy 349.338924 -248.19707) (xy 349.353077 -248.18292) (xy 349.371565 -248.175256)
			(xy 349.381572 -248.174764) (xy 349.59544 -248.174764) (xy 349.59544 -248.16562) (xy 349.595837 -248.155595)
			(xy 349.603508 -248.137071) (xy 349.617688 -248.122897) (xy 349.636215 -248.115233) (xy 349.64624 -248.11482)
			(xy 349.850456 -248.11482) (xy 349.870991 -248.115327) (xy 349.911306 -248.123169) (xy 349.949377 -248.138574)
			(xy 349.983802 -248.160971) (xy 350.013311 -248.189537) (xy 350.036815 -248.223217) (xy 350.053448 -248.260768)
			(xy 350.058482 -248.280682) (xy 350.060378 -248.287776) (xy 350.067597 -248.300554) (xy 350.072706 -248.305828)
			(xy 350.090628 -248.323944) (xy 350.121052 -248.364821) (xy 350.144577 -248.410021) (xy 350.160604 -248.458391)
			(xy 350.168723 -248.508696) (xy 350.169226 -248.534174) (xy 352.353118 -248.534174) (xy 352.353639 -248.509251)
			(xy 352.361444 -248.460018) (xy 352.376812 -248.412599) (xy 352.387662 -248.390156) (xy 352.387916 -248.389902)
			(xy 352.390289 -248.384621) (xy 352.392864 -248.373337) (xy 352.392996 -248.36755) (xy 352.392996 -248.32945)
			(xy 352.393388 -248.308403) (xy 352.401386 -248.267082) (xy 352.41732 -248.228127) (xy 352.440571 -248.193045)
			(xy 352.470242 -248.163194) (xy 352.505182 -248.13973) (xy 352.54404 -248.123561) (xy 352.585312 -248.115312)
			(xy 352.606356 -248.11482) (xy 352.861372 -248.11482) (xy 352.861372 -248.123964) (xy 352.861848 -248.13398)
			(xy 352.869501 -248.15249) (xy 352.883656 -248.166663) (xy 352.902157 -248.174339) (xy 352.912172 -248.174764)
			(xy 353.07524 -248.174764) (xy 353.085246 -248.175254) (xy 353.103732 -248.18292) (xy 353.117882 -248.197072)
			(xy 353.125546 -248.215558) (xy 353.12604 -248.225564) (xy 353.12604 -248.733056) (xy 355.051868 -248.733056)
			(xy 355.051868 -248.225564) (xy 355.052358 -248.215558) (xy 355.060023 -248.197072) (xy 355.074175 -248.182921)
			(xy 355.092662 -248.175257) (xy 355.102668 -248.174764) (xy 355.316536 -248.174764) (xy 355.316536 -248.16562)
			(xy 355.316937 -248.155596) (xy 355.324607 -248.137072) (xy 355.338786 -248.122898) (xy 355.357311 -248.115234)
			(xy 355.367336 -248.11482) (xy 355.571552 -248.11482) (xy 355.592596 -248.115367) (xy 355.633869 -248.1236)
			(xy 355.672732 -248.139757) (xy 355.707677 -248.163211) (xy 355.737353 -248.193054) (xy 355.76061 -248.228132)
			(xy 355.776547 -248.267085) (xy 355.784548 -248.308404) (xy 355.784912 -248.32945) (xy 355.784912 -248.329704)
			(xy 355.784912 -248.412) (xy 355.788214 -248.420636) (xy 355.79794 -248.448007) (xy 355.808419 -248.505134)
			(xy 355.809042 -248.534174) (xy 356.114853 -248.534174) (xy 356.118948 -248.483446) (xy 356.131127 -248.434032)
			(xy 356.151075 -248.387212) (xy 356.178276 -248.344198) (xy 356.212024 -248.306104) (xy 356.251446 -248.273917)
			(xy 356.29552 -248.248471) (xy 356.343106 -248.230424) (xy 356.39297 -248.220244) (xy 356.443822 -248.218195)
			(xy 356.494343 -248.224329) (xy 356.543227 -248.238489) (xy 356.589206 -248.260306) (xy 356.63109 -248.289216)
			(xy 356.667794 -248.324471) (xy 356.698367 -248.365157) (xy 356.722018 -248.41022) (xy 356.738134 -248.458494)
			(xy 356.746298 -248.508728) (xy 356.74681 -248.534174) (xy 357.054907 -248.534174) (xy 357.059002 -248.483446)
			(xy 357.071181 -248.434032) (xy 357.091129 -248.387212) (xy 357.11833 -248.344198) (xy 357.152078 -248.306104)
			(xy 357.1915 -248.273917) (xy 357.235574 -248.248471) (xy 357.28316 -248.230424) (xy 357.333024 -248.220244)
			(xy 357.383876 -248.218195) (xy 357.434397 -248.224329) (xy 357.483281 -248.238489) (xy 357.52926 -248.260306)
			(xy 357.571144 -248.289216) (xy 357.607848 -248.324471) (xy 357.638421 -248.365157) (xy 357.662072 -248.41022)
			(xy 357.678188 -248.458494) (xy 357.686352 -248.508728) (xy 357.686864 -248.534174) (xy 357.686352 -248.55962)
			(xy 357.678188 -248.609854) (xy 357.662072 -248.658128) (xy 357.638421 -248.703191) (xy 357.61043 -248.740441)
			(xy 357.817344 -248.740441) (xy 357.819956 -248.72062) (xy 357.824532 -248.71172) (xy 357.93172 -248.526554)
			(xy 357.923846 -248.521982) (xy 357.915331 -248.516658) (xy 357.903032 -248.500801) (xy 357.897782 -248.481433)
			(xy 357.900389 -248.461536) (xy 357.90505 -248.45264) (xy 358.007158 -248.275856) (xy 358.018145 -248.257874)
			(xy 358.045947 -248.226215) (xy 358.079412 -248.200616) (xy 358.117243 -248.182067) (xy 358.157974 -248.171289)
			(xy 358.200028 -248.168698) (xy 358.241774 -248.174395) (xy 358.281596 -248.188159) (xy 358.30002 -248.198386)
			(xy 358.300274 -248.198386) (xy 358.33177 -248.216674) (xy 358.342692 -248.21769) (xy 358.369952 -248.221003)
			(xy 358.422841 -248.235762) (xy 358.472414 -248.259375) (xy 358.517201 -248.291142) (xy 358.555875 -248.330122)
			(xy 358.572054 -248.35231) (xy 358.574368 -248.355538) (xy 358.579858 -248.361279) (xy 358.582976 -248.36374)
			(xy 358.600194 -248.377547) (xy 358.629124 -248.410866) (xy 358.650601 -248.449411) (xy 358.663713 -248.491544)
			(xy 358.6679 -248.53547) (xy 358.665245 -248.559163) (xy 360.807236 -248.559163) (xy 360.807236 -248.509185)
			(xy 360.815055 -248.459822) (xy 360.830499 -248.41229) (xy 360.853189 -248.367758) (xy 360.882565 -248.327325)
			(xy 360.917905 -248.291985) (xy 360.958338 -248.262609) (xy 361.00287 -248.239919) (xy 361.050402 -248.224475)
			(xy 361.099765 -248.216656) (xy 361.149743 -248.216656) (xy 361.199106 -248.224475) (xy 361.246638 -248.239919)
			(xy 361.29117 -248.262609) (xy 361.331603 -248.291985) (xy 361.366943 -248.327325) (xy 361.396319 -248.367758)
			(xy 361.419009 -248.41229) (xy 361.434453 -248.459822) (xy 361.442272 -248.509185) (xy 361.442762 -248.534174)
			(xy 361.748573 -248.534174) (xy 361.752668 -248.483446) (xy 361.764847 -248.434032) (xy 361.784795 -248.387212)
			(xy 361.811996 -248.344198) (xy 361.845744 -248.306104) (xy 361.885166 -248.273917) (xy 361.92924 -248.248471)
			(xy 361.976826 -248.230424) (xy 362.02669 -248.220244) (xy 362.077542 -248.218195) (xy 362.128063 -248.224329)
			(xy 362.176947 -248.238489) (xy 362.222926 -248.260306) (xy 362.26481 -248.289216) (xy 362.301514 -248.324471)
			(xy 362.332087 -248.365157) (xy 362.355738 -248.41022) (xy 362.371854 -248.458494) (xy 362.380018 -248.508728)
			(xy 362.38053 -248.534174) (xy 362.688627 -248.534174) (xy 362.692722 -248.483446) (xy 362.704901 -248.434032)
			(xy 362.724849 -248.387212) (xy 362.75205 -248.344198) (xy 362.785798 -248.306104) (xy 362.82522 -248.273917)
			(xy 362.869294 -248.248471) (xy 362.91688 -248.230424) (xy 362.966744 -248.220244) (xy 363.017596 -248.218195)
			(xy 363.068117 -248.224329) (xy 363.117001 -248.238489) (xy 363.16298 -248.260306) (xy 363.204864 -248.289216)
			(xy 363.241568 -248.324471) (xy 363.272141 -248.365157) (xy 363.295792 -248.41022) (xy 363.311908 -248.458494)
			(xy 363.320072 -248.508728) (xy 363.320584 -248.534174) (xy 363.626908 -248.534174) (xy 363.626908 -248.53392)
			(xy 363.627478 -248.507208) (xy 363.636414 -248.454537) (xy 363.654021 -248.404097) (xy 363.679805 -248.357307)
			(xy 363.695996 -248.336054) (xy 363.695996 -248.329704) (xy 363.696366 -248.308641) (xy 363.704327 -248.267281)
			(xy 363.720238 -248.228282) (xy 363.743481 -248.193156) (xy 363.773156 -248.163265) (xy 363.808112 -248.139767)
			(xy 363.846995 -248.123574) (xy 363.888296 -248.115313) (xy 363.909356 -248.11482) (xy 364.164372 -248.11482)
			(xy 364.164372 -248.123964) (xy 364.164848 -248.13398) (xy 364.172501 -248.15249) (xy 364.186656 -248.166663)
			(xy 364.205157 -248.174339) (xy 364.215172 -248.174764) (xy 364.37824 -248.174764) (xy 364.388246 -248.175254)
			(xy 364.406732 -248.18292) (xy 364.420882 -248.197072) (xy 364.428546 -248.215558) (xy 364.42904 -248.225564)
			(xy 364.42904 -248.733056) (xy 366.227868 -248.733056) (xy 366.227868 -248.225564) (xy 366.228358 -248.215558)
			(xy 366.236023 -248.197072) (xy 366.250175 -248.182921) (xy 366.268662 -248.175257) (xy 366.278668 -248.174764)
			(xy 366.492536 -248.174764) (xy 366.492536 -248.16562) (xy 366.492937 -248.155596) (xy 366.500607 -248.137072)
			(xy 366.514786 -248.122898) (xy 366.533311 -248.115234) (xy 366.543336 -248.11482) (xy 366.747552 -248.11482)
			(xy 366.766892 -248.115322) (xy 366.80493 -248.122352) (xy 366.84108 -248.136118) (xy 366.874159 -248.15617)
			(xy 366.903086 -248.181852) (xy 366.926914 -248.212324) (xy 366.944863 -248.246589) (xy 366.951006 -248.264934)
			(xy 366.953444 -248.271919) (xy 366.961701 -248.284185) (xy 366.967262 -248.289064) (xy 366.98498 -248.304265)
			(xy 367.016267 -248.338908) (xy 367.042146 -248.377758) (xy 367.062061 -248.419977) (xy 367.075582 -248.464657)
			(xy 367.082418 -248.510834) (xy 367.082832 -248.534174) (xy 367.082827 -248.534428) (xy 369.266724 -248.534428)
			(xy 369.266724 -248.534174) (xy 369.267192 -248.510334) (xy 369.274374 -248.463197) (xy 369.288498 -248.417656)
			(xy 369.298474 -248.395998) (xy 369.298728 -248.395236) (xy 369.300824 -248.390283) (xy 369.303135 -248.379783)
			(xy 369.3033 -248.374408) (xy 369.3033 -248.32945) (xy 369.303688 -248.308403) (xy 369.311686 -248.267082)
			(xy 369.32762 -248.228126) (xy 369.350873 -248.193043) (xy 369.380544 -248.163193) (xy 369.415485 -248.139729)
			(xy 369.454343 -248.12356) (xy 369.495616 -248.115312) (xy 369.51666 -248.11482) (xy 369.771676 -248.11482)
			(xy 369.771676 -248.123964) (xy 369.772149 -248.13398) (xy 369.779802 -248.152492) (xy 369.793958 -248.166664)
			(xy 369.812461 -248.17434) (xy 369.822476 -248.174764) (xy 369.985544 -248.174764) (xy 369.99555 -248.175251)
			(xy 370.014036 -248.182919) (xy 370.028186 -248.197071) (xy 370.03585 -248.215558) (xy 370.036344 -248.225564)
			(xy 370.036344 -248.534174) (xy 372.086886 -248.534174) (xy 372.087477 -248.50594) (xy 372.097427 -248.450355)
			(xy 372.11703 -248.397399) (xy 372.145668 -248.348732) (xy 372.163594 -248.32691) (xy 372.168237 -248.321187)
			(xy 372.174295 -248.307759) (xy 372.175532 -248.300494) (xy 372.178916 -248.278789) (xy 372.193391 -248.23732)
			(xy 372.216029 -248.199682) (xy 372.245876 -248.167458) (xy 372.281673 -248.142008) (xy 372.321913 -248.124404)
			(xy 372.3649 -248.115387) (xy 372.38686 -248.11482) (xy 372.641876 -248.11482) (xy 372.641876 -248.123964)
			(xy 372.642349 -248.13398) (xy 372.650002 -248.152492) (xy 372.664158 -248.166664) (xy 372.682661 -248.17434)
			(xy 372.692676 -248.174764) (xy 372.855744 -248.174764) (xy 372.86575 -248.175251) (xy 372.884236 -248.182919)
			(xy 372.898386 -248.197071) (xy 372.90605 -248.215558) (xy 372.906544 -248.225564) (xy 372.906544 -248.733056)
			(xy 372.905977 -248.743055) (xy 372.89834 -248.761538) (xy 372.884212 -248.775691) (xy 372.865743 -248.78336)
			(xy 372.855744 -248.783856) (xy 372.641876 -248.783856) (xy 372.641876 -248.793) (xy 372.64148 -248.803024)
			(xy 372.633805 -248.821546) (xy 372.619626 -248.835719) (xy 372.6011 -248.843385) (xy 372.591076 -248.8438)
			(xy 372.47703 -248.8438) (xy 372.471696 -248.84507) (xy 372.455197 -248.848404) (xy 372.421725 -248.851965)
			(xy 372.404894 -248.852182) (xy 372.379901 -248.851749) (xy 372.330532 -248.843928) (xy 372.282993 -248.828481)
			(xy 372.238457 -248.805786) (xy 372.198019 -248.776403) (xy 372.162676 -248.741057) (xy 372.133297 -248.700616)
			(xy 372.110607 -248.656077) (xy 372.095164 -248.608537) (xy 372.087348 -248.559167) (xy 372.086886 -248.534174)
			(xy 370.036344 -248.534174) (xy 370.036344 -248.733056) (xy 370.035777 -248.743055) (xy 370.02814 -248.761538)
			(xy 370.014012 -248.775691) (xy 369.995543 -248.78336) (xy 369.985544 -248.783856) (xy 369.781582 -248.783856)
			(xy 369.771676 -248.791476) (xy 369.771676 -248.793) (xy 369.77128 -248.803024) (xy 369.763605 -248.821546)
			(xy 369.749426 -248.835719) (xy 369.7309 -248.843385) (xy 369.720876 -248.8438) (xy 369.656868 -248.8438)
			(xy 369.651534 -248.84507) (xy 369.635034 -248.848398) (xy 369.601563 -248.851963) (xy 369.584732 -248.852182)
			(xy 369.567641 -248.851942) (xy 369.533658 -248.848253) (xy 369.516914 -248.844816) (xy 369.508278 -248.843546)
			(xy 369.487885 -248.842377) (xy 369.448108 -248.833092) (xy 369.410828 -248.816402) (xy 369.377409 -248.792916)
			(xy 369.349075 -248.763496) (xy 369.326863 -248.729217) (xy 369.318794 -248.71045) (xy 369.314984 -248.702576)
			(xy 369.303568 -248.683576) (xy 369.285541 -248.643084) (xy 369.273314 -248.60048) (xy 369.267124 -248.55659)
			(xy 369.266724 -248.534428) (xy 367.082827 -248.534428) (xy 367.082319 -248.559163) (xy 367.074505 -248.608527)
			(xy 367.059064 -248.656061) (xy 367.036378 -248.700594) (xy 367.007005 -248.741029) (xy 366.971668 -248.776372)
			(xy 366.931236 -248.805752) (xy 366.886707 -248.828445) (xy 366.839176 -248.843893) (xy 366.789813 -248.851715)
			(xy 366.764824 -248.852182) (xy 366.747994 -248.851962) (xy 366.714523 -248.848393) (xy 366.698022 -248.84507)
			(xy 366.692688 -248.8438) (xy 366.492536 -248.8438) (xy 366.492536 -248.834656) (xy 366.492049 -248.82465)
			(xy 366.484381 -248.806164) (xy 366.470229 -248.792014) (xy 366.451742 -248.78435) (xy 366.441736 -248.783856)
			(xy 366.278668 -248.783856) (xy 366.268639 -248.783506) (xy 366.250113 -248.775817) (xy 366.23594 -248.761623)
			(xy 366.228279 -248.743085) (xy 366.227868 -248.733056) (xy 364.42904 -248.733056) (xy 364.428545 -248.74307)
			(xy 364.420897 -248.761578) (xy 364.406748 -248.77575) (xy 364.388253 -248.783429) (xy 364.37824 -248.783856)
			(xy 364.164372 -248.783856) (xy 364.164372 -248.793) (xy 364.16398 -248.803025) (xy 364.156305 -248.821547)
			(xy 364.142124 -248.83572) (xy 364.123597 -248.843385) (xy 364.113572 -248.8438) (xy 364.017052 -248.8438)
			(xy 364.011718 -248.84507) (xy 363.995219 -248.848401) (xy 363.961747 -248.851964) (xy 363.944916 -248.852182)
			(xy 363.919924 -248.851729) (xy 363.870555 -248.843911) (xy 363.823017 -248.828467) (xy 363.77848 -248.805775)
			(xy 363.738042 -248.776395) (xy 363.702699 -248.74105) (xy 363.67332 -248.700611) (xy 363.65063 -248.656074)
			(xy 363.635186 -248.608535) (xy 363.62737 -248.559166) (xy 363.626908 -248.534174) (xy 363.320584 -248.534174)
			(xy 363.320072 -248.55962) (xy 363.311908 -248.609854) (xy 363.295792 -248.658128) (xy 363.272141 -248.703191)
			(xy 363.241568 -248.743877) (xy 363.204864 -248.779132) (xy 363.16298 -248.808042) (xy 363.117001 -248.829859)
			(xy 363.068117 -248.844019) (xy 363.017596 -248.850153) (xy 362.966744 -248.848104) (xy 362.91688 -248.837924)
			(xy 362.869294 -248.819877) (xy 362.82522 -248.794431) (xy 362.785798 -248.762244) (xy 362.75205 -248.72415)
			(xy 362.724849 -248.681136) (xy 362.704901 -248.634316) (xy 362.692722 -248.584902) (xy 362.688627 -248.534174)
			(xy 362.38053 -248.534174) (xy 362.380018 -248.55962) (xy 362.371854 -248.609854) (xy 362.355738 -248.658128)
			(xy 362.332087 -248.703191) (xy 362.301514 -248.743877) (xy 362.26481 -248.779132) (xy 362.222926 -248.808042)
			(xy 362.176947 -248.829859) (xy 362.128063 -248.844019) (xy 362.077542 -248.850153) (xy 362.02669 -248.848104)
			(xy 361.976826 -248.837924) (xy 361.92924 -248.819877) (xy 361.885166 -248.794431) (xy 361.845744 -248.762244)
			(xy 361.811996 -248.72415) (xy 361.784795 -248.681136) (xy 361.764847 -248.634316) (xy 361.752668 -248.584902)
			(xy 361.748573 -248.534174) (xy 361.442762 -248.534174) (xy 361.442272 -248.559163) (xy 361.434453 -248.608526)
			(xy 361.419009 -248.656058) (xy 361.396319 -248.70059) (xy 361.366943 -248.741023) (xy 361.331603 -248.776363)
			(xy 361.29117 -248.805739) (xy 361.246638 -248.828429) (xy 361.199106 -248.843873) (xy 361.149743 -248.851692)
			(xy 361.099765 -248.851692) (xy 361.050402 -248.843873) (xy 361.00287 -248.828429) (xy 360.958338 -248.805739)
			(xy 360.917905 -248.776363) (xy 360.882565 -248.741023) (xy 360.853189 -248.70059) (xy 360.830499 -248.656058)
			(xy 360.815055 -248.608526) (xy 360.807236 -248.559163) (xy 358.665245 -248.559163) (xy 358.662986 -248.579321)
			(xy 358.649179 -248.62123) (xy 358.638602 -248.6406) (xy 358.511602 -248.860818) (xy 358.503474 -248.856246)
			(xy 358.494584 -248.851641) (xy 358.474753 -248.849028) (xy 358.455431 -248.854201) (xy 358.439558 -248.866373)
			(xy 358.434132 -248.874788) (xy 358.352344 -249.01652) (xy 358.34692 -249.024933) (xy 358.331047 -249.037096)
			(xy 358.311728 -249.042261) (xy 358.291903 -249.039642) (xy 358.283002 -249.035062) (xy 357.843074 -248.781062)
			(xy 357.834674 -248.775621) (xy 357.822512 -248.759754) (xy 357.817344 -248.740441) (xy 357.61043 -248.740441)
			(xy 357.607848 -248.743877) (xy 357.571144 -248.779132) (xy 357.52926 -248.808042) (xy 357.483281 -248.829859)
			(xy 357.434397 -248.844019) (xy 357.383876 -248.850153) (xy 357.333024 -248.848104) (xy 357.28316 -248.837924)
			(xy 357.235574 -248.819877) (xy 357.1915 -248.794431) (xy 357.152078 -248.762244) (xy 357.11833 -248.72415)
			(xy 357.091129 -248.681136) (xy 357.071181 -248.634316) (xy 357.059002 -248.584902) (xy 357.054907 -248.534174)
			(xy 356.74681 -248.534174) (xy 356.746298 -248.55962) (xy 356.738134 -248.609854) (xy 356.722018 -248.658128)
			(xy 356.698367 -248.703191) (xy 356.667794 -248.743877) (xy 356.63109 -248.779132) (xy 356.589206 -248.808042)
			(xy 356.543227 -248.829859) (xy 356.494343 -248.844019) (xy 356.443822 -248.850153) (xy 356.39297 -248.848104)
			(xy 356.343106 -248.837924) (xy 356.29552 -248.819877) (xy 356.251446 -248.794431) (xy 356.212024 -248.762244)
			(xy 356.178276 -248.72415) (xy 356.151075 -248.681136) (xy 356.131127 -248.634316) (xy 356.118948 -248.584902)
			(xy 356.114853 -248.534174) (xy 355.809042 -248.534174) (xy 355.808294 -248.565408) (xy 355.796133 -248.626681)
			(xy 355.784912 -248.65584) (xy 355.781864 -248.666762) (xy 355.777707 -248.687713) (xy 355.762205 -248.727506)
			(xy 355.739112 -248.76343) (xy 355.709347 -248.794055) (xy 355.674095 -248.818161) (xy 355.634759 -248.834789)
			(xy 355.592905 -248.843278) (xy 355.571552 -248.8438) (xy 355.56317 -248.8438) (xy 355.557836 -248.84507)
			(xy 355.541336 -248.848398) (xy 355.507865 -248.851963) (xy 355.491034 -248.852182) (xy 355.474204 -248.85196)
			(xy 355.440733 -248.848392) (xy 355.424232 -248.84507) (xy 355.418898 -248.8438) (xy 355.346254 -248.8438)
			(xy 355.316536 -248.814082) (xy 355.316536 -248.800112) (xy 355.306884 -248.793508) (xy 355.300271 -248.789062)
			(xy 355.285129 -248.784132) (xy 355.277166 -248.783856) (xy 355.102668 -248.783856) (xy 355.092639 -248.783506)
			(xy 355.074113 -248.775817) (xy 355.05994 -248.761623) (xy 355.052279 -248.743085) (xy 355.051868 -248.733056)
			(xy 353.12604 -248.733056) (xy 353.125545 -248.74307) (xy 353.117897 -248.761578) (xy 353.103748 -248.77575)
			(xy 353.085253 -248.783429) (xy 353.07524 -248.783856) (xy 352.867976 -248.783856) (xy 352.861372 -248.78919)
			(xy 352.861372 -248.793) (xy 352.86098 -248.803025) (xy 352.853305 -248.821547) (xy 352.839124 -248.83572)
			(xy 352.820597 -248.843385) (xy 352.810572 -248.8438) (xy 352.743262 -248.8438) (xy 352.737928 -248.84507)
			(xy 352.721429 -248.848399) (xy 352.687957 -248.851963) (xy 352.671126 -248.852182) (xy 352.670872 -248.852182)
			(xy 352.653653 -248.851968) (xy 352.619414 -248.848281) (xy 352.602546 -248.844816) (xy 352.594418 -248.843546)
			(xy 352.575459 -248.842069) (xy 352.53848 -248.833214) (xy 352.503658 -248.817941) (xy 352.472097 -248.796734)
			(xy 352.444798 -248.770266) (xy 352.422626 -248.739375) (xy 352.414078 -248.722388) (xy 352.410014 -248.71553)
			(xy 352.396583 -248.695465) (xy 352.375324 -248.652113) (xy 352.360874 -248.606043) (xy 352.353567 -248.558316)
			(xy 352.353118 -248.534174) (xy 350.169226 -248.534174) (xy 350.168719 -248.559164) (xy 350.160905 -248.608528)
			(xy 350.145464 -248.656062) (xy 350.122777 -248.700595) (xy 350.093403 -248.741031) (xy 350.058065 -248.776374)
			(xy 350.017633 -248.805754) (xy 349.973103 -248.828447) (xy 349.925571 -248.843894) (xy 349.876208 -248.851716)
			(xy 349.851218 -248.852182) (xy 349.834388 -248.851947) (xy 349.800917 -248.848388) (xy 349.784416 -248.84507)
			(xy 349.779082 -248.8438) (xy 349.59544 -248.8438) (xy 349.59544 -248.834656) (xy 349.594949 -248.82465)
			(xy 349.587282 -248.806165) (xy 349.573131 -248.792015) (xy 349.554646 -248.78435) (xy 349.54464 -248.783856)
			(xy 349.381572 -248.783856) (xy 349.371543 -248.783503) (xy 349.353017 -248.775815) (xy 349.338844 -248.761622)
			(xy 349.331183 -248.743085) (xy 349.330772 -248.733056) (xy 347.29059 -248.733056) (xy 347.290535 -248.735416)
			(xy 347.291807 -248.74462) (xy 347.293184 -248.749058) (xy 347.29674 -248.757186) (xy 347.338904 -248.834148)
			(xy 347.342206 -248.83999) (xy 347.351604 -248.849896) (xy 347.357192 -248.853198) (xy 347.363161 -248.856478)
			(xy 347.376293 -248.860071) (xy 347.3831 -248.86031) (xy 347.897958 -248.86031) (xy 347.907796 -248.860844)
			(xy 347.925959 -248.868429) (xy 347.933264 -248.875042) (xy 348.0308 -248.972578) (xy 348.03752 -248.979814)
			(xy 348.045128 -248.998019) (xy 348.045532 -249.007884) (xy 348.045532 -249.622056) (xy 348.924372 -249.622056)
			(xy 348.924372 -249.114564) (xy 348.924858 -249.104557) (xy 348.932524 -249.08607) (xy 348.946677 -249.07192)
			(xy 348.965165 -249.064256) (xy 348.975172 -249.063764) (xy 349.18904 -249.063764) (xy 349.18904 -249.05462)
			(xy 349.189437 -249.044595) (xy 349.197108 -249.026071) (xy 349.211288 -249.011897) (xy 349.229815 -249.004233)
			(xy 349.23984 -249.00382) (xy 349.444056 -249.00382) (xy 349.46488 -249.004291) (xy 349.505731 -249.012405)
			(xy 349.544237 -249.028277) (xy 349.57894 -249.051305) (xy 349.608527 -249.080618) (xy 349.631878 -249.115105)
			(xy 349.648108 -249.153461) (xy 349.652844 -249.173746) (xy 349.653735 -249.177542) (xy 349.656539 -249.184816)
			(xy 349.658432 -249.188224) (xy 349.671204 -249.212123) (xy 349.689334 -249.263183) (xy 349.698527 -249.31658)
			(xy 349.699072 -249.343672) (xy 349.699072 -249.34418) (xy 349.698552 -249.369676) (xy 349.690422 -249.420016)
			(xy 349.674353 -249.468409) (xy 349.663004 -249.491246) (xy 349.660405 -249.496667) (xy 349.657582 -249.50835)
			(xy 349.657416 -249.51436) (xy 349.657416 -249.51817) (xy 349.65713 -249.539222) (xy 349.649124 -249.580555)
			(xy 349.633179 -249.619519) (xy 349.631497 -249.622056) (xy 350.829372 -249.622056) (xy 350.829372 -249.114564)
			(xy 350.829858 -249.104557) (xy 350.837524 -249.08607) (xy 350.851677 -249.07192) (xy 350.870165 -249.064256)
			(xy 350.880172 -249.063764) (xy 351.09404 -249.063764) (xy 351.09404 -249.05462) (xy 351.094437 -249.044595)
			(xy 351.102108 -249.026071) (xy 351.116288 -249.011897) (xy 351.134815 -249.004233) (xy 351.14484 -249.00382)
			(xy 351.349056 -249.00382) (xy 351.3701 -249.004364) (xy 351.411374 -249.012597) (xy 351.450236 -249.028754)
			(xy 351.485182 -249.052209) (xy 351.514858 -249.082053) (xy 351.538114 -249.117131) (xy 351.554051 -249.156084)
			(xy 351.562052 -249.197404) (xy 351.562416 -249.21845) (xy 351.562416 -249.218704) (xy 351.562416 -249.241564)
			(xy 351.564702 -249.24893) (xy 351.571466 -249.27216) (xy 351.578742 -249.31999) (xy 351.57918 -249.34418)
			(xy 351.578777 -249.368373) (xy 351.571501 -249.416208) (xy 351.564702 -249.43943) (xy 351.562416 -249.446796)
			(xy 351.562416 -249.517916) (xy 351.562416 -249.51817) (xy 351.56213 -249.539222) (xy 351.554124 -249.580555)
			(xy 351.538179 -249.619519) (xy 351.536497 -249.622056) (xy 352.734372 -249.622056) (xy 352.734372 -249.114564)
			(xy 352.734858 -249.104557) (xy 352.742524 -249.08607) (xy 352.756677 -249.07192) (xy 352.775165 -249.064256)
			(xy 352.785172 -249.063764) (xy 352.991166 -249.063764) (xy 352.99904 -249.059446) (xy 352.99904 -249.05462)
			(xy 352.999437 -249.044595) (xy 353.007108 -249.026071) (xy 353.021288 -249.011897) (xy 353.039815 -249.004233)
			(xy 353.04984 -249.00382) (xy 353.254056 -249.00382) (xy 353.2751 -249.004364) (xy 353.316374 -249.012597)
			(xy 353.355236 -249.028754) (xy 353.390182 -249.052209) (xy 353.419858 -249.082053) (xy 353.443114 -249.117131)
			(xy 353.459051 -249.156084) (xy 353.467052 -249.197404) (xy 353.467416 -249.21845) (xy 353.467416 -249.218704)
			(xy 353.467416 -249.517916) (xy 353.467416 -249.51817) (xy 353.46713 -249.539222) (xy 353.459124 -249.580555)
			(xy 353.443179 -249.619519) (xy 353.441497 -249.622056) (xy 354.639372 -249.622056) (xy 354.639372 -249.114564)
			(xy 354.639858 -249.104557) (xy 354.647524 -249.08607) (xy 354.661677 -249.07192) (xy 354.680165 -249.064256)
			(xy 354.690172 -249.063764) (xy 354.859082 -249.063764) (xy 354.864869 -249.063627) (xy 354.876155 -249.061061)
			(xy 354.881434 -249.058684) (xy 354.90404 -249.048524) (xy 354.90404 -249.033538) (xy 354.933758 -249.00382)
			(xy 355.159056 -249.00382) (xy 355.1801 -249.004364) (xy 355.221374 -249.012597) (xy 355.260236 -249.028754)
			(xy 355.295182 -249.052209) (xy 355.324858 -249.082053) (xy 355.348114 -249.117131) (xy 355.364051 -249.156084)
			(xy 355.372052 -249.197404) (xy 355.372416 -249.21845) (xy 355.372416 -249.218704) (xy 355.372416 -249.517916)
			(xy 355.372416 -249.51817) (xy 355.37213 -249.539222) (xy 355.364124 -249.580555) (xy 355.348179 -249.619519)
			(xy 355.346497 -249.622056) (xy 356.417372 -249.622056) (xy 356.417372 -249.114564) (xy 356.417858 -249.104557)
			(xy 356.425524 -249.08607) (xy 356.439677 -249.07192) (xy 356.458165 -249.064256) (xy 356.468172 -249.063764)
			(xy 356.68204 -249.063764) (xy 356.68204 -249.05462) (xy 356.682437 -249.044595) (xy 356.690108 -249.026071)
			(xy 356.704288 -249.011897) (xy 356.722815 -249.004233) (xy 356.73284 -249.00382) (xy 356.937056 -249.00382)
			(xy 356.956062 -249.004302) (xy 356.993467 -249.01107) (xy 357.029086 -249.024348) (xy 357.061794 -249.043716)
			(xy 357.090561 -249.068564) (xy 357.11448 -249.098109) (xy 357.124 -249.114564) (xy 357.13162 -249.125232)
			(xy 357.14798 -249.143036) (xy 357.175638 -249.182695) (xy 357.196962 -249.226088) (xy 357.21146 -249.272214)
			(xy 357.218795 -249.320005) (xy 357.21925 -249.34418) (xy 357.218753 -249.369575) (xy 357.210669 -249.419717)
			(xy 357.194705 -249.467932) (xy 357.171268 -249.51299) (xy 357.156512 -249.533664) (xy 357.153068 -249.538589)
			(xy 357.148309 -249.549619) (xy 357.148145 -249.550428) (xy 359.375964 -249.550428) (xy 359.375964 -249.346212)
			(xy 359.376424 -249.32689) (xy 359.383396 -249.28888) (xy 359.397078 -249.252739) (xy 359.406698 -249.235976)
			(xy 359.410254 -249.228864) (xy 359.420586 -249.204523) (xy 359.447391 -249.158943) (xy 359.480643 -249.117829)
			(xy 359.51961 -249.082085) (xy 359.563435 -249.052498) (xy 359.611155 -249.029719) (xy 359.661719 -249.014249)
			(xy 359.714015 -249.006428) (xy 359.766893 -249.006428) (xy 359.819189 -249.014249) (xy 359.869753 -249.029719)
			(xy 359.917473 -249.052498) (xy 359.961298 -249.082085) (xy 360.000265 -249.117829) (xy 360.033517 -249.158943)
			(xy 360.060322 -249.204523) (xy 360.070654 -249.228864) (xy 360.07421 -249.235976) (xy 360.083864 -249.252724)
			(xy 360.097573 -249.288864) (xy 360.104532 -249.326885) (xy 360.104901 -249.34418) (xy 361.2769 -249.34418)
			(xy 361.277324 -249.321879) (xy 361.283635 -249.277725) (xy 361.296047 -249.234884) (xy 361.30484 -249.214386)
			(xy 361.306426 -249.210485) (xy 361.308474 -249.202319) (xy 361.308904 -249.19813) (xy 361.311099 -249.178491)
			(xy 361.321837 -249.140464) (xy 361.339381 -249.105059) (xy 361.363133 -249.073481) (xy 361.392285 -249.046807)
			(xy 361.425843 -249.025945) (xy 361.462663 -249.011607) (xy 361.501492 -249.00428) (xy 361.521248 -249.00382)
			(xy 361.776264 -249.00382) (xy 361.776264 -249.012964) (xy 361.776816 -249.022965) (xy 361.784457 -249.041449)
			(xy 361.79859 -249.055602) (xy 361.817064 -249.063269) (xy 361.827064 -249.063764) (xy 361.990132 -249.063764)
			(xy 362.000137 -249.064261) (xy 362.018623 -249.071924) (xy 362.032773 -249.086074) (xy 362.040438 -249.104559)
			(xy 362.040932 -249.114564) (xy 362.040932 -249.344688) (xy 363.156754 -249.344688) (xy 363.156754 -249.34418)
			(xy 363.157162 -249.321742) (xy 363.163513 -249.277317) (xy 363.176057 -249.234229) (xy 363.184948 -249.213624)
			(xy 363.186548 -249.209729) (xy 363.188587 -249.201558) (xy 363.189012 -249.197368) (xy 363.191267 -249.177772)
			(xy 363.202056 -249.139835) (xy 363.219633 -249.104528) (xy 363.243401 -249.073053) (xy 363.27255 -249.046483)
			(xy 363.306085 -249.025723) (xy 363.342865 -249.011481) (xy 363.381635 -249.004242) (xy 363.401356 -249.00382)
			(xy 363.656372 -249.00382) (xy 363.656372 -249.012964) (xy 363.656848 -249.02298) (xy 363.664501 -249.04149)
			(xy 363.678656 -249.055663) (xy 363.697157 -249.063339) (xy 363.707172 -249.063764) (xy 363.87024 -249.063764)
			(xy 363.880246 -249.064254) (xy 363.898732 -249.07192) (xy 363.912882 -249.086072) (xy 363.920546 -249.104558)
			(xy 363.92104 -249.114564) (xy 363.92104 -249.34418) (xy 365.036862 -249.34418) (xy 365.037371 -249.318627)
			(xy 365.045559 -249.268181) (xy 365.061721 -249.219698) (xy 365.08544 -249.17443) (xy 365.100362 -249.15368)
			(xy 365.102396 -249.150787) (xy 365.10571 -249.14454) (xy 365.106966 -249.141234) (xy 365.115136 -249.121366)
			(xy 365.138134 -249.085091) (xy 365.167915 -249.054142) (xy 365.203278 -249.029765) (xy 365.242798 -249.012943)
			(xy 365.284881 -249.004355) (xy 365.306356 -249.00382) (xy 365.561372 -249.00382) (xy 365.561372 -249.012964)
			(xy 365.561848 -249.02298) (xy 365.569501 -249.04149) (xy 365.583656 -249.055663) (xy 365.602157 -249.063339)
			(xy 365.612172 -249.063764) (xy 365.77524 -249.063764) (xy 365.785246 -249.064254) (xy 365.803732 -249.07192)
			(xy 365.817882 -249.086072) (xy 365.825546 -249.104558) (xy 365.82604 -249.114564) (xy 365.82604 -249.34418)
			(xy 366.916716 -249.34418) (xy 366.917188 -249.321008) (xy 366.923922 -249.275155) (xy 366.937244 -249.230766)
			(xy 366.956871 -249.188783) (xy 366.982387 -249.150095) (xy 367.013252 -249.115523) (xy 367.030762 -249.10034)
			(xy 367.039144 -249.091196) (xy 367.051386 -249.075305) (xy 367.080693 -249.047925) (xy 367.114596 -249.026498)
			(xy 367.151903 -249.011777) (xy 367.191303 -249.004281) (xy 367.211356 -249.00382) (xy 367.466372 -249.00382)
			(xy 367.466372 -249.012964) (xy 367.466848 -249.02298) (xy 367.474501 -249.04149) (xy 367.488656 -249.055663)
			(xy 367.507157 -249.063339) (xy 367.517172 -249.063764) (xy 367.68024 -249.063764) (xy 367.690246 -249.064254)
			(xy 367.708732 -249.07192) (xy 367.722882 -249.086072) (xy 367.730546 -249.104558) (xy 367.73104 -249.114564)
			(xy 367.73104 -249.34418) (xy 368.796824 -249.34418) (xy 368.797208 -249.322306) (xy 368.803199 -249.278969)
			(xy 368.815066 -249.236861) (xy 368.823494 -249.216672) (xy 368.825081 -249.212772) (xy 368.827129 -249.204605)
			(xy 368.827558 -249.200416) (xy 368.829558 -249.1806) (xy 368.83997 -249.142163) (xy 368.857333 -249.106325)
			(xy 368.881045 -249.074332) (xy 368.910282 -249.047294) (xy 368.944028 -249.026152) (xy 368.981112 -249.011639)
			(xy 369.020245 -249.00426) (xy 369.040156 -249.00382) (xy 369.295172 -249.00382) (xy 369.295172 -249.012964)
			(xy 369.295648 -249.02298) (xy 369.303301 -249.04149) (xy 369.317456 -249.055663) (xy 369.335957 -249.063339)
			(xy 369.345972 -249.063764) (xy 369.50904 -249.063764) (xy 369.519046 -249.064254) (xy 369.537532 -249.07192)
			(xy 369.551682 -249.086072) (xy 369.559346 -249.104558) (xy 369.55984 -249.114564) (xy 369.55984 -249.34418)
			(xy 370.676678 -249.34418) (xy 370.677138 -249.319174) (xy 370.684969 -249.269779) (xy 370.700435 -249.222219)
			(xy 370.723153 -249.177665) (xy 370.752565 -249.137216) (xy 370.787946 -249.101869) (xy 370.828423 -249.072495)
			(xy 370.872998 -249.049819) (xy 370.896642 -249.041666) (xy 370.907818 -249.036332) (xy 370.924908 -249.026177)
			(xy 370.961922 -249.011692) (xy 371.000975 -249.004289) (xy 371.020848 -249.00382) (xy 371.276372 -249.00382)
			(xy 371.276372 -249.012964) (xy 371.276848 -249.02298) (xy 371.284501 -249.04149) (xy 371.298656 -249.055663)
			(xy 371.317157 -249.063339) (xy 371.327172 -249.063764) (xy 371.49024 -249.063764) (xy 371.500246 -249.064254)
			(xy 371.518732 -249.07192) (xy 371.532882 -249.086072) (xy 371.540546 -249.104558) (xy 371.54104 -249.114564)
			(xy 371.54104 -249.34418) (xy 372.556786 -249.34418) (xy 372.557161 -249.322671) (xy 372.562991 -249.280048)
			(xy 372.574517 -249.238602) (xy 372.582694 -249.218704) (xy 372.584312 -249.214748) (xy 372.586348 -249.206448)
			(xy 372.586758 -249.202194) (xy 372.588607 -249.182264) (xy 372.598811 -249.143565) (xy 372.616046 -249.107444)
			(xy 372.639708 -249.075168) (xy 372.668971 -249.047865) (xy 372.702807 -249.026492) (xy 372.740033 -249.011797)
			(xy 372.779346 -249.004296) (xy 372.799356 -249.00382) (xy 373.054372 -249.00382) (xy 373.054372 -249.012964)
			(xy 373.054848 -249.02298) (xy 373.062501 -249.04149) (xy 373.076656 -249.055663) (xy 373.095157 -249.063339)
			(xy 373.105172 -249.063764) (xy 373.26824 -249.063764) (xy 373.278246 -249.064254) (xy 373.296732 -249.07192)
			(xy 373.310882 -249.086072) (xy 373.318546 -249.104558) (xy 373.31904 -249.114564) (xy 373.31904 -249.622056)
			(xy 373.318545 -249.63207) (xy 373.310897 -249.650578) (xy 373.296748 -249.66475) (xy 373.278253 -249.672429)
			(xy 373.26824 -249.672856) (xy 373.054372 -249.672856) (xy 373.054372 -249.682) (xy 373.05398 -249.692025)
			(xy 373.046305 -249.710547) (xy 373.032124 -249.72472) (xy 373.013597 -249.732385) (xy 373.003572 -249.7328)
			(xy 372.799356 -249.7328) (xy 372.778311 -249.732316) (xy 372.737036 -249.724067) (xy 372.698174 -249.707898)
			(xy 372.663231 -249.684433) (xy 372.633557 -249.654582) (xy 372.610301 -249.619498) (xy 372.594364 -249.580541)
			(xy 372.586362 -249.539218) (xy 372.585996 -249.51817) (xy 372.585996 -249.517916) (xy 372.585996 -249.478038)
			(xy 372.582186 -249.468386) (xy 372.574161 -249.448673) (xy 372.562857 -249.407638) (xy 372.557141 -249.365461)
			(xy 372.556786 -249.34418) (xy 371.54104 -249.34418) (xy 371.54104 -249.622056) (xy 371.540545 -249.63207)
			(xy 371.532897 -249.650578) (xy 371.518748 -249.66475) (xy 371.500253 -249.672429) (xy 371.49024 -249.672856)
			(xy 371.276372 -249.672856) (xy 371.276372 -249.682) (xy 371.27598 -249.692025) (xy 371.268305 -249.710547)
			(xy 371.254124 -249.72472) (xy 371.235597 -249.732385) (xy 371.225572 -249.7328) (xy 371.021356 -249.7328)
			(xy 370.999191 -249.732239) (xy 370.955823 -249.723053) (xy 370.91528 -249.705124) (xy 370.879303 -249.679224)
			(xy 370.849436 -249.646464) (xy 370.837714 -249.627644) (xy 370.834542 -249.622671) (xy 370.826326 -249.614211)
			(xy 370.821458 -249.61088) (xy 370.799613 -249.596083) (xy 370.760719 -249.560433) (xy 370.728242 -249.518854)
			(xy 370.703072 -249.472485) (xy 370.685899 -249.422597) (xy 370.677195 -249.37056) (xy 370.676678 -249.34418)
			(xy 369.55984 -249.34418) (xy 369.55984 -249.622056) (xy 369.559345 -249.63207) (xy 369.551697 -249.650578)
			(xy 369.537548 -249.66475) (xy 369.519053 -249.672429) (xy 369.50904 -249.672856) (xy 369.295172 -249.672856)
			(xy 369.295172 -249.682) (xy 369.29478 -249.692025) (xy 369.287105 -249.710547) (xy 369.272924 -249.72472)
			(xy 369.254397 -249.732385) (xy 369.244372 -249.7328) (xy 369.040156 -249.7328) (xy 369.019111 -249.732316)
			(xy 368.977836 -249.724067) (xy 368.938974 -249.707898) (xy 368.904031 -249.684433) (xy 368.874357 -249.654582)
			(xy 368.851101 -249.619498) (xy 368.835164 -249.580541) (xy 368.827162 -249.539218) (xy 368.826796 -249.51817)
			(xy 368.826796 -249.517916) (xy 368.826796 -249.479562) (xy 368.822732 -249.46991) (xy 368.814533 -249.449975)
			(xy 368.803 -249.408442) (xy 368.797181 -249.365732) (xy 368.796824 -249.34418) (xy 367.73104 -249.34418)
			(xy 367.73104 -249.622056) (xy 367.730545 -249.63207) (xy 367.722897 -249.650578) (xy 367.708748 -249.66475)
			(xy 367.690253 -249.672429) (xy 367.68024 -249.672856) (xy 367.466372 -249.672856) (xy 367.466372 -249.682)
			(xy 367.46598 -249.692025) (xy 367.458305 -249.710547) (xy 367.444124 -249.72472) (xy 367.425597 -249.732385)
			(xy 367.415572 -249.7328) (xy 367.211356 -249.7328) (xy 367.191241 -249.732351) (xy 367.151724 -249.724803)
			(xy 367.114322 -249.709982) (xy 367.080361 -249.688414) (xy 367.051044 -249.660864) (xy 367.02741 -249.628307)
			(xy 367.010296 -249.591897) (xy 367.004854 -249.572526) (xy 367.003261 -249.566893) (xy 366.997867 -249.556505)
			(xy 366.994186 -249.551952) (xy 366.976127 -249.530113) (xy 366.94724 -249.481364) (xy 366.927443 -249.428271)
			(xy 366.91736 -249.372511) (xy 366.916716 -249.34418) (xy 365.82604 -249.34418) (xy 365.82604 -249.622056)
			(xy 365.825545 -249.63207) (xy 365.817897 -249.650578) (xy 365.803748 -249.66475) (xy 365.785253 -249.672429)
			(xy 365.77524 -249.672856) (xy 365.561372 -249.672856) (xy 365.561372 -249.682) (xy 365.56098 -249.692025)
			(xy 365.553305 -249.710547) (xy 365.539124 -249.72472) (xy 365.520597 -249.732385) (xy 365.510572 -249.7328)
			(xy 365.306356 -249.7328) (xy 365.286526 -249.732274) (xy 365.247557 -249.724905) (xy 365.210618 -249.710465)
			(xy 365.176982 -249.689452) (xy 365.147806 -249.662588) (xy 365.124093 -249.630797) (xy 365.106658 -249.595174)
			(xy 365.096103 -249.556944) (xy 365.094012 -249.53722) (xy 365.093304 -249.531084) (xy 365.089328 -249.519394)
			(xy 365.086138 -249.514106) (xy 365.07446 -249.49496) (xy 365.056029 -249.454077) (xy 365.04354 -249.411005)
			(xy 365.037241 -249.366603) (xy 365.036862 -249.34418) (xy 363.92104 -249.34418) (xy 363.92104 -249.622056)
			(xy 363.920545 -249.63207) (xy 363.912897 -249.650578) (xy 363.898748 -249.66475) (xy 363.880253 -249.672429)
			(xy 363.87024 -249.672856) (xy 363.656372 -249.672856) (xy 363.656372 -249.682) (xy 363.65598 -249.692025)
			(xy 363.648305 -249.710547) (xy 363.634124 -249.72472) (xy 363.615597 -249.732385) (xy 363.605572 -249.7328)
			(xy 363.401356 -249.7328) (xy 363.380311 -249.732316) (xy 363.339036 -249.724067) (xy 363.300174 -249.707898)
			(xy 363.265231 -249.684433) (xy 363.235557 -249.654582) (xy 363.212301 -249.619498) (xy 363.196364 -249.580541)
			(xy 363.188362 -249.539218) (xy 363.187996 -249.51817) (xy 363.187996 -249.517916) (xy 363.187996 -249.482356)
			(xy 363.183678 -249.47245) (xy 363.17517 -249.452237) (xy 363.163194 -249.410049) (xy 363.157136 -249.366615)
			(xy 363.156754 -249.344688) (xy 362.040932 -249.344688) (xy 362.040932 -249.622056) (xy 362.040445 -249.632071)
			(xy 362.032796 -249.65058) (xy 362.018644 -249.664753) (xy 362.000146 -249.67243) (xy 361.990132 -249.672856)
			(xy 361.776264 -249.672856) (xy 361.776264 -249.682) (xy 361.77588 -249.692026) (xy 361.768203 -249.71055)
			(xy 361.754019 -249.724723) (xy 361.73549 -249.732387) (xy 361.725464 -249.7328) (xy 361.521248 -249.7328)
			(xy 361.500206 -249.732233) (xy 361.458934 -249.724001) (xy 361.420074 -249.707846) (xy 361.385129 -249.684395)
			(xy 361.355454 -249.654554) (xy 361.332196 -249.61948) (xy 361.316257 -249.580531) (xy 361.308254 -249.539215)
			(xy 361.307888 -249.51817) (xy 361.307888 -249.517916) (xy 361.307888 -249.481848) (xy 361.303824 -249.471942)
			(xy 361.295316 -249.451729) (xy 361.28334 -249.409541) (xy 361.277281 -249.366107) (xy 361.2769 -249.34418)
			(xy 360.104901 -249.34418) (xy 360.104944 -249.346212) (xy 360.104944 -249.601228) (xy 360.0958 -249.601228)
			(xy 360.085775 -249.60162) (xy 360.067253 -249.609295) (xy 360.05308 -249.623476) (xy 360.045415 -249.642003)
			(xy 360.045 -249.652028) (xy 360.045 -249.815096) (xy 360.044577 -249.825117) (xy 360.036909 -249.843634)
			(xy 360.022737 -249.857806) (xy 360.004221 -249.865476) (xy 359.9942 -249.865896) (xy 359.486708 -249.865896)
			(xy 359.476687 -249.865474) (xy 359.458169 -249.857806) (xy 359.443996 -249.843634) (xy 359.436327 -249.825117)
			(xy 359.435908 -249.815096) (xy 359.435908 -249.601228) (xy 359.426764 -249.601228) (xy 359.416757 -249.600742)
			(xy 359.39827 -249.593076) (xy 359.38412 -249.578923) (xy 359.376456 -249.560435) (xy 359.375964 -249.550428)
			(xy 357.148145 -249.550428) (xy 357.147114 -249.555508) (xy 357.143 -249.576467) (xy 357.127558 -249.616283)
			(xy 357.104516 -249.652239) (xy 357.074792 -249.682903) (xy 357.03957 -249.707052) (xy 357.000253 -249.723725)
			(xy 356.958408 -249.732257) (xy 356.937056 -249.7328) (xy 356.68204 -249.7328) (xy 356.68204 -249.723656)
			(xy 356.681549 -249.71365) (xy 356.673882 -249.695165) (xy 356.659731 -249.681015) (xy 356.641246 -249.67335)
			(xy 356.63124 -249.672856) (xy 356.468172 -249.672856) (xy 356.458143 -249.672503) (xy 356.439617 -249.664815)
			(xy 356.425444 -249.650622) (xy 356.417783 -249.632085) (xy 356.417372 -249.622056) (xy 355.346497 -249.622056)
			(xy 355.324913 -249.654607) (xy 355.295226 -249.684459) (xy 355.260269 -249.70792) (xy 355.221394 -249.724081)
			(xy 355.180106 -249.732317) (xy 355.159056 -249.7328) (xy 354.90404 -249.7328) (xy 354.90404 -249.723656)
			(xy 354.903549 -249.71365) (xy 354.895882 -249.695165) (xy 354.881731 -249.681015) (xy 354.863246 -249.67335)
			(xy 354.85324 -249.672856) (xy 354.690172 -249.672856) (xy 354.680143 -249.672503) (xy 354.661617 -249.664815)
			(xy 354.647444 -249.650622) (xy 354.639783 -249.632085) (xy 354.639372 -249.622056) (xy 353.441497 -249.622056)
			(xy 353.419913 -249.654607) (xy 353.390226 -249.684459) (xy 353.355269 -249.70792) (xy 353.316394 -249.724081)
			(xy 353.275106 -249.732317) (xy 353.254056 -249.7328) (xy 352.99904 -249.7328) (xy 352.99904 -249.723656)
			(xy 352.998549 -249.71365) (xy 352.990882 -249.695165) (xy 352.976731 -249.681015) (xy 352.958246 -249.67335)
			(xy 352.94824 -249.672856) (xy 352.785172 -249.672856) (xy 352.775143 -249.672503) (xy 352.756617 -249.664815)
			(xy 352.742444 -249.650622) (xy 352.734783 -249.632085) (xy 352.734372 -249.622056) (xy 351.536497 -249.622056)
			(xy 351.514913 -249.654607) (xy 351.485226 -249.684459) (xy 351.450269 -249.70792) (xy 351.411394 -249.724081)
			(xy 351.370106 -249.732317) (xy 351.349056 -249.7328) (xy 351.09404 -249.7328) (xy 351.09404 -249.723656)
			(xy 351.093549 -249.71365) (xy 351.085882 -249.695165) (xy 351.071731 -249.681015) (xy 351.053246 -249.67335)
			(xy 351.04324 -249.672856) (xy 350.880172 -249.672856) (xy 350.870143 -249.672503) (xy 350.851617 -249.664815)
			(xy 350.837444 -249.650622) (xy 350.829783 -249.632085) (xy 350.829372 -249.622056) (xy 349.631497 -249.622056)
			(xy 349.609913 -249.654607) (xy 349.580226 -249.684459) (xy 349.545269 -249.70792) (xy 349.506394 -249.724081)
			(xy 349.465106 -249.732317) (xy 349.444056 -249.7328) (xy 349.18904 -249.7328) (xy 349.18904 -249.723656)
			(xy 349.188549 -249.71365) (xy 349.180882 -249.695165) (xy 349.166731 -249.681015) (xy 349.148246 -249.67335)
			(xy 349.13824 -249.672856) (xy 348.975172 -249.672856) (xy 348.965143 -249.672503) (xy 348.946617 -249.664815)
			(xy 348.932444 -249.650622) (xy 348.924783 -249.632085) (xy 348.924372 -249.622056) (xy 348.045532 -249.622056)
			(xy 348.045532 -249.728736) (xy 348.046294 -249.737372) (xy 348.049342 -249.74804) (xy 348.053152 -249.75693)
			(xy 348.489778 -250.193556) (xy 348.491048 -250.194572) (xy 348.492064 -250.195588) (xy 348.49308 -250.196604)
			(xy 348.666054 -250.369578) (xy 348.669119 -250.372471) (xy 348.676013 -250.37732) (xy 348.67977 -250.37923)
			(xy 348.681802 -250.379992) (xy 348.686643 -250.38199) (xy 348.696887 -250.384156) (xy 348.702122 -250.38431)
			(xy 349.453962 -250.38431) (xy 349.465392 -250.38377) (xy 349.485922 -250.373723) (xy 349.493332 -250.365006)
			(xy 349.548958 -250.288552) (xy 349.550736 -250.276614) (xy 349.552768 -250.264676) (xy 349.548958 -250.252992)
			(xy 349.541594 -250.228957) (xy 349.533679 -250.179319) (xy 349.53321 -250.154186) (xy 349.5337 -250.129197)
			(xy 349.541519 -250.079834) (xy 349.556963 -250.032302) (xy 349.579653 -249.98777) (xy 349.609029 -249.947337)
			(xy 349.644369 -249.911997) (xy 349.684802 -249.882621) (xy 349.729334 -249.859931) (xy 349.776866 -249.844487)
			(xy 349.826229 -249.836668) (xy 349.876207 -249.836668) (xy 349.92557 -249.844487) (xy 349.973102 -249.859931)
			(xy 350.017634 -249.882621) (xy 350.058067 -249.911997) (xy 350.093407 -249.947337) (xy 350.122783 -249.98777)
			(xy 350.145473 -250.032302) (xy 350.160917 -250.079834) (xy 350.168736 -250.129197) (xy 350.169226 -250.154186)
			(xy 350.16948 -250.154186) (xy 350.169049 -250.178222) (xy 350.168904 -250.179175) (xy 351.413554 -250.179175)
			(xy 351.413554 -250.129197) (xy 351.421373 -250.079834) (xy 351.436817 -250.032302) (xy 351.459507 -249.98777)
			(xy 351.488883 -249.947337) (xy 351.524223 -249.911997) (xy 351.564656 -249.882621) (xy 351.609188 -249.859931)
			(xy 351.65672 -249.844487) (xy 351.706083 -249.836668) (xy 351.756061 -249.836668) (xy 351.805424 -249.844487)
			(xy 351.852956 -249.859931) (xy 351.897488 -249.882621) (xy 351.937921 -249.911997) (xy 351.973261 -249.947337)
			(xy 352.002637 -249.98777) (xy 352.025327 -250.032302) (xy 352.040771 -250.079834) (xy 352.04859 -250.129197)
			(xy 352.04908 -250.154186) (xy 352.04859 -250.179175) (xy 353.293662 -250.179175) (xy 353.293662 -250.129197)
			(xy 353.301481 -250.079834) (xy 353.316925 -250.032302) (xy 353.339615 -249.98777) (xy 353.368991 -249.947337)
			(xy 353.404331 -249.911997) (xy 353.444764 -249.882621) (xy 353.489296 -249.859931) (xy 353.536828 -249.844487)
			(xy 353.586191 -249.836668) (xy 353.636169 -249.836668) (xy 353.685532 -249.844487) (xy 353.733064 -249.859931)
			(xy 353.777596 -249.882621) (xy 353.818029 -249.911997) (xy 353.853369 -249.947337) (xy 353.882745 -249.98777)
			(xy 353.905435 -250.032302) (xy 353.920879 -250.079834) (xy 353.928698 -250.129197) (xy 353.929188 -250.154186)
			(xy 355.173026 -250.154186) (xy 355.173444 -250.129193) (xy 355.181266 -250.079822) (xy 355.196715 -250.032283)
			(xy 355.219411 -249.987746) (xy 355.248796 -249.947308) (xy 355.284144 -249.911964) (xy 355.324587 -249.882586)
			(xy 355.369127 -249.859897) (xy 355.416669 -249.844455) (xy 355.466041 -249.83664) (xy 355.491034 -249.836178)
			(xy 355.513342 -249.836544) (xy 355.557517 -249.842804) (xy 355.600386 -249.855169) (xy 355.641109 -249.873397)
			(xy 355.660198 -249.884946) (xy 355.666346 -249.888541) (xy 355.680006 -249.892544) (xy 355.687122 -249.89282)
			(xy 355.806756 -249.89282) (xy 355.806756 -249.901964) (xy 355.807316 -249.911964) (xy 355.814956 -249.930447)
			(xy 355.829086 -249.944599) (xy 355.847557 -249.952268) (xy 355.857556 -249.952764) (xy 356.020624 -249.952764)
			(xy 356.030629 -249.953267) (xy 356.049114 -249.960928) (xy 356.063265 -249.975076) (xy 356.07093 -249.993559)
			(xy 356.071424 -250.003564) (xy 356.071424 -250.511056) (xy 356.070945 -250.521072) (xy 356.063294 -250.539583)
			(xy 356.04914 -250.553756) (xy 356.030639 -250.561432) (xy 356.020624 -250.561856) (xy 355.806756 -250.561856)
			(xy 355.806756 -250.571) (xy 355.806379 -250.581027) (xy 355.798701 -250.599552) (xy 355.784515 -250.613726)
			(xy 355.765983 -250.621388) (xy 355.755956 -250.6218) (xy 355.55174 -250.6218) (xy 355.531145 -250.621305)
			(xy 355.490723 -250.613376) (xy 355.452572 -250.597843) (xy 355.418108 -250.575283) (xy 355.388609 -250.546533)
			(xy 355.365171 -250.512659) (xy 355.348663 -250.47492) (xy 355.343714 -250.454922) (xy 355.34109 -250.445256)
			(xy 355.329588 -250.428883) (xy 355.321362 -250.423172) (xy 355.299036 -250.408461) (xy 355.259228 -250.37277)
			(xy 355.225949 -250.330926) (xy 355.200134 -250.284107) (xy 355.18251 -250.233631) (xy 355.173573 -250.180918)
			(xy 355.173026 -250.154186) (xy 353.929188 -250.154186) (xy 353.928698 -250.179175) (xy 353.920879 -250.228538)
			(xy 353.905435 -250.27607) (xy 353.882745 -250.320602) (xy 353.853369 -250.361035) (xy 353.818029 -250.396375)
			(xy 353.777596 -250.425751) (xy 353.733064 -250.448441) (xy 353.685532 -250.463885) (xy 353.636169 -250.471704)
			(xy 353.586191 -250.471704) (xy 353.536828 -250.463885) (xy 353.489296 -250.448441) (xy 353.444764 -250.425751)
			(xy 353.404331 -250.396375) (xy 353.368991 -250.361035) (xy 353.339615 -250.320602) (xy 353.316925 -250.27607)
			(xy 353.301481 -250.228538) (xy 353.293662 -250.179175) (xy 352.04859 -250.179175) (xy 352.040771 -250.228538)
			(xy 352.025327 -250.27607) (xy 352.002637 -250.320602) (xy 351.973261 -250.361035) (xy 351.937921 -250.396375)
			(xy 351.897488 -250.425751) (xy 351.852956 -250.448441) (xy 351.805424 -250.463885) (xy 351.756061 -250.471704)
			(xy 351.706083 -250.471704) (xy 351.65672 -250.463885) (xy 351.609188 -250.448441) (xy 351.564656 -250.425751)
			(xy 351.524223 -250.396375) (xy 351.488883 -250.361035) (xy 351.459507 -250.320602) (xy 351.436817 -250.27607)
			(xy 351.421373 -250.228538) (xy 351.413554 -250.179175) (xy 350.168904 -250.179175) (xy 350.161832 -250.225748)
			(xy 350.147546 -250.271647) (xy 350.126516 -250.314874) (xy 350.099221 -250.354444) (xy 350.066282 -250.389456)
			(xy 350.02845 -250.419113) (xy 349.986586 -250.44274) (xy 349.964248 -250.45162) (xy 349.957644 -250.45416)
			(xy 349.951548 -250.458478) (xy 349.948037 -250.461174) (xy 349.941908 -250.467561) (xy 349.939356 -250.471178)
			(xy 349.934276 -250.478798) (xy 349.929958 -250.499118) (xy 349.91421 -250.573032) (xy 349.913481 -250.579056)
			(xy 349.914632 -250.591133) (xy 349.916496 -250.596908) (xy 349.917512 -250.599194) (xy 349.918274 -250.600972)
			(xy 349.918782 -250.602242) (xy 349.920721 -250.606144) (xy 349.9257 -250.613295) (xy 349.928688 -250.616466)
			(xy 349.9358 -250.623578) (xy 349.94252 -250.630814) (xy 349.950128 -250.649019) (xy 349.950532 -250.658884)
			(xy 349.950532 -250.998736) (xy 349.951294 -251.007372) (xy 349.954342 -251.01804) (xy 349.958152 -251.02693)
			(xy 350.0628 -251.131578) (xy 350.065866 -251.134469) (xy 350.072763 -251.139312) (xy 350.076516 -251.14123)
			(xy 350.078548 -251.141992) (xy 350.083388 -251.143995) (xy 350.093632 -251.146172) (xy 350.098868 -251.14631)
			(xy 350.77908 -251.14631) (xy 350.788952 -251.1459) (xy 350.807193 -251.138347) (xy 350.821152 -251.124386)
			(xy 350.828701 -251.106144) (xy 350.829118 -251.096272) (xy 350.829118 -250.61672) (xy 350.858074 -250.587764)
			(xy 351.044256 -250.587764) (xy 351.054639 -250.587176) (xy 351.073639 -250.57877) (xy 351.081086 -250.571508)
			(xy 351.086513 -250.565085) (xy 351.09314 -250.549642) (xy 351.09404 -250.541282) (xy 351.09404 -250.52782)
			(xy 351.348294 -250.52782) (xy 351.370047 -250.528296) (xy 351.412673 -250.536994) (xy 351.452667 -250.554116)
			(xy 351.488383 -250.578956) (xy 351.503742 -250.594368) (xy 351.517482 -250.609485) (xy 351.539481 -250.643901)
			(xy 351.55452 -250.681878) (xy 351.562048 -250.722024) (xy 351.562416 -250.74245) (xy 351.562416 -250.860814)
			(xy 351.564702 -250.86818) (xy 351.571479 -250.891341) (xy 351.57875 -250.939047) (xy 351.57918 -250.963176)
			(xy 351.57918 -250.963684) (xy 351.578697 -250.989748) (xy 351.570268 -251.041188) (xy 351.562416 -251.066046)
			(xy 351.561654 -251.068332) (xy 351.559876 -251.076206) (xy 351.559622 -251.078238) (xy 351.55886 -251.081794)
			(xy 351.55886 -251.08281) (xy 351.558098 -251.08662) (xy 351.557844 -251.087636) (xy 351.557336 -251.090938)
			(xy 351.557336 -251.101352) (xy 351.558681 -251.110482) (xy 351.56701 -251.126931) (xy 351.580692 -251.13929)
			(xy 351.597901 -251.145907) (xy 351.60712 -251.14631) (xy 352.55708 -251.14631) (xy 352.566952 -251.1459)
			(xy 352.585193 -251.138347) (xy 352.599152 -251.124386) (xy 352.606701 -251.106144) (xy 352.607118 -251.096272)
			(xy 352.607118 -250.61672) (xy 352.636074 -250.587764) (xy 352.822256 -250.587764) (xy 352.832639 -250.587176)
			(xy 352.851639 -250.57877) (xy 352.859086 -250.571508) (xy 352.864513 -250.565085) (xy 352.87114 -250.549642)
			(xy 352.87204 -250.541282) (xy 352.87204 -250.52782) (xy 353.115372 -250.52782) (xy 353.126802 -250.527566)
			(xy 353.127056 -250.527566) (xy 353.147597 -250.528025) (xy 353.187924 -250.535857) (xy 353.226009 -250.551259)
			(xy 353.260443 -250.573662) (xy 353.289957 -250.602238) (xy 353.313458 -250.635933) (xy 353.330079 -250.673501)
			(xy 353.335082 -250.693428) (xy 353.33559 -250.696222) (xy 353.33559 -250.696476) (xy 353.335844 -250.697746)
			(xy 353.336098 -250.698508) (xy 353.33686 -250.702572) (xy 353.338039 -250.706269) (xy 353.341359 -250.713282)
			(xy 353.343464 -250.716542) (xy 353.346258 -250.720606) (xy 353.351084 -250.725432) (xy 353.371017 -250.743691)
			(xy 353.404979 -250.785742) (xy 353.431344 -250.832928) (xy 353.449355 -250.883891) (xy 353.458492 -250.937166)
			(xy 353.459034 -250.964192) (xy 353.458869 -250.979916) (xy 353.455815 -251.011216) (xy 353.452938 -251.026676)
			(xy 353.45243 -251.029216) (xy 353.450652 -251.037852) (xy 353.453446 -251.04852) (xy 353.454841 -251.053297)
			(xy 353.459196 -251.062245) (xy 353.462082 -251.0663) (xy 353.492054 -251.102876) (xy 353.513136 -251.128784)
			(xy 353.520598 -251.136717) (xy 353.540357 -251.145819) (xy 353.551236 -251.14631) (xy 354.38588 -251.14631)
			(xy 354.395752 -251.1459) (xy 354.413993 -251.138347) (xy 354.427952 -251.124386) (xy 354.435501 -251.106144)
			(xy 354.435918 -251.096272) (xy 354.435918 -250.61672) (xy 354.464874 -250.587764) (xy 354.651056 -250.587764)
			(xy 354.661439 -250.587176) (xy 354.680439 -250.57877) (xy 354.687886 -250.571508) (xy 354.693313 -250.565085)
			(xy 354.69994 -250.549642) (xy 354.70084 -250.541282) (xy 354.70084 -250.52782) (xy 354.950776 -250.52782)
			(xy 354.955856 -250.527566) (xy 354.97673 -250.528067) (xy 355.017684 -250.536174) (xy 355.056281 -250.552087)
			(xy 355.091049 -250.575199) (xy 355.106224 -250.589542) (xy 355.113174 -250.596573) (xy 355.125894 -250.611711)
			(xy 355.131624 -250.619768) (xy 355.132132 -250.62053) (xy 355.132386 -250.620784) (xy 355.135688 -250.625864)
			(xy 355.136196 -250.62688) (xy 355.137974 -250.62942) (xy 355.138482 -250.630436) (xy 355.151182 -250.65482)
			(xy 355.15423 -250.661932) (xy 355.174804 -250.685554) (xy 355.182424 -250.689872) (xy 355.202577 -250.702226)
			(xy 355.239329 -250.731952) (xy 355.271281 -250.766785) (xy 355.297733 -250.805959) (xy 355.318102 -250.848614)
			(xy 355.331941 -250.893811) (xy 355.338945 -250.940558) (xy 355.339396 -250.964192) (xy 355.339206 -250.979789)
			(xy 355.336154 -251.010833) (xy 355.3333 -251.026168) (xy 355.33076 -251.03836) (xy 355.333554 -251.04852)
			(xy 355.335085 -251.053834) (xy 355.340092 -251.063691) (xy 355.34346 -251.068078) (xy 355.372162 -251.102622)
			(xy 355.372162 -251.10313) (xy 355.393244 -251.128784) (xy 355.400707 -251.136716) (xy 355.420466 -251.145815)
			(xy 355.431344 -251.14631) (xy 356.406958 -251.14631) (xy 356.416708 -251.145795) (xy 356.434735 -251.138345)
			(xy 356.44201 -251.131832) (xy 356.5398 -251.034042) (xy 356.542697 -251.030979) (xy 356.547551 -251.024088)
			(xy 356.549452 -251.020326) (xy 356.550214 -251.018294) (xy 356.55222 -251.013455) (xy 356.554405 -251.003211)
			(xy 356.554532 -250.997974) (xy 356.554532 -250.785884) (xy 356.555059 -250.776043) (xy 356.562636 -250.757871)
			(xy 356.569264 -250.750578) (xy 356.6668 -250.653042) (xy 356.67404 -250.646332) (xy 356.692244 -250.638741)
			(xy 356.702106 -250.63831) (xy 357.020114 -250.63831) (xy 357.028498 -250.637991) (xy 357.044336 -250.632485)
			(xy 357.057491 -250.622087) (xy 357.062278 -250.615196) (xy 357.084884 -250.57989) (xy 357.10876 -250.542552)
			(xy 357.111549 -250.537487) (xy 357.115009 -250.526458) (xy 357.115618 -250.520708) (xy 357.11638 -250.508262)
			(xy 357.111046 -250.496324) (xy 357.106474 -250.485148) (xy 357.105712 -250.483116) (xy 357.105458 -250.482862)
			(xy 357.101394 -250.471178) (xy 357.099362 -250.464574) (xy 357.099108 -250.463304) (xy 357.098854 -250.462288)
			(xy 357.0986 -250.460764) (xy 357.098092 -250.458224) (xy 357.093774 -250.437142) (xy 357.093774 -250.436634)
			(xy 357.092634 -250.427537) (xy 357.091743 -250.409223) (xy 357.091996 -250.400058) (xy 357.091996 -250.31192)
			(xy 357.089456 -250.302268) (xy 357.086662 -250.296426) (xy 357.086408 -250.295918) (xy 357.075909 -250.273828)
			(xy 357.061081 -250.227223) (xy 357.053582 -250.178894) (xy 357.053134 -250.15444) (xy 357.053134 -250.150376)
			(xy 357.053908 -250.125585) (xy 357.062197 -250.076684) (xy 357.077978 -250.029664) (xy 357.100868 -249.985664)
			(xy 357.130311 -249.945752) (xy 357.165595 -249.910895) (xy 357.205862 -249.881939) (xy 357.250137 -249.859585)
			(xy 357.297346 -249.844377) (xy 357.346343 -249.836683) (xy 357.371142 -249.836178) (xy 357.37165 -249.836178)
			(xy 357.394342 -249.836575) (xy 357.439262 -249.843058) (xy 357.482801 -249.855871) (xy 357.524072 -249.874753)
			(xy 357.543354 -249.886724) (xy 357.552752 -249.89282) (xy 357.560372 -249.89282) (xy 357.560372 -249.897138)
			(xy 357.577898 -249.912378) (xy 357.580946 -249.915172) (xy 357.581454 -249.91568) (xy 357.584502 -249.918474)
			(xy 357.588058 -249.921522) (xy 357.589074 -249.922538) (xy 357.597456 -249.930666) (xy 357.604314 -249.937524)
			(xy 357.629968 -249.948446) (xy 357.634748 -249.950425) (xy 357.644863 -249.952595) (xy 357.650034 -249.952764)
			(xy 357.796338 -249.952764) (xy 357.825294 -249.98172) (xy 357.825294 -250.588272) (xy 357.825703 -250.598144)
			(xy 357.833254 -250.616388) (xy 357.847216 -250.630348) (xy 357.86546 -250.637898) (xy 357.875332 -250.63831)
			(xy 360.830114 -250.63831) (xy 360.842653 -250.63763) (xy 360.864668 -250.625627) (xy 360.872024 -250.61545)
			(xy 360.916982 -250.5456) (xy 360.920298 -250.540147) (xy 360.924406 -250.528068) (xy 360.92511 -250.521724)
			(xy 360.925872 -250.509278) (xy 360.920284 -250.49734) (xy 360.911629 -250.476859) (xy 360.902024 -250.433454)
			(xy 360.901234 -250.411234) (xy 360.901234 -250.400312) (xy 360.888534 -250.367038) (xy 360.88828 -250.366784)
			(xy 360.883454 -250.36145) (xy 360.8832 -250.361196) (xy 360.881676 -250.359418) (xy 360.864138 -250.337715)
			(xy 360.836163 -250.28944) (xy 360.81703 -250.237028) (xy 360.807325 -250.182084) (xy 360.806746 -250.154186)
			(xy 360.806746 -250.14555) (xy 360.807864 -250.121004) (xy 360.816725 -250.072676) (xy 360.832914 -250.026286)
			(xy 360.856047 -249.982939) (xy 360.885572 -249.943665) (xy 360.920787 -249.909401) (xy 360.960854 -249.880962)
			(xy 361.004818 -249.859025) (xy 361.051634 -249.844111) (xy 361.100187 -249.836577) (xy 361.124754 -249.836178)
			(xy 361.128564 -249.836178) (xy 361.135168 -249.836432) (xy 361.135676 -249.836432) (xy 361.145305 -249.836815)
			(xy 361.164495 -249.838596) (xy 361.17403 -249.839988) (xy 361.189584 -249.842594) (xy 361.220121 -249.850479)
			(xy 361.23499 -249.855736) (xy 361.248683 -249.860949) (xy 361.275143 -249.873539) (xy 361.287822 -249.880882)
			(xy 361.29341 -249.884184) (xy 361.318556 -249.89155) (xy 361.324144 -249.891804) (xy 361.326176 -249.892058)
			(xy 361.32643 -249.892058) (xy 361.3277 -249.892312) (xy 361.331002 -249.89282) (xy 361.340654 -249.89282)
			(xy 361.384596 -249.936762) (xy 361.390184 -249.941588) (xy 361.396924 -249.946258) (xy 361.41247 -249.951446)
			(xy 361.420664 -249.951748) (xy 361.586272 -249.951748) (xy 361.592876 -249.952256) (xy 361.596178 -249.952764)
			(xy 361.606338 -249.952764) (xy 361.635294 -249.98172) (xy 361.635294 -249.99061) (xy 361.635802 -249.994166)
			(xy 361.63631 -250.001786) (xy 361.63631 -250.179175) (xy 362.687344 -250.179175) (xy 362.687344 -250.129197)
			(xy 362.695163 -250.079834) (xy 362.710607 -250.032302) (xy 362.733297 -249.98777) (xy 362.762673 -249.947337)
			(xy 362.798013 -249.911997) (xy 362.838446 -249.882621) (xy 362.882978 -249.859931) (xy 362.93051 -249.844487)
			(xy 362.979873 -249.836668) (xy 363.029851 -249.836668) (xy 363.079214 -249.844487) (xy 363.126746 -249.859931)
			(xy 363.171278 -249.882621) (xy 363.211711 -249.911997) (xy 363.247051 -249.947337) (xy 363.276427 -249.98777)
			(xy 363.299117 -250.032302) (xy 363.314561 -250.079834) (xy 363.32238 -250.129197) (xy 363.32287 -250.154186)
			(xy 363.32238 -250.179175) (xy 363.314561 -250.228538) (xy 363.299117 -250.27607) (xy 363.276427 -250.320602)
			(xy 363.247051 -250.361035) (xy 363.211711 -250.396375) (xy 363.171278 -250.425751) (xy 363.126746 -250.448441)
			(xy 363.079214 -250.463885) (xy 363.029851 -250.471704) (xy 362.979873 -250.471704) (xy 362.93051 -250.463885)
			(xy 362.882978 -250.448441) (xy 362.838446 -250.425751) (xy 362.798013 -250.396375) (xy 362.762673 -250.361035)
			(xy 362.733297 -250.320602) (xy 362.710607 -250.27607) (xy 362.695163 -250.228538) (xy 362.687344 -250.179175)
			(xy 361.63631 -250.179175) (xy 361.63631 -250.588272) (xy 361.636719 -250.598143) (xy 361.644271 -250.616384)
			(xy 361.658233 -250.63034) (xy 361.676477 -250.637885) (xy 361.686348 -250.63831) (xy 363.186726 -250.63831)
			(xy 363.192736 -250.638146) (xy 363.204422 -250.635327) (xy 363.20984 -250.632722) (xy 363.21492 -250.630182)
			(xy 363.224064 -250.622308) (xy 363.22762 -250.617228) (xy 363.239783 -250.600949) (xy 363.269208 -250.572929)
			(xy 363.303405 -250.550985) (xy 363.341136 -250.535909) (xy 363.38104 -250.528248) (xy 363.401356 -250.52782)
			(xy 363.605572 -250.52782) (xy 363.615595 -250.528235) (xy 363.634118 -250.535901) (xy 363.648295 -250.550075)
			(xy 363.655963 -250.568597) (xy 363.656372 -250.57862) (xy 363.656372 -250.587764) (xy 363.892338 -250.587764)
			(xy 363.921294 -250.61672) (xy 363.921294 -250.999498) (xy 363.922056 -251.008134) (xy 363.925104 -251.018802)
			(xy 363.928914 -251.027692) (xy 364.0328 -251.131578) (xy 364.035866 -251.134469) (xy 364.042763 -251.139312)
			(xy 364.046516 -251.14123) (xy 364.048548 -251.141992) (xy 364.053388 -251.143995) (xy 364.063632 -251.146172)
			(xy 364.068868 -251.14631) (xy 364.661958 -251.14631) (xy 364.671708 -251.145795) (xy 364.689735 -251.138345)
			(xy 364.69701 -251.131832) (xy 364.7948 -251.034042) (xy 364.797697 -251.030979) (xy 364.802551 -251.024088)
			(xy 364.804452 -251.020326) (xy 364.805214 -251.018294) (xy 364.80722 -251.013455) (xy 364.809405 -251.003211)
			(xy 364.809532 -250.997974) (xy 364.809532 -250.658884) (xy 364.810059 -250.649043) (xy 364.817636 -250.630871)
			(xy 364.824264 -250.623578) (xy 364.825534 -250.622308) (xy 364.831294 -250.616022) (xy 364.838599 -250.600628)
			(xy 364.840391 -250.583683) (xy 364.838742 -250.575318) (xy 364.827566 -250.528582) (xy 364.81893 -250.492768)
			(xy 364.81893 -250.492514) (xy 364.818422 -250.49099) (xy 364.816736 -250.485259) (xy 364.811088 -250.474736)
			(xy 364.807246 -250.470162) (xy 364.802674 -250.465336) (xy 364.792006 -250.458478) (xy 364.78591 -250.456446)
			(xy 364.762343 -250.44823) (xy 364.717911 -250.425505) (xy 364.677574 -250.396117) (xy 364.642324 -250.360789)
			(xy 364.613026 -250.320387) (xy 364.590399 -250.275905) (xy 364.575 -250.228433) (xy 364.567205 -250.179139)
			(xy 364.566708 -250.154186) (xy 364.567173 -250.129196) (xy 364.574994 -250.079832) (xy 364.590441 -250.032298)
			(xy 364.613134 -249.987767) (xy 364.642513 -249.947333) (xy 364.677856 -249.911994) (xy 364.718292 -249.882618)
			(xy 364.762826 -249.85993) (xy 364.810361 -249.844487) (xy 364.859726 -249.836671) (xy 364.884716 -249.836178)
			(xy 364.909403 -249.836645) (xy 364.958185 -249.844276) (xy 365.005201 -249.859352) (xy 365.049324 -249.881511)
			(xy 365.089493 -249.910221) (xy 365.124745 -249.944793) (xy 365.154232 -249.984395) (xy 365.177246 -250.028078)
			(xy 365.193234 -250.074792) (xy 365.201814 -250.123416) (xy 365.202724 -250.14809) (xy 365.202724 -250.154186)
			(xy 365.202201 -250.180481) (xy 365.193595 -250.232362) (xy 365.176581 -250.282123) (xy 365.151622 -250.328413)
			(xy 365.135922 -250.349512) (xy 365.13389 -250.352052) (xy 365.130505 -250.357296) (xy 365.126147 -250.368988)
			(xy 365.125254 -250.375166) (xy 365.124748 -250.381731) (xy 365.126811 -250.394731) (xy 365.129318 -250.40082)
			(xy 365.149892 -250.442984) (xy 365.16945 -250.483116) (xy 365.170212 -250.48464) (xy 365.172498 -250.489466)
			(xy 365.182404 -250.500388) (xy 365.187738 -250.50369) (xy 365.193853 -250.507174) (xy 365.207376 -250.511045)
			(xy 365.214408 -250.51131) (xy 366.435132 -250.51131) (xy 366.444207 -250.51093) (xy 366.461184 -250.504518)
			(xy 366.474785 -250.492503) (xy 366.479328 -250.48464) (xy 366.489234 -250.464066) (xy 366.520984 -250.399042)
			(xy 366.52498 -250.387277) (xy 366.522185 -250.362619) (xy 366.51565 -250.352052) (xy 366.51438 -250.350274)
			(xy 366.513872 -250.349512) (xy 366.513618 -250.349512) (xy 366.497984 -250.328519) (xy 366.473081 -250.282482)
			(xy 366.456062 -250.232987) (xy 366.447385 -250.181371) (xy 366.446816 -250.155202) (xy 366.446816 -250.147836)
			(xy 366.447768 -250.123172) (xy 366.456354 -250.074569) (xy 366.472347 -250.027877) (xy 366.495364 -249.984217)
			(xy 366.52485 -249.944638) (xy 366.560099 -249.91009) (xy 366.600262 -249.881405) (xy 366.644376 -249.85927)
			(xy 366.69138 -249.844219) (xy 366.740146 -249.836611) (xy 366.764824 -249.836178) (xy 366.789511 -249.836646)
			(xy 366.838291 -249.844278) (xy 366.885307 -249.859354) (xy 366.929428 -249.881514) (xy 366.969597 -249.910224)
			(xy 367.004847 -249.944795) (xy 367.034333 -249.984398) (xy 367.057346 -250.02808) (xy 367.073335 -250.074794)
			(xy 367.081914 -250.123416) (xy 367.082832 -250.14809) (xy 367.082832 -250.154186) (xy 367.082336 -250.179175)
			(xy 368.32716 -250.179175) (xy 368.32716 -250.129197) (xy 368.334979 -250.079834) (xy 368.350423 -250.032302)
			(xy 368.373113 -249.98777) (xy 368.402489 -249.947337) (xy 368.437829 -249.911997) (xy 368.478262 -249.882621)
			(xy 368.522794 -249.859931) (xy 368.570326 -249.844487) (xy 368.619689 -249.836668) (xy 368.669667 -249.836668)
			(xy 368.71903 -249.844487) (xy 368.766562 -249.859931) (xy 368.811094 -249.882621) (xy 368.851527 -249.911997)
			(xy 368.886867 -249.947337) (xy 368.916243 -249.98777) (xy 368.938933 -250.032302) (xy 368.954377 -250.079834)
			(xy 368.962196 -250.129197) (xy 368.962686 -250.154186) (xy 368.962196 -250.179175) (xy 368.954377 -250.228538)
			(xy 368.938933 -250.27607) (xy 368.916243 -250.320602) (xy 368.886867 -250.361035) (xy 368.851527 -250.396375)
			(xy 368.811094 -250.425751) (xy 368.766562 -250.448441) (xy 368.71903 -250.463885) (xy 368.669667 -250.471704)
			(xy 368.619689 -250.471704) (xy 368.570326 -250.463885) (xy 368.522794 -250.448441) (xy 368.478262 -250.425751)
			(xy 368.437829 -250.396375) (xy 368.402489 -250.361035) (xy 368.373113 -250.320602) (xy 368.350423 -250.27607)
			(xy 368.334979 -250.228538) (xy 368.32716 -250.179175) (xy 367.082336 -250.179175) (xy 367.08231 -250.180481)
			(xy 367.073703 -250.232362) (xy 367.05669 -250.282123) (xy 367.031731 -250.328413) (xy 367.01603 -250.349512)
			(xy 367.013998 -250.352052) (xy 367.010613 -250.357296) (xy 367.006254 -250.368988) (xy 367.005362 -250.375166)
			(xy 367.004856 -250.381731) (xy 367.006919 -250.394731) (xy 367.009426 -250.40082) (xy 367.03 -250.442984)
			(xy 367.049558 -250.483116) (xy 367.05032 -250.48464) (xy 367.052606 -250.489466) (xy 367.062512 -250.500388)
			(xy 367.067846 -250.50369) (xy 367.073961 -250.507173) (xy 367.087484 -250.511042) (xy 367.094516 -250.51131)
			(xy 367.582958 -250.51131) (xy 367.592796 -250.511844) (xy 367.610959 -250.519429) (xy 367.618264 -250.526042)
			(xy 367.665508 -250.573286) (xy 367.67276 -250.579831) (xy 367.690803 -250.587262) (xy 367.70056 -250.587764)
			(xy 367.702338 -250.587764) (xy 367.731294 -250.61672) (xy 367.731294 -251.126498) (xy 367.732056 -251.135134)
			(xy 367.735104 -251.145802) (xy 367.738914 -251.154692) (xy 367.8428 -251.258578) (xy 367.845866 -251.261469)
			(xy 367.852763 -251.266312) (xy 367.856516 -251.26823) (xy 367.858548 -251.268992) (xy 367.863388 -251.270995)
			(xy 367.873632 -251.273172) (xy 367.878868 -251.27331)
		)
		(stroke
			(width 0)
			(type solid)
		)
		(fill yes)
		(layer "B.Cu")
		(net "PVDDCR_CPU0_P0")
	)
	(gr_poly
		(pts
			(xy 120.65889 -251.273564) (xy 120.668638 -251.273044) (xy 120.686663 -251.265592) (xy 120.693942 -251.259086)
			(xy 120.791986 -251.161042) (xy 120.798538 -251.153793) (xy 120.805988 -251.13575) (xy 120.806464 -251.12599)
			(xy 120.806464 -250.786138) (xy 120.806998 -250.776299) (xy 120.814579 -250.758133) (xy 120.821196 -250.750832)
			(xy 121.045732 -250.526296) (xy 121.052971 -250.519585) (xy 121.071176 -250.511997) (xy 121.081038 -250.511564)
			(xy 122.254518 -250.511564) (xy 122.263798 -250.511158) (xy 122.281124 -250.504508) (xy 122.2883 -250.49861)
			(xy 122.291624 -250.495576) (xy 122.297242 -250.488547) (xy 122.299476 -250.48464) (xy 122.317256 -250.447556)
			(xy 122.338846 -250.403106) (xy 122.342855 -250.392622) (xy 122.342324 -250.370212) (xy 122.33783 -250.359926)
			(xy 122.333258 -250.350782) (xy 122.329194 -250.343924) (xy 122.322082 -250.334018) (xy 122.320812 -250.33224)
			(xy 122.320304 -250.331224) (xy 122.319796 -250.330462) (xy 122.319542 -250.330208) (xy 122.30404 -250.305619)
			(xy 122.281301 -250.252129) (xy 122.26867 -250.195396) (xy 122.266964 -250.166378) (xy 122.266964 -250.165616)
			(xy 122.26671 -250.163076) (xy 122.26671 -250.160028) (xy 122.266456 -250.152916) (xy 122.266456 -250.14682)
			(xy 122.267218 -250.134628) (xy 122.267472 -250.132596) (xy 122.269825 -250.106141) (xy 122.282219 -250.054498)
			(xy 122.303021 -250.005632) (xy 122.331652 -249.960901) (xy 122.367317 -249.921549) (xy 122.409024 -249.888669)
			(xy 122.455614 -249.863175) (xy 122.505792 -249.845776) (xy 122.558163 -249.836956) (xy 122.584718 -249.836432)
			(xy 122.609404 -249.836899) (xy 122.658182 -249.844531) (xy 122.705195 -249.859608) (xy 122.749313 -249.881768)
			(xy 122.789478 -249.910479) (xy 122.824724 -249.945051) (xy 122.854205 -249.984654) (xy 122.877212 -250.028337)
			(xy 122.893194 -250.075051) (xy 122.901765 -250.123672) (xy 122.902726 -250.148344) (xy 122.902726 -250.157742)
			(xy 122.90208 -250.179429) (xy 124.147308 -250.179429) (xy 124.147308 -250.129451) (xy 124.155127 -250.080088)
			(xy 124.170571 -250.032556) (xy 124.193261 -249.988024) (xy 124.222637 -249.947591) (xy 124.257977 -249.912251)
			(xy 124.29841 -249.882875) (xy 124.342942 -249.860185) (xy 124.390474 -249.844741) (xy 124.439837 -249.836922)
			(xy 124.489815 -249.836922) (xy 124.539178 -249.844741) (xy 124.58671 -249.860185) (xy 124.631242 -249.882875)
			(xy 124.671675 -249.912251) (xy 124.707015 -249.947591) (xy 124.736391 -249.988024) (xy 124.759081 -250.032556)
			(xy 124.774525 -250.080088) (xy 124.782344 -250.129451) (xy 124.782834 -250.15444) (xy 124.782344 -250.179429)
			(xy 124.774525 -250.228792) (xy 124.759081 -250.276324) (xy 124.736391 -250.320856) (xy 124.707015 -250.361289)
			(xy 124.671675 -250.396629) (xy 124.631242 -250.426005) (xy 124.58671 -250.448695) (xy 124.539178 -250.464139)
			(xy 124.489815 -250.471958) (xy 124.439837 -250.471958) (xy 124.390474 -250.464139) (xy 124.342942 -250.448695)
			(xy 124.29841 -250.426005) (xy 124.257977 -250.396629) (xy 124.222637 -250.361289) (xy 124.193261 -250.320856)
			(xy 124.170571 -250.276324) (xy 124.155127 -250.228792) (xy 124.147308 -250.179429) (xy 122.90208 -250.179429)
			(xy 122.901956 -250.183595) (xy 122.893065 -250.234544) (xy 122.876045 -250.283382) (xy 122.864118 -250.306332)
			(xy 122.863102 -250.307856) (xy 122.862848 -250.308618) (xy 122.862848 -250.308872) (xy 122.86107 -250.312174)
			(xy 122.860816 -250.312428) (xy 122.860562 -250.312936) (xy 122.860054 -250.313698) (xy 122.859292 -250.314968)
			(xy 122.854974 -250.32335) (xy 122.85091 -250.330462) (xy 122.846592 -250.336304) (xy 122.84456 -250.338844)
			(xy 122.837956 -250.346718) (xy 122.83694 -250.348242) (xy 122.83567 -250.35002) (xy 122.828812 -250.37034)
			(xy 122.826018 -250.378214) (xy 122.825256 -250.380754) (xy 122.825381 -250.385566) (xy 122.827174 -250.395023)
			(xy 122.828812 -250.39955) (xy 122.866404 -250.47702) (xy 122.86742 -250.479306) (xy 122.870722 -250.48718)
			(xy 122.875548 -250.492768) (xy 122.878596 -250.49607) (xy 122.886216 -250.50242) (xy 122.887486 -250.503182)
			(xy 122.888248 -250.50369) (xy 122.894446 -250.507329) (xy 122.908243 -250.511333) (xy 122.915426 -250.511564)
			(xy 123.45289 -250.511564) (xy 123.462727 -250.512103) (xy 123.480886 -250.519691) (xy 123.488196 -250.526296)
			(xy 123.535186 -250.573286) (xy 123.540862 -250.578484) (xy 123.554567 -250.585474) (xy 123.56211 -250.587002)
			(xy 123.562618 -250.587002) (xy 123.570746 -250.587764) (xy 123.571254 -250.587764) (xy 123.600972 -250.617482)
			(xy 123.600972 -250.61799) (xy 123.601444 -250.627959) (xy 123.609009 -250.646406) (xy 123.615704 -250.653804)
			(xy 123.712732 -250.750832) (xy 123.71944 -250.758072) (xy 123.727023 -250.776277) (xy 123.727464 -250.786138)
			(xy 123.727464 -251.125482) (xy 123.728226 -251.13361) (xy 123.728226 -251.134118) (xy 123.729826 -251.141637)
			(xy 123.736802 -251.155326) (xy 123.741942 -251.161042) (xy 123.839986 -251.259086) (xy 123.845662 -251.264284)
			(xy 123.859367 -251.271274) (xy 123.86691 -251.272802) (xy 123.867418 -251.272802) (xy 123.875546 -251.273564)
			(xy 124.46889 -251.273564) (xy 124.478638 -251.273044) (xy 124.496663 -251.265592) (xy 124.503942 -251.259086)
			(xy 124.601986 -251.161042) (xy 124.608538 -251.153793) (xy 124.615988 -251.13575) (xy 124.616464 -251.12599)
			(xy 124.616464 -250.786138) (xy 124.616998 -250.776299) (xy 124.624579 -250.758133) (xy 124.631196 -250.750832)
			(xy 124.63272 -250.749308) (xy 124.638169 -250.743532) (xy 124.645427 -250.729416) (xy 124.646944 -250.721622)
			(xy 124.647198 -250.718828) (xy 124.647198 -250.718574) (xy 124.649897 -250.698036) (xy 124.662172 -250.65848)
			(xy 124.681836 -250.622028) (xy 124.708153 -250.590046) (xy 124.740136 -250.563731) (xy 124.776588 -250.544069)
			(xy 124.816145 -250.531795) (xy 124.836682 -250.52909) (xy 124.836936 -250.52909) (xy 124.840746 -250.528582)
			(xy 124.846732 -250.527298) (xy 124.857895 -250.522281) (xy 124.862844 -250.518676) (xy 124.867416 -250.514612)
			(xy 124.982732 -250.399296) (xy 124.989971 -250.392585) (xy 125.008176 -250.384997) (xy 125.018038 -250.384564)
			(xy 125.61189 -250.384564) (xy 125.621638 -250.384044) (xy 125.639663 -250.376592) (xy 125.646942 -250.370086)
			(xy 126.502922 -249.514106) (xy 126.507896 -249.508673) (xy 126.514727 -249.49563) (xy 126.516384 -249.488452)
			(xy 126.516384 -249.487944) (xy 126.5174 -249.478546) (xy 126.5174 -249.45721) (xy 126.514606 -249.449082)
			(xy 126.506321 -249.423717) (xy 126.497389 -249.371112) (xy 126.496826 -249.344434) (xy 126.497216 -249.322184)
			(xy 126.503454 -249.278122) (xy 126.515771 -249.235359) (xy 126.524512 -249.214894) (xy 126.52883 -249.204988)
			(xy 126.52883 -249.154442) (xy 126.53391 -249.154442) (xy 126.53391 -248.934732) (xy 126.533656 -248.932192)
			(xy 126.533656 -248.61139) (xy 126.53391 -248.610882) (xy 126.53391 -248.457974) (xy 126.533656 -248.457466)
			(xy 126.533656 -248.136664) (xy 126.53391 -248.134124) (xy 126.53391 -247.879616) (xy 126.53137 -247.868694)
			(xy 126.52883 -247.86336) (xy 126.518745 -247.841601) (xy 126.504493 -247.79581) (xy 126.497262 -247.7484)
			(xy 126.496826 -247.724422) (xy 126.497217 -247.702172) (xy 126.503456 -247.658111) (xy 126.515775 -247.615349)
			(xy 126.524512 -247.594882) (xy 126.52883 -247.584976) (xy 126.52883 -247.53443) (xy 126.53391 -247.53443)
			(xy 126.53391 -247.323864) (xy 126.533744 -247.317854) (xy 126.530924 -247.30617) (xy 126.528322 -247.30075)
			(xy 126.526481 -247.297277) (xy 126.521886 -247.290899) (xy 126.519178 -247.28805) (xy 126.515114 -247.283986)
			(xy 126.4539 -247.234456) (xy 126.449777 -247.231614) (xy 126.440694 -247.227402) (xy 126.435866 -247.226074)
			(xy 126.428246 -247.224296) (xy 126.413006 -247.225312) (xy 126.409704 -247.22582) (xy 126.408434 -247.226074)
			(xy 126.392667 -247.229071) (xy 126.360729 -247.232254) (xy 126.34468 -247.232424) (xy 126.319691 -247.231932)
			(xy 126.270327 -247.224111) (xy 126.222796 -247.208664) (xy 126.178265 -247.185972) (xy 126.137832 -247.156594)
			(xy 126.102493 -247.121252) (xy 126.073117 -247.080818) (xy 126.050428 -247.036286) (xy 126.034984 -246.988753)
			(xy 126.027166 -246.939389) (xy 126.027166 -246.889411) (xy 126.034984 -246.840047) (xy 126.050428 -246.792514)
			(xy 126.073117 -246.747982) (xy 126.102493 -246.707548) (xy 126.137832 -246.672206) (xy 126.178265 -246.642828)
			(xy 126.222796 -246.620136) (xy 126.270327 -246.604689) (xy 126.319691 -246.596868) (xy 126.34468 -246.596408)
			(xy 126.361702 -246.596589) (xy 126.395557 -246.600155) (xy 126.412244 -246.60352) (xy 126.423928 -246.60606)
			(xy 126.434596 -246.603266) (xy 126.439501 -246.601987) (xy 126.448718 -246.597771) (xy 126.452884 -246.594884)
			(xy 126.514606 -246.545608) (xy 126.516638 -246.543322) (xy 126.519432 -246.540528) (xy 126.524628 -246.53485)
			(xy 126.531615 -246.521146) (xy 126.533148 -246.513604) (xy 126.533148 -246.513096) (xy 126.53391 -246.504968)
			(xy 126.53391 -246.259604) (xy 126.53137 -246.248682) (xy 126.52883 -246.243348) (xy 126.518745 -246.221589)
			(xy 126.504496 -246.175797) (xy 126.497266 -246.128388) (xy 126.496826 -246.10441) (xy 126.497218 -246.08216)
			(xy 126.503459 -246.038099) (xy 126.515778 -245.995338) (xy 126.524512 -245.97487) (xy 126.52883 -245.964964)
			(xy 126.52883 -245.914418) (xy 126.53391 -245.914418) (xy 126.53391 -245.694708) (xy 126.533656 -245.692168)
			(xy 126.533656 -245.371366) (xy 126.53391 -245.370858) (xy 126.53391 -245.21795) (xy 126.533656 -245.217442)
			(xy 126.533656 -244.89664) (xy 126.53391 -244.8941) (xy 126.53391 -244.639592) (xy 126.53137 -244.62867)
			(xy 126.52883 -244.623336) (xy 126.518746 -244.601577) (xy 126.504498 -244.555785) (xy 126.497271 -244.508376)
			(xy 126.496826 -244.484398) (xy 126.497219 -244.462148) (xy 126.503461 -244.418088) (xy 126.515782 -244.375328)
			(xy 126.524512 -244.354858) (xy 126.52883 -244.344952) (xy 126.52883 -244.294406) (xy 126.53391 -244.294406)
			(xy 126.53391 -244.08384) (xy 126.533742 -244.077831) (xy 126.530916 -244.066149) (xy 126.528322 -244.060726)
			(xy 126.526486 -244.05725) (xy 126.521897 -244.050865) (xy 126.519178 -244.048026) (xy 126.515114 -244.043962)
			(xy 126.4539 -243.994432) (xy 126.449779 -243.991587) (xy 126.440697 -243.987369) (xy 126.435866 -243.98605)
			(xy 126.428246 -243.984272) (xy 126.413006 -243.985288) (xy 126.409704 -243.985796) (xy 126.408434 -243.98605)
			(xy 126.392667 -243.989046) (xy 126.360728 -243.992229) (xy 126.34468 -243.9924) (xy 126.319692 -243.991908)
			(xy 126.270333 -243.984088) (xy 126.222805 -243.968642) (xy 126.178278 -243.945952) (xy 126.137848 -243.916576)
			(xy 126.102511 -243.881237) (xy 126.073138 -243.840805) (xy 126.05045 -243.796277) (xy 126.035008 -243.748747)
			(xy 126.02719 -243.699388) (xy 126.02719 -243.649412) (xy 126.035008 -243.600053) (xy 126.05045 -243.552523)
			(xy 126.073138 -243.507995) (xy 126.102511 -243.467563) (xy 126.137848 -243.432224) (xy 126.178278 -243.402848)
			(xy 126.222805 -243.380158) (xy 126.270333 -243.364712) (xy 126.319692 -243.356892) (xy 126.34468 -243.356384)
			(xy 126.361702 -243.356565) (xy 126.395557 -243.360131) (xy 126.412244 -243.363496) (xy 126.423928 -243.366036)
			(xy 126.434596 -243.363242) (xy 126.439501 -243.361963) (xy 126.448716 -243.357745) (xy 126.452884 -243.35486)
			(xy 126.514606 -243.305584) (xy 126.516638 -243.303298) (xy 126.519432 -243.300504) (xy 126.524625 -243.294825)
			(xy 126.531606 -243.281119) (xy 126.533148 -243.27358) (xy 126.533148 -243.273072) (xy 126.53391 -243.264944)
			(xy 126.53391 -243.01958) (xy 126.53137 -243.008658) (xy 126.52883 -243.003324) (xy 126.518747 -242.981564)
			(xy 126.504501 -242.935773) (xy 126.497275 -242.888364) (xy 126.496826 -242.864386) (xy 126.497219 -242.842136)
			(xy 126.503464 -242.798077) (xy 126.515786 -242.755317) (xy 126.524512 -242.734846) (xy 126.52883 -242.72494)
			(xy 126.52883 -242.674394) (xy 126.53391 -242.674394) (xy 126.53391 -242.454684) (xy 126.533656 -242.452144)
			(xy 126.533656 -242.131342) (xy 126.53391 -242.130834) (xy 126.53391 -241.977926) (xy 126.533656 -241.977418)
			(xy 126.533656 -241.656616) (xy 126.53391 -241.654076) (xy 126.53391 -241.399568) (xy 126.53137 -241.388646)
			(xy 126.52883 -241.383312) (xy 126.518748 -241.361552) (xy 126.504504 -241.315761) (xy 126.497279 -241.268352)
			(xy 126.496826 -241.244374) (xy 126.497213 -241.222123) (xy 126.503446 -241.178059) (xy 126.515758 -241.135294)
			(xy 126.524512 -241.114834) (xy 126.52883 -241.104928) (xy 126.52883 -241.054382) (xy 126.53391 -241.054382)
			(xy 126.53391 -240.843816) (xy 126.533739 -240.837807) (xy 126.530909 -240.826128) (xy 126.528322 -240.820702)
			(xy 126.526484 -240.817227) (xy 126.521894 -240.810844) (xy 126.519178 -240.808002) (xy 126.515114 -240.803938)
			(xy 126.4539 -240.754408) (xy 126.449778 -240.751564) (xy 126.440696 -240.747348) (xy 126.435866 -240.746026)
			(xy 126.428246 -240.744248) (xy 126.413006 -240.745264) (xy 126.409704 -240.745772) (xy 126.408434 -240.746026)
			(xy 126.392667 -240.749022) (xy 126.360729 -240.752206) (xy 126.34468 -240.752376) (xy 126.319694 -240.751884)
			(xy 126.270339 -240.744064) (xy 126.222814 -240.72862) (xy 126.17829 -240.705931) (xy 126.137864 -240.676557)
			(xy 126.10253 -240.641221) (xy 126.073158 -240.600793) (xy 126.050472 -240.556268) (xy 126.035031 -240.508742)
			(xy 126.027214 -240.459386) (xy 126.027214 -240.409414) (xy 126.035031 -240.360058) (xy 126.050472 -240.312532)
			(xy 126.073158 -240.268007) (xy 126.10253 -240.227579) (xy 126.137864 -240.192243) (xy 126.17829 -240.162869)
			(xy 126.222814 -240.14018) (xy 126.270339 -240.124736) (xy 126.319694 -240.116916) (xy 126.34468 -240.11636)
			(xy 126.361702 -240.116541) (xy 126.395557 -240.120107) (xy 126.412244 -240.123472) (xy 126.423928 -240.126012)
			(xy 126.434596 -240.123218) (xy 126.4395 -240.121938) (xy 126.448715 -240.117718) (xy 126.452884 -240.114836)
			(xy 126.514606 -240.06556) (xy 126.516638 -240.063274) (xy 126.519432 -240.06048) (xy 126.524623 -240.0548)
			(xy 126.531597 -240.041093) (xy 126.533148 -240.033556) (xy 126.533148 -240.033048) (xy 126.53391 -240.02492)
			(xy 126.53391 -239.779556) (xy 126.53137 -239.768634) (xy 126.52883 -239.7633) (xy 126.518749 -239.74154)
			(xy 126.504506 -239.695748) (xy 126.497284 -239.648339) (xy 126.496826 -239.624362) (xy 126.497214 -239.602111)
			(xy 126.503448 -239.558048) (xy 126.515762 -239.515283) (xy 126.524512 -239.494822) (xy 126.52883 -239.484916)
			(xy 126.52883 -239.43437) (xy 126.53391 -239.43437) (xy 126.53391 -239.21466) (xy 126.533656 -239.21212)
			(xy 126.533656 -238.891318) (xy 126.53391 -238.89081) (xy 126.53391 -238.737902) (xy 126.533656 -238.737394)
			(xy 126.533656 -238.159544) (xy 126.531116 -238.148622) (xy 126.528576 -238.143288) (xy 126.518534 -238.12152)
			(xy 126.504372 -238.075722) (xy 126.497229 -238.028319) (xy 126.496826 -238.00435) (xy 126.497215 -237.980474)
			(xy 126.504285 -237.933249) (xy 126.518347 -237.887616) (xy 126.528322 -237.86592) (xy 126.528576 -237.865412)
			(xy 126.529846 -237.862618) (xy 126.531574 -237.85811) (xy 126.533492 -237.848648) (xy 126.533656 -237.843822)
			(xy 126.533656 -237.603538) (xy 126.533488 -237.597528) (xy 126.530665 -237.585846) (xy 126.528068 -237.580424)
			(xy 126.52623 -237.576949) (xy 126.521638 -237.570568) (xy 126.518924 -237.567724) (xy 126.515114 -237.563914)
			(xy 126.4539 -237.514384) (xy 126.449778 -237.511541) (xy 126.440695 -237.507327) (xy 126.435866 -237.506002)
			(xy 126.428246 -237.504224) (xy 126.413006 -237.50524) (xy 126.409704 -237.505748) (xy 126.408434 -237.506002)
			(xy 126.392667 -237.508998) (xy 126.360729 -237.512182) (xy 126.34468 -237.512352) (xy 126.319688 -237.51186)
			(xy 126.270321 -237.504038) (xy 126.222785 -237.48859) (xy 126.17825 -237.465896) (xy 126.137814 -237.436515)
			(xy 126.102472 -237.401171) (xy 126.073093 -237.360733) (xy 126.050402 -237.316197) (xy 126.034957 -237.26866)
			(xy 126.027138 -237.219292) (xy 126.027138 -237.169308) (xy 126.034957 -237.11994) (xy 126.050402 -237.072403)
			(xy 126.073093 -237.027867) (xy 126.102472 -236.987429) (xy 126.137814 -236.952085) (xy 126.17825 -236.922704)
			(xy 126.222785 -236.90001) (xy 126.270321 -236.884562) (xy 126.319688 -236.87674) (xy 126.34468 -236.876336)
			(xy 126.361702 -236.876517) (xy 126.395557 -236.880083) (xy 126.412244 -236.883448) (xy 126.423928 -236.885988)
			(xy 126.434596 -236.883194) (xy 126.439501 -236.881916) (xy 126.448719 -236.877701) (xy 126.452884 -236.874812)
			(xy 126.514606 -236.825536) (xy 126.516638 -236.82325) (xy 126.519432 -236.820456) (xy 126.524631 -236.81478)
			(xy 126.531626 -236.801077) (xy 126.533148 -236.793532) (xy 126.533148 -236.793024) (xy 126.53391 -236.784896)
			(xy 126.53391 -236.539532) (xy 126.53137 -236.52861) (xy 126.52883 -236.523276) (xy 126.51875 -236.501516)
			(xy 126.504511 -236.455724) (xy 126.497292 -236.408315) (xy 126.496826 -236.384338) (xy 126.497216 -236.362088)
			(xy 126.503453 -236.318026) (xy 126.515769 -236.275262) (xy 126.524512 -236.254798) (xy 126.52883 -236.244892)
			(xy 126.52883 -236.194346) (xy 126.53391 -236.194346) (xy 126.53391 -235.98378) (xy 126.533746 -235.977769)
			(xy 126.530929 -235.966084) (xy 126.528322 -235.960666) (xy 126.526482 -235.957192) (xy 126.521889 -235.950813)
			(xy 126.519178 -235.947966) (xy 126.515114 -235.943902) (xy 126.4539 -235.894372) (xy 126.449778 -235.891529)
			(xy 126.440695 -235.887316) (xy 126.435866 -235.88599) (xy 126.428246 -235.884212) (xy 126.413006 -235.885228)
			(xy 126.409704 -235.885736) (xy 126.408434 -235.88599) (xy 126.392667 -235.888986) (xy 126.360729 -235.89217)
			(xy 126.34468 -235.89234) (xy 126.319689 -235.891848) (xy 126.270324 -235.884026) (xy 126.222789 -235.868579)
			(xy 126.178257 -235.845886) (xy 126.137822 -235.816506) (xy 126.102481 -235.781163) (xy 126.073104 -235.740726)
			(xy 126.050413 -235.696192) (xy 126.034969 -235.648657) (xy 126.02715 -235.599291) (xy 126.02715 -235.549309)
			(xy 126.034969 -235.499943) (xy 126.050413 -235.452408) (xy 126.073104 -235.407874) (xy 126.102481 -235.367437)
			(xy 126.137822 -235.332094) (xy 126.178257 -235.302714) (xy 126.222789 -235.280021) (xy 126.270324 -235.264574)
			(xy 126.319689 -235.256752) (xy 126.34468 -235.256324) (xy 126.361702 -235.256505) (xy 126.395557 -235.260071)
			(xy 126.412244 -235.263436) (xy 126.423928 -235.265976) (xy 126.434596 -235.263182) (xy 126.439501 -235.261904)
			(xy 126.448719 -235.257688) (xy 126.452884 -235.2548) (xy 126.514606 -235.205524) (xy 126.516638 -235.203238)
			(xy 126.519432 -235.200444) (xy 126.52463 -235.194767) (xy 126.531621 -235.181063) (xy 126.533148 -235.17352)
			(xy 126.533148 -235.173012) (xy 126.53391 -235.164884) (xy 126.53391 -234.91952) (xy 126.53137 -234.908598)
			(xy 126.52883 -234.903264) (xy 126.518744 -234.881505) (xy 126.504493 -234.835714) (xy 126.49726 -234.788304)
			(xy 126.496826 -234.764326) (xy 126.497217 -234.742076) (xy 126.503456 -234.698014) (xy 126.515773 -234.655252)
			(xy 126.524512 -234.634786) (xy 126.52883 -234.62488) (xy 126.52883 -234.574334) (xy 126.53391 -234.574334)
			(xy 126.53391 -234.354624) (xy 126.533656 -234.352084) (xy 126.533656 -234.031282) (xy 126.53391 -234.030774)
			(xy 126.53391 -233.877866) (xy 126.533656 -233.877358) (xy 126.533656 -233.556556) (xy 126.53391 -233.554016)
			(xy 126.53391 -233.299508) (xy 126.53137 -233.288586) (xy 126.52883 -233.283252) (xy 126.518745 -233.261493)
			(xy 126.504495 -233.215702) (xy 126.497265 -233.168292) (xy 126.496826 -233.144314) (xy 126.497217 -233.122064)
			(xy 126.503458 -233.078003) (xy 126.515777 -233.035242) (xy 126.524512 -233.014774) (xy 126.52883 -233.004868)
			(xy 126.52883 -232.954322) (xy 126.53391 -232.954322) (xy 126.53391 -232.743756) (xy 126.533744 -232.737746)
			(xy 126.530921 -232.726063) (xy 126.528322 -232.720642) (xy 126.526486 -232.717165) (xy 126.5219 -232.710779)
			(xy 126.519178 -232.707942) (xy 126.515114 -232.703878) (xy 126.45517 -232.655618) (xy 126.444756 -232.649268)
			(xy 126.438914 -232.646728) (xy 126.426214 -232.644188) (xy 126.413006 -232.645204) (xy 126.409704 -232.645712)
			(xy 126.408434 -232.645966) (xy 126.392667 -232.648963) (xy 126.360729 -232.652147) (xy 126.34468 -232.652316)
			(xy 126.319691 -232.651824) (xy 126.270329 -232.644003) (xy 126.222799 -232.628557) (xy 126.178269 -232.605865)
			(xy 126.137838 -232.576488) (xy 126.102499 -232.541147) (xy 126.073124 -232.500714) (xy 126.050436 -232.456183)
			(xy 126.034992 -232.408651) (xy 126.027174 -232.359289) (xy 126.027174 -232.309311) (xy 126.034992 -232.259949)
			(xy 126.050436 -232.212417) (xy 126.073124 -232.167886) (xy 126.102499 -232.127453) (xy 126.137838 -232.092112)
			(xy 126.178269 -232.062735) (xy 126.222799 -232.040043) (xy 126.270329 -232.024597) (xy 126.319691 -232.016776)
			(xy 126.34468 -232.0163) (xy 126.361702 -232.016481) (xy 126.395557 -232.020047) (xy 126.412244 -232.023412)
			(xy 126.423928 -232.025952) (xy 126.434596 -232.023158) (xy 126.439501 -232.021879) (xy 126.448717 -232.017662)
			(xy 126.452884 -232.014776) (xy 126.514606 -231.9655) (xy 126.516638 -231.963214) (xy 126.519432 -231.96042)
			(xy 126.524627 -231.954742) (xy 126.531612 -231.941037) (xy 126.533148 -231.933496) (xy 126.533148 -231.932988)
			(xy 126.53391 -231.92486) (xy 126.53391 -231.679496) (xy 126.53137 -231.668574) (xy 126.52883 -231.66324)
			(xy 126.518746 -231.641481) (xy 126.504498 -231.595689) (xy 126.497269 -231.54828) (xy 126.496826 -231.524302)
			(xy 126.497218 -231.502052) (xy 126.50346 -231.457992) (xy 126.515781 -231.415231) (xy 126.524512 -231.394762)
			(xy 126.52883 -231.384856) (xy 126.52883 -231.33431) (xy 126.53391 -231.33431) (xy 126.53391 -231.1146)
			(xy 126.533656 -231.11206) (xy 126.533656 -230.791512) (xy 126.53391 -230.791004) (xy 126.53391 -230.638096)
			(xy 126.533656 -230.637588) (xy 126.533656 -230.316532) (xy 126.53391 -230.313992) (xy 126.53391 -230.059484)
			(xy 126.53137 -230.048562) (xy 126.52883 -230.043228) (xy 126.518747 -230.021469) (xy 126.5045 -229.975677)
			(xy 126.497273 -229.928268) (xy 126.496826 -229.90429) (xy 126.497219 -229.88204) (xy 126.503463 -229.837981)
			(xy 126.515785 -229.795221) (xy 126.524512 -229.77475) (xy 126.52883 -229.764844) (xy 126.52883 -229.714298)
			(xy 126.53391 -229.714298) (xy 126.53391 -229.503986) (xy 126.533747 -229.497975) (xy 126.530931 -229.486289)
			(xy 126.528322 -229.480872) (xy 126.526483 -229.477398) (xy 126.52189 -229.471018) (xy 126.519178 -229.468172)
			(xy 126.515114 -229.464108) (xy 126.45517 -229.415848) (xy 126.444756 -229.409498) (xy 126.438914 -229.406958)
			(xy 126.426214 -229.404418) (xy 126.413006 -229.405434) (xy 126.409704 -229.405942) (xy 126.408434 -229.406196)
			(xy 126.392667 -229.409192) (xy 126.360729 -229.412376) (xy 126.34468 -229.412546) (xy 126.319689 -229.412054)
			(xy 126.270322 -229.404232) (xy 126.222787 -229.388785) (xy 126.178254 -229.366091) (xy 126.137818 -229.336711)
			(xy 126.102476 -229.301367) (xy 126.073098 -229.260929) (xy 126.050408 -229.216394) (xy 126.034963 -229.168858)
			(xy 126.027144 -229.119491) (xy 126.027144 -229.069509) (xy 126.034963 -229.020142) (xy 126.050408 -228.972606)
			(xy 126.073098 -228.928071) (xy 126.102476 -228.887633) (xy 126.137818 -228.852289) (xy 126.178254 -228.822909)
			(xy 126.222787 -228.800215) (xy 126.270322 -228.784768) (xy 126.319689 -228.776946) (xy 126.34468 -228.77653)
			(xy 126.361702 -228.776711) (xy 126.395557 -228.780277) (xy 126.412244 -228.783642) (xy 126.423928 -228.786182)
			(xy 126.434596 -228.783388) (xy 126.439501 -228.78211) (xy 126.448719 -228.777895) (xy 126.452884 -228.775006)
			(xy 126.514606 -228.72573) (xy 126.516638 -228.723444) (xy 126.519432 -228.72065) (xy 126.524631 -228.714974)
			(xy 126.531623 -228.70127) (xy 126.533148 -228.693726) (xy 126.533148 -228.693218) (xy 126.53391 -228.68509)
			(xy 126.53391 -228.511862) (xy 126.534093 -228.508037) (xy 126.535494 -228.500509) (xy 126.536704 -228.496876)
			(xy 126.536958 -228.496368) (xy 126.537212 -228.495606) (xy 126.537974 -228.493574) (xy 126.542292 -228.484938)
			(xy 126.543816 -228.478588) (xy 126.545564 -228.469251) (xy 126.542806 -228.450471) (xy 126.538482 -228.442012)
			(xy 126.536958 -228.439472) (xy 126.536704 -228.439218) (xy 126.536704 -228.438964) (xy 126.535942 -228.437694)
			(xy 126.531116 -228.42855) (xy 126.52036 -228.406303) (xy 126.505113 -228.359303) (xy 126.49734 -228.310507)
			(xy 126.496826 -228.285802) (xy 126.496826 -228.285294) (xy 126.496826 -228.282246) (xy 126.497353 -228.26004)
			(xy 126.503849 -228.216098) (xy 126.516398 -228.173489) (xy 126.534758 -228.133042) (xy 126.546356 -228.114098)
			(xy 126.561385 -228.091401) (xy 126.597907 -228.051041) (xy 126.619 -228.033834) (xy 126.623572 -228.030278)
			(xy 126.63043 -228.021896) (xy 126.632208 -228.01834) (xy 126.642876 -227.997258) (xy 126.645162 -227.992686)
			(xy 126.647956 -227.981256) (xy 126.647956 -227.980748) (xy 126.648464 -227.974652) (xy 126.648464 -227.291138)
			(xy 126.648998 -227.281299) (xy 126.656579 -227.263133) (xy 126.663196 -227.255832) (xy 126.77648 -227.142548)
			(xy 126.783442 -227.13594) (xy 126.79229 -227.118921) (xy 126.794323 -227.099848) (xy 126.792228 -227.090478)
			(xy 126.778766 -227.04171) (xy 126.778766 -227.041202) (xy 126.77013 -227.00996) (xy 126.767336 -227.002086)
			(xy 126.763696 -226.994943) (xy 126.752834 -226.983163) (xy 126.746 -226.978972) (xy 126.733808 -226.972114)
			(xy 126.727712 -226.97059) (xy 126.703101 -226.963055) (xy 126.656526 -226.941155) (xy 126.614083 -226.912044)
			(xy 126.576877 -226.876482) (xy 126.545881 -226.835396) (xy 126.521901 -226.789857) (xy 126.505562 -226.741052)
			(xy 126.497292 -226.690254) (xy 126.496826 -226.66452) (xy 126.497289 -226.639529) (xy 126.505106 -226.590161)
			(xy 126.52055 -226.542625) (xy 126.543241 -226.49809) (xy 126.57262 -226.457653) (xy 126.607964 -226.422311)
			(xy 126.648402 -226.392934) (xy 126.692938 -226.370245) (xy 126.740475 -226.354803) (xy 126.789843 -226.346988)
			(xy 126.814834 -226.346512) (xy 126.840924 -226.347039) (xy 126.892405 -226.355555) (xy 126.941808 -226.372355)
			(xy 126.987808 -226.396988) (xy 127.029174 -226.428795) (xy 127.064799 -226.466923) (xy 127.093727 -226.51035)
			(xy 127.115184 -226.557915) (xy 127.122428 -226.582986) (xy 127.122428 -226.583494) (xy 127.123444 -226.58705)
			(xy 127.128135 -226.5987) (xy 127.146527 -226.615755) (xy 127.158496 -226.619562) (xy 127.191516 -226.628452)
			(xy 127.192024 -226.628452) (xy 127.240792 -226.641914) (xy 127.250155 -226.644119) (xy 127.26927 -226.642119)
			(xy 127.286288 -226.633188) (xy 127.292862 -226.626166) (xy 127.904748 -226.01428) (xy 127.908285 -226.010311)
			(xy 127.913794 -226.00122) (xy 127.91567 -225.996246) (xy 127.917702 -225.988626) (xy 127.919226 -225.983546)
			(xy 127.918718 -225.973132) (xy 127.908439 -225.944625) (xy 127.897318 -225.885063) (xy 127.89662 -225.854768)
			(xy 127.89662 -225.854514) (xy 127.897098 -225.828723) (xy 127.905165 -225.777777) (xy 127.921103 -225.728719)
			(xy 127.944518 -225.682759) (xy 127.974835 -225.641027) (xy 128.011308 -225.604552) (xy 128.053037 -225.574232)
			(xy 128.098995 -225.550813) (xy 128.148051 -225.534871) (xy 128.198997 -225.5268) (xy 128.224788 -225.526346)
			(xy 128.255501 -225.527088) (xy 128.315843 -225.538599) (xy 128.344676 -225.549206) (xy 128.351477 -225.549836)
			(xy 128.364991 -225.547899) (xy 128.371346 -225.545396) (xy 128.375664 -225.543364) (xy 128.386586 -225.535998)
			(xy 128.392428 -225.530664) (xy 128.396492 -225.524314) (xy 128.396492 -225.52406) (xy 128.39827 -225.52152)
			(xy 128.400302 -225.51898) (xy 128.403604 -225.515424) (xy 128.489456 -225.429572) (xy 128.49631 -225.422041)
			(xy 128.503922 -225.403174) (xy 128.504188 -225.392996) (xy 128.504188 -225.392488) (xy 128.503426 -225.369374)
			(xy 128.503426 -225.368866) (xy 128.501648 -225.31959) (xy 128.500886 -225.312478) (xy 128.499322 -225.305195)
			(xy 128.4926 -225.291909) (xy 128.487678 -225.286316) (xy 128.467231 -225.267971) (xy 128.432336 -225.225551)
			(xy 128.405212 -225.177786) (xy 128.38666 -225.126085) (xy 128.377227 -225.071972) (xy 128.37668 -225.044508)
			(xy 128.37668 -225.03892) (xy 128.377555 -225.014496) (xy 128.385877 -224.966338) (xy 128.401467 -224.92002)
			(xy 128.423958 -224.876631) (xy 128.452822 -224.837194) (xy 128.487378 -224.802635) (xy 128.526814 -224.773769)
			(xy 128.570201 -224.751275) (xy 128.616518 -224.735682) (xy 128.664676 -224.727357) (xy 128.6891 -224.7265)
			(xy 128.694688 -224.7265) (xy 128.72173 -224.727093) (xy 128.775033 -224.736256) (xy 128.82603 -224.754271)
			(xy 128.873261 -224.780622) (xy 128.915375 -224.814556) (xy 128.933702 -224.83445) (xy 128.940814 -224.842324)
			(xy 128.949704 -224.846642) (xy 128.954525 -224.848758) (xy 128.964766 -224.851193) (xy 128.970024 -224.851468)
			(xy 129.0193 -224.853246) (xy 129.041398 -224.854008) (xy 129.044192 -224.854008) (xy 129.051232 -224.853788)
			(xy 129.064772 -224.849927) (xy 129.070862 -224.846388) (xy 129.075688 -224.84334) (xy 129.198116 -224.720912)
			(xy 129.200402 -224.718372) (xy 129.200402 -224.718118) (xy 129.20301 -224.71482) (xy 129.207225 -224.707545)
			(xy 129.208784 -224.70364) (xy 129.204466 -224.661984) (xy 129.202942 -224.661222) (xy 129.202942 -224.651824)
			(xy 129.18821 -224.611692) (xy 129.177288 -224.581974) (xy 129.173478 -224.574354) (xy 129.17297 -224.573846)
			(xy 129.171446 -224.571306) (xy 129.16662 -224.565972) (xy 129.161794 -224.561654) (xy 129.156206 -224.557336)
			(xy 129.142998 -224.552002) (xy 129.137156 -224.551494) (xy 129.135124 -224.55124) (xy 129.109177 -224.54825)
			(xy 129.058687 -224.534896) (xy 129.011053 -224.51348) (xy 128.967553 -224.484577) (xy 128.929354 -224.448962)
			(xy 128.89748 -224.407589) (xy 128.872786 -224.361569) (xy 128.855935 -224.312136) (xy 128.847378 -224.260615)
			(xy 128.846834 -224.234502) (xy 128.847299 -224.209512) (xy 128.855118 -224.160147) (xy 128.870564 -224.112614)
			(xy 128.893256 -224.068082) (xy 128.922635 -224.027648) (xy 128.957979 -223.992309) (xy 128.998416 -223.962935)
			(xy 129.042951 -223.940248) (xy 129.090486 -223.924808) (xy 129.139852 -223.916996) (xy 129.164842 -223.916494)
			(xy 129.189664 -223.916975) (xy 129.238704 -223.924696) (xy 129.285949 -223.939944) (xy 129.330251 -223.962348)
			(xy 129.370532 -223.991364) (xy 129.405815 -224.026288) (xy 129.435243 -224.06627) (xy 129.4581 -224.11034)
			(xy 129.473831 -224.157426) (xy 129.482054 -224.206385) (xy 129.48285 -224.2312) (xy 129.48285 -224.235772)
			(xy 129.482187 -224.262938) (xy 129.472732 -224.316447) (xy 129.464054 -224.342198) (xy 129.464054 -224.342452)
			(xy 129.462128 -224.348279) (xy 129.460852 -224.360481) (xy 129.461514 -224.366582) (xy 129.463038 -224.378266)
			(xy 129.474722 -224.394776) (xy 129.485644 -224.41027) (xy 129.485644 -224.410524) (xy 129.518664 -224.457514)
			(xy 129.524699 -224.464419) (xy 129.540451 -224.473785) (xy 129.549398 -224.475802) (xy 129.558034 -224.476564)
			(xy 129.709926 -224.476564) (xy 129.719324 -224.475548) (xy 129.719832 -224.475548) (xy 129.726989 -224.473839)
			(xy 129.740011 -224.467002) (xy 129.745486 -224.462086) (xy 129.751836 -224.455736) (xy 129.799334 -224.387918)
			(xy 129.802722 -224.382864) (xy 129.807227 -224.371567) (xy 129.808224 -224.365566) (xy 129.809748 -224.353882)
			(xy 129.805938 -224.343214) (xy 129.801517 -224.330723) (xy 129.794527 -224.305161) (xy 129.791968 -224.29216)
			(xy 129.789428 -224.276412) (xy 129.788283 -224.267499) (xy 129.786885 -224.249581) (xy 129.786634 -224.240598)
			(xy 129.786634 -224.2312) (xy 129.78739 -224.205926) (xy 129.795917 -224.15609) (xy 129.812215 -224.108229)
			(xy 129.835874 -224.063546) (xy 129.866301 -224.023165) (xy 129.902728 -223.988102) (xy 129.944241 -223.95924)
			(xy 129.989795 -223.937303) (xy 130.038244 -223.922845) (xy 130.06324 -223.919034) (xy 130.063494 -223.919034)
			(xy 130.066542 -223.91878) (xy 130.07603 -223.917707) (xy 130.095093 -223.916566) (xy 130.104642 -223.916494)
			(xy 130.10515 -223.916494) (xy 130.105658 -223.916494) (xy 130.108706 -223.916494) (xy 130.132126 -223.917213)
			(xy 130.178381 -223.924683) (xy 130.22304 -223.938857) (xy 130.265138 -223.959428) (xy 130.303763 -223.985951)
			(xy 130.338079 -224.017852) (xy 130.353054 -224.035874) (xy 130.354832 -224.03816) (xy 130.360166 -224.043494)
			(xy 130.36755 -224.05007) (xy 130.385848 -224.057509) (xy 130.395726 -224.057972) (xy 130.402076 -224.057972)
			(xy 130.425444 -224.054924) (xy 130.425952 -224.054924) (xy 130.490976 -224.04578) (xy 130.494786 -224.044764)
			(xy 130.504438 -224.0407) (xy 130.504692 -224.0407) (xy 130.511755 -224.036419) (xy 130.522893 -224.024237)
			(xy 130.526536 -224.016824) (xy 130.53695 -223.993456) (xy 130.537204 -223.992948) (xy 130.543808 -223.979486)
			(xy 130.554001 -223.959925) (xy 130.577015 -223.92229) (xy 130.589782 -223.904302) (xy 130.590798 -223.902778)
			(xy 130.596132 -223.892364) (xy 130.599942 -223.88068) (xy 130.601212 -223.87687) (xy 130.602953 -223.868944)
			(xy 130.601921 -223.852758) (xy 130.59918 -223.84512) (xy 130.595624 -223.83623) (xy 130.585464 -223.811084)
			(xy 130.582661 -223.805325) (xy 130.574693 -223.795304) (xy 130.569716 -223.791272) (xy 130.563874 -223.787208)
			(xy 130.551174 -223.782382) (xy 130.545332 -223.781874) (xy 130.543554 -223.78162) (xy 130.517081 -223.778838)
			(xy 130.465315 -223.766448) (xy 130.41595 -223.746537) (xy 130.370074 -223.719543) (xy 130.328696 -223.686061)
			(xy 130.292725 -223.646826) (xy 130.262954 -223.602702) (xy 130.240036 -223.554659) (xy 130.224478 -223.503756)
			(xy 130.216619 -223.45111) (xy 130.216148 -223.424496) (xy 130.216605 -223.398878) (xy 130.223897 -223.348163)
			(xy 130.238333 -223.299002) (xy 130.259617 -223.252396) (xy 130.287318 -223.209293) (xy 130.320871 -223.170571)
			(xy 130.359593 -223.137018) (xy 130.402696 -223.109317) (xy 130.449302 -223.088033) (xy 130.498463 -223.073597)
			(xy 130.549178 -223.066305) (xy 130.574796 -223.065848) (xy 130.674618 -223.065848) (xy 130.680629 -223.065685)
			(xy 130.692316 -223.06287) (xy 130.697732 -223.06026) (xy 130.701205 -223.058418) (xy 130.70758 -223.053821)
			(xy 130.710432 -223.051116) (xy 130.831844 -222.929704) (xy 130.838458 -222.92253) (xy 130.846157 -222.904618)
			(xy 130.846574 -222.885126) (xy 130.843528 -222.875856) (xy 130.842766 -222.874586) (xy 130.839972 -222.86849)
			(xy 130.827272 -222.849694) (xy 130.82397 -222.846138) (xy 130.810762 -222.83293) (xy 130.809746 -222.832168)
			(xy 130.809746 -222.831914) (xy 130.809492 -222.83166) (xy 130.793637 -222.813836) (xy 130.766844 -222.77437)
			(xy 130.746209 -222.731362) (xy 130.732191 -222.685767) (xy 130.7251 -222.638595) (xy 130.724656 -222.614744)
			(xy 130.724656 -222.61449) (xy 130.725027 -222.591563) (xy 130.731524 -222.546173) (xy 130.73761 -222.524066)
			(xy 130.73761 -222.523812) (xy 130.738372 -222.521272) (xy 130.738372 -222.513398) (xy 130.738103 -222.505668)
			(xy 130.733444 -222.490927) (xy 130.729228 -222.484442) (xy 130.702304 -222.449136) (xy 130.702304 -222.448628)
			(xy 130.68173 -222.422212) (xy 130.679083 -222.419118) (xy 130.672956 -222.413757) (xy 130.669538 -222.411544)
			(xy 130.664458 -222.408496) (xy 130.660915 -222.406646) (xy 130.653387 -222.403965) (xy 130.649472 -222.403162)
			(xy 130.64109 -222.4024) (xy 129.992374 -222.4024) (xy 129.982581 -222.402914) (xy 129.964498 -222.410453)
			(xy 129.950647 -222.424307) (xy 129.943112 -222.442391) (xy 129.94259 -222.452184) (xy 129.94259 -223.338644)
			(xy 129.943606 -223.347026) (xy 129.945892 -223.358456) (xy 129.945892 -223.35871) (xy 129.9464 -223.361758)
			(xy 129.948686 -223.372934) (xy 129.948686 -223.373696) (xy 129.94894 -223.37522) (xy 129.95021 -223.384364)
			(xy 129.95021 -223.384872) (xy 129.95148 -223.395286) (xy 129.95148 -223.395794) (xy 129.95275 -223.41967)
			(xy 129.95275 -223.426528) (xy 129.952098 -223.451777) (xy 129.943791 -223.501593) (xy 129.927722 -223.549474)
			(xy 129.904296 -223.594217) (xy 129.874099 -223.634699) (xy 129.837889 -223.669907) (xy 129.796574 -223.698956)
			(xy 129.751191 -223.721117) (xy 129.702879 -223.735835) (xy 129.677922 -223.73971) (xy 129.677414 -223.73971)
			(xy 129.673858 -223.740218) (xy 129.664117 -223.741319) (xy 129.644545 -223.742464) (xy 129.634742 -223.742504)
			(xy 129.609981 -223.742028) (xy 129.561059 -223.734345) (xy 129.513919 -223.719173) (xy 129.469699 -223.69688)
			(xy 129.429468 -223.668003) (xy 129.394198 -223.63324) (xy 129.364742 -223.593432) (xy 129.34181 -223.54954)
			(xy 129.325957 -223.502625) (xy 129.317565 -223.453819) (xy 129.316734 -223.429068) (xy 129.316734 -223.42348)
			(xy 129.317028 -223.405019) (xy 129.321351 -223.368349) (xy 129.32537 -223.350328) (xy 129.326894 -223.344486)
			(xy 129.326894 -222.27159) (xy 129.327278 -222.249667) (xy 129.333501 -222.206265) (xy 129.345835 -222.164189)
			(xy 129.35458 -222.144082) (xy 129.35458 -222.143828) (xy 129.358336 -222.134374) (xy 129.358826 -222.114055)
			(xy 129.351403 -222.095134) (xy 129.337227 -222.080568) (xy 129.318513 -222.072635) (xy 129.308352 -222.0722)
			(xy 129.28473 -222.0722) (xy 129.27474 -222.072732) (xy 129.2563 -222.080438) (xy 129.248916 -222.087186)
			(xy 129.069592 -222.26651) (xy 129.052151 -222.283279) (xy 129.013009 -222.311716) (xy 128.969902 -222.33368)
			(xy 128.923889 -222.348631) (xy 128.876104 -222.3562) (xy 128.851914 -222.35668) (xy 127.313182 -222.35668)
			(xy 127.303948 -222.357034) (xy 127.286721 -222.363681) (xy 127.279654 -222.369634) (xy 127.135636 -222.513652)
			(xy 127.129759 -222.520767) (xy 127.1231 -222.537962) (xy 127.122682 -222.54718) (xy 127.122682 -223.338644)
			(xy 127.123698 -223.347026) (xy 127.125984 -223.358456) (xy 127.125984 -223.35871) (xy 127.126492 -223.361758)
			(xy 127.128778 -223.372934) (xy 127.128778 -223.373696) (xy 127.129032 -223.37522) (xy 127.130302 -223.384364)
			(xy 127.130302 -223.384872) (xy 127.131572 -223.395286) (xy 127.131572 -223.395794) (xy 127.132842 -223.41967)
			(xy 127.132842 -223.426528) (xy 127.132249 -223.449485) (xy 127.437116 -223.449485) (xy 127.437116 -223.399507)
			(xy 127.444935 -223.350144) (xy 127.460379 -223.302612) (xy 127.483069 -223.25808) (xy 127.512445 -223.217647)
			(xy 127.547785 -223.182307) (xy 127.588218 -223.152931) (xy 127.63275 -223.130241) (xy 127.680282 -223.114797)
			(xy 127.729645 -223.106978) (xy 127.779623 -223.106978) (xy 127.828986 -223.114797) (xy 127.876518 -223.130241)
			(xy 127.92105 -223.152931) (xy 127.961483 -223.182307) (xy 127.996823 -223.217647) (xy 128.026199 -223.25808)
			(xy 128.048889 -223.302612) (xy 128.064333 -223.350144) (xy 128.072152 -223.399507) (xy 128.072642 -223.424496)
			(xy 128.072152 -223.449485) (xy 128.064333 -223.498848) (xy 128.048889 -223.54638) (xy 128.026199 -223.590912)
			(xy 127.996823 -223.631345) (xy 127.961483 -223.666685) (xy 127.92105 -223.696061) (xy 127.876518 -223.718751)
			(xy 127.828986 -223.734195) (xy 127.779623 -223.742014) (xy 127.729645 -223.742014) (xy 127.680282 -223.734195)
			(xy 127.63275 -223.718751) (xy 127.588218 -223.696061) (xy 127.547785 -223.666685) (xy 127.512445 -223.631345)
			(xy 127.483069 -223.590912) (xy 127.460379 -223.54638) (xy 127.444935 -223.498848) (xy 127.437116 -223.449485)
			(xy 127.132249 -223.449485) (xy 127.13219 -223.451776) (xy 127.123882 -223.501593) (xy 127.107814 -223.549473)
			(xy 127.084387 -223.594215) (xy 127.05419 -223.634697) (xy 127.01798 -223.669904) (xy 126.976665 -223.698952)
			(xy 126.931282 -223.721112) (xy 126.88297 -223.735829) (xy 126.858014 -223.73971) (xy 126.857506 -223.73971)
			(xy 126.85395 -223.740218) (xy 126.844209 -223.741319) (xy 126.824637 -223.742463) (xy 126.814834 -223.742504)
			(xy 126.790074 -223.742027) (xy 126.741153 -223.734343) (xy 126.694013 -223.719171) (xy 126.649795 -223.696877)
			(xy 126.609565 -223.668) (xy 126.574296 -223.633238) (xy 126.54484 -223.59343) (xy 126.521909 -223.549538)
			(xy 126.506056 -223.502623) (xy 126.497665 -223.453819) (xy 126.496826 -223.429068) (xy 126.496826 -223.42348)
			(xy 126.49712 -223.405019) (xy 126.501443 -223.368349) (xy 126.505462 -223.350328) (xy 126.506986 -223.344486)
			(xy 126.506986 -222.399352) (xy 126.507432 -222.375158) (xy 126.514995 -222.327365) (xy 126.529942 -222.281343)
			(xy 126.551906 -222.238227) (xy 126.580345 -222.199078) (xy 126.597156 -222.181674) (xy 126.9492 -221.82963)
			(xy 126.953264 -221.82582) (xy 126.953772 -221.825312) (xy 126.980188 -221.80296) (xy 126.981204 -221.802198)
			(xy 126.987046 -221.797626) (xy 126.993904 -221.788736) (xy 126.999492 -221.780862) (xy 127.014224 -221.711266)
			(xy 127.014224 -221.710758) (xy 127.017018 -221.698566) (xy 127.009652 -221.672658) (xy 127.006604 -221.66707)
			(xy 126.994931 -221.643969) (xy 126.978408 -221.594923) (xy 126.970038 -221.543849) (xy 126.96952 -221.517972)
			(xy 126.96952 -221.51213) (xy 126.970028 -221.50578) (xy 126.970028 -221.505272) (xy 126.971467 -221.480958)
			(xy 126.980813 -221.433158) (xy 126.997339 -221.387343) (xy 127.020657 -221.344583) (xy 127.050222 -221.305878)
			(xy 127.085343 -221.272134) (xy 127.125198 -221.24414) (xy 127.168856 -221.222549) (xy 127.215295 -221.207868)
			(xy 127.26343 -221.200439) (xy 127.287782 -221.199964) (xy 127.312773 -221.200453) (xy 127.36214 -221.208269)
			(xy 127.409676 -221.223711) (xy 127.454212 -221.246399) (xy 127.49465 -221.275775) (xy 127.529995 -221.311115)
			(xy 127.559377 -221.351549) (xy 127.582071 -221.396081) (xy 127.59752 -221.443615) (xy 127.605343 -221.492981)
			(xy 127.60579 -221.517972) (xy 127.60579 -221.51848) (xy 127.605419 -221.539501) (xy 127.599816 -221.581168)
			(xy 127.594614 -221.601538) (xy 127.592836 -221.608142) (xy 127.59182 -221.611698) (xy 127.590804 -221.617794)
			(xy 127.590804 -221.63659) (xy 127.592582 -221.644718) (xy 127.598678 -221.655386) (xy 127.599694 -221.65691)
			(xy 127.620014 -221.684088) (xy 127.623062 -221.688152) (xy 127.647192 -221.721172) (xy 127.654778 -221.730032)
			(xy 127.675677 -221.740335) (xy 127.687324 -221.740984) (xy 128.704086 -221.740984) (xy 128.713314 -221.740617)
			(xy 128.730523 -221.733949) (xy 128.737614 -221.72803) (xy 128.796542 -221.669102) (xy 128.918716 -221.546674)
			(xy 128.91897 -221.54642) (xy 128.936811 -221.529165) (xy 128.977014 -221.500063) (xy 128.99898 -221.488508)
			(xy 129.000758 -221.487746) (xy 129.003298 -221.486476) (xy 129.00406 -221.486222) (xy 129.019554 -221.474284)
			(xy 129.019808 -221.473776) (xy 129.02438 -221.46768) (xy 129.032 -221.455488) (xy 129.032 -221.440756)
			(xy 129.031746 -221.436692) (xy 129.023872 -221.413324) (xy 129.019044 -221.406337) (xy 129.005727 -221.395811)
			(xy 128.989688 -221.390255) (xy 128.9812 -221.389956) (xy 128.509268 -221.389956) (xy 128.481059 -221.389402)
			(xy 128.425299 -221.380799) (xy 128.371488 -221.363843) (xy 128.345946 -221.351856) (xy 128.338072 -221.351856)
			(xy 128.310595 -221.351558) (xy 128.25589 -221.346342) (xy 128.228852 -221.341442) (xy 128.204831 -221.33653)
			(xy 128.15765 -221.323178) (xy 128.134618 -221.314772) (xy 128.106432 -221.30367) (xy 128.052366 -221.27634)
			(xy 128.00149 -221.24345) (xy 127.954374 -221.205367) (xy 127.932688 -221.184216) (xy 127.557276 -220.80855)
			(xy 127.551111 -220.802869) (xy 127.536077 -220.795474) (xy 127.527812 -220.794072) (xy 127.521208 -220.793564)
			(xy 107.873038 -220.793564) (xy 107.863288 -220.79408) (xy 107.845259 -220.801528) (xy 107.837986 -220.808042)
			(xy 107.358942 -221.287086) (xy 107.352391 -221.294335) (xy 107.344947 -221.312378) (xy 107.344464 -221.322138)
			(xy 107.344464 -221.607888) (xy 107.346496 -221.621858) (xy 107.34802 -221.627446) (xy 107.353608 -221.6404)
			(xy 107.354624 -221.642432) (xy 107.355386 -221.643702) (xy 107.369091 -221.668259) (xy 107.388564 -221.721012)
			(xy 107.398456 -221.776368) (xy 107.399074 -221.804484) (xy 107.399074 -221.810072) (xy 107.398803 -221.821169)
			(xy 107.398088 -221.829473) (xy 114.277122 -221.829473) (xy 114.277122 -221.779495) (xy 114.284941 -221.730132)
			(xy 114.300385 -221.6826) (xy 114.323075 -221.638068) (xy 114.352451 -221.597635) (xy 114.387791 -221.562295)
			(xy 114.428224 -221.532919) (xy 114.472756 -221.510229) (xy 114.520288 -221.494785) (xy 114.569651 -221.486966)
			(xy 114.619629 -221.486966) (xy 114.668992 -221.494785) (xy 114.716524 -221.510229) (xy 114.761056 -221.532919)
			(xy 114.801489 -221.562295) (xy 114.836829 -221.597635) (xy 114.866205 -221.638068) (xy 114.888895 -221.6826)
			(xy 114.904339 -221.730132) (xy 114.912158 -221.779495) (xy 114.912648 -221.804484) (xy 114.912158 -221.829473)
			(xy 115.217176 -221.829473) (xy 115.217176 -221.779495) (xy 115.224995 -221.730132) (xy 115.240439 -221.6826)
			(xy 115.263129 -221.638068) (xy 115.292505 -221.597635) (xy 115.327845 -221.562295) (xy 115.368278 -221.532919)
			(xy 115.41281 -221.510229) (xy 115.460342 -221.494785) (xy 115.509705 -221.486966) (xy 115.559683 -221.486966)
			(xy 115.609046 -221.494785) (xy 115.656578 -221.510229) (xy 115.70111 -221.532919) (xy 115.741543 -221.562295)
			(xy 115.776883 -221.597635) (xy 115.806259 -221.638068) (xy 115.828949 -221.6826) (xy 115.844393 -221.730132)
			(xy 115.852212 -221.779495) (xy 115.852702 -221.804484) (xy 115.852212 -221.829473) (xy 116.15723 -221.829473)
			(xy 116.15723 -221.779495) (xy 116.165049 -221.730132) (xy 116.180493 -221.6826) (xy 116.203183 -221.638068)
			(xy 116.232559 -221.597635) (xy 116.267899 -221.562295) (xy 116.308332 -221.532919) (xy 116.352864 -221.510229)
			(xy 116.400396 -221.494785) (xy 116.449759 -221.486966) (xy 116.499737 -221.486966) (xy 116.5491 -221.494785)
			(xy 116.596632 -221.510229) (xy 116.641164 -221.532919) (xy 116.681597 -221.562295) (xy 116.716937 -221.597635)
			(xy 116.746313 -221.638068) (xy 116.769003 -221.6826) (xy 116.784447 -221.730132) (xy 116.792266 -221.779495)
			(xy 116.792756 -221.804484) (xy 116.792266 -221.829473) (xy 117.097284 -221.829473) (xy 117.097284 -221.779495)
			(xy 117.105103 -221.730132) (xy 117.120547 -221.6826) (xy 117.143237 -221.638068) (xy 117.172613 -221.597635)
			(xy 117.207953 -221.562295) (xy 117.248386 -221.532919) (xy 117.292918 -221.510229) (xy 117.34045 -221.494785)
			(xy 117.389813 -221.486966) (xy 117.439791 -221.486966) (xy 117.489154 -221.494785) (xy 117.536686 -221.510229)
			(xy 117.581218 -221.532919) (xy 117.621651 -221.562295) (xy 117.656991 -221.597635) (xy 117.686367 -221.638068)
			(xy 117.709057 -221.6826) (xy 117.724501 -221.730132) (xy 117.73232 -221.779495) (xy 117.73281 -221.804484)
			(xy 117.73232 -221.829473) (xy 118.037338 -221.829473) (xy 118.037338 -221.779495) (xy 118.045157 -221.730132)
			(xy 118.060601 -221.6826) (xy 118.083291 -221.638068) (xy 118.112667 -221.597635) (xy 118.148007 -221.562295)
			(xy 118.18844 -221.532919) (xy 118.232972 -221.510229) (xy 118.280504 -221.494785) (xy 118.329867 -221.486966)
			(xy 118.379845 -221.486966) (xy 118.429208 -221.494785) (xy 118.47674 -221.510229) (xy 118.521272 -221.532919)
			(xy 118.561705 -221.562295) (xy 118.597045 -221.597635) (xy 118.626421 -221.638068) (xy 118.649111 -221.6826)
			(xy 118.664555 -221.730132) (xy 118.672374 -221.779495) (xy 118.672864 -221.804484) (xy 118.672374 -221.829473)
			(xy 119.917192 -221.829473) (xy 119.917192 -221.779495) (xy 119.925011 -221.730132) (xy 119.940455 -221.6826)
			(xy 119.963145 -221.638068) (xy 119.992521 -221.597635) (xy 120.027861 -221.562295) (xy 120.068294 -221.532919)
			(xy 120.112826 -221.510229) (xy 120.160358 -221.494785) (xy 120.209721 -221.486966) (xy 120.259699 -221.486966)
			(xy 120.309062 -221.494785) (xy 120.356594 -221.510229) (xy 120.401126 -221.532919) (xy 120.441559 -221.562295)
			(xy 120.476899 -221.597635) (xy 120.506275 -221.638068) (xy 120.528965 -221.6826) (xy 120.544409 -221.730132)
			(xy 120.552228 -221.779495) (xy 120.552718 -221.804484) (xy 120.552228 -221.829473) (xy 120.857246 -221.829473)
			(xy 120.857246 -221.779495) (xy 120.865065 -221.730132) (xy 120.880509 -221.6826) (xy 120.903199 -221.638068)
			(xy 120.932575 -221.597635) (xy 120.967915 -221.562295) (xy 121.008348 -221.532919) (xy 121.05288 -221.510229)
			(xy 121.100412 -221.494785) (xy 121.149775 -221.486966) (xy 121.199753 -221.486966) (xy 121.249116 -221.494785)
			(xy 121.296648 -221.510229) (xy 121.34118 -221.532919) (xy 121.381613 -221.562295) (xy 121.416953 -221.597635)
			(xy 121.446329 -221.638068) (xy 121.469019 -221.6826) (xy 121.484463 -221.730132) (xy 121.492282 -221.779495)
			(xy 121.492772 -221.804484) (xy 121.492282 -221.829473) (xy 121.7973 -221.829473) (xy 121.7973 -221.779495)
			(xy 121.805119 -221.730132) (xy 121.820563 -221.6826) (xy 121.843253 -221.638068) (xy 121.872629 -221.597635)
			(xy 121.907969 -221.562295) (xy 121.948402 -221.532919) (xy 121.992934 -221.510229) (xy 122.040466 -221.494785)
			(xy 122.089829 -221.486966) (xy 122.139807 -221.486966) (xy 122.18917 -221.494785) (xy 122.236702 -221.510229)
			(xy 122.281234 -221.532919) (xy 122.321667 -221.562295) (xy 122.357007 -221.597635) (xy 122.386383 -221.638068)
			(xy 122.409073 -221.6826) (xy 122.424517 -221.730132) (xy 122.432336 -221.779495) (xy 122.432826 -221.804484)
			(xy 122.432336 -221.829473) (xy 122.7371 -221.829473) (xy 122.7371 -221.779495) (xy 122.744919 -221.730132)
			(xy 122.760363 -221.6826) (xy 122.783053 -221.638068) (xy 122.812429 -221.597635) (xy 122.847769 -221.562295)
			(xy 122.888202 -221.532919) (xy 122.932734 -221.510229) (xy 122.980266 -221.494785) (xy 123.029629 -221.486966)
			(xy 123.079607 -221.486966) (xy 123.12897 -221.494785) (xy 123.176502 -221.510229) (xy 123.221034 -221.532919)
			(xy 123.261467 -221.562295) (xy 123.296807 -221.597635) (xy 123.326183 -221.638068) (xy 123.348873 -221.6826)
			(xy 123.364317 -221.730132) (xy 123.372136 -221.779495) (xy 123.372626 -221.804484) (xy 123.372136 -221.829473)
			(xy 123.677154 -221.829473) (xy 123.677154 -221.779495) (xy 123.684973 -221.730132) (xy 123.700417 -221.6826)
			(xy 123.723107 -221.638068) (xy 123.752483 -221.597635) (xy 123.787823 -221.562295) (xy 123.828256 -221.532919)
			(xy 123.872788 -221.510229) (xy 123.92032 -221.494785) (xy 123.969683 -221.486966) (xy 124.019661 -221.486966)
			(xy 124.069024 -221.494785) (xy 124.116556 -221.510229) (xy 124.161088 -221.532919) (xy 124.201521 -221.562295)
			(xy 124.236861 -221.597635) (xy 124.266237 -221.638068) (xy 124.288927 -221.6826) (xy 124.304371 -221.730132)
			(xy 124.31219 -221.779495) (xy 124.31268 -221.804484) (xy 124.31219 -221.829473) (xy 124.304371 -221.878836)
			(xy 124.288927 -221.926368) (xy 124.266237 -221.9709) (xy 124.236861 -222.011333) (xy 124.201521 -222.046673)
			(xy 124.161088 -222.076049) (xy 124.116556 -222.098739) (xy 124.069024 -222.114183) (xy 124.019661 -222.122002)
			(xy 123.969683 -222.122002) (xy 123.92032 -222.114183) (xy 123.872788 -222.098739) (xy 123.828256 -222.076049)
			(xy 123.787823 -222.046673) (xy 123.752483 -222.011333) (xy 123.723107 -221.9709) (xy 123.700417 -221.926368)
			(xy 123.684973 -221.878836) (xy 123.677154 -221.829473) (xy 123.372136 -221.829473) (xy 123.364317 -221.878836)
			(xy 123.348873 -221.926368) (xy 123.326183 -221.9709) (xy 123.296807 -222.011333) (xy 123.261467 -222.046673)
			(xy 123.221034 -222.076049) (xy 123.176502 -222.098739) (xy 123.12897 -222.114183) (xy 123.079607 -222.122002)
			(xy 123.029629 -222.122002) (xy 122.980266 -222.114183) (xy 122.932734 -222.098739) (xy 122.888202 -222.076049)
			(xy 122.847769 -222.046673) (xy 122.812429 -222.011333) (xy 122.783053 -221.9709) (xy 122.760363 -221.926368)
			(xy 122.744919 -221.878836) (xy 122.7371 -221.829473) (xy 122.432336 -221.829473) (xy 122.424517 -221.878836)
			(xy 122.409073 -221.926368) (xy 122.386383 -221.9709) (xy 122.357007 -222.011333) (xy 122.321667 -222.046673)
			(xy 122.281234 -222.076049) (xy 122.236702 -222.098739) (xy 122.18917 -222.114183) (xy 122.139807 -222.122002)
			(xy 122.089829 -222.122002) (xy 122.040466 -222.114183) (xy 121.992934 -222.098739) (xy 121.948402 -222.076049)
			(xy 121.907969 -222.046673) (xy 121.872629 -222.011333) (xy 121.843253 -221.9709) (xy 121.820563 -221.926368)
			(xy 121.805119 -221.878836) (xy 121.7973 -221.829473) (xy 121.492282 -221.829473) (xy 121.484463 -221.878836)
			(xy 121.469019 -221.926368) (xy 121.446329 -221.9709) (xy 121.416953 -222.011333) (xy 121.381613 -222.046673)
			(xy 121.34118 -222.076049) (xy 121.296648 -222.098739) (xy 121.249116 -222.114183) (xy 121.199753 -222.122002)
			(xy 121.149775 -222.122002) (xy 121.100412 -222.114183) (xy 121.05288 -222.098739) (xy 121.008348 -222.076049)
			(xy 120.967915 -222.046673) (xy 120.932575 -222.011333) (xy 120.903199 -221.9709) (xy 120.880509 -221.926368)
			(xy 120.865065 -221.878836) (xy 120.857246 -221.829473) (xy 120.552228 -221.829473) (xy 120.544409 -221.878836)
			(xy 120.528965 -221.926368) (xy 120.506275 -221.9709) (xy 120.476899 -222.011333) (xy 120.441559 -222.046673)
			(xy 120.401126 -222.076049) (xy 120.356594 -222.098739) (xy 120.309062 -222.114183) (xy 120.259699 -222.122002)
			(xy 120.209721 -222.122002) (xy 120.160358 -222.114183) (xy 120.112826 -222.098739) (xy 120.068294 -222.076049)
			(xy 120.027861 -222.046673) (xy 119.992521 -222.011333) (xy 119.963145 -221.9709) (xy 119.940455 -221.926368)
			(xy 119.925011 -221.878836) (xy 119.917192 -221.829473) (xy 118.672374 -221.829473) (xy 118.664555 -221.878836)
			(xy 118.649111 -221.926368) (xy 118.626421 -221.9709) (xy 118.597045 -222.011333) (xy 118.561705 -222.046673)
			(xy 118.521272 -222.076049) (xy 118.47674 -222.098739) (xy 118.429208 -222.114183) (xy 118.379845 -222.122002)
			(xy 118.329867 -222.122002) (xy 118.280504 -222.114183) (xy 118.232972 -222.098739) (xy 118.18844 -222.076049)
			(xy 118.148007 -222.046673) (xy 118.112667 -222.011333) (xy 118.083291 -221.9709) (xy 118.060601 -221.926368)
			(xy 118.045157 -221.878836) (xy 118.037338 -221.829473) (xy 117.73232 -221.829473) (xy 117.724501 -221.878836)
			(xy 117.709057 -221.926368) (xy 117.686367 -221.9709) (xy 117.656991 -222.011333) (xy 117.621651 -222.046673)
			(xy 117.581218 -222.076049) (xy 117.536686 -222.098739) (xy 117.489154 -222.114183) (xy 117.439791 -222.122002)
			(xy 117.389813 -222.122002) (xy 117.34045 -222.114183) (xy 117.292918 -222.098739) (xy 117.248386 -222.076049)
			(xy 117.207953 -222.046673) (xy 117.172613 -222.011333) (xy 117.143237 -221.9709) (xy 117.120547 -221.926368)
			(xy 117.105103 -221.878836) (xy 117.097284 -221.829473) (xy 116.792266 -221.829473) (xy 116.784447 -221.878836)
			(xy 116.769003 -221.926368) (xy 116.746313 -221.9709) (xy 116.716937 -222.011333) (xy 116.681597 -222.046673)
			(xy 116.641164 -222.076049) (xy 116.596632 -222.098739) (xy 116.5491 -222.114183) (xy 116.499737 -222.122002)
			(xy 116.449759 -222.122002) (xy 116.400396 -222.114183) (xy 116.352864 -222.098739) (xy 116.308332 -222.076049)
			(xy 116.267899 -222.046673) (xy 116.232559 -222.011333) (xy 116.203183 -221.9709) (xy 116.180493 -221.926368)
			(xy 116.165049 -221.878836) (xy 116.15723 -221.829473) (xy 115.852212 -221.829473) (xy 115.844393 -221.878836)
			(xy 115.828949 -221.926368) (xy 115.806259 -221.9709) (xy 115.776883 -222.011333) (xy 115.741543 -222.046673)
			(xy 115.70111 -222.076049) (xy 115.656578 -222.098739) (xy 115.609046 -222.114183) (xy 115.559683 -222.122002)
			(xy 115.509705 -222.122002) (xy 115.460342 -222.114183) (xy 115.41281 -222.098739) (xy 115.368278 -222.076049)
			(xy 115.327845 -222.046673) (xy 115.292505 -222.011333) (xy 115.263129 -221.9709) (xy 115.240439 -221.926368)
			(xy 115.224995 -221.878836) (xy 115.217176 -221.829473) (xy 114.912158 -221.829473) (xy 114.904339 -221.878836)
			(xy 114.888895 -221.926368) (xy 114.866205 -221.9709) (xy 114.836829 -222.011333) (xy 114.801489 -222.046673)
			(xy 114.761056 -222.076049) (xy 114.716524 -222.098739) (xy 114.668992 -222.114183) (xy 114.619629 -222.122002)
			(xy 114.569651 -222.122002) (xy 114.520288 -222.114183) (xy 114.472756 -222.098739) (xy 114.428224 -222.076049)
			(xy 114.387791 -222.046673) (xy 114.352451 -222.011333) (xy 114.323075 -221.9709) (xy 114.300385 -221.926368)
			(xy 114.284941 -221.878836) (xy 114.277122 -221.829473) (xy 107.398088 -221.829473) (xy 107.396898 -221.843288)
			(xy 107.395264 -221.854268) (xy 107.394756 -221.8563) (xy 107.394248 -221.859094) (xy 107.394248 -221.859856)
			(xy 107.391962 -221.871286) (xy 107.391962 -221.872302) (xy 107.389168 -221.883224) (xy 107.384342 -221.899988)
			(xy 107.37888 -221.916705) (xy 107.364752 -221.948912) (xy 107.356148 -221.96425) (xy 107.35437 -221.967298)
			(xy 107.354116 -221.967806) (xy 107.353608 -221.968568) (xy 107.34802 -221.980506) (xy 107.347004 -221.985078)
			(xy 107.344464 -221.994476) (xy 107.344464 -222.639479) (xy 110.05361 -222.639479) (xy 110.05361 -222.589501)
			(xy 110.061429 -222.540138) (xy 110.076873 -222.492606) (xy 110.099563 -222.448074) (xy 110.128939 -222.407641)
			(xy 110.164279 -222.372301) (xy 110.204712 -222.342925) (xy 110.249244 -222.320235) (xy 110.296776 -222.304791)
			(xy 110.346139 -222.296972) (xy 110.396117 -222.296972) (xy 110.44548 -222.304791) (xy 110.493012 -222.320235)
			(xy 110.537544 -222.342925) (xy 110.577977 -222.372301) (xy 110.613317 -222.407641) (xy 110.642693 -222.448074)
			(xy 110.665383 -222.492606) (xy 110.680827 -222.540138) (xy 110.688646 -222.589501) (xy 110.689136 -222.61449)
			(xy 110.688646 -222.639479) (xy 112.867168 -222.639479) (xy 112.867168 -222.589501) (xy 112.874987 -222.540138)
			(xy 112.890431 -222.492606) (xy 112.913121 -222.448074) (xy 112.942497 -222.407641) (xy 112.977837 -222.372301)
			(xy 113.01827 -222.342925) (xy 113.062802 -222.320235) (xy 113.110334 -222.304791) (xy 113.159697 -222.296972)
			(xy 113.209675 -222.296972) (xy 113.259038 -222.304791) (xy 113.30657 -222.320235) (xy 113.351102 -222.342925)
			(xy 113.391535 -222.372301) (xy 113.426875 -222.407641) (xy 113.456251 -222.448074) (xy 113.478941 -222.492606)
			(xy 113.494385 -222.540138) (xy 113.502204 -222.589501) (xy 113.502694 -222.61449) (xy 113.502204 -222.639479)
			(xy 113.807222 -222.639479) (xy 113.807222 -222.589501) (xy 113.815041 -222.540138) (xy 113.830485 -222.492606)
			(xy 113.853175 -222.448074) (xy 113.882551 -222.407641) (xy 113.917891 -222.372301) (xy 113.958324 -222.342925)
			(xy 114.002856 -222.320235) (xy 114.050388 -222.304791) (xy 114.099751 -222.296972) (xy 114.149729 -222.296972)
			(xy 114.199092 -222.304791) (xy 114.246624 -222.320235) (xy 114.291156 -222.342925) (xy 114.331589 -222.372301)
			(xy 114.366929 -222.407641) (xy 114.396305 -222.448074) (xy 114.418995 -222.492606) (xy 114.434439 -222.540138)
			(xy 114.442258 -222.589501) (xy 114.442748 -222.61449) (xy 114.442258 -222.639479) (xy 116.62713 -222.639479)
			(xy 116.62713 -222.589501) (xy 116.634949 -222.540138) (xy 116.650393 -222.492606) (xy 116.673083 -222.448074)
			(xy 116.702459 -222.407641) (xy 116.737799 -222.372301) (xy 116.778232 -222.342925) (xy 116.822764 -222.320235)
			(xy 116.870296 -222.304791) (xy 116.919659 -222.296972) (xy 116.969637 -222.296972) (xy 117.019 -222.304791)
			(xy 117.066532 -222.320235) (xy 117.111064 -222.342925) (xy 117.151497 -222.372301) (xy 117.186837 -222.407641)
			(xy 117.216213 -222.448074) (xy 117.238903 -222.492606) (xy 117.254347 -222.540138) (xy 117.262166 -222.589501)
			(xy 117.262656 -222.61449) (xy 117.262166 -222.639479) (xy 119.447292 -222.639479) (xy 119.447292 -222.589501)
			(xy 119.455111 -222.540138) (xy 119.470555 -222.492606) (xy 119.493245 -222.448074) (xy 119.522621 -222.407641)
			(xy 119.557961 -222.372301) (xy 119.598394 -222.342925) (xy 119.642926 -222.320235) (xy 119.690458 -222.304791)
			(xy 119.739821 -222.296972) (xy 119.789799 -222.296972) (xy 119.839162 -222.304791) (xy 119.886694 -222.320235)
			(xy 119.931226 -222.342925) (xy 119.971659 -222.372301) (xy 120.006999 -222.407641) (xy 120.036375 -222.448074)
			(xy 120.059065 -222.492606) (xy 120.074509 -222.540138) (xy 120.082328 -222.589501) (xy 120.082818 -222.61449)
			(xy 120.082328 -222.639479) (xy 122.2672 -222.639479) (xy 122.2672 -222.589501) (xy 122.275019 -222.540138)
			(xy 122.290463 -222.492606) (xy 122.313153 -222.448074) (xy 122.342529 -222.407641) (xy 122.377869 -222.372301)
			(xy 122.418302 -222.342925) (xy 122.462834 -222.320235) (xy 122.510366 -222.304791) (xy 122.559729 -222.296972)
			(xy 122.609707 -222.296972) (xy 122.65907 -222.304791) (xy 122.706602 -222.320235) (xy 122.751134 -222.342925)
			(xy 122.791567 -222.372301) (xy 122.826907 -222.407641) (xy 122.856283 -222.448074) (xy 122.878973 -222.492606)
			(xy 122.894417 -222.540138) (xy 122.902236 -222.589501) (xy 122.902726 -222.61449) (xy 122.902236 -222.639479)
			(xy 125.087108 -222.639479) (xy 125.087108 -222.589501) (xy 125.094927 -222.540138) (xy 125.110371 -222.492606)
			(xy 125.133061 -222.448074) (xy 125.162437 -222.407641) (xy 125.197777 -222.372301) (xy 125.23821 -222.342925)
			(xy 125.282742 -222.320235) (xy 125.330274 -222.304791) (xy 125.379637 -222.296972) (xy 125.429615 -222.296972)
			(xy 125.478978 -222.304791) (xy 125.52651 -222.320235) (xy 125.571042 -222.342925) (xy 125.611475 -222.372301)
			(xy 125.646815 -222.407641) (xy 125.676191 -222.448074) (xy 125.698881 -222.492606) (xy 125.714325 -222.540138)
			(xy 125.722144 -222.589501) (xy 125.722634 -222.61449) (xy 125.722144 -222.639479) (xy 125.714325 -222.688842)
			(xy 125.698881 -222.736374) (xy 125.676191 -222.780906) (xy 125.646815 -222.821339) (xy 125.611475 -222.856679)
			(xy 125.571042 -222.886055) (xy 125.52651 -222.908745) (xy 125.478978 -222.924189) (xy 125.429615 -222.932008)
			(xy 125.379637 -222.932008) (xy 125.330274 -222.924189) (xy 125.282742 -222.908745) (xy 125.23821 -222.886055)
			(xy 125.197777 -222.856679) (xy 125.162437 -222.821339) (xy 125.133061 -222.780906) (xy 125.110371 -222.736374)
			(xy 125.094927 -222.688842) (xy 125.087108 -222.639479) (xy 122.902236 -222.639479) (xy 122.894417 -222.688842)
			(xy 122.878973 -222.736374) (xy 122.856283 -222.780906) (xy 122.826907 -222.821339) (xy 122.791567 -222.856679)
			(xy 122.751134 -222.886055) (xy 122.706602 -222.908745) (xy 122.65907 -222.924189) (xy 122.609707 -222.932008)
			(xy 122.559729 -222.932008) (xy 122.510366 -222.924189) (xy 122.462834 -222.908745) (xy 122.418302 -222.886055)
			(xy 122.377869 -222.856679) (xy 122.342529 -222.821339) (xy 122.313153 -222.780906) (xy 122.290463 -222.736374)
			(xy 122.275019 -222.688842) (xy 122.2672 -222.639479) (xy 120.082328 -222.639479) (xy 120.074509 -222.688842)
			(xy 120.059065 -222.736374) (xy 120.036375 -222.780906) (xy 120.006999 -222.821339) (xy 119.971659 -222.856679)
			(xy 119.931226 -222.886055) (xy 119.886694 -222.908745) (xy 119.839162 -222.924189) (xy 119.789799 -222.932008)
			(xy 119.739821 -222.932008) (xy 119.690458 -222.924189) (xy 119.642926 -222.908745) (xy 119.598394 -222.886055)
			(xy 119.557961 -222.856679) (xy 119.522621 -222.821339) (xy 119.493245 -222.780906) (xy 119.470555 -222.736374)
			(xy 119.455111 -222.688842) (xy 119.447292 -222.639479) (xy 117.262166 -222.639479) (xy 117.254347 -222.688842)
			(xy 117.238903 -222.736374) (xy 117.216213 -222.780906) (xy 117.186837 -222.821339) (xy 117.151497 -222.856679)
			(xy 117.111064 -222.886055) (xy 117.066532 -222.908745) (xy 117.019 -222.924189) (xy 116.969637 -222.932008)
			(xy 116.919659 -222.932008) (xy 116.870296 -222.924189) (xy 116.822764 -222.908745) (xy 116.778232 -222.886055)
			(xy 116.737799 -222.856679) (xy 116.702459 -222.821339) (xy 116.673083 -222.780906) (xy 116.650393 -222.736374)
			(xy 116.634949 -222.688842) (xy 116.62713 -222.639479) (xy 114.442258 -222.639479) (xy 114.434439 -222.688842)
			(xy 114.418995 -222.736374) (xy 114.396305 -222.780906) (xy 114.366929 -222.821339) (xy 114.331589 -222.856679)
			(xy 114.291156 -222.886055) (xy 114.246624 -222.908745) (xy 114.199092 -222.924189) (xy 114.149729 -222.932008)
			(xy 114.099751 -222.932008) (xy 114.050388 -222.924189) (xy 114.002856 -222.908745) (xy 113.958324 -222.886055)
			(xy 113.917891 -222.856679) (xy 113.882551 -222.821339) (xy 113.853175 -222.780906) (xy 113.830485 -222.736374)
			(xy 113.815041 -222.688842) (xy 113.807222 -222.639479) (xy 113.502204 -222.639479) (xy 113.494385 -222.688842)
			(xy 113.478941 -222.736374) (xy 113.456251 -222.780906) (xy 113.426875 -222.821339) (xy 113.391535 -222.856679)
			(xy 113.351102 -222.886055) (xy 113.30657 -222.908745) (xy 113.259038 -222.924189) (xy 113.209675 -222.932008)
			(xy 113.159697 -222.932008) (xy 113.110334 -222.924189) (xy 113.062802 -222.908745) (xy 113.01827 -222.886055)
			(xy 112.977837 -222.856679) (xy 112.942497 -222.821339) (xy 112.913121 -222.780906) (xy 112.890431 -222.736374)
			(xy 112.874987 -222.688842) (xy 112.867168 -222.639479) (xy 110.688646 -222.639479) (xy 110.680827 -222.688842)
			(xy 110.665383 -222.736374) (xy 110.642693 -222.780906) (xy 110.613317 -222.821339) (xy 110.577977 -222.856679)
			(xy 110.537544 -222.886055) (xy 110.493012 -222.908745) (xy 110.44548 -222.924189) (xy 110.396117 -222.932008)
			(xy 110.346139 -222.932008) (xy 110.296776 -222.924189) (xy 110.249244 -222.908745) (xy 110.204712 -222.886055)
			(xy 110.164279 -222.856679) (xy 110.128939 -222.821339) (xy 110.099563 -222.780906) (xy 110.076873 -222.736374)
			(xy 110.061429 -222.688842) (xy 110.05361 -222.639479) (xy 107.344464 -222.639479) (xy 107.344464 -223.2279)
			(xy 107.346496 -223.24187) (xy 107.34802 -223.247458) (xy 107.353608 -223.260158) (xy 107.355132 -223.262952)
			(xy 107.368919 -223.287575) (xy 107.388517 -223.340488) (xy 107.398477 -223.396029) (xy 107.399074 -223.424242)
			(xy 107.399074 -223.42475) (xy 107.398542 -223.449485) (xy 109.583456 -223.449485) (xy 109.583456 -223.399507)
			(xy 109.591275 -223.350144) (xy 109.606719 -223.302612) (xy 109.629409 -223.25808) (xy 109.658785 -223.217647)
			(xy 109.694125 -223.182307) (xy 109.734558 -223.152931) (xy 109.77909 -223.130241) (xy 109.826622 -223.114797)
			(xy 109.875985 -223.106978) (xy 109.925963 -223.106978) (xy 109.975326 -223.114797) (xy 110.022858 -223.130241)
			(xy 110.06739 -223.152931) (xy 110.107823 -223.182307) (xy 110.143163 -223.217647) (xy 110.172539 -223.25808)
			(xy 110.195229 -223.302612) (xy 110.210673 -223.350144) (xy 110.218492 -223.399507) (xy 110.218982 -223.424496)
			(xy 110.218492 -223.449485) (xy 113.337322 -223.449485) (xy 113.337322 -223.399507) (xy 113.345141 -223.350144)
			(xy 113.360585 -223.302612) (xy 113.383275 -223.25808) (xy 113.412651 -223.217647) (xy 113.447991 -223.182307)
			(xy 113.488424 -223.152931) (xy 113.532956 -223.130241) (xy 113.580488 -223.114797) (xy 113.629851 -223.106978)
			(xy 113.679829 -223.106978) (xy 113.729192 -223.114797) (xy 113.776724 -223.130241) (xy 113.821256 -223.152931)
			(xy 113.861689 -223.182307) (xy 113.897029 -223.217647) (xy 113.926405 -223.25808) (xy 113.949095 -223.302612)
			(xy 113.964539 -223.350144) (xy 113.972358 -223.399507) (xy 113.972848 -223.424496) (xy 113.972358 -223.449485)
			(xy 114.277122 -223.449485) (xy 114.277122 -223.399507) (xy 114.284941 -223.350144) (xy 114.300385 -223.302612)
			(xy 114.323075 -223.25808) (xy 114.352451 -223.217647) (xy 114.387791 -223.182307) (xy 114.428224 -223.152931)
			(xy 114.472756 -223.130241) (xy 114.520288 -223.114797) (xy 114.569651 -223.106978) (xy 114.619629 -223.106978)
			(xy 114.668992 -223.114797) (xy 114.716524 -223.130241) (xy 114.761056 -223.152931) (xy 114.801489 -223.182307)
			(xy 114.836829 -223.217647) (xy 114.866205 -223.25808) (xy 114.888895 -223.302612) (xy 114.904339 -223.350144)
			(xy 114.912158 -223.399507) (xy 114.912648 -223.424496) (xy 114.912158 -223.449485) (xy 115.217176 -223.449485)
			(xy 115.217176 -223.399507) (xy 115.224995 -223.350144) (xy 115.240439 -223.302612) (xy 115.263129 -223.25808)
			(xy 115.292505 -223.217647) (xy 115.327845 -223.182307) (xy 115.368278 -223.152931) (xy 115.41281 -223.130241)
			(xy 115.460342 -223.114797) (xy 115.509705 -223.106978) (xy 115.559683 -223.106978) (xy 115.609046 -223.114797)
			(xy 115.656578 -223.130241) (xy 115.70111 -223.152931) (xy 115.741543 -223.182307) (xy 115.776883 -223.217647)
			(xy 115.806259 -223.25808) (xy 115.828949 -223.302612) (xy 115.844393 -223.350144) (xy 115.852212 -223.399507)
			(xy 115.852702 -223.424496) (xy 115.852212 -223.449485) (xy 116.15723 -223.449485) (xy 116.15723 -223.399507)
			(xy 116.165049 -223.350144) (xy 116.180493 -223.302612) (xy 116.203183 -223.25808) (xy 116.232559 -223.217647)
			(xy 116.267899 -223.182307) (xy 116.308332 -223.152931) (xy 116.352864 -223.130241) (xy 116.400396 -223.114797)
			(xy 116.449759 -223.106978) (xy 116.499737 -223.106978) (xy 116.5491 -223.114797) (xy 116.596632 -223.130241)
			(xy 116.641164 -223.152931) (xy 116.681597 -223.182307) (xy 116.716937 -223.217647) (xy 116.746313 -223.25808)
			(xy 116.769003 -223.302612) (xy 116.784447 -223.350144) (xy 116.792266 -223.399507) (xy 116.792756 -223.424496)
			(xy 116.792266 -223.449485) (xy 117.097284 -223.449485) (xy 117.097284 -223.399507) (xy 117.105103 -223.350144)
			(xy 117.120547 -223.302612) (xy 117.143237 -223.25808) (xy 117.172613 -223.217647) (xy 117.207953 -223.182307)
			(xy 117.248386 -223.152931) (xy 117.292918 -223.130241) (xy 117.34045 -223.114797) (xy 117.389813 -223.106978)
			(xy 117.439791 -223.106978) (xy 117.489154 -223.114797) (xy 117.536686 -223.130241) (xy 117.581218 -223.152931)
			(xy 117.621651 -223.182307) (xy 117.656991 -223.217647) (xy 117.686367 -223.25808) (xy 117.709057 -223.302612)
			(xy 117.724501 -223.350144) (xy 117.73232 -223.399507) (xy 117.73281 -223.424496) (xy 117.73232 -223.449485)
			(xy 118.037338 -223.449485) (xy 118.037338 -223.399507) (xy 118.045157 -223.350144) (xy 118.060601 -223.302612)
			(xy 118.083291 -223.25808) (xy 118.112667 -223.217647) (xy 118.148007 -223.182307) (xy 118.18844 -223.152931)
			(xy 118.232972 -223.130241) (xy 118.280504 -223.114797) (xy 118.329867 -223.106978) (xy 118.379845 -223.106978)
			(xy 118.429208 -223.114797) (xy 118.47674 -223.130241) (xy 118.521272 -223.152931) (xy 118.561705 -223.182307)
			(xy 118.597045 -223.217647) (xy 118.626421 -223.25808) (xy 118.649111 -223.302612) (xy 118.664555 -223.350144)
			(xy 118.672374 -223.399507) (xy 118.672864 -223.424496) (xy 118.672374 -223.449485) (xy 118.977138 -223.449485)
			(xy 118.977138 -223.399507) (xy 118.984957 -223.350144) (xy 119.000401 -223.302612) (xy 119.023091 -223.25808)
			(xy 119.052467 -223.217647) (xy 119.087807 -223.182307) (xy 119.12824 -223.152931) (xy 119.172772 -223.130241)
			(xy 119.220304 -223.114797) (xy 119.269667 -223.106978) (xy 119.319645 -223.106978) (xy 119.369008 -223.114797)
			(xy 119.41654 -223.130241) (xy 119.461072 -223.152931) (xy 119.501505 -223.182307) (xy 119.536845 -223.217647)
			(xy 119.566221 -223.25808) (xy 119.588911 -223.302612) (xy 119.604355 -223.350144) (xy 119.612174 -223.399507)
			(xy 119.612664 -223.424496) (xy 119.612174 -223.449485) (xy 119.917192 -223.449485) (xy 119.917192 -223.399507)
			(xy 119.925011 -223.350144) (xy 119.940455 -223.302612) (xy 119.963145 -223.25808) (xy 119.992521 -223.217647)
			(xy 120.027861 -223.182307) (xy 120.068294 -223.152931) (xy 120.112826 -223.130241) (xy 120.160358 -223.114797)
			(xy 120.209721 -223.106978) (xy 120.259699 -223.106978) (xy 120.309062 -223.114797) (xy 120.356594 -223.130241)
			(xy 120.401126 -223.152931) (xy 120.441559 -223.182307) (xy 120.476899 -223.217647) (xy 120.506275 -223.25808)
			(xy 120.528965 -223.302612) (xy 120.544409 -223.350144) (xy 120.552228 -223.399507) (xy 120.552718 -223.424496)
			(xy 120.552228 -223.449485) (xy 120.857246 -223.449485) (xy 120.857246 -223.399507) (xy 120.865065 -223.350144)
			(xy 120.880509 -223.302612) (xy 120.903199 -223.25808) (xy 120.932575 -223.217647) (xy 120.967915 -223.182307)
			(xy 121.008348 -223.152931) (xy 121.05288 -223.130241) (xy 121.100412 -223.114797) (xy 121.149775 -223.106978)
			(xy 121.199753 -223.106978) (xy 121.249116 -223.114797) (xy 121.296648 -223.130241) (xy 121.34118 -223.152931)
			(xy 121.381613 -223.182307) (xy 121.416953 -223.217647) (xy 121.446329 -223.25808) (xy 121.469019 -223.302612)
			(xy 121.484463 -223.350144) (xy 121.492282 -223.399507) (xy 121.492772 -223.424496) (xy 121.492282 -223.449485)
			(xy 121.7973 -223.449485) (xy 121.7973 -223.399507) (xy 121.805119 -223.350144) (xy 121.820563 -223.302612)
			(xy 121.843253 -223.25808) (xy 121.872629 -223.217647) (xy 121.907969 -223.182307) (xy 121.948402 -223.152931)
			(xy 121.992934 -223.130241) (xy 122.040466 -223.114797) (xy 122.089829 -223.106978) (xy 122.139807 -223.106978)
			(xy 122.18917 -223.114797) (xy 122.236702 -223.130241) (xy 122.281234 -223.152931) (xy 122.321667 -223.182307)
			(xy 122.357007 -223.217647) (xy 122.386383 -223.25808) (xy 122.409073 -223.302612) (xy 122.424517 -223.350144)
			(xy 122.432336 -223.399507) (xy 122.432826 -223.424496) (xy 122.432336 -223.449485) (xy 122.7371 -223.449485)
			(xy 122.7371 -223.399507) (xy 122.744919 -223.350144) (xy 122.760363 -223.302612) (xy 122.783053 -223.25808)
			(xy 122.812429 -223.217647) (xy 122.847769 -223.182307) (xy 122.888202 -223.152931) (xy 122.932734 -223.130241)
			(xy 122.980266 -223.114797) (xy 123.029629 -223.106978) (xy 123.079607 -223.106978) (xy 123.12897 -223.114797)
			(xy 123.176502 -223.130241) (xy 123.221034 -223.152931) (xy 123.261467 -223.182307) (xy 123.296807 -223.217647)
			(xy 123.326183 -223.25808) (xy 123.348873 -223.302612) (xy 123.364317 -223.350144) (xy 123.372136 -223.399507)
			(xy 123.372626 -223.424496) (xy 123.372136 -223.449485) (xy 123.677154 -223.449485) (xy 123.677154 -223.399507)
			(xy 123.684973 -223.350144) (xy 123.700417 -223.302612) (xy 123.723107 -223.25808) (xy 123.752483 -223.217647)
			(xy 123.787823 -223.182307) (xy 123.828256 -223.152931) (xy 123.872788 -223.130241) (xy 123.92032 -223.114797)
			(xy 123.969683 -223.106978) (xy 124.019661 -223.106978) (xy 124.069024 -223.114797) (xy 124.116556 -223.130241)
			(xy 124.161088 -223.152931) (xy 124.201521 -223.182307) (xy 124.236861 -223.217647) (xy 124.266237 -223.25808)
			(xy 124.288927 -223.302612) (xy 124.304371 -223.350144) (xy 124.31219 -223.399507) (xy 124.31268 -223.424496)
			(xy 124.31219 -223.449485) (xy 124.617208 -223.449485) (xy 124.617208 -223.399507) (xy 124.625027 -223.350144)
			(xy 124.640471 -223.302612) (xy 124.663161 -223.25808) (xy 124.692537 -223.217647) (xy 124.727877 -223.182307)
			(xy 124.76831 -223.152931) (xy 124.812842 -223.130241) (xy 124.860374 -223.114797) (xy 124.909737 -223.106978)
			(xy 124.959715 -223.106978) (xy 125.009078 -223.114797) (xy 125.05661 -223.130241) (xy 125.101142 -223.152931)
			(xy 125.141575 -223.182307) (xy 125.176915 -223.217647) (xy 125.206291 -223.25808) (xy 125.228981 -223.302612)
			(xy 125.244425 -223.350144) (xy 125.252244 -223.399507) (xy 125.252734 -223.424496) (xy 125.252244 -223.449485)
			(xy 125.557262 -223.449485) (xy 125.557262 -223.399507) (xy 125.565081 -223.350144) (xy 125.580525 -223.302612)
			(xy 125.603215 -223.25808) (xy 125.632591 -223.217647) (xy 125.667931 -223.182307) (xy 125.708364 -223.152931)
			(xy 125.752896 -223.130241) (xy 125.800428 -223.114797) (xy 125.849791 -223.106978) (xy 125.899769 -223.106978)
			(xy 125.949132 -223.114797) (xy 125.996664 -223.130241) (xy 126.041196 -223.152931) (xy 126.081629 -223.182307)
			(xy 126.116969 -223.217647) (xy 126.146345 -223.25808) (xy 126.169035 -223.302612) (xy 126.184479 -223.350144)
			(xy 126.192298 -223.399507) (xy 126.192788 -223.424496) (xy 126.192298 -223.449485) (xy 126.184479 -223.498848)
			(xy 126.169035 -223.54638) (xy 126.146345 -223.590912) (xy 126.116969 -223.631345) (xy 126.081629 -223.666685)
			(xy 126.041196 -223.696061) (xy 125.996664 -223.718751) (xy 125.949132 -223.734195) (xy 125.899769 -223.742014)
			(xy 125.849791 -223.742014) (xy 125.800428 -223.734195) (xy 125.752896 -223.718751) (xy 125.708364 -223.696061)
			(xy 125.667931 -223.666685) (xy 125.632591 -223.631345) (xy 125.603215 -223.590912) (xy 125.580525 -223.54638)
			(xy 125.565081 -223.498848) (xy 125.557262 -223.449485) (xy 125.252244 -223.449485) (xy 125.244425 -223.498848)
			(xy 125.228981 -223.54638) (xy 125.206291 -223.590912) (xy 125.176915 -223.631345) (xy 125.141575 -223.666685)
			(xy 125.101142 -223.696061) (xy 125.05661 -223.718751) (xy 125.009078 -223.734195) (xy 124.959715 -223.742014)
			(xy 124.909737 -223.742014) (xy 124.860374 -223.734195) (xy 124.812842 -223.718751) (xy 124.76831 -223.696061)
			(xy 124.727877 -223.666685) (xy 124.692537 -223.631345) (xy 124.663161 -223.590912) (xy 124.640471 -223.54638)
			(xy 124.625027 -223.498848) (xy 124.617208 -223.449485) (xy 124.31219 -223.449485) (xy 124.304371 -223.498848)
			(xy 124.288927 -223.54638) (xy 124.266237 -223.590912) (xy 124.236861 -223.631345) (xy 124.201521 -223.666685)
			(xy 124.161088 -223.696061) (xy 124.116556 -223.718751) (xy 124.069024 -223.734195) (xy 124.019661 -223.742014)
			(xy 123.969683 -223.742014) (xy 123.92032 -223.734195) (xy 123.872788 -223.718751) (xy 123.828256 -223.696061)
			(xy 123.787823 -223.666685) (xy 123.752483 -223.631345) (xy 123.723107 -223.590912) (xy 123.700417 -223.54638)
			(xy 123.684973 -223.498848) (xy 123.677154 -223.449485) (xy 123.372136 -223.449485) (xy 123.364317 -223.498848)
			(xy 123.348873 -223.54638) (xy 123.326183 -223.590912) (xy 123.296807 -223.631345) (xy 123.261467 -223.666685)
			(xy 123.221034 -223.696061) (xy 123.176502 -223.718751) (xy 123.12897 -223.734195) (xy 123.079607 -223.742014)
			(xy 123.029629 -223.742014) (xy 122.980266 -223.734195) (xy 122.932734 -223.718751) (xy 122.888202 -223.696061)
			(xy 122.847769 -223.666685) (xy 122.812429 -223.631345) (xy 122.783053 -223.590912) (xy 122.760363 -223.54638)
			(xy 122.744919 -223.498848) (xy 122.7371 -223.449485) (xy 122.432336 -223.449485) (xy 122.424517 -223.498848)
			(xy 122.409073 -223.54638) (xy 122.386383 -223.590912) (xy 122.357007 -223.631345) (xy 122.321667 -223.666685)
			(xy 122.281234 -223.696061) (xy 122.236702 -223.718751) (xy 122.18917 -223.734195) (xy 122.139807 -223.742014)
			(xy 122.089829 -223.742014) (xy 122.040466 -223.734195) (xy 121.992934 -223.718751) (xy 121.948402 -223.696061)
			(xy 121.907969 -223.666685) (xy 121.872629 -223.631345) (xy 121.843253 -223.590912) (xy 121.820563 -223.54638)
			(xy 121.805119 -223.498848) (xy 121.7973 -223.449485) (xy 121.492282 -223.449485) (xy 121.484463 -223.498848)
			(xy 121.469019 -223.54638) (xy 121.446329 -223.590912) (xy 121.416953 -223.631345) (xy 121.381613 -223.666685)
			(xy 121.34118 -223.696061) (xy 121.296648 -223.718751) (xy 121.249116 -223.734195) (xy 121.199753 -223.742014)
			(xy 121.149775 -223.742014) (xy 121.100412 -223.734195) (xy 121.05288 -223.718751) (xy 121.008348 -223.696061)
			(xy 120.967915 -223.666685) (xy 120.932575 -223.631345) (xy 120.903199 -223.590912) (xy 120.880509 -223.54638)
			(xy 120.865065 -223.498848) (xy 120.857246 -223.449485) (xy 120.552228 -223.449485) (xy 120.544409 -223.498848)
			(xy 120.528965 -223.54638) (xy 120.506275 -223.590912) (xy 120.476899 -223.631345) (xy 120.441559 -223.666685)
			(xy 120.401126 -223.696061) (xy 120.356594 -223.718751) (xy 120.309062 -223.734195) (xy 120.259699 -223.742014)
			(xy 120.209721 -223.742014) (xy 120.160358 -223.734195) (xy 120.112826 -223.718751) (xy 120.068294 -223.696061)
			(xy 120.027861 -223.666685) (xy 119.992521 -223.631345) (xy 119.963145 -223.590912) (xy 119.940455 -223.54638)
			(xy 119.925011 -223.498848) (xy 119.917192 -223.449485) (xy 119.612174 -223.449485) (xy 119.604355 -223.498848)
			(xy 119.588911 -223.54638) (xy 119.566221 -223.590912) (xy 119.536845 -223.631345) (xy 119.501505 -223.666685)
			(xy 119.461072 -223.696061) (xy 119.41654 -223.718751) (xy 119.369008 -223.734195) (xy 119.319645 -223.742014)
			(xy 119.269667 -223.742014) (xy 119.220304 -223.734195) (xy 119.172772 -223.718751) (xy 119.12824 -223.696061)
			(xy 119.087807 -223.666685) (xy 119.052467 -223.631345) (xy 119.023091 -223.590912) (xy 119.000401 -223.54638)
			(xy 118.984957 -223.498848) (xy 118.977138 -223.449485) (xy 118.672374 -223.449485) (xy 118.664555 -223.498848)
			(xy 118.649111 -223.54638) (xy 118.626421 -223.590912) (xy 118.597045 -223.631345) (xy 118.561705 -223.666685)
			(xy 118.521272 -223.696061) (xy 118.47674 -223.718751) (xy 118.429208 -223.734195) (xy 118.379845 -223.742014)
			(xy 118.329867 -223.742014) (xy 118.280504 -223.734195) (xy 118.232972 -223.718751) (xy 118.18844 -223.696061)
			(xy 118.148007 -223.666685) (xy 118.112667 -223.631345) (xy 118.083291 -223.590912) (xy 118.060601 -223.54638)
			(xy 118.045157 -223.498848) (xy 118.037338 -223.449485) (xy 117.73232 -223.449485) (xy 117.724501 -223.498848)
			(xy 117.709057 -223.54638) (xy 117.686367 -223.590912) (xy 117.656991 -223.631345) (xy 117.621651 -223.666685)
			(xy 117.581218 -223.696061) (xy 117.536686 -223.718751) (xy 117.489154 -223.734195) (xy 117.439791 -223.742014)
			(xy 117.389813 -223.742014) (xy 117.34045 -223.734195) (xy 117.292918 -223.718751) (xy 117.248386 -223.696061)
			(xy 117.207953 -223.666685) (xy 117.172613 -223.631345) (xy 117.143237 -223.590912) (xy 117.120547 -223.54638)
			(xy 117.105103 -223.498848) (xy 117.097284 -223.449485) (xy 116.792266 -223.449485) (xy 116.784447 -223.498848)
			(xy 116.769003 -223.54638) (xy 116.746313 -223.590912) (xy 116.716937 -223.631345) (xy 116.681597 -223.666685)
			(xy 116.641164 -223.696061) (xy 116.596632 -223.718751) (xy 116.5491 -223.734195) (xy 116.499737 -223.742014)
			(xy 116.449759 -223.742014) (xy 116.400396 -223.734195) (xy 116.352864 -223.718751) (xy 116.308332 -223.696061)
			(xy 116.267899 -223.666685) (xy 116.232559 -223.631345) (xy 116.203183 -223.590912) (xy 116.180493 -223.54638)
			(xy 116.165049 -223.498848) (xy 116.15723 -223.449485) (xy 115.852212 -223.449485) (xy 115.844393 -223.498848)
			(xy 115.828949 -223.54638) (xy 115.806259 -223.590912) (xy 115.776883 -223.631345) (xy 115.741543 -223.666685)
			(xy 115.70111 -223.696061) (xy 115.656578 -223.718751) (xy 115.609046 -223.734195) (xy 115.559683 -223.742014)
			(xy 115.509705 -223.742014) (xy 115.460342 -223.734195) (xy 115.41281 -223.718751) (xy 115.368278 -223.696061)
			(xy 115.327845 -223.666685) (xy 115.292505 -223.631345) (xy 115.263129 -223.590912) (xy 115.240439 -223.54638)
			(xy 115.224995 -223.498848) (xy 115.217176 -223.449485) (xy 114.912158 -223.449485) (xy 114.904339 -223.498848)
			(xy 114.888895 -223.54638) (xy 114.866205 -223.590912) (xy 114.836829 -223.631345) (xy 114.801489 -223.666685)
			(xy 114.761056 -223.696061) (xy 114.716524 -223.718751) (xy 114.668992 -223.734195) (xy 114.619629 -223.742014)
			(xy 114.569651 -223.742014) (xy 114.520288 -223.734195) (xy 114.472756 -223.718751) (xy 114.428224 -223.696061)
			(xy 114.387791 -223.666685) (xy 114.352451 -223.631345) (xy 114.323075 -223.590912) (xy 114.300385 -223.54638)
			(xy 114.284941 -223.498848) (xy 114.277122 -223.449485) (xy 113.972358 -223.449485) (xy 113.964539 -223.498848)
			(xy 113.949095 -223.54638) (xy 113.926405 -223.590912) (xy 113.897029 -223.631345) (xy 113.861689 -223.666685)
			(xy 113.821256 -223.696061) (xy 113.776724 -223.718751) (xy 113.729192 -223.734195) (xy 113.679829 -223.742014)
			(xy 113.629851 -223.742014) (xy 113.580488 -223.734195) (xy 113.532956 -223.718751) (xy 113.488424 -223.696061)
			(xy 113.447991 -223.666685) (xy 113.412651 -223.631345) (xy 113.383275 -223.590912) (xy 113.360585 -223.54638)
			(xy 113.345141 -223.498848) (xy 113.337322 -223.449485) (xy 110.218492 -223.449485) (xy 110.210673 -223.498848)
			(xy 110.195229 -223.54638) (xy 110.172539 -223.590912) (xy 110.143163 -223.631345) (xy 110.107823 -223.666685)
			(xy 110.06739 -223.696061) (xy 110.022858 -223.718751) (xy 109.975326 -223.734195) (xy 109.925963 -223.742014)
			(xy 109.875985 -223.742014) (xy 109.826622 -223.734195) (xy 109.77909 -223.718751) (xy 109.734558 -223.696061)
			(xy 109.694125 -223.666685) (xy 109.658785 -223.631345) (xy 109.629409 -223.590912) (xy 109.606719 -223.54638)
			(xy 109.591275 -223.498848) (xy 109.583456 -223.449485) (xy 107.398542 -223.449485) (xy 107.398475 -223.452578)
			(xy 107.388738 -223.507377) (xy 107.369604 -223.559642) (xy 107.356148 -223.584008) (xy 107.354878 -223.58604)
			(xy 107.34802 -223.600518) (xy 107.347004 -223.60509) (xy 107.344464 -223.614488) (xy 107.344464 -223.829118)
			(xy 107.344718 -223.833182) (xy 107.344718 -223.83369) (xy 107.345985 -223.843339) (xy 107.354744 -223.860701)
			(xy 107.361736 -223.867472) (xy 107.379262 -223.881188) (xy 107.417616 -223.911414) (xy 107.418124 -223.911414)
			(xy 107.426252 -223.917764) (xy 107.430877 -223.921159) (xy 107.441258 -223.926036) (xy 107.446826 -223.927416)
			(xy 107.458256 -223.929702) (xy 107.46994 -223.926654) (xy 107.489536 -223.921901) (xy 107.529535 -223.9168)
			(xy 107.549696 -223.916494) (xy 107.555284 -223.916494) (xy 107.580053 -223.917301) (xy 107.6289 -223.925646)
			(xy 107.675862 -223.941467) (xy 107.719801 -223.964379) (xy 107.759655 -223.99383) (xy 107.794459 -224.029106)
			(xy 107.82337 -224.069353) (xy 107.845689 -224.113597) (xy 107.860875 -224.160768) (xy 107.868561 -224.209723)
			(xy 107.868561 -224.259277) (xy 107.868527 -224.259491) (xy 108.173502 -224.259491) (xy 108.173502 -224.209513)
			(xy 108.181321 -224.16015) (xy 108.196765 -224.112618) (xy 108.219455 -224.068086) (xy 108.248831 -224.027653)
			(xy 108.284171 -223.992313) (xy 108.324604 -223.962937) (xy 108.369136 -223.940247) (xy 108.416668 -223.924803)
			(xy 108.466031 -223.916984) (xy 108.516009 -223.916984) (xy 108.565372 -223.924803) (xy 108.612904 -223.940247)
			(xy 108.657436 -223.962937) (xy 108.697869 -223.992313) (xy 108.733209 -224.027653) (xy 108.762585 -224.068086)
			(xy 108.785275 -224.112618) (xy 108.800719 -224.16015) (xy 108.808538 -224.209513) (xy 108.809028 -224.234502)
			(xy 108.808538 -224.259491) (xy 109.113556 -224.259491) (xy 109.113556 -224.209513) (xy 109.121375 -224.16015)
			(xy 109.136819 -224.112618) (xy 109.159509 -224.068086) (xy 109.188885 -224.027653) (xy 109.224225 -223.992313)
			(xy 109.264658 -223.962937) (xy 109.30919 -223.940247) (xy 109.356722 -223.924803) (xy 109.406085 -223.916984)
			(xy 109.456063 -223.916984) (xy 109.505426 -223.924803) (xy 109.552958 -223.940247) (xy 109.59749 -223.962937)
			(xy 109.637923 -223.992313) (xy 109.673263 -224.027653) (xy 109.702639 -224.068086) (xy 109.725329 -224.112618)
			(xy 109.740773 -224.16015) (xy 109.748592 -224.209513) (xy 109.749082 -224.234502) (xy 109.748592 -224.259491)
			(xy 112.867168 -224.259491) (xy 112.867168 -224.209513) (xy 112.874987 -224.16015) (xy 112.890431 -224.112618)
			(xy 112.913121 -224.068086) (xy 112.942497 -224.027653) (xy 112.977837 -223.992313) (xy 113.01827 -223.962937)
			(xy 113.062802 -223.940247) (xy 113.110334 -223.924803) (xy 113.159697 -223.916984) (xy 113.209675 -223.916984)
			(xy 113.259038 -223.924803) (xy 113.30657 -223.940247) (xy 113.351102 -223.962937) (xy 113.391535 -223.992313)
			(xy 113.426875 -224.027653) (xy 113.456251 -224.068086) (xy 113.478941 -224.112618) (xy 113.494385 -224.16015)
			(xy 113.502204 -224.209513) (xy 113.502694 -224.234502) (xy 113.502204 -224.259491) (xy 113.807222 -224.259491)
			(xy 113.807222 -224.209513) (xy 113.815041 -224.16015) (xy 113.830485 -224.112618) (xy 113.853175 -224.068086)
			(xy 113.882551 -224.027653) (xy 113.917891 -223.992313) (xy 113.958324 -223.962937) (xy 114.002856 -223.940247)
			(xy 114.050388 -223.924803) (xy 114.099751 -223.916984) (xy 114.149729 -223.916984) (xy 114.199092 -223.924803)
			(xy 114.246624 -223.940247) (xy 114.291156 -223.962937) (xy 114.331589 -223.992313) (xy 114.366929 -224.027653)
			(xy 114.396305 -224.068086) (xy 114.418995 -224.112618) (xy 114.434439 -224.16015) (xy 114.442258 -224.209513)
			(xy 114.442748 -224.234502) (xy 114.442258 -224.259491) (xy 114.747276 -224.259491) (xy 114.747276 -224.209513)
			(xy 114.755095 -224.16015) (xy 114.770539 -224.112618) (xy 114.793229 -224.068086) (xy 114.822605 -224.027653)
			(xy 114.857945 -223.992313) (xy 114.898378 -223.962937) (xy 114.94291 -223.940247) (xy 114.990442 -223.924803)
			(xy 115.039805 -223.916984) (xy 115.089783 -223.916984) (xy 115.139146 -223.924803) (xy 115.186678 -223.940247)
			(xy 115.23121 -223.962937) (xy 115.271643 -223.992313) (xy 115.306983 -224.027653) (xy 115.336359 -224.068086)
			(xy 115.359049 -224.112618) (xy 115.374493 -224.16015) (xy 115.382312 -224.209513) (xy 115.382802 -224.234502)
			(xy 115.382312 -224.259491) (xy 115.68733 -224.259491) (xy 115.68733 -224.209513) (xy 115.695149 -224.16015)
			(xy 115.710593 -224.112618) (xy 115.733283 -224.068086) (xy 115.762659 -224.027653) (xy 115.797999 -223.992313)
			(xy 115.838432 -223.962937) (xy 115.882964 -223.940247) (xy 115.930496 -223.924803) (xy 115.979859 -223.916984)
			(xy 116.029837 -223.916984) (xy 116.0792 -223.924803) (xy 116.126732 -223.940247) (xy 116.171264 -223.962937)
			(xy 116.211697 -223.992313) (xy 116.247037 -224.027653) (xy 116.276413 -224.068086) (xy 116.299103 -224.112618)
			(xy 116.314547 -224.16015) (xy 116.322366 -224.209513) (xy 116.322856 -224.234502) (xy 116.322366 -224.259491)
			(xy 116.62713 -224.259491) (xy 116.62713 -224.209513) (xy 116.634949 -224.16015) (xy 116.650393 -224.112618)
			(xy 116.673083 -224.068086) (xy 116.702459 -224.027653) (xy 116.737799 -223.992313) (xy 116.778232 -223.962937)
			(xy 116.822764 -223.940247) (xy 116.870296 -223.924803) (xy 116.919659 -223.916984) (xy 116.969637 -223.916984)
			(xy 117.019 -223.924803) (xy 117.066532 -223.940247) (xy 117.111064 -223.962937) (xy 117.151497 -223.992313)
			(xy 117.186837 -224.027653) (xy 117.216213 -224.068086) (xy 117.238903 -224.112618) (xy 117.254347 -224.16015)
			(xy 117.262166 -224.209513) (xy 117.262656 -224.234502) (xy 117.262166 -224.259491) (xy 117.567184 -224.259491)
			(xy 117.567184 -224.209513) (xy 117.575003 -224.16015) (xy 117.590447 -224.112618) (xy 117.613137 -224.068086)
			(xy 117.642513 -224.027653) (xy 117.677853 -223.992313) (xy 117.718286 -223.962937) (xy 117.762818 -223.940247)
			(xy 117.81035 -223.924803) (xy 117.859713 -223.916984) (xy 117.909691 -223.916984) (xy 117.959054 -223.924803)
			(xy 118.006586 -223.940247) (xy 118.051118 -223.962937) (xy 118.091551 -223.992313) (xy 118.126891 -224.027653)
			(xy 118.156267 -224.068086) (xy 118.178957 -224.112618) (xy 118.194401 -224.16015) (xy 118.20222 -224.209513)
			(xy 118.20271 -224.234502) (xy 118.20222 -224.259491) (xy 118.507238 -224.259491) (xy 118.507238 -224.209513)
			(xy 118.515057 -224.16015) (xy 118.530501 -224.112618) (xy 118.553191 -224.068086) (xy 118.582567 -224.027653)
			(xy 118.617907 -223.992313) (xy 118.65834 -223.962937) (xy 118.702872 -223.940247) (xy 118.750404 -223.924803)
			(xy 118.799767 -223.916984) (xy 118.849745 -223.916984) (xy 118.899108 -223.924803) (xy 118.94664 -223.940247)
			(xy 118.991172 -223.962937) (xy 119.031605 -223.992313) (xy 119.066945 -224.027653) (xy 119.096321 -224.068086)
			(xy 119.119011 -224.112618) (xy 119.134455 -224.16015) (xy 119.142274 -224.209513) (xy 119.142764 -224.234502)
			(xy 119.142274 -224.259491) (xy 119.447292 -224.259491) (xy 119.447292 -224.209513) (xy 119.455111 -224.16015)
			(xy 119.470555 -224.112618) (xy 119.493245 -224.068086) (xy 119.522621 -224.027653) (xy 119.557961 -223.992313)
			(xy 119.598394 -223.962937) (xy 119.642926 -223.940247) (xy 119.690458 -223.924803) (xy 119.739821 -223.916984)
			(xy 119.789799 -223.916984) (xy 119.839162 -223.924803) (xy 119.886694 -223.940247) (xy 119.931226 -223.962937)
			(xy 119.971659 -223.992313) (xy 120.006999 -224.027653) (xy 120.036375 -224.068086) (xy 120.059065 -224.112618)
			(xy 120.074509 -224.16015) (xy 120.082328 -224.209513) (xy 120.082818 -224.234502) (xy 120.082328 -224.259491)
			(xy 120.387092 -224.259491) (xy 120.387092 -224.209513) (xy 120.394911 -224.16015) (xy 120.410355 -224.112618)
			(xy 120.433045 -224.068086) (xy 120.462421 -224.027653) (xy 120.497761 -223.992313) (xy 120.538194 -223.962937)
			(xy 120.582726 -223.940247) (xy 120.630258 -223.924803) (xy 120.679621 -223.916984) (xy 120.729599 -223.916984)
			(xy 120.778962 -223.924803) (xy 120.826494 -223.940247) (xy 120.871026 -223.962937) (xy 120.911459 -223.992313)
			(xy 120.946799 -224.027653) (xy 120.976175 -224.068086) (xy 120.998865 -224.112618) (xy 121.014309 -224.16015)
			(xy 121.022128 -224.209513) (xy 121.022618 -224.234502) (xy 121.022128 -224.259491) (xy 121.327146 -224.259491)
			(xy 121.327146 -224.209513) (xy 121.334965 -224.16015) (xy 121.350409 -224.112618) (xy 121.373099 -224.068086)
			(xy 121.402475 -224.027653) (xy 121.437815 -223.992313) (xy 121.478248 -223.962937) (xy 121.52278 -223.940247)
			(xy 121.570312 -223.924803) (xy 121.619675 -223.916984) (xy 121.669653 -223.916984) (xy 121.719016 -223.924803)
			(xy 121.766548 -223.940247) (xy 121.81108 -223.962937) (xy 121.851513 -223.992313) (xy 121.886853 -224.027653)
			(xy 121.916229 -224.068086) (xy 121.938919 -224.112618) (xy 121.954363 -224.16015) (xy 121.962182 -224.209513)
			(xy 121.962672 -224.234502) (xy 121.962182 -224.259491) (xy 122.2672 -224.259491) (xy 122.2672 -224.209513)
			(xy 122.275019 -224.16015) (xy 122.290463 -224.112618) (xy 122.313153 -224.068086) (xy 122.342529 -224.027653)
			(xy 122.377869 -223.992313) (xy 122.418302 -223.962937) (xy 122.462834 -223.940247) (xy 122.510366 -223.924803)
			(xy 122.559729 -223.916984) (xy 122.609707 -223.916984) (xy 122.65907 -223.924803) (xy 122.706602 -223.940247)
			(xy 122.751134 -223.962937) (xy 122.791567 -223.992313) (xy 122.826907 -224.027653) (xy 122.856283 -224.068086)
			(xy 122.878973 -224.112618) (xy 122.894417 -224.16015) (xy 122.902236 -224.209513) (xy 122.902726 -224.234502)
			(xy 122.902236 -224.259491) (xy 123.207254 -224.259491) (xy 123.207254 -224.209513) (xy 123.215073 -224.16015)
			(xy 123.230517 -224.112618) (xy 123.253207 -224.068086) (xy 123.282583 -224.027653) (xy 123.317923 -223.992313)
			(xy 123.358356 -223.962937) (xy 123.402888 -223.940247) (xy 123.45042 -223.924803) (xy 123.499783 -223.916984)
			(xy 123.549761 -223.916984) (xy 123.599124 -223.924803) (xy 123.646656 -223.940247) (xy 123.691188 -223.962937)
			(xy 123.731621 -223.992313) (xy 123.766961 -224.027653) (xy 123.796337 -224.068086) (xy 123.819027 -224.112618)
			(xy 123.834471 -224.16015) (xy 123.84229 -224.209513) (xy 123.84278 -224.234502) (xy 123.84229 -224.259491)
			(xy 124.147308 -224.259491) (xy 124.147308 -224.209513) (xy 124.155127 -224.16015) (xy 124.170571 -224.112618)
			(xy 124.193261 -224.068086) (xy 124.222637 -224.027653) (xy 124.257977 -223.992313) (xy 124.29841 -223.962937)
			(xy 124.342942 -223.940247) (xy 124.390474 -223.924803) (xy 124.439837 -223.916984) (xy 124.489815 -223.916984)
			(xy 124.539178 -223.924803) (xy 124.58671 -223.940247) (xy 124.631242 -223.962937) (xy 124.671675 -223.992313)
			(xy 124.707015 -224.027653) (xy 124.736391 -224.068086) (xy 124.759081 -224.112618) (xy 124.774525 -224.16015)
			(xy 124.782344 -224.209513) (xy 124.782834 -224.234502) (xy 124.782344 -224.259491) (xy 125.087108 -224.259491)
			(xy 125.087108 -224.209513) (xy 125.094927 -224.16015) (xy 125.110371 -224.112618) (xy 125.133061 -224.068086)
			(xy 125.162437 -224.027653) (xy 125.197777 -223.992313) (xy 125.23821 -223.962937) (xy 125.282742 -223.940247)
			(xy 125.330274 -223.924803) (xy 125.379637 -223.916984) (xy 125.429615 -223.916984) (xy 125.478978 -223.924803)
			(xy 125.52651 -223.940247) (xy 125.571042 -223.962937) (xy 125.611475 -223.992313) (xy 125.646815 -224.027653)
			(xy 125.676191 -224.068086) (xy 125.698881 -224.112618) (xy 125.714325 -224.16015) (xy 125.722144 -224.209513)
			(xy 125.722634 -224.234502) (xy 125.722144 -224.259491) (xy 126.027162 -224.259491) (xy 126.027162 -224.209513)
			(xy 126.034981 -224.16015) (xy 126.050425 -224.112618) (xy 126.073115 -224.068086) (xy 126.102491 -224.027653)
			(xy 126.137831 -223.992313) (xy 126.178264 -223.962937) (xy 126.222796 -223.940247) (xy 126.270328 -223.924803)
			(xy 126.319691 -223.916984) (xy 126.369669 -223.916984) (xy 126.419032 -223.924803) (xy 126.466564 -223.940247)
			(xy 126.511096 -223.962937) (xy 126.551529 -223.992313) (xy 126.586869 -224.027653) (xy 126.616245 -224.068086)
			(xy 126.638935 -224.112618) (xy 126.654379 -224.16015) (xy 126.662198 -224.209513) (xy 126.662688 -224.234502)
			(xy 126.662198 -224.259491) (xy 126.967216 -224.259491) (xy 126.967216 -224.209513) (xy 126.975035 -224.16015)
			(xy 126.990479 -224.112618) (xy 127.013169 -224.068086) (xy 127.042545 -224.027653) (xy 127.077885 -223.992313)
			(xy 127.118318 -223.962937) (xy 127.16285 -223.940247) (xy 127.210382 -223.924803) (xy 127.259745 -223.916984)
			(xy 127.309723 -223.916984) (xy 127.359086 -223.924803) (xy 127.406618 -223.940247) (xy 127.45115 -223.962937)
			(xy 127.491583 -223.992313) (xy 127.526923 -224.027653) (xy 127.556299 -224.068086) (xy 127.578989 -224.112618)
			(xy 127.594433 -224.16015) (xy 127.602252 -224.209513) (xy 127.602742 -224.234502) (xy 127.602252 -224.259491)
			(xy 127.90727 -224.259491) (xy 127.90727 -224.209513) (xy 127.915089 -224.16015) (xy 127.930533 -224.112618)
			(xy 127.953223 -224.068086) (xy 127.982599 -224.027653) (xy 128.017939 -223.992313) (xy 128.058372 -223.962937)
			(xy 128.102904 -223.940247) (xy 128.150436 -223.924803) (xy 128.199799 -223.916984) (xy 128.249777 -223.916984)
			(xy 128.29914 -223.924803) (xy 128.346672 -223.940247) (xy 128.391204 -223.962937) (xy 128.431637 -223.992313)
			(xy 128.466977 -224.027653) (xy 128.496353 -224.068086) (xy 128.519043 -224.112618) (xy 128.534487 -224.16015)
			(xy 128.542306 -224.209513) (xy 128.542796 -224.234502) (xy 128.542306 -224.259491) (xy 128.534487 -224.308854)
			(xy 128.519043 -224.356386) (xy 128.496353 -224.400918) (xy 128.466977 -224.441351) (xy 128.431637 -224.476691)
			(xy 128.391204 -224.506067) (xy 128.346672 -224.528757) (xy 128.29914 -224.544201) (xy 128.249777 -224.55202)
			(xy 128.199799 -224.55202) (xy 128.150436 -224.544201) (xy 128.102904 -224.528757) (xy 128.058372 -224.506067)
			(xy 128.017939 -224.476691) (xy 127.982599 -224.441351) (xy 127.953223 -224.400918) (xy 127.930533 -224.356386)
			(xy 127.915089 -224.308854) (xy 127.90727 -224.259491) (xy 127.602252 -224.259491) (xy 127.594433 -224.308854)
			(xy 127.578989 -224.356386) (xy 127.556299 -224.400918) (xy 127.526923 -224.441351) (xy 127.491583 -224.476691)
			(xy 127.45115 -224.506067) (xy 127.406618 -224.528757) (xy 127.359086 -224.544201) (xy 127.309723 -224.55202)
			(xy 127.259745 -224.55202) (xy 127.210382 -224.544201) (xy 127.16285 -224.528757) (xy 127.118318 -224.506067)
			(xy 127.077885 -224.476691) (xy 127.042545 -224.441351) (xy 127.013169 -224.400918) (xy 126.990479 -224.356386)
			(xy 126.975035 -224.308854) (xy 126.967216 -224.259491) (xy 126.662198 -224.259491) (xy 126.654379 -224.308854)
			(xy 126.638935 -224.356386) (xy 126.616245 -224.400918) (xy 126.586869 -224.441351) (xy 126.551529 -224.476691)
			(xy 126.511096 -224.506067) (xy 126.466564 -224.528757) (xy 126.419032 -224.544201) (xy 126.369669 -224.55202)
			(xy 126.319691 -224.55202) (xy 126.270328 -224.544201) (xy 126.222796 -224.528757) (xy 126.178264 -224.506067)
			(xy 126.137831 -224.476691) (xy 126.102491 -224.441351) (xy 126.073115 -224.400918) (xy 126.050425 -224.356386)
			(xy 126.034981 -224.308854) (xy 126.027162 -224.259491) (xy 125.722144 -224.259491) (xy 125.714325 -224.308854)
			(xy 125.698881 -224.356386) (xy 125.676191 -224.400918) (xy 125.646815 -224.441351) (xy 125.611475 -224.476691)
			(xy 125.571042 -224.506067) (xy 125.52651 -224.528757) (xy 125.478978 -224.544201) (xy 125.429615 -224.55202)
			(xy 125.379637 -224.55202) (xy 125.330274 -224.544201) (xy 125.282742 -224.528757) (xy 125.23821 -224.506067)
			(xy 125.197777 -224.476691) (xy 125.162437 -224.441351) (xy 125.133061 -224.400918) (xy 125.110371 -224.356386)
			(xy 125.094927 -224.308854) (xy 125.087108 -224.259491) (xy 124.782344 -224.259491) (xy 124.774525 -224.308854)
			(xy 124.759081 -224.356386) (xy 124.736391 -224.400918) (xy 124.707015 -224.441351) (xy 124.671675 -224.476691)
			(xy 124.631242 -224.506067) (xy 124.58671 -224.528757) (xy 124.539178 -224.544201) (xy 124.489815 -224.55202)
			(xy 124.439837 -224.55202) (xy 124.390474 -224.544201) (xy 124.342942 -224.528757) (xy 124.29841 -224.506067)
			(xy 124.257977 -224.476691) (xy 124.222637 -224.441351) (xy 124.193261 -224.400918) (xy 124.170571 -224.356386)
			(xy 124.155127 -224.308854) (xy 124.147308 -224.259491) (xy 123.84229 -224.259491) (xy 123.834471 -224.308854)
			(xy 123.819027 -224.356386) (xy 123.796337 -224.400918) (xy 123.766961 -224.441351) (xy 123.731621 -224.476691)
			(xy 123.691188 -224.506067) (xy 123.646656 -224.528757) (xy 123.599124 -224.544201) (xy 123.549761 -224.55202)
			(xy 123.499783 -224.55202) (xy 123.45042 -224.544201) (xy 123.402888 -224.528757) (xy 123.358356 -224.506067)
			(xy 123.317923 -224.476691) (xy 123.282583 -224.441351) (xy 123.253207 -224.400918) (xy 123.230517 -224.356386)
			(xy 123.215073 -224.308854) (xy 123.207254 -224.259491) (xy 122.902236 -224.259491) (xy 122.894417 -224.308854)
			(xy 122.878973 -224.356386) (xy 122.856283 -224.400918) (xy 122.826907 -224.441351) (xy 122.791567 -224.476691)
			(xy 122.751134 -224.506067) (xy 122.706602 -224.528757) (xy 122.65907 -224.544201) (xy 122.609707 -224.55202)
			(xy 122.559729 -224.55202) (xy 122.510366 -224.544201) (xy 122.462834 -224.528757) (xy 122.418302 -224.506067)
			(xy 122.377869 -224.476691) (xy 122.342529 -224.441351) (xy 122.313153 -224.400918) (xy 122.290463 -224.356386)
			(xy 122.275019 -224.308854) (xy 122.2672 -224.259491) (xy 121.962182 -224.259491) (xy 121.954363 -224.308854)
			(xy 121.938919 -224.356386) (xy 121.916229 -224.400918) (xy 121.886853 -224.441351) (xy 121.851513 -224.476691)
			(xy 121.81108 -224.506067) (xy 121.766548 -224.528757) (xy 121.719016 -224.544201) (xy 121.669653 -224.55202)
			(xy 121.619675 -224.55202) (xy 121.570312 -224.544201) (xy 121.52278 -224.528757) (xy 121.478248 -224.506067)
			(xy 121.437815 -224.476691) (xy 121.402475 -224.441351) (xy 121.373099 -224.400918) (xy 121.350409 -224.356386)
			(xy 121.334965 -224.308854) (xy 121.327146 -224.259491) (xy 121.022128 -224.259491) (xy 121.014309 -224.308854)
			(xy 120.998865 -224.356386) (xy 120.976175 -224.400918) (xy 120.946799 -224.441351) (xy 120.911459 -224.476691)
			(xy 120.871026 -224.506067) (xy 120.826494 -224.528757) (xy 120.778962 -224.544201) (xy 120.729599 -224.55202)
			(xy 120.679621 -224.55202) (xy 120.630258 -224.544201) (xy 120.582726 -224.528757) (xy 120.538194 -224.506067)
			(xy 120.497761 -224.476691) (xy 120.462421 -224.441351) (xy 120.433045 -224.400918) (xy 120.410355 -224.356386)
			(xy 120.394911 -224.308854) (xy 120.387092 -224.259491) (xy 120.082328 -224.259491) (xy 120.074509 -224.308854)
			(xy 120.059065 -224.356386) (xy 120.036375 -224.400918) (xy 120.006999 -224.441351) (xy 119.971659 -224.476691)
			(xy 119.931226 -224.506067) (xy 119.886694 -224.528757) (xy 119.839162 -224.544201) (xy 119.789799 -224.55202)
			(xy 119.739821 -224.55202) (xy 119.690458 -224.544201) (xy 119.642926 -224.528757) (xy 119.598394 -224.506067)
			(xy 119.557961 -224.476691) (xy 119.522621 -224.441351) (xy 119.493245 -224.400918) (xy 119.470555 -224.356386)
			(xy 119.455111 -224.308854) (xy 119.447292 -224.259491) (xy 119.142274 -224.259491) (xy 119.134455 -224.308854)
			(xy 119.119011 -224.356386) (xy 119.096321 -224.400918) (xy 119.066945 -224.441351) (xy 119.031605 -224.476691)
			(xy 118.991172 -224.506067) (xy 118.94664 -224.528757) (xy 118.899108 -224.544201) (xy 118.849745 -224.55202)
			(xy 118.799767 -224.55202) (xy 118.750404 -224.544201) (xy 118.702872 -224.528757) (xy 118.65834 -224.506067)
			(xy 118.617907 -224.476691) (xy 118.582567 -224.441351) (xy 118.553191 -224.400918) (xy 118.530501 -224.356386)
			(xy 118.515057 -224.308854) (xy 118.507238 -224.259491) (xy 118.20222 -224.259491) (xy 118.194401 -224.308854)
			(xy 118.178957 -224.356386) (xy 118.156267 -224.400918) (xy 118.126891 -224.441351) (xy 118.091551 -224.476691)
			(xy 118.051118 -224.506067) (xy 118.006586 -224.528757) (xy 117.959054 -224.544201) (xy 117.909691 -224.55202)
			(xy 117.859713 -224.55202) (xy 117.81035 -224.544201) (xy 117.762818 -224.528757) (xy 117.718286 -224.506067)
			(xy 117.677853 -224.476691) (xy 117.642513 -224.441351) (xy 117.613137 -224.400918) (xy 117.590447 -224.356386)
			(xy 117.575003 -224.308854) (xy 117.567184 -224.259491) (xy 117.262166 -224.259491) (xy 117.254347 -224.308854)
			(xy 117.238903 -224.356386) (xy 117.216213 -224.400918) (xy 117.186837 -224.441351) (xy 117.151497 -224.476691)
			(xy 117.111064 -224.506067) (xy 117.066532 -224.528757) (xy 117.019 -224.544201) (xy 116.969637 -224.55202)
			(xy 116.919659 -224.55202) (xy 116.870296 -224.544201) (xy 116.822764 -224.528757) (xy 116.778232 -224.506067)
			(xy 116.737799 -224.476691) (xy 116.702459 -224.441351) (xy 116.673083 -224.400918) (xy 116.650393 -224.356386)
			(xy 116.634949 -224.308854) (xy 116.62713 -224.259491) (xy 116.322366 -224.259491) (xy 116.314547 -224.308854)
			(xy 116.299103 -224.356386) (xy 116.276413 -224.400918) (xy 116.247037 -224.441351) (xy 116.211697 -224.476691)
			(xy 116.171264 -224.506067) (xy 116.126732 -224.528757) (xy 116.0792 -224.544201) (xy 116.029837 -224.55202)
			(xy 115.979859 -224.55202) (xy 115.930496 -224.544201) (xy 115.882964 -224.528757) (xy 115.838432 -224.506067)
			(xy 115.797999 -224.476691) (xy 115.762659 -224.441351) (xy 115.733283 -224.400918) (xy 115.710593 -224.356386)
			(xy 115.695149 -224.308854) (xy 115.68733 -224.259491) (xy 115.382312 -224.259491) (xy 115.374493 -224.308854)
			(xy 115.359049 -224.356386) (xy 115.336359 -224.400918) (xy 115.306983 -224.441351) (xy 115.271643 -224.476691)
			(xy 115.23121 -224.506067) (xy 115.186678 -224.528757) (xy 115.139146 -224.544201) (xy 115.089783 -224.55202)
			(xy 115.039805 -224.55202) (xy 114.990442 -224.544201) (xy 114.94291 -224.528757) (xy 114.898378 -224.506067)
			(xy 114.857945 -224.476691) (xy 114.822605 -224.441351) (xy 114.793229 -224.400918) (xy 114.770539 -224.356386)
			(xy 114.755095 -224.308854) (xy 114.747276 -224.259491) (xy 114.442258 -224.259491) (xy 114.434439 -224.308854)
			(xy 114.418995 -224.356386) (xy 114.396305 -224.400918) (xy 114.366929 -224.441351) (xy 114.331589 -224.476691)
			(xy 114.291156 -224.506067) (xy 114.246624 -224.528757) (xy 114.199092 -224.544201) (xy 114.149729 -224.55202)
			(xy 114.099751 -224.55202) (xy 114.050388 -224.544201) (xy 114.002856 -224.528757) (xy 113.958324 -224.506067)
			(xy 113.917891 -224.476691) (xy 113.882551 -224.441351) (xy 113.853175 -224.400918) (xy 113.830485 -224.356386)
			(xy 113.815041 -224.308854) (xy 113.807222 -224.259491) (xy 113.502204 -224.259491) (xy 113.494385 -224.308854)
			(xy 113.478941 -224.356386) (xy 113.456251 -224.400918) (xy 113.426875 -224.441351) (xy 113.391535 -224.476691)
			(xy 113.351102 -224.506067) (xy 113.30657 -224.528757) (xy 113.259038 -224.544201) (xy 113.209675 -224.55202)
			(xy 113.159697 -224.55202) (xy 113.110334 -224.544201) (xy 113.062802 -224.528757) (xy 113.01827 -224.506067)
			(xy 112.977837 -224.476691) (xy 112.942497 -224.441351) (xy 112.913121 -224.400918) (xy 112.890431 -224.356386)
			(xy 112.874987 -224.308854) (xy 112.867168 -224.259491) (xy 109.748592 -224.259491) (xy 109.740773 -224.308854)
			(xy 109.725329 -224.356386) (xy 109.702639 -224.400918) (xy 109.673263 -224.441351) (xy 109.637923 -224.476691)
			(xy 109.59749 -224.506067) (xy 109.552958 -224.528757) (xy 109.505426 -224.544201) (xy 109.456063 -224.55202)
			(xy 109.406085 -224.55202) (xy 109.356722 -224.544201) (xy 109.30919 -224.528757) (xy 109.264658 -224.506067)
			(xy 109.224225 -224.476691) (xy 109.188885 -224.441351) (xy 109.159509 -224.400918) (xy 109.136819 -224.356386)
			(xy 109.121375 -224.308854) (xy 109.113556 -224.259491) (xy 108.808538 -224.259491) (xy 108.800719 -224.308854)
			(xy 108.785275 -224.356386) (xy 108.762585 -224.400918) (xy 108.733209 -224.441351) (xy 108.697869 -224.476691)
			(xy 108.657436 -224.506067) (xy 108.612904 -224.528757) (xy 108.565372 -224.544201) (xy 108.516009 -224.55202)
			(xy 108.466031 -224.55202) (xy 108.416668 -224.544201) (xy 108.369136 -224.528757) (xy 108.324604 -224.506067)
			(xy 108.284171 -224.476691) (xy 108.248831 -224.441351) (xy 108.219455 -224.400918) (xy 108.196765 -224.356386)
			(xy 108.181321 -224.308854) (xy 108.173502 -224.259491) (xy 107.868527 -224.259491) (xy 107.860875 -224.308233)
			(xy 107.845689 -224.355403) (xy 107.82337 -224.399647) (xy 107.794459 -224.439894) (xy 107.759655 -224.47517)
			(xy 107.719801 -224.504621) (xy 107.675862 -224.527534) (xy 107.6289 -224.543354) (xy 107.580053 -224.551699)
			(xy 107.555284 -224.55251) (xy 107.550458 -224.55251) (xy 107.530162 -224.552158) (xy 107.489907 -224.546939)
			(xy 107.470194 -224.542096) (xy 107.45851 -224.539048) (xy 107.447588 -224.541334) (xy 107.441872 -224.542626)
			(xy 107.431224 -224.54751) (xy 107.426506 -224.550986) (xy 107.418124 -224.55759) (xy 107.417616 -224.55759)
			(xy 107.362244 -224.60077) (xy 107.355011 -224.607566) (xy 107.345984 -224.625217) (xy 107.344718 -224.63506)
			(xy 107.344718 -224.635568) (xy 107.344464 -224.639378) (xy 107.344464 -224.847912) (xy 107.346496 -224.861882)
			(xy 107.34802 -224.86747) (xy 107.353608 -224.88017) (xy 107.355132 -224.882964) (xy 107.368918 -224.907587)
			(xy 107.388514 -224.960501) (xy 107.398472 -225.016041) (xy 107.399074 -225.044254) (xy 107.399074 -225.044762)
			(xy 107.398549 -225.069497) (xy 113.337322 -225.069497) (xy 113.337322 -225.019519) (xy 113.345141 -224.970156)
			(xy 113.360585 -224.922624) (xy 113.383275 -224.878092) (xy 113.412651 -224.837659) (xy 113.447991 -224.802319)
			(xy 113.488424 -224.772943) (xy 113.532956 -224.750253) (xy 113.580488 -224.734809) (xy 113.629851 -224.72699)
			(xy 113.679829 -224.72699) (xy 113.729192 -224.734809) (xy 113.776724 -224.750253) (xy 113.821256 -224.772943)
			(xy 113.861689 -224.802319) (xy 113.897029 -224.837659) (xy 113.926405 -224.878092) (xy 113.949095 -224.922624)
			(xy 113.964539 -224.970156) (xy 113.972358 -225.019519) (xy 113.972848 -225.044508) (xy 113.972358 -225.069497)
			(xy 116.15723 -225.069497) (xy 116.15723 -225.019519) (xy 116.165049 -224.970156) (xy 116.180493 -224.922624)
			(xy 116.203183 -224.878092) (xy 116.232559 -224.837659) (xy 116.267899 -224.802319) (xy 116.308332 -224.772943)
			(xy 116.352864 -224.750253) (xy 116.400396 -224.734809) (xy 116.449759 -224.72699) (xy 116.499737 -224.72699)
			(xy 116.5491 -224.734809) (xy 116.596632 -224.750253) (xy 116.641164 -224.772943) (xy 116.681597 -224.802319)
			(xy 116.716937 -224.837659) (xy 116.746313 -224.878092) (xy 116.769003 -224.922624) (xy 116.784447 -224.970156)
			(xy 116.792266 -225.019519) (xy 116.792756 -225.044508) (xy 116.792266 -225.069497) (xy 117.097284 -225.069497)
			(xy 117.097284 -225.019519) (xy 117.105103 -224.970156) (xy 117.120547 -224.922624) (xy 117.143237 -224.878092)
			(xy 117.172613 -224.837659) (xy 117.207953 -224.802319) (xy 117.248386 -224.772943) (xy 117.292918 -224.750253)
			(xy 117.34045 -224.734809) (xy 117.389813 -224.72699) (xy 117.439791 -224.72699) (xy 117.489154 -224.734809)
			(xy 117.536686 -224.750253) (xy 117.581218 -224.772943) (xy 117.621651 -224.802319) (xy 117.656991 -224.837659)
			(xy 117.686367 -224.878092) (xy 117.709057 -224.922624) (xy 117.724501 -224.970156) (xy 117.73232 -225.019519)
			(xy 117.73281 -225.044508) (xy 117.73232 -225.069497) (xy 118.977138 -225.069497) (xy 118.977138 -225.019519)
			(xy 118.984957 -224.970156) (xy 119.000401 -224.922624) (xy 119.023091 -224.878092) (xy 119.052467 -224.837659)
			(xy 119.087807 -224.802319) (xy 119.12824 -224.772943) (xy 119.172772 -224.750253) (xy 119.220304 -224.734809)
			(xy 119.269667 -224.72699) (xy 119.319645 -224.72699) (xy 119.369008 -224.734809) (xy 119.41654 -224.750253)
			(xy 119.461072 -224.772943) (xy 119.501505 -224.802319) (xy 119.536845 -224.837659) (xy 119.566221 -224.878092)
			(xy 119.588911 -224.922624) (xy 119.604355 -224.970156) (xy 119.612174 -225.019519) (xy 119.612664 -225.044508)
			(xy 119.612174 -225.069497) (xy 119.917192 -225.069497) (xy 119.917192 -225.019519) (xy 119.925011 -224.970156)
			(xy 119.940455 -224.922624) (xy 119.963145 -224.878092) (xy 119.992521 -224.837659) (xy 120.027861 -224.802319)
			(xy 120.068294 -224.772943) (xy 120.112826 -224.750253) (xy 120.160358 -224.734809) (xy 120.209721 -224.72699)
			(xy 120.259699 -224.72699) (xy 120.309062 -224.734809) (xy 120.356594 -224.750253) (xy 120.401126 -224.772943)
			(xy 120.441559 -224.802319) (xy 120.476899 -224.837659) (xy 120.506275 -224.878092) (xy 120.528965 -224.922624)
			(xy 120.544409 -224.970156) (xy 120.552228 -225.019519) (xy 120.552718 -225.044508) (xy 120.552228 -225.069497)
			(xy 121.7973 -225.069497) (xy 121.7973 -225.019519) (xy 121.805119 -224.970156) (xy 121.820563 -224.922624)
			(xy 121.843253 -224.878092) (xy 121.872629 -224.837659) (xy 121.907969 -224.802319) (xy 121.948402 -224.772943)
			(xy 121.992934 -224.750253) (xy 122.040466 -224.734809) (xy 122.089829 -224.72699) (xy 122.139807 -224.72699)
			(xy 122.18917 -224.734809) (xy 122.236702 -224.750253) (xy 122.281234 -224.772943) (xy 122.321667 -224.802319)
			(xy 122.357007 -224.837659) (xy 122.386383 -224.878092) (xy 122.409073 -224.922624) (xy 122.424517 -224.970156)
			(xy 122.432336 -225.019519) (xy 122.432826 -225.044508) (xy 122.432336 -225.069497) (xy 122.7371 -225.069497)
			(xy 122.7371 -225.019519) (xy 122.744919 -224.970156) (xy 122.760363 -224.922624) (xy 122.783053 -224.878092)
			(xy 122.812429 -224.837659) (xy 122.847769 -224.802319) (xy 122.888202 -224.772943) (xy 122.932734 -224.750253)
			(xy 122.980266 -224.734809) (xy 123.029629 -224.72699) (xy 123.079607 -224.72699) (xy 123.12897 -224.734809)
			(xy 123.176502 -224.750253) (xy 123.221034 -224.772943) (xy 123.261467 -224.802319) (xy 123.296807 -224.837659)
			(xy 123.326183 -224.878092) (xy 123.348873 -224.922624) (xy 123.364317 -224.970156) (xy 123.372136 -225.019519)
			(xy 123.372626 -225.044508) (xy 123.372136 -225.069497) (xy 124.617208 -225.069497) (xy 124.617208 -225.019519)
			(xy 124.625027 -224.970156) (xy 124.640471 -224.922624) (xy 124.663161 -224.878092) (xy 124.692537 -224.837659)
			(xy 124.727877 -224.802319) (xy 124.76831 -224.772943) (xy 124.812842 -224.750253) (xy 124.860374 -224.734809)
			(xy 124.909737 -224.72699) (xy 124.959715 -224.72699) (xy 125.009078 -224.734809) (xy 125.05661 -224.750253)
			(xy 125.101142 -224.772943) (xy 125.141575 -224.802319) (xy 125.176915 -224.837659) (xy 125.206291 -224.878092)
			(xy 125.228981 -224.922624) (xy 125.244425 -224.970156) (xy 125.252244 -225.019519) (xy 125.252734 -225.044508)
			(xy 125.252244 -225.069497) (xy 125.557262 -225.069497) (xy 125.557262 -225.019519) (xy 125.565081 -224.970156)
			(xy 125.580525 -224.922624) (xy 125.603215 -224.878092) (xy 125.632591 -224.837659) (xy 125.667931 -224.802319)
			(xy 125.708364 -224.772943) (xy 125.752896 -224.750253) (xy 125.800428 -224.734809) (xy 125.849791 -224.72699)
			(xy 125.899769 -224.72699) (xy 125.949132 -224.734809) (xy 125.996664 -224.750253) (xy 126.041196 -224.772943)
			(xy 126.081629 -224.802319) (xy 126.116969 -224.837659) (xy 126.146345 -224.878092) (xy 126.169035 -224.922624)
			(xy 126.184479 -224.970156) (xy 126.192298 -225.019519) (xy 126.192788 -225.044508) (xy 126.192298 -225.069497)
			(xy 127.437116 -225.069497) (xy 127.437116 -225.019519) (xy 127.444935 -224.970156) (xy 127.460379 -224.922624)
			(xy 127.483069 -224.878092) (xy 127.512445 -224.837659) (xy 127.547785 -224.802319) (xy 127.588218 -224.772943)
			(xy 127.63275 -224.750253) (xy 127.680282 -224.734809) (xy 127.729645 -224.72699) (xy 127.779623 -224.72699)
			(xy 127.828986 -224.734809) (xy 127.876518 -224.750253) (xy 127.92105 -224.772943) (xy 127.961483 -224.802319)
			(xy 127.996823 -224.837659) (xy 128.026199 -224.878092) (xy 128.048889 -224.922624) (xy 128.064333 -224.970156)
			(xy 128.072152 -225.019519) (xy 128.072642 -225.044508) (xy 128.072152 -225.069497) (xy 128.064333 -225.11886)
			(xy 128.048889 -225.166392) (xy 128.026199 -225.210924) (xy 127.996823 -225.251357) (xy 127.961483 -225.286697)
			(xy 127.92105 -225.316073) (xy 127.876518 -225.338763) (xy 127.828986 -225.354207) (xy 127.779623 -225.362026)
			(xy 127.729645 -225.362026) (xy 127.680282 -225.354207) (xy 127.63275 -225.338763) (xy 127.588218 -225.316073)
			(xy 127.547785 -225.286697) (xy 127.512445 -225.251357) (xy 127.483069 -225.210924) (xy 127.460379 -225.166392)
			(xy 127.444935 -225.11886) (xy 127.437116 -225.069497) (xy 126.192298 -225.069497) (xy 126.184479 -225.11886)
			(xy 126.169035 -225.166392) (xy 126.146345 -225.210924) (xy 126.116969 -225.251357) (xy 126.081629 -225.286697)
			(xy 126.041196 -225.316073) (xy 125.996664 -225.338763) (xy 125.949132 -225.354207) (xy 125.899769 -225.362026)
			(xy 125.849791 -225.362026) (xy 125.800428 -225.354207) (xy 125.752896 -225.338763) (xy 125.708364 -225.316073)
			(xy 125.667931 -225.286697) (xy 125.632591 -225.251357) (xy 125.603215 -225.210924) (xy 125.580525 -225.166392)
			(xy 125.565081 -225.11886) (xy 125.557262 -225.069497) (xy 125.252244 -225.069497) (xy 125.244425 -225.11886)
			(xy 125.228981 -225.166392) (xy 125.206291 -225.210924) (xy 125.176915 -225.251357) (xy 125.141575 -225.286697)
			(xy 125.101142 -225.316073) (xy 125.05661 -225.338763) (xy 125.009078 -225.354207) (xy 124.959715 -225.362026)
			(xy 124.909737 -225.362026) (xy 124.860374 -225.354207) (xy 124.812842 -225.338763) (xy 124.76831 -225.316073)
			(xy 124.727877 -225.286697) (xy 124.692537 -225.251357) (xy 124.663161 -225.210924) (xy 124.640471 -225.166392)
			(xy 124.625027 -225.11886) (xy 124.617208 -225.069497) (xy 123.372136 -225.069497) (xy 123.364317 -225.11886)
			(xy 123.348873 -225.166392) (xy 123.326183 -225.210924) (xy 123.296807 -225.251357) (xy 123.261467 -225.286697)
			(xy 123.221034 -225.316073) (xy 123.176502 -225.338763) (xy 123.12897 -225.354207) (xy 123.079607 -225.362026)
			(xy 123.029629 -225.362026) (xy 122.980266 -225.354207) (xy 122.932734 -225.338763) (xy 122.888202 -225.316073)
			(xy 122.847769 -225.286697) (xy 122.812429 -225.251357) (xy 122.783053 -225.210924) (xy 122.760363 -225.166392)
			(xy 122.744919 -225.11886) (xy 122.7371 -225.069497) (xy 122.432336 -225.069497) (xy 122.424517 -225.11886)
			(xy 122.409073 -225.166392) (xy 122.386383 -225.210924) (xy 122.357007 -225.251357) (xy 122.321667 -225.286697)
			(xy 122.281234 -225.316073) (xy 122.236702 -225.338763) (xy 122.18917 -225.354207) (xy 122.139807 -225.362026)
			(xy 122.089829 -225.362026) (xy 122.040466 -225.354207) (xy 121.992934 -225.338763) (xy 121.948402 -225.316073)
			(xy 121.907969 -225.286697) (xy 121.872629 -225.251357) (xy 121.843253 -225.210924) (xy 121.820563 -225.166392)
			(xy 121.805119 -225.11886) (xy 121.7973 -225.069497) (xy 120.552228 -225.069497) (xy 120.544409 -225.11886)
			(xy 120.528965 -225.166392) (xy 120.506275 -225.210924) (xy 120.476899 -225.251357) (xy 120.441559 -225.286697)
			(xy 120.401126 -225.316073) (xy 120.356594 -225.338763) (xy 120.309062 -225.354207) (xy 120.259699 -225.362026)
			(xy 120.209721 -225.362026) (xy 120.160358 -225.354207) (xy 120.112826 -225.338763) (xy 120.068294 -225.316073)
			(xy 120.027861 -225.286697) (xy 119.992521 -225.251357) (xy 119.963145 -225.210924) (xy 119.940455 -225.166392)
			(xy 119.925011 -225.11886) (xy 119.917192 -225.069497) (xy 119.612174 -225.069497) (xy 119.604355 -225.11886)
			(xy 119.588911 -225.166392) (xy 119.566221 -225.210924) (xy 119.536845 -225.251357) (xy 119.501505 -225.286697)
			(xy 119.461072 -225.316073) (xy 119.41654 -225.338763) (xy 119.369008 -225.354207) (xy 119.319645 -225.362026)
			(xy 119.269667 -225.362026) (xy 119.220304 -225.354207) (xy 119.172772 -225.338763) (xy 119.12824 -225.316073)
			(xy 119.087807 -225.286697) (xy 119.052467 -225.251357) (xy 119.023091 -225.210924) (xy 119.000401 -225.166392)
			(xy 118.984957 -225.11886) (xy 118.977138 -225.069497) (xy 117.73232 -225.069497) (xy 117.724501 -225.11886)
			(xy 117.709057 -225.166392) (xy 117.686367 -225.210924) (xy 117.656991 -225.251357) (xy 117.621651 -225.286697)
			(xy 117.581218 -225.316073) (xy 117.536686 -225.338763) (xy 117.489154 -225.354207) (xy 117.439791 -225.362026)
			(xy 117.389813 -225.362026) (xy 117.34045 -225.354207) (xy 117.292918 -225.338763) (xy 117.248386 -225.316073)
			(xy 117.207953 -225.286697) (xy 117.172613 -225.251357) (xy 117.143237 -225.210924) (xy 117.120547 -225.166392)
			(xy 117.105103 -225.11886) (xy 117.097284 -225.069497) (xy 116.792266 -225.069497) (xy 116.784447 -225.11886)
			(xy 116.769003 -225.166392) (xy 116.746313 -225.210924) (xy 116.716937 -225.251357) (xy 116.681597 -225.286697)
			(xy 116.641164 -225.316073) (xy 116.596632 -225.338763) (xy 116.5491 -225.354207) (xy 116.499737 -225.362026)
			(xy 116.449759 -225.362026) (xy 116.400396 -225.354207) (xy 116.352864 -225.338763) (xy 116.308332 -225.316073)
			(xy 116.267899 -225.286697) (xy 116.232559 -225.251357) (xy 116.203183 -225.210924) (xy 116.180493 -225.166392)
			(xy 116.165049 -225.11886) (xy 116.15723 -225.069497) (xy 113.972358 -225.069497) (xy 113.964539 -225.11886)
			(xy 113.949095 -225.166392) (xy 113.926405 -225.210924) (xy 113.897029 -225.251357) (xy 113.861689 -225.286697)
			(xy 113.821256 -225.316073) (xy 113.776724 -225.338763) (xy 113.729192 -225.354207) (xy 113.679829 -225.362026)
			(xy 113.629851 -225.362026) (xy 113.580488 -225.354207) (xy 113.532956 -225.338763) (xy 113.488424 -225.316073)
			(xy 113.447991 -225.286697) (xy 113.412651 -225.251357) (xy 113.383275 -225.210924) (xy 113.360585 -225.166392)
			(xy 113.345141 -225.11886) (xy 113.337322 -225.069497) (xy 107.398549 -225.069497) (xy 107.398483 -225.072592)
			(xy 107.388759 -225.127397) (xy 107.369638 -225.179671) (xy 107.356148 -225.20402) (xy 107.354878 -225.206052)
			(xy 107.34802 -225.22053) (xy 107.347004 -225.225102) (xy 107.344464 -225.2345) (xy 107.344464 -225.47199)
			(xy 107.343926 -225.481827) (xy 107.336341 -225.499989) (xy 107.329732 -225.507296) (xy 107.232196 -225.604832)
			(xy 107.224957 -225.611544) (xy 107.206753 -225.619138) (xy 107.19689 -225.619564) (xy 107.01274 -225.619564)
			(xy 107.00766 -225.619818) (xy 107.001564 -225.620834) (xy 106.998262 -225.621342) (xy 106.988529 -225.62328)
			(xy 106.971525 -225.633473) (xy 106.965242 -225.641154) (xy 106.957876 -225.652076) (xy 106.957368 -225.652838)
			(xy 106.92892 -225.692716) (xy 106.928666 -225.693224) (xy 106.917744 -225.708972) (xy 106.914928 -225.713526)
			(xy 106.911081 -225.723516) (xy 106.910124 -225.728784) (xy 106.908346 -225.740214) (xy 106.91241 -225.752406)
			(xy 106.919706 -225.775307) (xy 106.928122 -225.822628) (xy 106.929174 -225.84664) (xy 106.929174 -225.857054)
			(xy 106.92856 -225.879503) (xy 108.173502 -225.879503) (xy 108.173502 -225.829525) (xy 108.181321 -225.780162)
			(xy 108.196765 -225.73263) (xy 108.219455 -225.688098) (xy 108.248831 -225.647665) (xy 108.284171 -225.612325)
			(xy 108.324604 -225.582949) (xy 108.369136 -225.560259) (xy 108.416668 -225.544815) (xy 108.466031 -225.536996)
			(xy 108.516009 -225.536996) (xy 108.565372 -225.544815) (xy 108.612904 -225.560259) (xy 108.657436 -225.582949)
			(xy 108.697869 -225.612325) (xy 108.733209 -225.647665) (xy 108.762585 -225.688098) (xy 108.785275 -225.73263)
			(xy 108.800719 -225.780162) (xy 108.808538 -225.829525) (xy 108.809028 -225.854514) (xy 108.808538 -225.879503)
			(xy 109.113556 -225.879503) (xy 109.113556 -225.829525) (xy 109.121375 -225.780162) (xy 109.136819 -225.73263)
			(xy 109.159509 -225.688098) (xy 109.188885 -225.647665) (xy 109.224225 -225.612325) (xy 109.264658 -225.582949)
			(xy 109.30919 -225.560259) (xy 109.356722 -225.544815) (xy 109.406085 -225.536996) (xy 109.456063 -225.536996)
			(xy 109.505426 -225.544815) (xy 109.552958 -225.560259) (xy 109.59749 -225.582949) (xy 109.637923 -225.612325)
			(xy 109.673263 -225.647665) (xy 109.702639 -225.688098) (xy 109.725329 -225.73263) (xy 109.740773 -225.780162)
			(xy 109.748592 -225.829525) (xy 109.749082 -225.854514) (xy 109.748592 -225.879503) (xy 110.05361 -225.879503)
			(xy 110.05361 -225.829525) (xy 110.061429 -225.780162) (xy 110.076873 -225.73263) (xy 110.099563 -225.688098)
			(xy 110.128939 -225.647665) (xy 110.164279 -225.612325) (xy 110.204712 -225.582949) (xy 110.249244 -225.560259)
			(xy 110.296776 -225.544815) (xy 110.346139 -225.536996) (xy 110.396117 -225.536996) (xy 110.44548 -225.544815)
			(xy 110.493012 -225.560259) (xy 110.537544 -225.582949) (xy 110.577977 -225.612325) (xy 110.613317 -225.647665)
			(xy 110.642693 -225.688098) (xy 110.665383 -225.73263) (xy 110.680827 -225.780162) (xy 110.688646 -225.829525)
			(xy 110.689136 -225.854514) (xy 110.688646 -225.879503) (xy 112.867168 -225.879503) (xy 112.867168 -225.829525)
			(xy 112.874987 -225.780162) (xy 112.890431 -225.73263) (xy 112.913121 -225.688098) (xy 112.942497 -225.647665)
			(xy 112.977837 -225.612325) (xy 113.01827 -225.582949) (xy 113.062802 -225.560259) (xy 113.110334 -225.544815)
			(xy 113.159697 -225.536996) (xy 113.209675 -225.536996) (xy 113.259038 -225.544815) (xy 113.30657 -225.560259)
			(xy 113.351102 -225.582949) (xy 113.391535 -225.612325) (xy 113.426875 -225.647665) (xy 113.456251 -225.688098)
			(xy 113.478941 -225.73263) (xy 113.494385 -225.780162) (xy 113.502204 -225.829525) (xy 113.502694 -225.854514)
			(xy 113.502204 -225.879503) (xy 113.807222 -225.879503) (xy 113.807222 -225.829525) (xy 113.815041 -225.780162)
			(xy 113.830485 -225.73263) (xy 113.853175 -225.688098) (xy 113.882551 -225.647665) (xy 113.917891 -225.612325)
			(xy 113.958324 -225.582949) (xy 114.002856 -225.560259) (xy 114.050388 -225.544815) (xy 114.099751 -225.536996)
			(xy 114.149729 -225.536996) (xy 114.199092 -225.544815) (xy 114.246624 -225.560259) (xy 114.291156 -225.582949)
			(xy 114.331589 -225.612325) (xy 114.366929 -225.647665) (xy 114.396305 -225.688098) (xy 114.418995 -225.73263)
			(xy 114.434439 -225.780162) (xy 114.442258 -225.829525) (xy 114.442748 -225.854514) (xy 114.442258 -225.879503)
			(xy 114.747276 -225.879503) (xy 114.747276 -225.829525) (xy 114.755095 -225.780162) (xy 114.770539 -225.73263)
			(xy 114.793229 -225.688098) (xy 114.822605 -225.647665) (xy 114.857945 -225.612325) (xy 114.898378 -225.582949)
			(xy 114.94291 -225.560259) (xy 114.990442 -225.544815) (xy 115.039805 -225.536996) (xy 115.089783 -225.536996)
			(xy 115.139146 -225.544815) (xy 115.186678 -225.560259) (xy 115.23121 -225.582949) (xy 115.271643 -225.612325)
			(xy 115.306983 -225.647665) (xy 115.336359 -225.688098) (xy 115.359049 -225.73263) (xy 115.374493 -225.780162)
			(xy 115.382312 -225.829525) (xy 115.382802 -225.854514) (xy 115.382312 -225.879503) (xy 116.62713 -225.879503)
			(xy 116.62713 -225.829525) (xy 116.634949 -225.780162) (xy 116.650393 -225.73263) (xy 116.673083 -225.688098)
			(xy 116.702459 -225.647665) (xy 116.737799 -225.612325) (xy 116.778232 -225.582949) (xy 116.822764 -225.560259)
			(xy 116.870296 -225.544815) (xy 116.919659 -225.536996) (xy 116.969637 -225.536996) (xy 117.019 -225.544815)
			(xy 117.066532 -225.560259) (xy 117.111064 -225.582949) (xy 117.151497 -225.612325) (xy 117.186837 -225.647665)
			(xy 117.216213 -225.688098) (xy 117.238903 -225.73263) (xy 117.254347 -225.780162) (xy 117.262166 -225.829525)
			(xy 117.262656 -225.854514) (xy 117.262166 -225.879503) (xy 117.567184 -225.879503) (xy 117.567184 -225.829525)
			(xy 117.575003 -225.780162) (xy 117.590447 -225.73263) (xy 117.613137 -225.688098) (xy 117.642513 -225.647665)
			(xy 117.677853 -225.612325) (xy 117.718286 -225.582949) (xy 117.762818 -225.560259) (xy 117.81035 -225.544815)
			(xy 117.859713 -225.536996) (xy 117.909691 -225.536996) (xy 117.959054 -225.544815) (xy 118.006586 -225.560259)
			(xy 118.051118 -225.582949) (xy 118.091551 -225.612325) (xy 118.126891 -225.647665) (xy 118.156267 -225.688098)
			(xy 118.178957 -225.73263) (xy 118.194401 -225.780162) (xy 118.20222 -225.829525) (xy 118.20271 -225.854514)
			(xy 118.20222 -225.879503) (xy 119.447292 -225.879503) (xy 119.447292 -225.829525) (xy 119.455111 -225.780162)
			(xy 119.470555 -225.73263) (xy 119.493245 -225.688098) (xy 119.522621 -225.647665) (xy 119.557961 -225.612325)
			(xy 119.598394 -225.582949) (xy 119.642926 -225.560259) (xy 119.690458 -225.544815) (xy 119.739821 -225.536996)
			(xy 119.789799 -225.536996) (xy 119.839162 -225.544815) (xy 119.886694 -225.560259) (xy 119.931226 -225.582949)
			(xy 119.971659 -225.612325) (xy 120.006999 -225.647665) (xy 120.036375 -225.688098) (xy 120.059065 -225.73263)
			(xy 120.074509 -225.780162) (xy 120.082328 -225.829525) (xy 120.082818 -225.854514) (xy 120.082328 -225.879503)
			(xy 120.387092 -225.879503) (xy 120.387092 -225.829525) (xy 120.394911 -225.780162) (xy 120.410355 -225.73263)
			(xy 120.433045 -225.688098) (xy 120.462421 -225.647665) (xy 120.497761 -225.612325) (xy 120.538194 -225.582949)
			(xy 120.582726 -225.560259) (xy 120.630258 -225.544815) (xy 120.679621 -225.536996) (xy 120.729599 -225.536996)
			(xy 120.778962 -225.544815) (xy 120.826494 -225.560259) (xy 120.871026 -225.582949) (xy 120.911459 -225.612325)
			(xy 120.946799 -225.647665) (xy 120.976175 -225.688098) (xy 120.998865 -225.73263) (xy 121.014309 -225.780162)
			(xy 121.022128 -225.829525) (xy 121.022618 -225.854514) (xy 121.022128 -225.879503) (xy 122.2672 -225.879503)
			(xy 122.2672 -225.829525) (xy 122.275019 -225.780162) (xy 122.290463 -225.73263) (xy 122.313153 -225.688098)
			(xy 122.342529 -225.647665) (xy 122.377869 -225.612325) (xy 122.418302 -225.582949) (xy 122.462834 -225.560259)
			(xy 122.510366 -225.544815) (xy 122.559729 -225.536996) (xy 122.609707 -225.536996) (xy 122.65907 -225.544815)
			(xy 122.706602 -225.560259) (xy 122.751134 -225.582949) (xy 122.791567 -225.612325) (xy 122.826907 -225.647665)
			(xy 122.856283 -225.688098) (xy 122.878973 -225.73263) (xy 122.894417 -225.780162) (xy 122.902236 -225.829525)
			(xy 122.902726 -225.854514) (xy 122.902236 -225.879503) (xy 123.207254 -225.879503) (xy 123.207254 -225.829525)
			(xy 123.215073 -225.780162) (xy 123.230517 -225.73263) (xy 123.253207 -225.688098) (xy 123.282583 -225.647665)
			(xy 123.317923 -225.612325) (xy 123.358356 -225.582949) (xy 123.402888 -225.560259) (xy 123.45042 -225.544815)
			(xy 123.499783 -225.536996) (xy 123.549761 -225.536996) (xy 123.599124 -225.544815) (xy 123.646656 -225.560259)
			(xy 123.691188 -225.582949) (xy 123.731621 -225.612325) (xy 123.766961 -225.647665) (xy 123.796337 -225.688098)
			(xy 123.819027 -225.73263) (xy 123.834471 -225.780162) (xy 123.84229 -225.829525) (xy 123.84278 -225.854514)
			(xy 123.84229 -225.879503) (xy 125.087108 -225.879503) (xy 125.087108 -225.829525) (xy 125.094927 -225.780162)
			(xy 125.110371 -225.73263) (xy 125.133061 -225.688098) (xy 125.162437 -225.647665) (xy 125.197777 -225.612325)
			(xy 125.23821 -225.582949) (xy 125.282742 -225.560259) (xy 125.330274 -225.544815) (xy 125.379637 -225.536996)
			(xy 125.429615 -225.536996) (xy 125.478978 -225.544815) (xy 125.52651 -225.560259) (xy 125.571042 -225.582949)
			(xy 125.611475 -225.612325) (xy 125.646815 -225.647665) (xy 125.676191 -225.688098) (xy 125.698881 -225.73263)
			(xy 125.714325 -225.780162) (xy 125.722144 -225.829525) (xy 125.722634 -225.854514) (xy 125.722144 -225.879503)
			(xy 126.027162 -225.879503) (xy 126.027162 -225.829525) (xy 126.034981 -225.780162) (xy 126.050425 -225.73263)
			(xy 126.073115 -225.688098) (xy 126.102491 -225.647665) (xy 126.137831 -225.612325) (xy 126.178264 -225.582949)
			(xy 126.222796 -225.560259) (xy 126.270328 -225.544815) (xy 126.319691 -225.536996) (xy 126.369669 -225.536996)
			(xy 126.419032 -225.544815) (xy 126.466564 -225.560259) (xy 126.511096 -225.582949) (xy 126.551529 -225.612325)
			(xy 126.586869 -225.647665) (xy 126.616245 -225.688098) (xy 126.638935 -225.73263) (xy 126.654379 -225.780162)
			(xy 126.662198 -225.829525) (xy 126.662688 -225.854514) (xy 126.662198 -225.879503) (xy 126.654379 -225.928866)
			(xy 126.638935 -225.976398) (xy 126.616245 -226.02093) (xy 126.586869 -226.061363) (xy 126.551529 -226.096703)
			(xy 126.511096 -226.126079) (xy 126.466564 -226.148769) (xy 126.419032 -226.164213) (xy 126.369669 -226.172032)
			(xy 126.319691 -226.172032) (xy 126.270328 -226.164213) (xy 126.222796 -226.148769) (xy 126.178264 -226.126079)
			(xy 126.137831 -226.096703) (xy 126.102491 -226.061363) (xy 126.073115 -226.02093) (xy 126.050425 -225.976398)
			(xy 126.034981 -225.928866) (xy 126.027162 -225.879503) (xy 125.722144 -225.879503) (xy 125.714325 -225.928866)
			(xy 125.698881 -225.976398) (xy 125.676191 -226.02093) (xy 125.646815 -226.061363) (xy 125.611475 -226.096703)
			(xy 125.571042 -226.126079) (xy 125.52651 -226.148769) (xy 125.478978 -226.164213) (xy 125.429615 -226.172032)
			(xy 125.379637 -226.172032) (xy 125.330274 -226.164213) (xy 125.282742 -226.148769) (xy 125.23821 -226.126079)
			(xy 125.197777 -226.096703) (xy 125.162437 -226.061363) (xy 125.133061 -226.02093) (xy 125.110371 -225.976398)
			(xy 125.094927 -225.928866) (xy 125.087108 -225.879503) (xy 123.84229 -225.879503) (xy 123.834471 -225.928866)
			(xy 123.819027 -225.976398) (xy 123.796337 -226.02093) (xy 123.766961 -226.061363) (xy 123.731621 -226.096703)
			(xy 123.691188 -226.126079) (xy 123.646656 -226.148769) (xy 123.599124 -226.164213) (xy 123.549761 -226.172032)
			(xy 123.499783 -226.172032) (xy 123.45042 -226.164213) (xy 123.402888 -226.148769) (xy 123.358356 -226.126079)
			(xy 123.317923 -226.096703) (xy 123.282583 -226.061363) (xy 123.253207 -226.02093) (xy 123.230517 -225.976398)
			(xy 123.215073 -225.928866) (xy 123.207254 -225.879503) (xy 122.902236 -225.879503) (xy 122.894417 -225.928866)
			(xy 122.878973 -225.976398) (xy 122.856283 -226.02093) (xy 122.826907 -226.061363) (xy 122.791567 -226.096703)
			(xy 122.751134 -226.126079) (xy 122.706602 -226.148769) (xy 122.65907 -226.164213) (xy 122.609707 -226.172032)
			(xy 122.559729 -226.172032) (xy 122.510366 -226.164213) (xy 122.462834 -226.148769) (xy 122.418302 -226.126079)
			(xy 122.377869 -226.096703) (xy 122.342529 -226.061363) (xy 122.313153 -226.02093) (xy 122.290463 -225.976398)
			(xy 122.275019 -225.928866) (xy 122.2672 -225.879503) (xy 121.022128 -225.879503) (xy 121.014309 -225.928866)
			(xy 120.998865 -225.976398) (xy 120.976175 -226.02093) (xy 120.946799 -226.061363) (xy 120.911459 -226.096703)
			(xy 120.871026 -226.126079) (xy 120.826494 -226.148769) (xy 120.778962 -226.164213) (xy 120.729599 -226.172032)
			(xy 120.679621 -226.172032) (xy 120.630258 -226.164213) (xy 120.582726 -226.148769) (xy 120.538194 -226.126079)
			(xy 120.497761 -226.096703) (xy 120.462421 -226.061363) (xy 120.433045 -226.02093) (xy 120.410355 -225.976398)
			(xy 120.394911 -225.928866) (xy 120.387092 -225.879503) (xy 120.082328 -225.879503) (xy 120.074509 -225.928866)
			(xy 120.059065 -225.976398) (xy 120.036375 -226.02093) (xy 120.006999 -226.061363) (xy 119.971659 -226.096703)
			(xy 119.931226 -226.126079) (xy 119.886694 -226.148769) (xy 119.839162 -226.164213) (xy 119.789799 -226.172032)
			(xy 119.739821 -226.172032) (xy 119.690458 -226.164213) (xy 119.642926 -226.148769) (xy 119.598394 -226.126079)
			(xy 119.557961 -226.096703) (xy 119.522621 -226.061363) (xy 119.493245 -226.02093) (xy 119.470555 -225.976398)
			(xy 119.455111 -225.928866) (xy 119.447292 -225.879503) (xy 118.20222 -225.879503) (xy 118.194401 -225.928866)
			(xy 118.178957 -225.976398) (xy 118.156267 -226.02093) (xy 118.126891 -226.061363) (xy 118.091551 -226.096703)
			(xy 118.051118 -226.126079) (xy 118.006586 -226.148769) (xy 117.959054 -226.164213) (xy 117.909691 -226.172032)
			(xy 117.859713 -226.172032) (xy 117.81035 -226.164213) (xy 117.762818 -226.148769) (xy 117.718286 -226.126079)
			(xy 117.677853 -226.096703) (xy 117.642513 -226.061363) (xy 117.613137 -226.02093) (xy 117.590447 -225.976398)
			(xy 117.575003 -225.928866) (xy 117.567184 -225.879503) (xy 117.262166 -225.879503) (xy 117.254347 -225.928866)
			(xy 117.238903 -225.976398) (xy 117.216213 -226.02093) (xy 117.186837 -226.061363) (xy 117.151497 -226.096703)
			(xy 117.111064 -226.126079) (xy 117.066532 -226.148769) (xy 117.019 -226.164213) (xy 116.969637 -226.172032)
			(xy 116.919659 -226.172032) (xy 116.870296 -226.164213) (xy 116.822764 -226.148769) (xy 116.778232 -226.126079)
			(xy 116.737799 -226.096703) (xy 116.702459 -226.061363) (xy 116.673083 -226.02093) (xy 116.650393 -225.976398)
			(xy 116.634949 -225.928866) (xy 116.62713 -225.879503) (xy 115.382312 -225.879503) (xy 115.374493 -225.928866)
			(xy 115.359049 -225.976398) (xy 115.336359 -226.02093) (xy 115.306983 -226.061363) (xy 115.271643 -226.096703)
			(xy 115.23121 -226.126079) (xy 115.186678 -226.148769) (xy 115.139146 -226.164213) (xy 115.089783 -226.172032)
			(xy 115.039805 -226.172032) (xy 114.990442 -226.164213) (xy 114.94291 -226.148769) (xy 114.898378 -226.126079)
			(xy 114.857945 -226.096703) (xy 114.822605 -226.061363) (xy 114.793229 -226.02093) (xy 114.770539 -225.976398)
			(xy 114.755095 -225.928866) (xy 114.747276 -225.879503) (xy 114.442258 -225.879503) (xy 114.434439 -225.928866)
			(xy 114.418995 -225.976398) (xy 114.396305 -226.02093) (xy 114.366929 -226.061363) (xy 114.331589 -226.096703)
			(xy 114.291156 -226.126079) (xy 114.246624 -226.148769) (xy 114.199092 -226.164213) (xy 114.149729 -226.172032)
			(xy 114.099751 -226.172032) (xy 114.050388 -226.164213) (xy 114.002856 -226.148769) (xy 113.958324 -226.126079)
			(xy 113.917891 -226.096703) (xy 113.882551 -226.061363) (xy 113.853175 -226.02093) (xy 113.830485 -225.976398)
			(xy 113.815041 -225.928866) (xy 113.807222 -225.879503) (xy 113.502204 -225.879503) (xy 113.494385 -225.928866)
			(xy 113.478941 -225.976398) (xy 113.456251 -226.02093) (xy 113.426875 -226.061363) (xy 113.391535 -226.096703)
			(xy 113.351102 -226.126079) (xy 113.30657 -226.148769) (xy 113.259038 -226.164213) (xy 113.209675 -226.172032)
			(xy 113.159697 -226.172032) (xy 113.110334 -226.164213) (xy 113.062802 -226.148769) (xy 113.01827 -226.126079)
			(xy 112.977837 -226.096703) (xy 112.942497 -226.061363) (xy 112.913121 -226.02093) (xy 112.890431 -225.976398)
			(xy 112.874987 -225.928866) (xy 112.867168 -225.879503) (xy 110.688646 -225.879503) (xy 110.680827 -225.928866)
			(xy 110.665383 -225.976398) (xy 110.642693 -226.02093) (xy 110.613317 -226.061363) (xy 110.577977 -226.096703)
			(xy 110.537544 -226.126079) (xy 110.493012 -226.148769) (xy 110.44548 -226.164213) (xy 110.396117 -226.172032)
			(xy 110.346139 -226.172032) (xy 110.296776 -226.164213) (xy 110.249244 -226.148769) (xy 110.204712 -226.126079)
			(xy 110.164279 -226.096703) (xy 110.128939 -226.061363) (xy 110.099563 -226.02093) (xy 110.076873 -225.976398)
			(xy 110.061429 -225.928866) (xy 110.05361 -225.879503) (xy 109.748592 -225.879503) (xy 109.740773 -225.928866)
			(xy 109.725329 -225.976398) (xy 109.702639 -226.02093) (xy 109.673263 -226.061363) (xy 109.637923 -226.096703)
			(xy 109.59749 -226.126079) (xy 109.552958 -226.148769) (xy 109.505426 -226.164213) (xy 109.456063 -226.172032)
			(xy 109.406085 -226.172032) (xy 109.356722 -226.164213) (xy 109.30919 -226.148769) (xy 109.264658 -226.126079)
			(xy 109.224225 -226.096703) (xy 109.188885 -226.061363) (xy 109.159509 -226.02093) (xy 109.136819 -225.976398)
			(xy 109.121375 -225.928866) (xy 109.113556 -225.879503) (xy 108.808538 -225.879503) (xy 108.800719 -225.928866)
			(xy 108.785275 -225.976398) (xy 108.762585 -226.02093) (xy 108.733209 -226.061363) (xy 108.697869 -226.096703)
			(xy 108.657436 -226.126079) (xy 108.612904 -226.148769) (xy 108.565372 -226.164213) (xy 108.516009 -226.172032)
			(xy 108.466031 -226.172032) (xy 108.416668 -226.164213) (xy 108.369136 -226.148769) (xy 108.324604 -226.126079)
			(xy 108.284171 -226.096703) (xy 108.248831 -226.061363) (xy 108.219455 -226.02093) (xy 108.196765 -225.976398)
			(xy 108.181321 -225.928866) (xy 108.173502 -225.879503) (xy 106.92856 -225.879503) (xy 106.928494 -225.881911)
			(xy 106.92036 -225.930964) (xy 106.90469 -225.978153) (xy 106.881866 -226.022329) (xy 106.852445 -226.062413)
			(xy 106.817143 -226.097429) (xy 106.77682 -226.126523) (xy 106.732461 -226.148987) (xy 106.685145 -226.164272)
			(xy 106.636028 -226.172007) (xy 106.611166 -226.172522) (xy 106.586178 -226.172029) (xy 106.536818 -226.164207)
			(xy 106.48929 -226.14876) (xy 106.444762 -226.126068) (xy 106.404333 -226.096692) (xy 106.368995 -226.061352)
			(xy 106.339621 -226.02092) (xy 106.316933 -225.976392) (xy 106.301489 -225.928862) (xy 106.293669 -225.879502)
			(xy 106.293158 -225.854514) (xy 106.293682 -225.828641) (xy 106.3021 -225.777582) (xy 106.309922 -225.752914)
			(xy 106.311192 -225.74885) (xy 106.312462 -225.740468) (xy 106.312462 -225.73234) (xy 106.311805 -225.725249)
			(xy 106.307033 -225.711837) (xy 106.303064 -225.705924) (xy 106.274362 -225.666046) (xy 106.255058 -225.639376)
			(xy 106.247479 -225.630501) (xy 106.22658 -225.620168) (xy 106.214926 -225.619564) (xy 106.072686 -225.619564)
			(xy 106.067606 -225.619818) (xy 106.06151 -225.620834) (xy 106.058208 -225.621342) (xy 106.048481 -225.623289)
			(xy 106.031492 -225.633493) (xy 106.025188 -225.641154) (xy 106.017822 -225.652076) (xy 106.017314 -225.652838)
			(xy 105.988866 -225.692716) (xy 105.988612 -225.693224) (xy 105.97769 -225.708972) (xy 105.974872 -225.713525)
			(xy 105.971021 -225.723515) (xy 105.97007 -225.728784) (xy 105.968292 -225.740214) (xy 105.972356 -225.752406)
			(xy 105.979651 -225.775308) (xy 105.988066 -225.822628) (xy 105.98912 -225.84664) (xy 105.98912 -225.857054)
			(xy 105.98844 -225.881912) (xy 105.980307 -225.930968) (xy 105.964637 -225.97816) (xy 105.941814 -226.022339)
			(xy 105.912393 -226.062427) (xy 105.877092 -226.097448) (xy 105.83677 -226.126547) (xy 105.79241 -226.149016)
			(xy 105.745094 -226.164308) (xy 105.695975 -226.172049) (xy 105.671112 -226.172522) (xy 105.646122 -226.172033)
			(xy 105.596756 -226.164216) (xy 105.549222 -226.148773) (xy 105.504688 -226.126084) (xy 105.464252 -226.096708)
			(xy 105.428909 -226.061368) (xy 105.39953 -226.020934) (xy 105.376837 -225.976402) (xy 105.36139 -225.928869)
			(xy 105.353569 -225.879504) (xy 105.353104 -225.854514) (xy 105.353629 -225.828641) (xy 105.362048 -225.777583)
			(xy 105.369868 -225.752914) (xy 105.371138 -225.74885) (xy 105.372408 -225.740468) (xy 105.372408 -225.73234)
			(xy 105.371751 -225.725248) (xy 105.366984 -225.711834) (xy 105.36301 -225.705924) (xy 105.334308 -225.666046)
			(xy 105.315004 -225.639376) (xy 105.307422 -225.63051) (xy 105.286521 -225.620199) (xy 105.274872 -225.619564)
			(xy 104.321102 -225.619564) (xy 104.317546 -225.620072) (xy 104.311958 -225.62058) (xy 104.299346 -225.621573)
			(xy 104.274063 -225.622587) (xy 104.261412 -225.622612) (xy 104.187752 -225.622612) (xy 104.177084 -225.624898)
			(xy 104.16794 -225.62693) (xy 104.160066 -225.631756) (xy 104.156784 -225.633999) (xy 104.150908 -225.639355)
			(xy 104.148382 -225.642424) (xy 104.10698 -225.69932) (xy 104.10698 -225.699828) (xy 104.102662 -225.705162)
			(xy 104.098481 -225.711337) (xy 104.09358 -225.725412) (xy 104.09301 -225.732848) (xy 104.09301 -225.75393)
			(xy 104.095296 -225.761296) (xy 104.10172 -225.783868) (xy 104.108614 -225.830287) (xy 104.109012 -225.853752)
			(xy 104.109012 -225.854514) (xy 104.108521 -225.879503) (xy 104.100701 -225.928864) (xy 104.085255 -225.976395)
			(xy 104.062565 -226.020924) (xy 104.033188 -226.061356) (xy 103.997848 -226.096695) (xy 103.957416 -226.12607)
			(xy 103.912886 -226.148759) (xy 103.865354 -226.164203) (xy 103.815993 -226.172021) (xy 103.791004 -226.172522)
			(xy 103.766141 -226.172042) (xy 103.717021 -226.164303) (xy 103.669704 -226.149013) (xy 103.625343 -226.126545)
			(xy 103.58502 -226.097447) (xy 103.549718 -226.062427) (xy 103.520296 -226.022339) (xy 103.497472 -225.978161)
			(xy 103.481802 -225.930969) (xy 103.473668 -225.881912) (xy 103.472996 -225.857054) (xy 103.472996 -225.854006)
			(xy 103.473419 -225.830543) (xy 103.480309 -225.784126) (xy 103.486712 -225.76155) (xy 103.488998 -225.754184)
			(xy 103.488998 -225.735134) (xy 103.488723 -225.727171) (xy 103.483797 -225.712025) (xy 103.479346 -225.705416)
			(xy 103.453184 -225.669094) (xy 103.43388 -225.642424) (xy 103.426299 -225.633553) (xy 103.4054 -225.623222)
			(xy 103.393748 -225.622612) (xy 103.320342 -225.622612) (xy 103.306222 -225.622512) (xy 103.278015 -225.621112)
			(xy 103.263954 -225.619818) (xy 103.261414 -225.619564) (xy 103.24719 -225.619564) (xy 103.237284 -225.621342)
			(xy 103.232215 -225.622368) (xy 103.222615 -225.626212) (xy 103.218234 -225.628962) (xy 103.217726 -225.628962)
			(xy 103.211884 -225.633534) (xy 103.206042 -225.639884) (xy 103.203756 -225.642932) (xy 103.19766 -225.652076)
			(xy 103.196644 -225.6536) (xy 103.168704 -225.692716) (xy 103.16845 -225.693224) (xy 103.157528 -225.708972)
			(xy 103.154713 -225.713527) (xy 103.150867 -225.723517) (xy 103.149908 -225.728784) (xy 103.14813 -225.740214)
			(xy 103.152194 -225.752406) (xy 103.15949 -225.775307) (xy 103.167907 -225.822628) (xy 103.168958 -225.84664)
			(xy 103.168958 -225.860102) (xy 103.168072 -225.884859) (xy 103.159576 -225.933662) (xy 103.143615 -225.980557)
			(xy 103.120575 -226.02441) (xy 103.091014 -226.06416) (xy 103.055647 -226.098845) (xy 103.015329 -226.127626)
			(xy 102.971036 -226.149808) (xy 102.923839 -226.164853) (xy 102.87488 -226.172397) (xy 102.825343 -226.172259)
			(xy 102.776427 -226.16444) (xy 102.729315 -226.149132) (xy 102.685147 -226.126703) (xy 102.644991 -226.097696)
			(xy 102.609818 -226.062814) (xy 102.58048 -226.022899) (xy 102.557686 -225.978918) (xy 102.541988 -225.931934)
			(xy 102.533765 -225.883085) (xy 102.532942 -225.858324) (xy 102.532942 -225.85426) (xy 102.533435 -225.828513)
			(xy 102.541727 -225.77769) (xy 102.558102 -225.728869) (xy 102.582133 -225.683325) (xy 102.613191 -225.642251)
			(xy 102.631494 -225.624136) (xy 102.63886 -225.617024) (xy 102.64394 -225.60534) (xy 102.64648 -225.596704)
			(xy 102.646988 -225.591878) (xy 102.648512 -225.495612) (xy 102.645464 -225.492564) (xy 102.645464 -224.751646)
			(xy 102.645296 -224.745637) (xy 102.64247 -224.733956) (xy 102.639876 -224.728532) (xy 102.638038 -224.725056)
			(xy 102.633448 -224.718674) (xy 102.630732 -224.715832) (xy 102.322376 -224.407476) (xy 102.318645 -224.403956)
			(xy 102.31007 -224.398329) (xy 102.305358 -224.3963) (xy 102.296722 -224.392744) (xy 102.282752 -224.392744)
			(xy 102.252018 -224.39503) (xy 102.251764 -224.39503) (xy 102.239064 -224.396046) (xy 102.206298 -224.398586)
			(xy 102.195122 -224.40138) (xy 102.194614 -224.40138) (xy 102.18952 -224.403392) (xy 102.180295 -224.40929)
			(xy 102.176326 -224.413064) (xy 102.169722 -224.419668) (xy 102.167436 -224.422716) (xy 102.152366 -224.442459)
			(xy 102.11712 -224.477452) (xy 102.076856 -224.506529) (xy 102.032554 -224.528982) (xy 101.985297 -224.544262)
			(xy 101.936237 -224.551997) (xy 101.911404 -224.55251) (xy 101.91115 -224.55251) (xy 101.885648 -224.552001)
			(xy 101.835298 -224.543855) (xy 101.786893 -224.527779) (xy 101.741674 -224.504186) (xy 101.700798 -224.473679)
			(xy 101.665314 -224.437042) (xy 101.63613 -224.395211) (xy 101.613995 -224.34926) (xy 101.599476 -224.300366)
			(xy 101.595682 -224.275142) (xy 101.595682 -224.274888) (xy 101.594412 -224.265744) (xy 101.592328 -224.238791)
			(xy 101.596185 -224.184873) (xy 101.609097 -224.132382) (xy 101.630691 -224.082827) (xy 101.660346 -224.037633)
			(xy 101.697211 -223.998098) (xy 101.718364 -223.981264) (xy 101.722166 -223.978264) (xy 101.728682 -223.971103)
			(xy 101.731318 -223.96704) (xy 101.74224 -223.948498) (xy 101.744224 -223.944542) (xy 101.746917 -223.936111)
			(xy 101.747574 -223.931734) (xy 101.751638 -223.883474) (xy 101.751638 -223.882966) (xy 101.753162 -223.860868)
			(xy 101.752996 -223.850494) (xy 101.745408 -223.831205) (xy 101.73843 -223.82353) (xy 101.663754 -223.748854)
			(xy 101.660021 -223.745336) (xy 101.651444 -223.739715) (xy 101.646736 -223.737678) (xy 101.6381 -223.734122)
			(xy 101.616764 -223.734122) (xy 101.605588 -223.735392) (xy 101.58984 -223.738948) (xy 101.58476 -223.741234)
			(xy 101.562154 -223.751006) (xy 101.514877 -223.764796) (xy 101.466127 -223.771775) (xy 101.441504 -223.772222)
			(xy 101.440996 -223.772222) (xy 101.413672 -223.771686) (xy 101.359697 -223.763136) (xy 101.307723 -223.746248)
			(xy 101.259031 -223.721438) (xy 101.214821 -223.689316) (xy 101.176179 -223.650673) (xy 101.144058 -223.606462)
			(xy 101.119249 -223.557769) (xy 101.102362 -223.505796) (xy 101.093814 -223.45182) (xy 101.09327 -223.424496)
			(xy 101.09327 -223.424242) (xy 101.093684 -223.401142) (xy 101.099868 -223.355357) (xy 101.112055 -223.310792)
			(xy 101.120702 -223.289368) (xy 101.124004 -223.281748) (xy 101.127052 -223.27489) (xy 101.131624 -223.253554)
			(xy 101.13137 -223.246696) (xy 101.129846 -223.215454) (xy 101.125782 -223.206564) (xy 101.123779 -223.201724)
			(xy 101.1216 -223.19148) (xy 101.121464 -223.186244) (xy 101.121464 -223.029526) (xy 101.121403 -223.02592)
			(xy 101.120388 -223.018779) (xy 101.119432 -223.015302) (xy 101.117908 -223.01073) (xy 101.114098 -223.001586)
			(xy 101.105208 -222.992696) (xy 101.101398 -222.98914) (xy 101.048058 -222.94215) (xy 101.036628 -222.935038)
			(xy 101.026468 -222.930466) (xy 101.007164 -222.930466) (xy 101.00437 -222.93072) (xy 100.995226 -222.931736)
			(xy 100.99421 -222.931736) (xy 100.977192 -222.932498) (xy 100.969318 -222.932498) (xy 100.944421 -222.931875)
			(xy 100.895273 -222.923836) (xy 100.84798 -222.908235) (xy 100.803696 -222.885451) (xy 100.763506 -222.856044)
			(xy 100.72839 -222.82073) (xy 100.69921 -222.780374) (xy 100.676676 -222.735963) (xy 100.661341 -222.688582)
			(xy 100.65358 -222.63939) (xy 100.653088 -222.61449) (xy 100.653579 -222.589501) (xy 100.661399 -222.540139)
			(xy 100.676844 -222.492608) (xy 100.699534 -222.448078) (xy 100.72891 -222.407646) (xy 100.76425 -222.372307)
			(xy 100.804683 -222.342931) (xy 100.849214 -222.320241) (xy 100.896745 -222.304797) (xy 100.946107 -222.296979)
			(xy 100.971096 -222.296482) (xy 101.006402 -222.298514) (xy 101.00691 -222.298514) (xy 101.013115 -222.299021)
			(xy 101.025448 -222.297351) (xy 101.031294 -222.295212) (xy 101.04755 -222.287084) (xy 101.05263 -222.282512)
			(xy 101.094032 -222.24619) (xy 101.105716 -222.23603) (xy 101.112526 -222.228933) (xy 101.120634 -222.211032)
			(xy 101.121464 -222.201232) (xy 101.121464 -221.446344) (xy 101.120194 -221.436184) (xy 101.120194 -221.058486)
			(xy 101.12072 -221.048644) (xy 101.128292 -221.030468) (xy 101.134926 -221.02318) (xy 112.05083 -210.107276)
			(xy 112.057394 -210.100032) (xy 112.064865 -210.081988) (xy 112.065308 -210.072224) (xy 112.065308 -201.547222)
			(xy 112.065425 -201.542267) (xy 112.06734 -201.532544) (xy 112.069118 -201.527918) (xy 112.076484 -201.510138)
			(xy 112.079024 -201.501756) (xy 112.079786 -201.493628) (xy 112.079786 -191.322706) (xy 112.079614 -191.316698)
			(xy 112.07678 -191.30502) (xy 112.074198 -191.299592) (xy 112.072359 -191.296117) (xy 112.067766 -191.289738)
			(xy 112.065054 -191.286892) (xy 111.980726 -191.202564) (xy 111.977877 -191.199856) (xy 111.971501 -191.195257)
			(xy 111.968026 -191.19342) (xy 111.962599 -191.190839) (xy 111.950919 -191.188021) (xy 111.944912 -191.187832)
			(xy 110.656116 -191.187832) (xy 110.646066 -191.187326) (xy 110.627506 -191.179604) (xy 110.620048 -191.172846)
			(xy 110.40618 -190.958978) (xy 110.399328 -190.951582) (xy 110.391589 -190.932983) (xy 110.391194 -190.92291)
			(xy 110.391194 -190.720472) (xy 110.391029 -190.714462) (xy 110.38821 -190.702777) (xy 110.385606 -190.697358)
			(xy 110.383765 -190.693885) (xy 110.37917 -190.687507) (xy 110.376462 -190.684658) (xy 110.29823 -190.606426)
			(xy 110.297468 -190.605664) (xy 110.296706 -190.604902) (xy 110.295944 -190.603886) (xy 110.29188 -190.599822)
			(xy 110.28426 -190.58128) (xy 110.28426 -190.574676) (xy 110.284006 -190.573406) (xy 110.284006 -187.428124)
			(xy 110.283836 -187.422115) (xy 110.281007 -187.410435) (xy 110.278418 -187.40501) (xy 110.276581 -187.401534)
			(xy 110.271991 -187.395152) (xy 110.269274 -187.39231) (xy 110.253018 -187.376054) (xy 110.253018 -187.3758)
			(xy 110.221268 -187.344304) (xy 109.753908 -186.876944) (xy 109.750177 -186.873423) (xy 109.741603 -186.867794)
			(xy 109.73689 -186.865768) (xy 109.728254 -186.862212) (xy 103.56596 -186.862212) (xy 103.557769 -186.862528)
			(xy 103.542231 -186.867721) (xy 103.53548 -186.872372) (xy 103.532178 -186.87542) (xy 103.530908 -186.876436)
			(xy 103.52913 -186.87796) (xy 103.306118 -187.100972) (xy 103.303411 -187.103823) (xy 103.298817 -187.1102)
			(xy 103.296974 -187.113672) (xy 103.294395 -187.1191) (xy 103.291579 -187.130779) (xy 103.291386 -187.136786)
			(xy 103.291386 -190.896494) (xy 103.290878 -190.897002) (xy 103.290878 -191.03213) (xy 103.290449 -191.042197)
			(xy 103.282724 -191.060792) (xy 103.275892 -191.068198) (xy 102.924864 -191.419226) (xy 102.917467 -191.426075)
			(xy 102.898868 -191.433808) (xy 102.888796 -191.434212) (xy 78.41996 -191.434212) (xy 78.409893 -191.433782)
			(xy 78.391298 -191.426059) (xy 78.383892 -191.419226) (xy 77.905864 -190.941198) (xy 77.899011 -190.933803)
			(xy 77.891267 -190.915204) (xy 77.890878 -190.90513) (xy 77.890878 -186.621166) (xy 77.890563 -186.612975)
			(xy 77.885371 -186.597436) (xy 77.880718 -186.590686) (xy 77.87767 -186.587384) (xy 77.876654 -186.586114)
			(xy 77.87513 -186.584336) (xy 77.525118 -186.234324) (xy 77.522267 -186.231618) (xy 77.515889 -186.227024)
			(xy 77.512418 -186.22518) (xy 77.50699 -186.222602) (xy 77.49531 -186.219788) (xy 77.489304 -186.219592)
			(xy 71.15175 -186.219592) (xy 71.143622 -186.21756) (xy 71.136996 -186.215651) (xy 71.125019 -186.208827)
			(xy 71.12 -186.204098) (xy 70.387718 -185.471816) (xy 70.384867 -185.46911) (xy 70.378489 -185.464517)
			(xy 70.375018 -185.462672) (xy 70.36959 -185.460094) (xy 70.35791 -185.457281) (xy 70.351904 -185.457084)
			(xy 69.02196 -185.457084) (xy 69.011893 -185.456653) (xy 68.993301 -185.448927) (xy 68.985892 -185.442098)
			(xy 68.82257 -185.278776) (xy 68.81572 -185.27138) (xy 68.807983 -185.252781) (xy 68.807584 -185.242708)
			(xy 68.807584 -177.688494) (xy 68.807521 -177.684888) (xy 68.806502 -177.677749) (xy 68.805552 -177.67427)
			(xy 68.804028 -177.669698) (xy 68.800218 -177.660554) (xy 68.74129 -177.601626) (xy 68.740528 -177.600864)
			(xy 68.60413 -177.464466) (xy 68.597366 -177.458308) (xy 68.580707 -177.450781) (xy 68.571618 -177.449734)
			(xy 68.568062 -177.44948) (xy 59.449462 -177.44948) (xy 59.439394 -177.449909) (xy 59.420798 -177.457631)
			(xy 59.413394 -177.464466) (xy 59.306206 -177.571654) (xy 59.299367 -177.579055) (xy 59.291652 -177.597653)
			(xy 59.29122 -177.607722) (xy 59.29122 -180.26761) (xy 60.538104 -180.26761) (xy 60.542175 -180.211988)
			(xy 60.554301 -180.157551) (xy 60.574224 -180.10546) (xy 60.60152 -180.056825) (xy 60.635606 -180.012682)
			(xy 60.675755 -179.973973) (xy 60.721113 -179.941522) (xy 60.770713 -179.916021) (xy 60.823497 -179.898014)
			(xy 60.87834 -179.887884) (xy 60.934074 -179.885847) (xy 60.989511 -179.891947) (xy 61.043468 -179.906053)
			(xy 61.094797 -179.927865) (xy 61.142403 -179.956919) (xy 61.185271 -179.992594) (xy 61.222488 -180.034131)
			(xy 61.253261 -180.080644) (xy 61.276933 -180.131141) (xy 61.293001 -180.184548) (xy 61.301121 -180.239724)
			(xy 61.30163 -180.26761) (xy 61.301121 -180.295496) (xy 61.293001 -180.350672) (xy 61.276933 -180.404079)
			(xy 61.253261 -180.454576) (xy 61.222488 -180.501089) (xy 61.185271 -180.542626) (xy 61.142403 -180.578301)
			(xy 61.094797 -180.607355) (xy 61.043468 -180.629167) (xy 60.989511 -180.643273) (xy 60.934074 -180.649373)
			(xy 60.87834 -180.647336) (xy 60.823497 -180.637206) (xy 60.770713 -180.619199) (xy 60.721113 -180.593698)
			(xy 60.675755 -180.561247) (xy 60.635606 -180.522538) (xy 60.60152 -180.478395) (xy 60.574224 -180.42976)
			(xy 60.554301 -180.377669) (xy 60.542175 -180.323232) (xy 60.538104 -180.26761) (xy 59.29122 -180.26761)
			(xy 59.29122 -188.015626) (xy 59.291648 -188.025694) (xy 59.299372 -188.044289) (xy 59.306206 -188.051694)
			(xy 60.115196 -188.860684) (xy 60.12203 -188.868087) (xy 60.129734 -188.886685) (xy 60.130182 -188.896752)
			(xy 60.130182 -189.545976) (xy 60.131198 -189.555374) (xy 60.131198 -189.555882) (xy 60.132902 -189.563041)
			(xy 60.139735 -189.576068) (xy 60.14466 -189.581536) (xy 66.781934 -196.21881) (xy 66.78933 -196.225661)
			(xy 66.807929 -196.233397) (xy 66.818002 -196.233796) (xy 67.912996 -196.233796) (xy 67.923067 -196.234218)
			(xy 67.941672 -196.241931) (xy 67.949064 -196.248782) (xy 68.764912 -197.06463) (xy 68.771763 -197.072026)
			(xy 68.779501 -197.090625) (xy 68.779898 -197.100698) (xy 68.779898 -197.61327) (xy 68.780403 -197.623693)
			(xy 68.788667 -197.642832) (xy 68.7959 -197.650354) (xy 68.818506 -197.671436) (xy 68.826143 -197.678015)
			(xy 68.845002 -197.685081) (xy 68.855082 -197.685152) (xy 68.874894 -197.684644) (xy 68.907832 -197.685094)
			(xy 68.97329 -197.692497) (xy 69.037502 -197.707209) (xy 69.099654 -197.729045) (xy 69.158958 -197.757727)
			(xy 69.214663 -197.792892) (xy 69.266062 -197.834095) (xy 69.312506 -197.880814) (xy 69.353405 -197.932456)
			(xy 69.388241 -197.988367) (xy 69.416572 -198.047839) (xy 69.438041 -198.110119) (xy 69.452374 -198.174416)
			(xy 69.4563 -198.207122) (xy 69.458078 -198.224648) (xy 69.458078 -198.228966) (xy 69.459602 -198.268844)
			(xy 69.459602 -198.275194) (xy 69.458768 -198.309177) (xy 69.450211 -198.376615) (xy 69.433896 -198.442607)
			(xy 69.410044 -198.506264) (xy 69.378976 -198.566728) (xy 69.341111 -198.623185) (xy 69.319394 -198.649336)
			(xy 69.313298 -198.656448) (xy 69.304916 -198.679816) (xy 69.301614 -198.68896) (xy 69.301868 -198.71436)
			(xy 69.301868 -198.716138) (xy 69.302242 -198.72134) (xy 69.304805 -198.731449) (xy 69.306948 -198.736204)
			(xy 69.314314 -198.751444) (xy 69.320664 -198.75754) (xy 69.826124 -199.263) (xy 69.826632 -199.263508)
			(xy 69.83095 -199.267826) (xy 69.840094 -199.273668) (xy 69.846698 -199.2757) (xy 69.881173 -199.287351)
			(xy 69.947163 -199.318029) (xy 70.008832 -199.356664) (xy 70.065225 -199.402659) (xy 70.11547 -199.455302)
			(xy 70.158789 -199.513776) (xy 70.177152 -199.545194) (xy 70.184264 -199.554846) (xy 70.206749 -199.57977)
			(xy 70.246248 -199.634048) (xy 70.278993 -199.692647) (xy 70.292214 -199.723502) (xy 70.296024 -199.7329)
			(xy 71.948802 -201.385678) (xy 71.951088 -201.38771) (xy 71.951596 -201.388218) (xy 71.95439 -201.390504)
			(xy 71.959978 -201.393298) (xy 71.992363 -201.410014) (xy 72.05291 -201.450582) (xy 72.107698 -201.498643)
			(xy 72.13219 -201.525632) (xy 72.155818 -201.553391) (xy 72.19646 -201.613908) (xy 72.213216 -201.646282)
			(xy 72.215756 -201.651362) (xy 72.218296 -201.654918) (xy 72.220582 -201.657458) (xy 72.718422 -202.155298)
			(xy 72.725136 -202.162536) (xy 72.732734 -202.180741) (xy 72.733154 -202.190604) (xy 72.733154 -202.200764)
			(xy 72.736964 -202.209654) (xy 72.738973 -202.214217) (xy 72.744473 -202.22253) (xy 72.747886 -202.226164)
			(xy 75.527154 -205.005432) (xy 88.13038 -205.005432) (xy 88.13038 -204.087984) (xy 88.130872 -204.064101)
			(xy 88.138394 -204.01693) (xy 88.15319 -203.971512) (xy 88.174895 -203.92896) (xy 88.202978 -203.89032)
			(xy 88.219534 -203.8731) (xy 88.397334 -203.694792) (xy 88.414647 -203.678203) (xy 88.453493 -203.650097)
			(xy 88.496257 -203.628415) (xy 88.541888 -203.613692) (xy 88.58926 -203.606288) (xy 88.613234 -203.605892)
			(xy 89.267538 -203.605892) (xy 89.270332 -203.605638) (xy 89.283818 -203.604316) (xy 89.310883 -203.602916)
			(xy 89.324434 -203.602844) (xy 89.337985 -203.602909) (xy 89.365051 -203.604305) (xy 89.378536 -203.605638)
			(xy 89.38133 -203.605892) (xy 90.537538 -203.605892) (xy 90.540332 -203.605638) (xy 90.553818 -203.604316)
			(xy 90.580883 -203.602916) (xy 90.594434 -203.602844) (xy 90.607985 -203.602909) (xy 90.635051 -203.604305)
			(xy 90.648536 -203.605638) (xy 90.65133 -203.605892) (xy 91.807538 -203.605892) (xy 91.810332 -203.605638)
			(xy 91.823818 -203.604316) (xy 91.850883 -203.602916) (xy 91.864434 -203.602844) (xy 91.877985 -203.602909)
			(xy 91.905051 -203.604305) (xy 91.918536 -203.605638) (xy 91.92133 -203.605892) (xy 93.077538 -203.605892)
			(xy 93.080332 -203.605638) (xy 93.093818 -203.604316) (xy 93.120883 -203.602916) (xy 93.134434 -203.602844)
			(xy 93.147985 -203.602909) (xy 93.175051 -203.604305) (xy 93.188536 -203.605638) (xy 93.19133 -203.605892)
			(xy 94.347538 -203.605892) (xy 94.350332 -203.605638) (xy 94.363818 -203.604316) (xy 94.390883 -203.602916)
			(xy 94.404434 -203.602844) (xy 94.417985 -203.602909) (xy 94.445051 -203.604305) (xy 94.458536 -203.605638)
			(xy 94.46133 -203.605892) (xy 95.617538 -203.605892) (xy 95.620332 -203.605638) (xy 95.633818 -203.604316)
			(xy 95.660883 -203.602916) (xy 95.674434 -203.602844) (xy 95.687985 -203.602909) (xy 95.715051 -203.604305)
			(xy 95.728536 -203.605638) (xy 95.73133 -203.605892) (xy 96.114362 -203.605892) (xy 96.138183 -203.6064)
			(xy 96.185231 -203.613923) (xy 96.230532 -203.628681) (xy 96.272982 -203.650315) (xy 96.311545 -203.678296)
			(xy 96.328738 -203.694792) (xy 96.372934 -203.738734) (xy 96.389539 -203.755947) (xy 96.417665 -203.794629)
			(xy 96.439388 -203.837237) (xy 96.45417 -203.882721) (xy 96.461648 -203.929959) (xy 96.462088 -203.953872)
			(xy 96.462088 -205.030832) (xy 96.461605 -205.054741) (xy 96.45411 -205.101967) (xy 96.439324 -205.147441)
			(xy 96.417612 -205.190045) (xy 96.389507 -205.228731) (xy 96.372934 -205.24597) (xy 96.30664 -205.312264)
			(xy 96.306386 -205.312264) (xy 96.291509 -205.326715) (xy 96.258498 -205.351823) (xy 96.2406 -205.362302)
			(xy 96.228662 -205.368906) (xy 96.214692 -205.392782) (xy 96.214692 -205.679548) (xy 96.21422 -205.700044)
			(xy 96.206802 -205.74036) (xy 96.192254 -205.778684) (xy 96.171049 -205.813767) (xy 96.157796 -205.829408)
			(xy 96.152013 -205.836563) (xy 96.14549 -205.853746) (xy 96.145096 -205.862936) (xy 96.145096 -208.244948)
			(xy 97.278952 -208.244948) (xy 97.278952 -208.24444) (xy 97.279452 -208.216223) (xy 97.287742 -208.1604)
			(xy 97.304121 -208.106395) (xy 97.328235 -208.055371) (xy 97.359563 -208.00843) (xy 97.397429 -207.966585)
			(xy 97.418906 -207.948276) (xy 97.427034 -207.941672) (xy 97.436432 -207.923892) (xy 97.443798 -207.841342)
			(xy 97.444273 -207.831231) (xy 97.438108 -207.811969) (xy 97.43186 -207.804004) (xy 97.410839 -207.778374)
			(xy 97.375433 -207.722337) (xy 97.348234 -207.661889) (xy 97.32978 -207.598224) (xy 97.320436 -207.5326)
			(xy 97.319846 -207.499458) (xy 97.319846 -207.49895) (xy 97.320261 -207.471132) (xy 97.326871 -207.41589)
			(xy 97.339947 -207.361812) (xy 97.359307 -207.309653) (xy 97.384679 -207.260139) (xy 97.399856 -207.236822)
			(xy 97.403834 -207.230393) (xy 97.408218 -207.21593) (xy 97.408492 -207.208374) (xy 97.408492 -206.926942)
			(xy 97.408261 -206.919378) (xy 97.40388 -206.904902) (xy 97.399856 -206.898494) (xy 97.384656 -206.875191)
			(xy 97.359275 -206.825679) (xy 97.339918 -206.773516) (xy 97.326854 -206.719433) (xy 97.320266 -206.664185)
			(xy 97.319846 -206.636366) (xy 97.319846 -206.635858) (xy 97.320299 -206.606903) (xy 97.32744 -206.549433)
			(xy 97.341573 -206.493272) (xy 97.362483 -206.439268) (xy 97.389856 -206.388234) (xy 97.406206 -206.364332)
			(xy 97.411029 -206.356782) (xy 97.415709 -206.339502) (xy 97.41535 -206.33055) (xy 97.409508 -206.264764)
			(xy 97.408333 -206.255808) (xy 97.400518 -206.239536) (xy 97.394268 -206.233014) (xy 97.376386 -206.214896)
			(xy 97.345035 -206.17479) (xy 97.319261 -206.130892) (xy 97.299515 -206.083973) (xy 97.286144 -206.034855)
			(xy 97.279383 -205.9844) (xy 97.278952 -205.958948) (xy 97.279441 -205.931515) (xy 97.287249 -205.877208)
			(xy 97.302707 -205.824566) (xy 97.325499 -205.774658) (xy 97.355161 -205.728503) (xy 97.39109 -205.687038)
			(xy 97.432555 -205.651109) (xy 97.47871 -205.621447) (xy 97.528618 -205.598655) (xy 97.58126 -205.583197)
			(xy 97.635567 -205.575389) (xy 97.690433 -205.575389) (xy 97.74474 -205.583197) (xy 97.797382 -205.598655)
			(xy 97.84729 -205.621447) (xy 97.893445 -205.651109) (xy 97.93491 -205.687038) (xy 97.970839 -205.728503)
			(xy 98.000501 -205.774658) (xy 98.023293 -205.824566) (xy 98.038751 -205.877208) (xy 98.046559 -205.931515)
			(xy 98.047048 -205.958948) (xy 98.046572 -205.986098) (xy 98.038915 -206.039856) (xy 98.02376 -206.091999)
			(xy 98.013012 -206.116936) (xy 98.009651 -206.125224) (xy 98.008345 -206.143048) (xy 98.010472 -206.151734)
			(xy 98.02876 -206.21498) (xy 98.03158 -206.223571) (xy 98.042244 -206.238154) (xy 98.049588 -206.243428)
			(xy 98.073575 -206.259774) (xy 98.117704 -206.297486) (xy 98.156855 -206.340344) (xy 98.190434 -206.387694)
			(xy 98.21793 -206.438817) (xy 98.238924 -206.492935) (xy 98.253097 -206.549226) (xy 98.260235 -206.606834)
			(xy 98.260662 -206.635858) (xy 98.260662 -206.636366) (xy 98.260204 -206.664182) (xy 98.253603 -206.719423)
			(xy 98.240537 -206.7735) (xy 98.221188 -206.82566) (xy 98.195825 -206.875176) (xy 98.180652 -206.898494)
			(xy 98.176697 -206.904936) (xy 98.172301 -206.919389) (xy 98.172016 -206.926942) (xy 98.172016 -207.208374)
			(xy 98.172239 -207.215939) (xy 98.176626 -207.230415) (xy 98.180652 -207.236822) (xy 98.19586 -207.26012)
			(xy 98.221239 -207.309634) (xy 98.240595 -207.361798) (xy 98.253657 -207.415882) (xy 98.260243 -207.47113)
			(xy 98.260662 -207.49895) (xy 98.260662 -207.499458) (xy 98.260136 -207.530142) (xy 98.252167 -207.590991)
			(xy 98.236347 -207.650284) (xy 98.212945 -207.707015) (xy 98.182359 -207.760218) (xy 98.145109 -207.808987)
			(xy 98.101828 -207.852493) (xy 98.053253 -207.889997) (xy 98.026982 -207.905858) (xy 98.018092 -207.910938)
			(xy 98.0059 -207.927194) (xy 97.98558 -208.007458) (xy 97.983574 -208.017309) (xy 97.986456 -208.037185)
			(xy 97.991168 -208.046066) (xy 97.991168 -208.04632) (xy 98.004307 -208.068883) (xy 98.025014 -208.116814)
			(xy 98.039033 -208.16711) (xy 98.046104 -208.218842) (xy 98.04654 -208.244948) (xy 98.046051 -208.272363)
			(xy 98.038248 -208.326633) (xy 98.022801 -208.379241) (xy 98.000024 -208.429116) (xy 97.970381 -208.475241)
			(xy 97.934476 -208.516678) (xy 97.893039 -208.552583) (xy 97.846914 -208.582226) (xy 97.797039 -208.605003)
			(xy 97.744431 -208.62045) (xy 97.690161 -208.628253) (xy 97.635331 -208.628253) (xy 97.581061 -208.62045)
			(xy 97.528453 -208.605003) (xy 97.478578 -208.582226) (xy 97.432453 -208.552583) (xy 97.391016 -208.516678)
			(xy 97.355111 -208.475241) (xy 97.325468 -208.429116) (xy 97.302691 -208.379241) (xy 97.287244 -208.326633)
			(xy 97.279441 -208.272363) (xy 97.278952 -208.244948) (xy 96.145096 -208.244948) (xy 96.145096 -216.166954)
			(xy 96.144601 -216.191085) (xy 96.13706 -216.238755) (xy 96.122157 -216.284658) (xy 96.100258 -216.327666)
			(xy 96.071903 -216.36672) (xy 96.05518 -216.384124) (xy 94.23146 -218.20759) (xy 94.23146 -218.249246)
			(xy 94.246192 -218.264232) (xy 94.269101 -218.288126) (xy 94.309203 -218.34079) (xy 94.342132 -218.398214)
			(xy 94.367331 -218.459424) (xy 94.384375 -218.523387) (xy 94.392975 -218.589021) (xy 94.393512 -218.622118)
			(xy 94.393061 -218.652849) (xy 94.38565 -218.713863) (xy 94.37094 -218.773539) (xy 94.349143 -218.831007)
			(xy 94.320579 -218.885429) (xy 94.285664 -218.936011) (xy 94.244906 -218.982016) (xy 94.1989 -219.022772)
			(xy 94.148317 -219.057686) (xy 94.093894 -219.086249) (xy 94.036426 -219.108044) (xy 93.97675 -219.122753)
			(xy 93.915735 -219.130162) (xy 93.885004 -219.130626) (xy 93.853203 -219.130119) (xy 93.790095 -219.122198)
			(xy 93.728468 -219.106468) (xy 93.669285 -219.083173) (xy 93.613469 -219.052678) (xy 93.561894 -219.01546)
			(xy 93.515363 -218.972098) (xy 93.494606 -218.948) (xy 93.487015 -218.939835) (xy 93.466873 -218.930342)
			(xy 93.455744 -218.929712) (xy 93.308678 -218.929712) (xy 93.274388 -218.927934) (xy 93.264894 -218.927196)
			(xy 93.24649 -218.932038) (xy 93.238574 -218.937332) (xy 93.183202 -218.977972) (xy 93.175753 -218.983891)
			(xy 93.165579 -218.999954) (xy 93.16339 -219.009214) (xy 93.156738 -219.040313) (xy 93.136688 -219.100669)
			(xy 93.10927 -219.158053) (xy 93.074911 -219.211572) (xy 93.034148 -219.260389) (xy 92.987617 -219.303743)
			(xy 92.936043 -219.340958) (xy 92.880232 -219.371453) (xy 92.821055 -219.394751) (xy 92.759435 -219.410489)
			(xy 92.696333 -219.418423) (xy 92.664534 -219.418916) (xy 92.633803 -219.41843) (xy 92.572788 -219.411026)
			(xy 92.513111 -219.396321) (xy 92.455642 -219.374529) (xy 92.401219 -219.345969) (xy 92.350635 -219.311057)
			(xy 92.304628 -219.270302) (xy 92.263869 -219.224298) (xy 92.228953 -219.173717) (xy 92.200388 -219.119296)
			(xy 92.178592 -219.061829) (xy 92.163882 -219.002153) (xy 92.156472 -218.941139) (xy 92.156026 -218.910408)
			(xy 92.156083 -218.899026) (xy 92.157102 -218.876284) (xy 92.158058 -218.864942) (xy 92.158481 -218.853779)
			(xy 92.150844 -218.832818) (xy 92.143326 -218.824556) (xy 91.886786 -218.568016) (xy 91.870023 -218.550567)
			(xy 91.841577 -218.511431) (xy 91.819603 -218.468326) (xy 91.804645 -218.422315) (xy 91.797069 -218.374529)
			(xy 91.796616 -218.350338) (xy 91.796616 -217.01633) (xy 91.779852 -216.99093) (xy 91.765628 -216.985088)
			(xy 91.756185 -216.981573) (xy 91.736048 -216.981526) (xy 91.71743 -216.989199) (xy 91.710002 -216.99601)
			(xy 91.295728 -217.410538) (xy 91.288108 -217.42781) (xy 91.287854 -217.437462) (xy 91.286181 -217.469952)
			(xy 91.275567 -217.534138) (xy 91.256859 -217.596448) (xy 91.230362 -217.655866) (xy 91.196508 -217.711422)
			(xy 91.15585 -217.76221) (xy 91.109051 -217.807403) (xy 91.056873 -217.846262) (xy 91.028774 -217.862658)
			(xy 91.018782 -217.869014) (xy 91.005534 -217.888607) (xy 91.003374 -217.90025) (xy 90.990928 -217.992706)
			(xy 90.998802 -218.015566) (xy 91.007438 -218.023948) (xy 91.031101 -218.047947) (xy 91.072563 -218.101081)
			(xy 91.106639 -218.159227) (xy 91.132733 -218.221367) (xy 91.150387 -218.28641) (xy 91.159291 -218.353216)
			(xy 91.159838 -218.386914) (xy 91.159357 -218.417644) (xy 91.151948 -218.478656) (xy 91.137238 -218.53833)
			(xy 91.115444 -218.595797) (xy 91.086882 -218.650217) (xy 91.051969 -218.700798) (xy 91.011213 -218.746802)
			(xy 90.965211 -218.787559) (xy 90.914631 -218.822473) (xy 90.860211 -218.851037) (xy 90.802746 -218.872834)
			(xy 90.743072 -218.887545) (xy 90.68206 -218.894956) (xy 90.65133 -218.895422) (xy 90.618627 -218.894919)
			(xy 90.553761 -218.886521) (xy 90.490508 -218.869872) (xy 90.429914 -218.845247) (xy 90.372978 -218.813053)
			(xy 90.320643 -218.773822) (xy 90.273771 -218.728203) (xy 90.253058 -218.70289) (xy 90.252804 -218.702636)
			(xy 90.245677 -218.694543) (xy 90.226461 -218.684803) (xy 90.21572 -218.68384) (xy 90.12809 -218.679522)
			(xy 90.108024 -218.68765) (xy 90.10015 -218.695778) (xy 90.076081 -218.720011) (xy 90.022594 -218.762486)
			(xy 89.963904 -218.79742) (xy 89.901066 -218.824185) (xy 89.835211 -218.8423) (xy 89.767524 -218.851437)
			(xy 89.733374 -218.851988) (xy 89.702642 -218.851568) (xy 89.641626 -218.844156) (xy 89.581948 -218.829444)
			(xy 89.524478 -218.807646) (xy 89.470055 -218.779079) (xy 89.419473 -218.744161) (xy 89.373467 -218.7034)
			(xy 89.332711 -218.657391) (xy 89.297797 -218.606805) (xy 89.269235 -218.55238) (xy 89.247442 -218.494908)
			(xy 89.232735 -218.435229) (xy 89.225329 -218.374212) (xy 89.224866 -218.34348) (xy 89.225496 -218.307465)
			(xy 89.235667 -218.236158) (xy 89.255801 -218.167) (xy 89.270078 -218.13393) (xy 89.274396 -218.124024)
			(xy 89.274396 -215.410542) (xy 89.274935 -215.382363) (xy 89.283778 -215.326703) (xy 89.30122 -215.273112)
			(xy 89.326833 -215.222911) (xy 89.359985 -215.177335) (xy 89.379552 -215.15705) (xy 90.830654 -213.705948)
			(xy 90.837459 -213.69852) (xy 90.845201 -213.679942) (xy 90.84564 -213.66988) (xy 90.84564 -213.563454)
			(xy 90.845077 -213.552343) (xy 90.835737 -213.532183) (xy 90.827606 -213.524592) (xy 90.800133 -213.50074)
			(xy 90.750689 -213.447366) (xy 90.708253 -213.388267) (xy 90.673482 -213.324357) (xy 90.646914 -213.256626)
			(xy 90.62896 -213.186119) (xy 90.619896 -213.11393) (xy 90.619326 -213.077552) (xy 90.619914 -213.041174)
			(xy 90.628975 -212.968985) (xy 90.646926 -212.898479) (xy 90.67349 -212.830746) (xy 90.708256 -212.766833)
			(xy 90.750685 -212.707731) (xy 90.800122 -212.654351) (xy 90.827606 -212.630512) (xy 90.835716 -212.622901)
			(xy 90.845074 -212.602756) (xy 90.84564 -212.59165) (xy 90.84564 -212.158072) (xy 90.845245 -212.147999)
			(xy 90.837505 -212.129401) (xy 90.830654 -212.122004) (xy 89.804494 -211.095844) (xy 89.784992 -211.075516)
			(xy 89.751907 -211.029927) (xy 89.726353 -210.979728) (xy 89.708957 -210.926152) (xy 89.700146 -210.870516)
			(xy 89.699592 -210.842352) (xy 89.699592 -208.423256) (xy 89.699192 -208.413184) (xy 89.691454 -208.394586)
			(xy 89.684606 -208.387188) (xy 89.470738 -208.173574) (xy 89.454736 -208.166208) (xy 89.445592 -208.165446)
			(xy 89.424591 -208.16337) (xy 89.383867 -208.152317) (xy 89.3459 -208.133902) (xy 89.312007 -208.108764)
			(xy 89.283366 -208.077775) (xy 89.260969 -208.042011) (xy 89.245596 -208.002714) (xy 89.237778 -207.961247)
			(xy 89.237312 -207.940148) (xy 89.237312 -207.70215) (xy 89.26703 -207.672432) (xy 89.28354 -207.672432)
			(xy 89.292176 -207.653382) (xy 89.294558 -207.648105) (xy 89.297127 -207.636818) (xy 89.297256 -207.63103)
			(xy 89.297256 -207.18907) (xy 89.297136 -207.183282) (xy 89.294558 -207.171996) (xy 89.292176 -207.166718)
			(xy 89.28354 -207.147668) (xy 89.26703 -207.147668) (xy 89.237312 -207.11795) (xy 89.237312 -206.879444)
			(xy 89.237816 -206.858639) (xy 89.245488 -206.81774) (xy 89.252552 -206.798164) (xy 89.256108 -206.789274)
			(xy 89.256108 -206.677006) (xy 89.255719 -206.66739) (xy 89.248672 -206.6495) (xy 89.242392 -206.642208)
			(xy 89.221064 -206.618644) (xy 89.183874 -206.567101) (xy 89.153402 -206.511322) (xy 89.130124 -206.452179)
			(xy 89.114402 -206.390595) (xy 89.106482 -206.327532) (xy 89.105994 -206.295752) (xy 89.106496 -206.263955)
			(xy 89.114424 -206.200857) (xy 89.130151 -206.139239) (xy 89.153431 -206.080059) (xy 89.183902 -206.024241)
			(xy 89.221089 -205.972653) (xy 89.242392 -205.949042) (xy 89.248628 -205.941801) (xy 89.255665 -205.924045)
			(xy 89.256108 -205.914498) (xy 89.256108 -205.770226) (xy 89.252552 -205.761336) (xy 89.245467 -205.741766)
			(xy 89.237804 -205.700863) (xy 89.237312 -205.680056) (xy 89.237312 -205.45806) (xy 89.236845 -205.448051)
			(xy 89.229174 -205.429561) (xy 89.215016 -205.41541) (xy 89.196521 -205.40775) (xy 89.186512 -205.40726)
			(xy 88.531954 -205.40726) (xy 88.508032 -205.406787) (xy 88.460783 -205.399258) (xy 88.415296 -205.384424)
			(xy 88.372692 -205.362652) (xy 88.334023 -205.334477) (xy 88.316816 -205.317852) (xy 88.219534 -205.22057)
			(xy 88.202925 -205.20336) (xy 88.174801 -205.164677) (xy 88.15308 -205.122068) (xy 88.138298 -205.076583)
			(xy 88.130821 -205.029345) (xy 88.13038 -205.005432) (xy 75.527154 -205.005432) (xy 79.739236 -209.217514)
			(xy 79.744916 -209.222704) (xy 79.758623 -209.229677) (xy 79.76616 -209.23123) (xy 79.766668 -209.23123)
			(xy 79.774796 -209.231992) (xy 81.115662 -209.231992) (xy 81.11871 -209.231992) (xy 81.223233 -209.226875)
			(xy 81.432525 -209.226875) (xy 81.537048 -209.231992) (xy 82.99196 -209.231992) (xy 83.001798 -209.232526)
			(xy 83.019963 -209.240109) (xy 83.027266 -209.246724) (xy 85.072982 -211.29244) (xy 85.079694 -211.299678)
			(xy 85.087283 -211.317884) (xy 85.087714 -211.327746) (xy 85.087714 -214.520018) (xy 85.087188 -214.52986)
			(xy 85.079616 -214.548036) (xy 85.072982 -214.555324) (xy 84.495132 -215.133174) (xy 84.48858 -215.140423)
			(xy 84.481134 -215.158466) (xy 84.480654 -215.168226) (xy 84.480654 -221.529753) (xy 84.670374 -221.529753)
			(xy 84.670374 -221.479775) (xy 84.678193 -221.430412) (xy 84.693637 -221.38288) (xy 84.716327 -221.338348)
			(xy 84.745703 -221.297915) (xy 84.781043 -221.262575) (xy 84.821476 -221.233199) (xy 84.866008 -221.210509)
			(xy 84.91354 -221.195065) (xy 84.962903 -221.187246) (xy 85.012881 -221.187246) (xy 85.062244 -221.195065)
			(xy 85.109776 -221.210509) (xy 85.154308 -221.233199) (xy 85.194741 -221.262575) (xy 85.230081 -221.297915)
			(xy 85.259457 -221.338348) (xy 85.282147 -221.38288) (xy 85.297591 -221.430412) (xy 85.30541 -221.479775)
			(xy 85.3059 -221.504764) (xy 85.30541 -221.529753) (xy 90.310444 -221.529753) (xy 90.310444 -221.479775)
			(xy 90.318263 -221.430412) (xy 90.333707 -221.38288) (xy 90.356397 -221.338348) (xy 90.385773 -221.297915)
			(xy 90.421113 -221.262575) (xy 90.461546 -221.233199) (xy 90.506078 -221.210509) (xy 90.55361 -221.195065)
			(xy 90.602973 -221.187246) (xy 90.652951 -221.187246) (xy 90.702314 -221.195065) (xy 90.749846 -221.210509)
			(xy 90.794378 -221.233199) (xy 90.834811 -221.262575) (xy 90.870151 -221.297915) (xy 90.899527 -221.338348)
			(xy 90.922217 -221.38288) (xy 90.937661 -221.430412) (xy 90.94548 -221.479775) (xy 90.94597 -221.504764)
			(xy 90.94548 -221.529753) (xy 90.937661 -221.579116) (xy 90.922217 -221.626648) (xy 90.899527 -221.67118)
			(xy 90.870151 -221.711613) (xy 90.834811 -221.746953) (xy 90.794378 -221.776329) (xy 90.749846 -221.799019)
			(xy 90.702314 -221.814463) (xy 90.652951 -221.822282) (xy 90.602973 -221.822282) (xy 90.55361 -221.814463)
			(xy 90.506078 -221.799019) (xy 90.461546 -221.776329) (xy 90.421113 -221.746953) (xy 90.385773 -221.711613)
			(xy 90.356397 -221.67118) (xy 90.333707 -221.626648) (xy 90.318263 -221.579116) (xy 90.310444 -221.529753)
			(xy 85.30541 -221.529753) (xy 85.297591 -221.579116) (xy 85.282147 -221.626648) (xy 85.259457 -221.67118)
			(xy 85.230081 -221.711613) (xy 85.194741 -221.746953) (xy 85.154308 -221.776329) (xy 85.109776 -221.799019)
			(xy 85.062244 -221.814463) (xy 85.012881 -221.822282) (xy 84.962903 -221.822282) (xy 84.91354 -221.814463)
			(xy 84.866008 -221.799019) (xy 84.821476 -221.776329) (xy 84.781043 -221.746953) (xy 84.745703 -221.711613)
			(xy 84.716327 -221.67118) (xy 84.693637 -221.626648) (xy 84.678193 -221.579116) (xy 84.670374 -221.529753)
			(xy 84.480654 -221.529753) (xy 84.480654 -221.829473) (xy 93.603554 -221.829473) (xy 93.603554 -221.779495)
			(xy 93.611373 -221.730132) (xy 93.626817 -221.6826) (xy 93.649507 -221.638068) (xy 93.678883 -221.597635)
			(xy 93.714223 -221.562295) (xy 93.754656 -221.532919) (xy 93.799188 -221.510229) (xy 93.84672 -221.494785)
			(xy 93.896083 -221.486966) (xy 93.946061 -221.486966) (xy 93.995424 -221.494785) (xy 94.042956 -221.510229)
			(xy 94.087488 -221.532919) (xy 94.127921 -221.562295) (xy 94.163261 -221.597635) (xy 94.192637 -221.638068)
			(xy 94.215327 -221.6826) (xy 94.230771 -221.730132) (xy 94.23859 -221.779495) (xy 94.23908 -221.804484)
			(xy 94.23859 -221.829473) (xy 94.543608 -221.829473) (xy 94.543608 -221.779495) (xy 94.551427 -221.730132)
			(xy 94.566871 -221.6826) (xy 94.589561 -221.638068) (xy 94.618937 -221.597635) (xy 94.654277 -221.562295)
			(xy 94.69471 -221.532919) (xy 94.739242 -221.510229) (xy 94.786774 -221.494785) (xy 94.836137 -221.486966)
			(xy 94.886115 -221.486966) (xy 94.935478 -221.494785) (xy 94.98301 -221.510229) (xy 95.027542 -221.532919)
			(xy 95.067975 -221.562295) (xy 95.103315 -221.597635) (xy 95.132691 -221.638068) (xy 95.155381 -221.6826)
			(xy 95.170825 -221.730132) (xy 95.178644 -221.779495) (xy 95.179134 -221.804484) (xy 95.178644 -221.829473)
			(xy 95.483408 -221.829473) (xy 95.483408 -221.779495) (xy 95.491227 -221.730132) (xy 95.506671 -221.6826)
			(xy 95.529361 -221.638068) (xy 95.558737 -221.597635) (xy 95.594077 -221.562295) (xy 95.63451 -221.532919)
			(xy 95.679042 -221.510229) (xy 95.726574 -221.494785) (xy 95.775937 -221.486966) (xy 95.825915 -221.486966)
			(xy 95.875278 -221.494785) (xy 95.92281 -221.510229) (xy 95.967342 -221.532919) (xy 96.007775 -221.562295)
			(xy 96.043115 -221.597635) (xy 96.072491 -221.638068) (xy 96.095181 -221.6826) (xy 96.110625 -221.730132)
			(xy 96.118444 -221.779495) (xy 96.118934 -221.804484) (xy 96.118444 -221.829473) (xy 96.423462 -221.829473)
			(xy 96.423462 -221.779495) (xy 96.431281 -221.730132) (xy 96.446725 -221.6826) (xy 96.469415 -221.638068)
			(xy 96.498791 -221.597635) (xy 96.534131 -221.562295) (xy 96.574564 -221.532919) (xy 96.619096 -221.510229)
			(xy 96.666628 -221.494785) (xy 96.715991 -221.486966) (xy 96.765969 -221.486966) (xy 96.815332 -221.494785)
			(xy 96.862864 -221.510229) (xy 96.907396 -221.532919) (xy 96.947829 -221.562295) (xy 96.983169 -221.597635)
			(xy 97.012545 -221.638068) (xy 97.035235 -221.6826) (xy 97.050679 -221.730132) (xy 97.058498 -221.779495)
			(xy 97.058988 -221.804484) (xy 97.058498 -221.829473) (xy 97.363516 -221.829473) (xy 97.363516 -221.779495)
			(xy 97.371335 -221.730132) (xy 97.386779 -221.6826) (xy 97.409469 -221.638068) (xy 97.438845 -221.597635)
			(xy 97.474185 -221.562295) (xy 97.514618 -221.532919) (xy 97.55915 -221.510229) (xy 97.606682 -221.494785)
			(xy 97.656045 -221.486966) (xy 97.706023 -221.486966) (xy 97.755386 -221.494785) (xy 97.802918 -221.510229)
			(xy 97.84745 -221.532919) (xy 97.887883 -221.562295) (xy 97.923223 -221.597635) (xy 97.952599 -221.638068)
			(xy 97.975289 -221.6826) (xy 97.990733 -221.730132) (xy 97.998552 -221.779495) (xy 97.999042 -221.804484)
			(xy 97.998552 -221.829473) (xy 99.243624 -221.829473) (xy 99.243624 -221.779495) (xy 99.251443 -221.730132)
			(xy 99.266887 -221.6826) (xy 99.289577 -221.638068) (xy 99.318953 -221.597635) (xy 99.354293 -221.562295)
			(xy 99.394726 -221.532919) (xy 99.439258 -221.510229) (xy 99.48679 -221.494785) (xy 99.536153 -221.486966)
			(xy 99.586131 -221.486966) (xy 99.635494 -221.494785) (xy 99.683026 -221.510229) (xy 99.727558 -221.532919)
			(xy 99.767991 -221.562295) (xy 99.803331 -221.597635) (xy 99.832707 -221.638068) (xy 99.855397 -221.6826)
			(xy 99.870841 -221.730132) (xy 99.87866 -221.779495) (xy 99.87915 -221.804484) (xy 99.87866 -221.829473)
			(xy 100.183424 -221.829473) (xy 100.183424 -221.779495) (xy 100.191243 -221.730132) (xy 100.206687 -221.6826)
			(xy 100.229377 -221.638068) (xy 100.258753 -221.597635) (xy 100.294093 -221.562295) (xy 100.334526 -221.532919)
			(xy 100.379058 -221.510229) (xy 100.42659 -221.494785) (xy 100.475953 -221.486966) (xy 100.525931 -221.486966)
			(xy 100.575294 -221.494785) (xy 100.622826 -221.510229) (xy 100.667358 -221.532919) (xy 100.707791 -221.562295)
			(xy 100.743131 -221.597635) (xy 100.772507 -221.638068) (xy 100.795197 -221.6826) (xy 100.810641 -221.730132)
			(xy 100.81846 -221.779495) (xy 100.81895 -221.804484) (xy 100.81846 -221.829473) (xy 100.810641 -221.878836)
			(xy 100.795197 -221.926368) (xy 100.772507 -221.9709) (xy 100.743131 -222.011333) (xy 100.707791 -222.046673)
			(xy 100.667358 -222.076049) (xy 100.622826 -222.098739) (xy 100.575294 -222.114183) (xy 100.525931 -222.122002)
			(xy 100.475953 -222.122002) (xy 100.42659 -222.114183) (xy 100.379058 -222.098739) (xy 100.334526 -222.076049)
			(xy 100.294093 -222.046673) (xy 100.258753 -222.011333) (xy 100.229377 -221.9709) (xy 100.206687 -221.926368)
			(xy 100.191243 -221.878836) (xy 100.183424 -221.829473) (xy 99.87866 -221.829473) (xy 99.870841 -221.878836)
			(xy 99.855397 -221.926368) (xy 99.832707 -221.9709) (xy 99.803331 -222.011333) (xy 99.767991 -222.046673)
			(xy 99.727558 -222.076049) (xy 99.683026 -222.098739) (xy 99.635494 -222.114183) (xy 99.586131 -222.122002)
			(xy 99.536153 -222.122002) (xy 99.48679 -222.114183) (xy 99.439258 -222.098739) (xy 99.394726 -222.076049)
			(xy 99.354293 -222.046673) (xy 99.318953 -222.011333) (xy 99.289577 -221.9709) (xy 99.266887 -221.926368)
			(xy 99.251443 -221.878836) (xy 99.243624 -221.829473) (xy 97.998552 -221.829473) (xy 97.990733 -221.878836)
			(xy 97.975289 -221.926368) (xy 97.952599 -221.9709) (xy 97.923223 -222.011333) (xy 97.887883 -222.046673)
			(xy 97.84745 -222.076049) (xy 97.802918 -222.098739) (xy 97.755386 -222.114183) (xy 97.706023 -222.122002)
			(xy 97.656045 -222.122002) (xy 97.606682 -222.114183) (xy 97.55915 -222.098739) (xy 97.514618 -222.076049)
			(xy 97.474185 -222.046673) (xy 97.438845 -222.011333) (xy 97.409469 -221.9709) (xy 97.386779 -221.926368)
			(xy 97.371335 -221.878836) (xy 97.363516 -221.829473) (xy 97.058498 -221.829473) (xy 97.050679 -221.878836)
			(xy 97.035235 -221.926368) (xy 97.012545 -221.9709) (xy 96.983169 -222.011333) (xy 96.947829 -222.046673)
			(xy 96.907396 -222.076049) (xy 96.862864 -222.098739) (xy 96.815332 -222.114183) (xy 96.765969 -222.122002)
			(xy 96.715991 -222.122002) (xy 96.666628 -222.114183) (xy 96.619096 -222.098739) (xy 96.574564 -222.076049)
			(xy 96.534131 -222.046673) (xy 96.498791 -222.011333) (xy 96.469415 -221.9709) (xy 96.446725 -221.926368)
			(xy 96.431281 -221.878836) (xy 96.423462 -221.829473) (xy 96.118444 -221.829473) (xy 96.110625 -221.878836)
			(xy 96.095181 -221.926368) (xy 96.072491 -221.9709) (xy 96.043115 -222.011333) (xy 96.007775 -222.046673)
			(xy 95.967342 -222.076049) (xy 95.92281 -222.098739) (xy 95.875278 -222.114183) (xy 95.825915 -222.122002)
			(xy 95.775937 -222.122002) (xy 95.726574 -222.114183) (xy 95.679042 -222.098739) (xy 95.63451 -222.076049)
			(xy 95.594077 -222.046673) (xy 95.558737 -222.011333) (xy 95.529361 -221.9709) (xy 95.506671 -221.926368)
			(xy 95.491227 -221.878836) (xy 95.483408 -221.829473) (xy 95.178644 -221.829473) (xy 95.170825 -221.878836)
			(xy 95.155381 -221.926368) (xy 95.132691 -221.9709) (xy 95.103315 -222.011333) (xy 95.067975 -222.046673)
			(xy 95.027542 -222.076049) (xy 94.98301 -222.098739) (xy 94.935478 -222.114183) (xy 94.886115 -222.122002)
			(xy 94.836137 -222.122002) (xy 94.786774 -222.114183) (xy 94.739242 -222.098739) (xy 94.69471 -222.076049)
			(xy 94.654277 -222.046673) (xy 94.618937 -222.011333) (xy 94.589561 -221.9709) (xy 94.566871 -221.926368)
			(xy 94.551427 -221.878836) (xy 94.543608 -221.829473) (xy 94.23859 -221.829473) (xy 94.230771 -221.878836)
			(xy 94.215327 -221.926368) (xy 94.192637 -221.9709) (xy 94.163261 -222.011333) (xy 94.127921 -222.046673)
			(xy 94.087488 -222.076049) (xy 94.042956 -222.098739) (xy 93.995424 -222.114183) (xy 93.946061 -222.122002)
			(xy 93.896083 -222.122002) (xy 93.84672 -222.114183) (xy 93.799188 -222.098739) (xy 93.754656 -222.076049)
			(xy 93.714223 -222.046673) (xy 93.678883 -222.011333) (xy 93.649507 -221.9709) (xy 93.626817 -221.926368)
			(xy 93.611373 -221.878836) (xy 93.603554 -221.829473) (xy 84.480654 -221.829473) (xy 84.480654 -222.639479)
			(xy 91.253546 -222.639479) (xy 91.253546 -222.589501) (xy 91.261365 -222.540138) (xy 91.276809 -222.492606)
			(xy 91.299499 -222.448074) (xy 91.328875 -222.407641) (xy 91.364215 -222.372301) (xy 91.404648 -222.342925)
			(xy 91.44918 -222.320235) (xy 91.496712 -222.304791) (xy 91.546075 -222.296972) (xy 91.596053 -222.296972)
			(xy 91.645416 -222.304791) (xy 91.692948 -222.320235) (xy 91.73748 -222.342925) (xy 91.777913 -222.372301)
			(xy 91.813253 -222.407641) (xy 91.842629 -222.448074) (xy 91.865319 -222.492606) (xy 91.880763 -222.540138)
			(xy 91.888582 -222.589501) (xy 91.889072 -222.61449) (xy 91.888582 -222.639479) (xy 92.1936 -222.639479)
			(xy 92.1936 -222.589501) (xy 92.201419 -222.540138) (xy 92.216863 -222.492606) (xy 92.239553 -222.448074)
			(xy 92.268929 -222.407641) (xy 92.304269 -222.372301) (xy 92.344702 -222.342925) (xy 92.389234 -222.320235)
			(xy 92.436766 -222.304791) (xy 92.486129 -222.296972) (xy 92.536107 -222.296972) (xy 92.58547 -222.304791)
			(xy 92.633002 -222.320235) (xy 92.677534 -222.342925) (xy 92.717967 -222.372301) (xy 92.753307 -222.407641)
			(xy 92.782683 -222.448074) (xy 92.805373 -222.492606) (xy 92.820817 -222.540138) (xy 92.828636 -222.589501)
			(xy 92.829126 -222.61449) (xy 92.828636 -222.639479) (xy 95.013508 -222.639479) (xy 95.013508 -222.589501)
			(xy 95.021327 -222.540138) (xy 95.036771 -222.492606) (xy 95.059461 -222.448074) (xy 95.088837 -222.407641)
			(xy 95.124177 -222.372301) (xy 95.16461 -222.342925) (xy 95.209142 -222.320235) (xy 95.256674 -222.304791)
			(xy 95.306037 -222.296972) (xy 95.356015 -222.296972) (xy 95.405378 -222.304791) (xy 95.45291 -222.320235)
			(xy 95.497442 -222.342925) (xy 95.537875 -222.372301) (xy 95.573215 -222.407641) (xy 95.602591 -222.448074)
			(xy 95.625281 -222.492606) (xy 95.640725 -222.540138) (xy 95.648544 -222.589501) (xy 95.649034 -222.61449)
			(xy 95.648544 -222.639479) (xy 97.833416 -222.639479) (xy 97.833416 -222.589501) (xy 97.841235 -222.540138)
			(xy 97.856679 -222.492606) (xy 97.879369 -222.448074) (xy 97.908745 -222.407641) (xy 97.944085 -222.372301)
			(xy 97.984518 -222.342925) (xy 98.02905 -222.320235) (xy 98.076582 -222.304791) (xy 98.125945 -222.296972)
			(xy 98.175923 -222.296972) (xy 98.225286 -222.304791) (xy 98.272818 -222.320235) (xy 98.31735 -222.342925)
			(xy 98.357783 -222.372301) (xy 98.393123 -222.407641) (xy 98.422499 -222.448074) (xy 98.445189 -222.492606)
			(xy 98.460633 -222.540138) (xy 98.468452 -222.589501) (xy 98.468942 -222.61449) (xy 98.468452 -222.639479)
			(xy 98.460633 -222.688842) (xy 98.445189 -222.736374) (xy 98.422499 -222.780906) (xy 98.393123 -222.821339)
			(xy 98.357783 -222.856679) (xy 98.31735 -222.886055) (xy 98.272818 -222.908745) (xy 98.225286 -222.924189)
			(xy 98.175923 -222.932008) (xy 98.125945 -222.932008) (xy 98.076582 -222.924189) (xy 98.02905 -222.908745)
			(xy 97.984518 -222.886055) (xy 97.944085 -222.856679) (xy 97.908745 -222.821339) (xy 97.879369 -222.780906)
			(xy 97.856679 -222.736374) (xy 97.841235 -222.688842) (xy 97.833416 -222.639479) (xy 95.648544 -222.639479)
			(xy 95.640725 -222.688842) (xy 95.625281 -222.736374) (xy 95.602591 -222.780906) (xy 95.573215 -222.821339)
			(xy 95.537875 -222.856679) (xy 95.497442 -222.886055) (xy 95.45291 -222.908745) (xy 95.405378 -222.924189)
			(xy 95.356015 -222.932008) (xy 95.306037 -222.932008) (xy 95.256674 -222.924189) (xy 95.209142 -222.908745)
			(xy 95.16461 -222.886055) (xy 95.124177 -222.856679) (xy 95.088837 -222.821339) (xy 95.059461 -222.780906)
			(xy 95.036771 -222.736374) (xy 95.021327 -222.688842) (xy 95.013508 -222.639479) (xy 92.828636 -222.639479)
			(xy 92.820817 -222.688842) (xy 92.805373 -222.736374) (xy 92.782683 -222.780906) (xy 92.753307 -222.821339)
			(xy 92.717967 -222.856679) (xy 92.677534 -222.886055) (xy 92.633002 -222.908745) (xy 92.58547 -222.924189)
			(xy 92.536107 -222.932008) (xy 92.486129 -222.932008) (xy 92.436766 -222.924189) (xy 92.389234 -222.908745)
			(xy 92.344702 -222.886055) (xy 92.304269 -222.856679) (xy 92.268929 -222.821339) (xy 92.239553 -222.780906)
			(xy 92.216863 -222.736374) (xy 92.201419 -222.688842) (xy 92.1936 -222.639479) (xy 91.888582 -222.639479)
			(xy 91.880763 -222.688842) (xy 91.865319 -222.736374) (xy 91.842629 -222.780906) (xy 91.813253 -222.821339)
			(xy 91.777913 -222.856679) (xy 91.73748 -222.886055) (xy 91.692948 -222.908745) (xy 91.645416 -222.924189)
			(xy 91.596053 -222.932008) (xy 91.546075 -222.932008) (xy 91.496712 -222.924189) (xy 91.44918 -222.908745)
			(xy 91.404648 -222.886055) (xy 91.364215 -222.856679) (xy 91.328875 -222.821339) (xy 91.299499 -222.780906)
			(xy 91.276809 -222.736374) (xy 91.261365 -222.688842) (xy 91.253546 -222.639479) (xy 84.480654 -222.639479)
			(xy 84.480654 -223.038162) (xy 84.480916 -223.041993) (xy 84.482447 -223.049518) (xy 84.483702 -223.053148)
			(xy 84.486242 -223.059244) (xy 84.488122 -223.062799) (xy 84.49284 -223.069311) (xy 84.49564 -223.072198)
			(xy 84.50961 -223.086168) (xy 84.51596 -223.092772) (xy 84.547202 -223.10725) (xy 84.555584 -223.108266)
			(xy 84.581102 -223.111549) (xy 84.630679 -223.125292) (xy 84.677396 -223.146838) (xy 84.720034 -223.175626)
			(xy 84.75748 -223.210904) (xy 84.788757 -223.251751) (xy 84.813048 -223.297101) (xy 84.829721 -223.345771)
			(xy 84.838338 -223.396491) (xy 84.839048 -223.42221) (xy 84.839048 -223.425004) (xy 84.838815 -223.435261)
			(xy 86.08363 -223.435261) (xy 86.08363 -223.385283) (xy 86.091449 -223.33592) (xy 86.106893 -223.288388)
			(xy 86.129583 -223.243856) (xy 86.158959 -223.203423) (xy 86.194299 -223.168083) (xy 86.234732 -223.138707)
			(xy 86.279264 -223.116017) (xy 86.326796 -223.100573) (xy 86.376159 -223.092754) (xy 86.426137 -223.092754)
			(xy 86.4755 -223.100573) (xy 86.523032 -223.116017) (xy 86.567564 -223.138707) (xy 86.607997 -223.168083)
			(xy 86.643337 -223.203423) (xy 86.672713 -223.243856) (xy 86.695403 -223.288388) (xy 86.710847 -223.33592)
			(xy 86.718666 -223.385283) (xy 86.719156 -223.410272) (xy 86.718666 -223.435261) (xy 86.716413 -223.449485)
			(xy 87.02343 -223.449485) (xy 87.02343 -223.399507) (xy 87.031249 -223.350144) (xy 87.046693 -223.302612)
			(xy 87.069383 -223.25808) (xy 87.098759 -223.217647) (xy 87.134099 -223.182307) (xy 87.174532 -223.152931)
			(xy 87.219064 -223.130241) (xy 87.266596 -223.114797) (xy 87.315959 -223.106978) (xy 87.365937 -223.106978)
			(xy 87.4153 -223.114797) (xy 87.462832 -223.130241) (xy 87.507364 -223.152931) (xy 87.547797 -223.182307)
			(xy 87.583137 -223.217647) (xy 87.612513 -223.25808) (xy 87.635203 -223.302612) (xy 87.650647 -223.350144)
			(xy 87.658466 -223.399507) (xy 87.658956 -223.424496) (xy 87.658745 -223.435261) (xy 88.903792 -223.435261)
			(xy 88.903792 -223.385283) (xy 88.911611 -223.33592) (xy 88.927055 -223.288388) (xy 88.949745 -223.243856)
			(xy 88.979121 -223.203423) (xy 89.014461 -223.168083) (xy 89.054894 -223.138707) (xy 89.099426 -223.116017)
			(xy 89.146958 -223.100573) (xy 89.196321 -223.092754) (xy 89.246299 -223.092754) (xy 89.295662 -223.100573)
			(xy 89.343194 -223.116017) (xy 89.387726 -223.138707) (xy 89.428159 -223.168083) (xy 89.463499 -223.203423)
			(xy 89.492875 -223.243856) (xy 89.515565 -223.288388) (xy 89.531009 -223.33592) (xy 89.538828 -223.385283)
			(xy 89.539318 -223.410272) (xy 89.538828 -223.435261) (xy 89.536575 -223.449485) (xy 89.843592 -223.449485)
			(xy 89.843592 -223.399507) (xy 89.851411 -223.350144) (xy 89.866855 -223.302612) (xy 89.889545 -223.25808)
			(xy 89.918921 -223.217647) (xy 89.954261 -223.182307) (xy 89.994694 -223.152931) (xy 90.039226 -223.130241)
			(xy 90.086758 -223.114797) (xy 90.136121 -223.106978) (xy 90.186099 -223.106978) (xy 90.235462 -223.114797)
			(xy 90.282994 -223.130241) (xy 90.327526 -223.152931) (xy 90.367959 -223.182307) (xy 90.403299 -223.217647)
			(xy 90.432675 -223.25808) (xy 90.455365 -223.302612) (xy 90.470809 -223.350144) (xy 90.478628 -223.399507)
			(xy 90.479118 -223.424496) (xy 90.478628 -223.449485) (xy 90.783392 -223.449485) (xy 90.783392 -223.399507)
			(xy 90.791211 -223.350144) (xy 90.806655 -223.302612) (xy 90.829345 -223.25808) (xy 90.858721 -223.217647)
			(xy 90.894061 -223.182307) (xy 90.934494 -223.152931) (xy 90.979026 -223.130241) (xy 91.026558 -223.114797)
			(xy 91.075921 -223.106978) (xy 91.125899 -223.106978) (xy 91.175262 -223.114797) (xy 91.222794 -223.130241)
			(xy 91.267326 -223.152931) (xy 91.307759 -223.182307) (xy 91.343099 -223.217647) (xy 91.372475 -223.25808)
			(xy 91.395165 -223.302612) (xy 91.410609 -223.350144) (xy 91.418428 -223.399507) (xy 91.418918 -223.424496)
			(xy 91.418428 -223.449485) (xy 93.603554 -223.449485) (xy 93.603554 -223.399507) (xy 93.611373 -223.350144)
			(xy 93.626817 -223.302612) (xy 93.649507 -223.25808) (xy 93.678883 -223.217647) (xy 93.714223 -223.182307)
			(xy 93.754656 -223.152931) (xy 93.799188 -223.130241) (xy 93.84672 -223.114797) (xy 93.896083 -223.106978)
			(xy 93.946061 -223.106978) (xy 93.995424 -223.114797) (xy 94.042956 -223.130241) (xy 94.087488 -223.152931)
			(xy 94.127921 -223.182307) (xy 94.163261 -223.217647) (xy 94.192637 -223.25808) (xy 94.215327 -223.302612)
			(xy 94.230771 -223.350144) (xy 94.23859 -223.399507) (xy 94.23908 -223.424496) (xy 94.23859 -223.449485)
			(xy 94.543608 -223.449485) (xy 94.543608 -223.399507) (xy 94.551427 -223.350144) (xy 94.566871 -223.302612)
			(xy 94.589561 -223.25808) (xy 94.618937 -223.217647) (xy 94.654277 -223.182307) (xy 94.69471 -223.152931)
			(xy 94.739242 -223.130241) (xy 94.786774 -223.114797) (xy 94.836137 -223.106978) (xy 94.886115 -223.106978)
			(xy 94.935478 -223.114797) (xy 94.98301 -223.130241) (xy 95.027542 -223.152931) (xy 95.067975 -223.182307)
			(xy 95.103315 -223.217647) (xy 95.132691 -223.25808) (xy 95.155381 -223.302612) (xy 95.170825 -223.350144)
			(xy 95.178644 -223.399507) (xy 95.179134 -223.424496) (xy 95.178644 -223.449485) (xy 95.483408 -223.449485)
			(xy 95.483408 -223.399507) (xy 95.491227 -223.350144) (xy 95.506671 -223.302612) (xy 95.529361 -223.25808)
			(xy 95.558737 -223.217647) (xy 95.594077 -223.182307) (xy 95.63451 -223.152931) (xy 95.679042 -223.130241)
			(xy 95.726574 -223.114797) (xy 95.775937 -223.106978) (xy 95.825915 -223.106978) (xy 95.875278 -223.114797)
			(xy 95.92281 -223.130241) (xy 95.967342 -223.152931) (xy 96.007775 -223.182307) (xy 96.043115 -223.217647)
			(xy 96.072491 -223.25808) (xy 96.095181 -223.302612) (xy 96.110625 -223.350144) (xy 96.118444 -223.399507)
			(xy 96.118934 -223.424496) (xy 96.118444 -223.449485) (xy 96.423462 -223.449485) (xy 96.423462 -223.399507)
			(xy 96.431281 -223.350144) (xy 96.446725 -223.302612) (xy 96.469415 -223.25808) (xy 96.498791 -223.217647)
			(xy 96.534131 -223.182307) (xy 96.574564 -223.152931) (xy 96.619096 -223.130241) (xy 96.666628 -223.114797)
			(xy 96.715991 -223.106978) (xy 96.765969 -223.106978) (xy 96.815332 -223.114797) (xy 96.862864 -223.130241)
			(xy 96.907396 -223.152931) (xy 96.947829 -223.182307) (xy 96.983169 -223.217647) (xy 97.012545 -223.25808)
			(xy 97.035235 -223.302612) (xy 97.050679 -223.350144) (xy 97.058498 -223.399507) (xy 97.058988 -223.424496)
			(xy 97.058498 -223.449485) (xy 97.363516 -223.449485) (xy 97.363516 -223.399507) (xy 97.371335 -223.350144)
			(xy 97.386779 -223.302612) (xy 97.409469 -223.25808) (xy 97.438845 -223.217647) (xy 97.474185 -223.182307)
			(xy 97.514618 -223.152931) (xy 97.55915 -223.130241) (xy 97.606682 -223.114797) (xy 97.656045 -223.106978)
			(xy 97.706023 -223.106978) (xy 97.755386 -223.114797) (xy 97.802918 -223.130241) (xy 97.84745 -223.152931)
			(xy 97.887883 -223.182307) (xy 97.923223 -223.217647) (xy 97.952599 -223.25808) (xy 97.975289 -223.302612)
			(xy 97.990733 -223.350144) (xy 97.998552 -223.399507) (xy 97.999042 -223.424496) (xy 97.998552 -223.449485)
			(xy 98.30357 -223.449485) (xy 98.30357 -223.399507) (xy 98.311389 -223.350144) (xy 98.326833 -223.302612)
			(xy 98.349523 -223.25808) (xy 98.378899 -223.217647) (xy 98.414239 -223.182307) (xy 98.454672 -223.152931)
			(xy 98.499204 -223.130241) (xy 98.546736 -223.114797) (xy 98.596099 -223.106978) (xy 98.646077 -223.106978)
			(xy 98.69544 -223.114797) (xy 98.742972 -223.130241) (xy 98.787504 -223.152931) (xy 98.827937 -223.182307)
			(xy 98.863277 -223.217647) (xy 98.892653 -223.25808) (xy 98.915343 -223.302612) (xy 98.930787 -223.350144)
			(xy 98.938606 -223.399507) (xy 98.939096 -223.424496) (xy 98.938606 -223.449485) (xy 99.243624 -223.449485)
			(xy 99.243624 -223.399507) (xy 99.251443 -223.350144) (xy 99.266887 -223.302612) (xy 99.289577 -223.25808)
			(xy 99.318953 -223.217647) (xy 99.354293 -223.182307) (xy 99.394726 -223.152931) (xy 99.439258 -223.130241)
			(xy 99.48679 -223.114797) (xy 99.536153 -223.106978) (xy 99.586131 -223.106978) (xy 99.635494 -223.114797)
			(xy 99.683026 -223.130241) (xy 99.727558 -223.152931) (xy 99.767991 -223.182307) (xy 99.803331 -223.217647)
			(xy 99.832707 -223.25808) (xy 99.855397 -223.302612) (xy 99.870841 -223.350144) (xy 99.87866 -223.399507)
			(xy 99.87915 -223.424496) (xy 99.87866 -223.449485) (xy 100.183424 -223.449485) (xy 100.183424 -223.399507)
			(xy 100.191243 -223.350144) (xy 100.206687 -223.302612) (xy 100.229377 -223.25808) (xy 100.258753 -223.217647)
			(xy 100.294093 -223.182307) (xy 100.334526 -223.152931) (xy 100.379058 -223.130241) (xy 100.42659 -223.114797)
			(xy 100.475953 -223.106978) (xy 100.525931 -223.106978) (xy 100.575294 -223.114797) (xy 100.622826 -223.130241)
			(xy 100.667358 -223.152931) (xy 100.707791 -223.182307) (xy 100.743131 -223.217647) (xy 100.772507 -223.25808)
			(xy 100.795197 -223.302612) (xy 100.810641 -223.350144) (xy 100.81846 -223.399507) (xy 100.81895 -223.424496)
			(xy 100.81846 -223.449485) (xy 100.810641 -223.498848) (xy 100.795197 -223.54638) (xy 100.772507 -223.590912)
			(xy 100.743131 -223.631345) (xy 100.707791 -223.666685) (xy 100.667358 -223.696061) (xy 100.622826 -223.718751)
			(xy 100.575294 -223.734195) (xy 100.525931 -223.742014) (xy 100.475953 -223.742014) (xy 100.42659 -223.734195)
			(xy 100.379058 -223.718751) (xy 100.334526 -223.696061) (xy 100.294093 -223.666685) (xy 100.258753 -223.631345)
			(xy 100.229377 -223.590912) (xy 100.206687 -223.54638) (xy 100.191243 -223.498848) (xy 100.183424 -223.449485)
			(xy 99.87866 -223.449485) (xy 99.870841 -223.498848) (xy 99.855397 -223.54638) (xy 99.832707 -223.590912)
			(xy 99.803331 -223.631345) (xy 99.767991 -223.666685) (xy 99.727558 -223.696061) (xy 99.683026 -223.718751)
			(xy 99.635494 -223.734195) (xy 99.586131 -223.742014) (xy 99.536153 -223.742014) (xy 99.48679 -223.734195)
			(xy 99.439258 -223.718751) (xy 99.394726 -223.696061) (xy 99.354293 -223.666685) (xy 99.318953 -223.631345)
			(xy 99.289577 -223.590912) (xy 99.266887 -223.54638) (xy 99.251443 -223.498848) (xy 99.243624 -223.449485)
			(xy 98.938606 -223.449485) (xy 98.930787 -223.498848) (xy 98.915343 -223.54638) (xy 98.892653 -223.590912)
			(xy 98.863277 -223.631345) (xy 98.827937 -223.666685) (xy 98.787504 -223.696061) (xy 98.742972 -223.718751)
			(xy 98.69544 -223.734195) (xy 98.646077 -223.742014) (xy 98.596099 -223.742014) (xy 98.546736 -223.734195)
			(xy 98.499204 -223.718751) (xy 98.454672 -223.696061) (xy 98.414239 -223.666685) (xy 98.378899 -223.631345)
			(xy 98.349523 -223.590912) (xy 98.326833 -223.54638) (xy 98.311389 -223.498848) (xy 98.30357 -223.449485)
			(xy 97.998552 -223.449485) (xy 97.990733 -223.498848) (xy 97.975289 -223.54638) (xy 97.952599 -223.590912)
			(xy 97.923223 -223.631345) (xy 97.887883 -223.666685) (xy 97.84745 -223.696061) (xy 97.802918 -223.718751)
			(xy 97.755386 -223.734195) (xy 97.706023 -223.742014) (xy 97.656045 -223.742014) (xy 97.606682 -223.734195)
			(xy 97.55915 -223.718751) (xy 97.514618 -223.696061) (xy 97.474185 -223.666685) (xy 97.438845 -223.631345)
			(xy 97.409469 -223.590912) (xy 97.386779 -223.54638) (xy 97.371335 -223.498848) (xy 97.363516 -223.449485)
			(xy 97.058498 -223.449485) (xy 97.050679 -223.498848) (xy 97.035235 -223.54638) (xy 97.012545 -223.590912)
			(xy 96.983169 -223.631345) (xy 96.947829 -223.666685) (xy 96.907396 -223.696061) (xy 96.862864 -223.718751)
			(xy 96.815332 -223.734195) (xy 96.765969 -223.742014) (xy 96.715991 -223.742014) (xy 96.666628 -223.734195)
			(xy 96.619096 -223.718751) (xy 96.574564 -223.696061) (xy 96.534131 -223.666685) (xy 96.498791 -223.631345)
			(xy 96.469415 -223.590912) (xy 96.446725 -223.54638) (xy 96.431281 -223.498848) (xy 96.423462 -223.449485)
			(xy 96.118444 -223.449485) (xy 96.110625 -223.498848) (xy 96.095181 -223.54638) (xy 96.072491 -223.590912)
			(xy 96.043115 -223.631345) (xy 96.007775 -223.666685) (xy 95.967342 -223.696061) (xy 95.92281 -223.718751)
			(xy 95.875278 -223.734195) (xy 95.825915 -223.742014) (xy 95.775937 -223.742014) (xy 95.726574 -223.734195)
			(xy 95.679042 -223.718751) (xy 95.63451 -223.696061) (xy 95.594077 -223.666685) (xy 95.558737 -223.631345)
			(xy 95.529361 -223.590912) (xy 95.506671 -223.54638) (xy 95.491227 -223.498848) (xy 95.483408 -223.449485)
			(xy 95.178644 -223.449485) (xy 95.170825 -223.498848) (xy 95.155381 -223.54638) (xy 95.132691 -223.590912)
			(xy 95.103315 -223.631345) (xy 95.067975 -223.666685) (xy 95.027542 -223.696061) (xy 94.98301 -223.718751)
			(xy 94.935478 -223.734195) (xy 94.886115 -223.742014) (xy 94.836137 -223.742014) (xy 94.786774 -223.734195)
			(xy 94.739242 -223.718751) (xy 94.69471 -223.696061) (xy 94.654277 -223.666685) (xy 94.618937 -223.631345)
			(xy 94.589561 -223.590912) (xy 94.566871 -223.54638) (xy 94.551427 -223.498848) (xy 94.543608 -223.449485)
			(xy 94.23859 -223.449485) (xy 94.230771 -223.498848) (xy 94.215327 -223.54638) (xy 94.192637 -223.590912)
			(xy 94.163261 -223.631345) (xy 94.127921 -223.666685) (xy 94.087488 -223.696061) (xy 94.042956 -223.718751)
			(xy 93.995424 -223.734195) (xy 93.946061 -223.742014) (xy 93.896083 -223.742014) (xy 93.84672 -223.734195)
			(xy 93.799188 -223.718751) (xy 93.754656 -223.696061) (xy 93.714223 -223.666685) (xy 93.678883 -223.631345)
			(xy 93.649507 -223.590912) (xy 93.626817 -223.54638) (xy 93.611373 -223.498848) (xy 93.603554 -223.449485)
			(xy 91.418428 -223.449485) (xy 91.410609 -223.498848) (xy 91.395165 -223.54638) (xy 91.372475 -223.590912)
			(xy 91.343099 -223.631345) (xy 91.307759 -223.666685) (xy 91.267326 -223.696061) (xy 91.222794 -223.718751)
			(xy 91.175262 -223.734195) (xy 91.125899 -223.742014) (xy 91.075921 -223.742014) (xy 91.026558 -223.734195)
			(xy 90.979026 -223.718751) (xy 90.934494 -223.696061) (xy 90.894061 -223.666685) (xy 90.858721 -223.631345)
			(xy 90.829345 -223.590912) (xy 90.806655 -223.54638) (xy 90.791211 -223.498848) (xy 90.783392 -223.449485)
			(xy 90.478628 -223.449485) (xy 90.470809 -223.498848) (xy 90.455365 -223.54638) (xy 90.432675 -223.590912)
			(xy 90.403299 -223.631345) (xy 90.367959 -223.666685) (xy 90.327526 -223.696061) (xy 90.282994 -223.718751)
			(xy 90.235462 -223.734195) (xy 90.186099 -223.742014) (xy 90.136121 -223.742014) (xy 90.086758 -223.734195)
			(xy 90.039226 -223.718751) (xy 89.994694 -223.696061) (xy 89.954261 -223.666685) (xy 89.918921 -223.631345)
			(xy 89.889545 -223.590912) (xy 89.866855 -223.54638) (xy 89.851411 -223.498848) (xy 89.843592 -223.449485)
			(xy 89.536575 -223.449485) (xy 89.531009 -223.484624) (xy 89.515565 -223.532156) (xy 89.492875 -223.576688)
			(xy 89.463499 -223.617121) (xy 89.428159 -223.652461) (xy 89.387726 -223.681837) (xy 89.343194 -223.704527)
			(xy 89.295662 -223.719971) (xy 89.246299 -223.72779) (xy 89.196321 -223.72779) (xy 89.146958 -223.719971)
			(xy 89.099426 -223.704527) (xy 89.054894 -223.681837) (xy 89.014461 -223.652461) (xy 88.979121 -223.617121)
			(xy 88.949745 -223.576688) (xy 88.927055 -223.532156) (xy 88.911611 -223.484624) (xy 88.903792 -223.435261)
			(xy 87.658745 -223.435261) (xy 87.658466 -223.449485) (xy 87.650647 -223.498848) (xy 87.635203 -223.54638)
			(xy 87.612513 -223.590912) (xy 87.583137 -223.631345) (xy 87.547797 -223.666685) (xy 87.507364 -223.696061)
			(xy 87.462832 -223.718751) (xy 87.4153 -223.734195) (xy 87.365937 -223.742014) (xy 87.315959 -223.742014)
			(xy 87.266596 -223.734195) (xy 87.219064 -223.718751) (xy 87.174532 -223.696061) (xy 87.134099 -223.666685)
			(xy 87.098759 -223.631345) (xy 87.069383 -223.590912) (xy 87.046693 -223.54638) (xy 87.031249 -223.498848)
			(xy 87.02343 -223.449485) (xy 86.716413 -223.449485) (xy 86.710847 -223.484624) (xy 86.695403 -223.532156)
			(xy 86.672713 -223.576688) (xy 86.643337 -223.617121) (xy 86.607997 -223.652461) (xy 86.567564 -223.681837)
			(xy 86.523032 -223.704527) (xy 86.4755 -223.719971) (xy 86.426137 -223.72779) (xy 86.376159 -223.72779)
			(xy 86.326796 -223.719971) (xy 86.279264 -223.704527) (xy 86.234732 -223.681837) (xy 86.194299 -223.652461)
			(xy 86.158959 -223.617121) (xy 86.129583 -223.576688) (xy 86.106893 -223.532156) (xy 86.091449 -223.484624)
			(xy 86.08363 -223.435261) (xy 84.838815 -223.435261) (xy 84.838402 -223.453421) (xy 84.828264 -223.509344)
			(xy 84.808348 -223.562575) (xy 84.794344 -223.58731) (xy 84.79409 -223.587564) (xy 84.790026 -223.594676)
			(xy 84.78774 -223.605598) (xy 84.786978 -223.617282) (xy 84.78774 -223.621854) (xy 84.78774 -223.622362)
			(xy 84.789248 -223.630216) (xy 84.796505 -223.644457) (xy 84.801964 -223.650302) (xy 85.072474 -223.920812)
			(xy 85.076759 -223.924834) (xy 85.086763 -223.930995) (xy 85.092286 -223.933004) (xy 85.115325 -223.941224)
			(xy 85.158756 -223.96373) (xy 85.19823 -223.992619) (xy 85.232816 -224.02721) (xy 85.261698 -224.066689)
			(xy 85.284196 -224.110124) (xy 85.292438 -224.133156) (xy 85.294443 -224.138681) (xy 85.300601 -224.148688)
			(xy 85.30463 -224.152968) (xy 85.324696 -224.173034) (xy 85.330375 -224.178227) (xy 85.344081 -224.185207)
			(xy 85.35162 -224.18675) (xy 85.352128 -224.18675) (xy 85.360256 -224.187512) (xy 86.514432 -224.187512)
			(xy 86.523072 -224.187177) (xy 86.539367 -224.181429) (xy 86.552808 -224.170571) (xy 86.557612 -224.163382)
			(xy 86.560406 -224.158302) (xy 86.564216 -224.150682) (xy 86.565486 -224.14611) (xy 86.573078 -224.121609)
			(xy 86.595047 -224.075262) (xy 86.624172 -224.033042) (xy 86.659697 -223.996045) (xy 86.7007 -223.965232)
			(xy 86.746118 -223.9414) (xy 86.794773 -223.925168) (xy 86.845402 -223.916958) (xy 86.871048 -223.916494)
			(xy 86.896934 -223.917006) (xy 86.94802 -223.925397) (xy 86.997074 -223.94195) (xy 87.0428 -223.966228)
			(xy 87.08399 -223.99759) (xy 87.119559 -224.035209) (xy 87.148567 -224.07809) (xy 87.170247 -224.125103)
			(xy 87.177626 -224.14992) (xy 87.177626 -224.150174) (xy 87.17788 -224.150682) (xy 87.17788 -224.150936)
			(xy 87.180376 -224.158611) (xy 87.18944 -224.171955) (xy 87.19566 -224.177098) (xy 87.20201 -224.182178)
			(xy 87.210138 -224.184972) (xy 87.220806 -224.187258) (xy 87.225886 -224.187512) (xy 87.454486 -224.187512)
			(xy 87.463121 -224.187169) (xy 87.479404 -224.181409) (xy 87.49283 -224.170546) (xy 87.497666 -224.163382)
			(xy 87.50046 -224.158302) (xy 87.50427 -224.150682) (xy 87.50554 -224.14611) (xy 87.513133 -224.121611)
			(xy 87.535104 -224.075268) (xy 87.56423 -224.033054) (xy 87.599756 -223.996063) (xy 87.640759 -223.965256)
			(xy 87.686177 -223.941432) (xy 87.734831 -223.925208) (xy 87.785458 -223.917006) (xy 87.811102 -223.916494)
			(xy 87.83699 -223.917002) (xy 87.888082 -223.925388) (xy 87.937141 -223.941936) (xy 87.982873 -223.966211)
			(xy 88.02407 -223.997572) (xy 88.059645 -224.035191) (xy 88.088657 -224.078074) (xy 88.110342 -224.12509)
			(xy 88.11768 -224.14992) (xy 88.11768 -224.150174) (xy 88.117934 -224.150682) (xy 88.117934 -224.150936)
			(xy 88.120428 -224.158613) (xy 88.129486 -224.171963) (xy 88.135714 -224.177098) (xy 88.142064 -224.182178)
			(xy 88.150192 -224.184972) (xy 88.16086 -224.187258) (xy 88.16594 -224.187512) (xy 88.7984 -224.187512)
			(xy 88.808235 -224.188054) (xy 88.826387 -224.19565) (xy 88.833706 -224.202244) (xy 88.890953 -224.259491)
			(xy 89.373438 -224.259491) (xy 89.373438 -224.209513) (xy 89.381257 -224.16015) (xy 89.396701 -224.112618)
			(xy 89.419391 -224.068086) (xy 89.448767 -224.027653) (xy 89.484107 -223.992313) (xy 89.52454 -223.962937)
			(xy 89.569072 -223.940247) (xy 89.616604 -223.924803) (xy 89.665967 -223.916984) (xy 89.715945 -223.916984)
			(xy 89.765308 -223.924803) (xy 89.81284 -223.940247) (xy 89.857372 -223.962937) (xy 89.897805 -223.992313)
			(xy 89.933145 -224.027653) (xy 89.962521 -224.068086) (xy 89.985211 -224.112618) (xy 90.000655 -224.16015)
			(xy 90.008474 -224.209513) (xy 90.008964 -224.234502) (xy 90.008474 -224.259491) (xy 90.313492 -224.259491)
			(xy 90.313492 -224.209513) (xy 90.321311 -224.16015) (xy 90.336755 -224.112618) (xy 90.359445 -224.068086)
			(xy 90.388821 -224.027653) (xy 90.424161 -223.992313) (xy 90.464594 -223.962937) (xy 90.509126 -223.940247)
			(xy 90.556658 -223.924803) (xy 90.606021 -223.916984) (xy 90.655999 -223.916984) (xy 90.705362 -223.924803)
			(xy 90.752894 -223.940247) (xy 90.797426 -223.962937) (xy 90.837859 -223.992313) (xy 90.873199 -224.027653)
			(xy 90.902575 -224.068086) (xy 90.925265 -224.112618) (xy 90.940709 -224.16015) (xy 90.948528 -224.209513)
			(xy 90.949018 -224.234502) (xy 90.948528 -224.259491) (xy 91.253546 -224.259491) (xy 91.253546 -224.209513)
			(xy 91.261365 -224.16015) (xy 91.276809 -224.112618) (xy 91.299499 -224.068086) (xy 91.328875 -224.027653)
			(xy 91.364215 -223.992313) (xy 91.404648 -223.962937) (xy 91.44918 -223.940247) (xy 91.496712 -223.924803)
			(xy 91.546075 -223.916984) (xy 91.596053 -223.916984) (xy 91.645416 -223.924803) (xy 91.692948 -223.940247)
			(xy 91.73748 -223.962937) (xy 91.777913 -223.992313) (xy 91.813253 -224.027653) (xy 91.842629 -224.068086)
			(xy 91.865319 -224.112618) (xy 91.880763 -224.16015) (xy 91.888582 -224.209513) (xy 91.889072 -224.234502)
			(xy 91.888582 -224.259491) (xy 93.1334 -224.259491) (xy 93.1334 -224.209513) (xy 93.141219 -224.16015)
			(xy 93.156663 -224.112618) (xy 93.179353 -224.068086) (xy 93.208729 -224.027653) (xy 93.244069 -223.992313)
			(xy 93.284502 -223.962937) (xy 93.329034 -223.940247) (xy 93.376566 -223.924803) (xy 93.425929 -223.916984)
			(xy 93.475907 -223.916984) (xy 93.52527 -223.924803) (xy 93.572802 -223.940247) (xy 93.617334 -223.962937)
			(xy 93.657767 -223.992313) (xy 93.693107 -224.027653) (xy 93.722483 -224.068086) (xy 93.745173 -224.112618)
			(xy 93.760617 -224.16015) (xy 93.768436 -224.209513) (xy 93.768926 -224.234502) (xy 93.768436 -224.259491)
			(xy 95.953562 -224.259491) (xy 95.953562 -224.209513) (xy 95.961381 -224.16015) (xy 95.976825 -224.112618)
			(xy 95.999515 -224.068086) (xy 96.028891 -224.027653) (xy 96.064231 -223.992313) (xy 96.104664 -223.962937)
			(xy 96.149196 -223.940247) (xy 96.196728 -223.924803) (xy 96.246091 -223.916984) (xy 96.296069 -223.916984)
			(xy 96.345432 -223.924803) (xy 96.392964 -223.940247) (xy 96.437496 -223.962937) (xy 96.477929 -223.992313)
			(xy 96.513269 -224.027653) (xy 96.542645 -224.068086) (xy 96.565335 -224.112618) (xy 96.580779 -224.16015)
			(xy 96.588598 -224.209513) (xy 96.589088 -224.234502) (xy 96.588598 -224.259491) (xy 96.893616 -224.259491)
			(xy 96.893616 -224.209513) (xy 96.901435 -224.16015) (xy 96.916879 -224.112618) (xy 96.939569 -224.068086)
			(xy 96.968945 -224.027653) (xy 97.004285 -223.992313) (xy 97.044718 -223.962937) (xy 97.08925 -223.940247)
			(xy 97.136782 -223.924803) (xy 97.186145 -223.916984) (xy 97.236123 -223.916984) (xy 97.285486 -223.924803)
			(xy 97.333018 -223.940247) (xy 97.37755 -223.962937) (xy 97.417983 -223.992313) (xy 97.453323 -224.027653)
			(xy 97.482699 -224.068086) (xy 97.505389 -224.112618) (xy 97.520833 -224.16015) (xy 97.528652 -224.209513)
			(xy 97.529142 -224.234502) (xy 97.528652 -224.259491) (xy 97.833416 -224.259491) (xy 97.833416 -224.209513)
			(xy 97.841235 -224.16015) (xy 97.856679 -224.112618) (xy 97.879369 -224.068086) (xy 97.908745 -224.027653)
			(xy 97.944085 -223.992313) (xy 97.984518 -223.962937) (xy 98.02905 -223.940247) (xy 98.076582 -223.924803)
			(xy 98.125945 -223.916984) (xy 98.175923 -223.916984) (xy 98.225286 -223.924803) (xy 98.272818 -223.940247)
			(xy 98.31735 -223.962937) (xy 98.357783 -223.992313) (xy 98.393123 -224.027653) (xy 98.422499 -224.068086)
			(xy 98.445189 -224.112618) (xy 98.460633 -224.16015) (xy 98.468452 -224.209513) (xy 98.468942 -224.234502)
			(xy 98.468452 -224.259491) (xy 98.77347 -224.259491) (xy 98.77347 -224.209513) (xy 98.781289 -224.16015)
			(xy 98.796733 -224.112618) (xy 98.819423 -224.068086) (xy 98.848799 -224.027653) (xy 98.884139 -223.992313)
			(xy 98.924572 -223.962937) (xy 98.969104 -223.940247) (xy 99.016636 -223.924803) (xy 99.065999 -223.916984)
			(xy 99.115977 -223.916984) (xy 99.16534 -223.924803) (xy 99.212872 -223.940247) (xy 99.257404 -223.962937)
			(xy 99.297837 -223.992313) (xy 99.333177 -224.027653) (xy 99.362553 -224.068086) (xy 99.385243 -224.112618)
			(xy 99.400687 -224.16015) (xy 99.408506 -224.209513) (xy 99.408996 -224.234502) (xy 99.408506 -224.259491)
			(xy 99.713524 -224.259491) (xy 99.713524 -224.209513) (xy 99.721343 -224.16015) (xy 99.736787 -224.112618)
			(xy 99.759477 -224.068086) (xy 99.788853 -224.027653) (xy 99.824193 -223.992313) (xy 99.864626 -223.962937)
			(xy 99.909158 -223.940247) (xy 99.95669 -223.924803) (xy 100.006053 -223.916984) (xy 100.056031 -223.916984)
			(xy 100.105394 -223.924803) (xy 100.152926 -223.940247) (xy 100.197458 -223.962937) (xy 100.237891 -223.992313)
			(xy 100.273231 -224.027653) (xy 100.302607 -224.068086) (xy 100.325297 -224.112618) (xy 100.340741 -224.16015)
			(xy 100.34856 -224.209513) (xy 100.34905 -224.234502) (xy 100.34856 -224.259491) (xy 100.653578 -224.259491)
			(xy 100.653578 -224.209513) (xy 100.661397 -224.16015) (xy 100.676841 -224.112618) (xy 100.699531 -224.068086)
			(xy 100.728907 -224.027653) (xy 100.764247 -223.992313) (xy 100.80468 -223.962937) (xy 100.849212 -223.940247)
			(xy 100.896744 -223.924803) (xy 100.946107 -223.916984) (xy 100.996085 -223.916984) (xy 101.045448 -223.924803)
			(xy 101.09298 -223.940247) (xy 101.137512 -223.962937) (xy 101.177945 -223.992313) (xy 101.213285 -224.027653)
			(xy 101.242661 -224.068086) (xy 101.265351 -224.112618) (xy 101.280795 -224.16015) (xy 101.288614 -224.209513)
			(xy 101.289104 -224.234502) (xy 101.288614 -224.259491) (xy 101.280795 -224.308854) (xy 101.265351 -224.356386)
			(xy 101.242661 -224.400918) (xy 101.213285 -224.441351) (xy 101.177945 -224.476691) (xy 101.137512 -224.506067)
			(xy 101.09298 -224.528757) (xy 101.045448 -224.544201) (xy 100.996085 -224.55202) (xy 100.946107 -224.55202)
			(xy 100.896744 -224.544201) (xy 100.849212 -224.528757) (xy 100.80468 -224.506067) (xy 100.764247 -224.476691)
			(xy 100.728907 -224.441351) (xy 100.699531 -224.400918) (xy 100.676841 -224.356386) (xy 100.661397 -224.308854)
			(xy 100.653578 -224.259491) (xy 100.34856 -224.259491) (xy 100.340741 -224.308854) (xy 100.325297 -224.356386)
			(xy 100.302607 -224.400918) (xy 100.273231 -224.441351) (xy 100.237891 -224.476691) (xy 100.197458 -224.506067)
			(xy 100.152926 -224.528757) (xy 100.105394 -224.544201) (xy 100.056031 -224.55202) (xy 100.006053 -224.55202)
			(xy 99.95669 -224.544201) (xy 99.909158 -224.528757) (xy 99.864626 -224.506067) (xy 99.824193 -224.476691)
			(xy 99.788853 -224.441351) (xy 99.759477 -224.400918) (xy 99.736787 -224.356386) (xy 99.721343 -224.308854)
			(xy 99.713524 -224.259491) (xy 99.408506 -224.259491) (xy 99.400687 -224.308854) (xy 99.385243 -224.356386)
			(xy 99.362553 -224.400918) (xy 99.333177 -224.441351) (xy 99.297837 -224.476691) (xy 99.257404 -224.506067)
			(xy 99.212872 -224.528757) (xy 99.16534 -224.544201) (xy 99.115977 -224.55202) (xy 99.065999 -224.55202)
			(xy 99.016636 -224.544201) (xy 98.969104 -224.528757) (xy 98.924572 -224.506067) (xy 98.884139 -224.476691)
			(xy 98.848799 -224.441351) (xy 98.819423 -224.400918) (xy 98.796733 -224.356386) (xy 98.781289 -224.308854)
			(xy 98.77347 -224.259491) (xy 98.468452 -224.259491) (xy 98.460633 -224.308854) (xy 98.445189 -224.356386)
			(xy 98.422499 -224.400918) (xy 98.393123 -224.441351) (xy 98.357783 -224.476691) (xy 98.31735 -224.506067)
			(xy 98.272818 -224.528757) (xy 98.225286 -224.544201) (xy 98.175923 -224.55202) (xy 98.125945 -224.55202)
			(xy 98.076582 -224.544201) (xy 98.02905 -224.528757) (xy 97.984518 -224.506067) (xy 97.944085 -224.476691)
			(xy 97.908745 -224.441351) (xy 97.879369 -224.400918) (xy 97.856679 -224.356386) (xy 97.841235 -224.308854)
			(xy 97.833416 -224.259491) (xy 97.528652 -224.259491) (xy 97.520833 -224.308854) (xy 97.505389 -224.356386)
			(xy 97.482699 -224.400918) (xy 97.453323 -224.441351) (xy 97.417983 -224.476691) (xy 97.37755 -224.506067)
			(xy 97.333018 -224.528757) (xy 97.285486 -224.544201) (xy 97.236123 -224.55202) (xy 97.186145 -224.55202)
			(xy 97.136782 -224.544201) (xy 97.08925 -224.528757) (xy 97.044718 -224.506067) (xy 97.004285 -224.476691)
			(xy 96.968945 -224.441351) (xy 96.939569 -224.400918) (xy 96.916879 -224.356386) (xy 96.901435 -224.308854)
			(xy 96.893616 -224.259491) (xy 96.588598 -224.259491) (xy 96.580779 -224.308854) (xy 96.565335 -224.356386)
			(xy 96.542645 -224.400918) (xy 96.513269 -224.441351) (xy 96.477929 -224.476691) (xy 96.437496 -224.506067)
			(xy 96.392964 -224.528757) (xy 96.345432 -224.544201) (xy 96.296069 -224.55202) (xy 96.246091 -224.55202)
			(xy 96.196728 -224.544201) (xy 96.149196 -224.528757) (xy 96.104664 -224.506067) (xy 96.064231 -224.476691)
			(xy 96.028891 -224.441351) (xy 95.999515 -224.400918) (xy 95.976825 -224.356386) (xy 95.961381 -224.308854)
			(xy 95.953562 -224.259491) (xy 93.768436 -224.259491) (xy 93.760617 -224.308854) (xy 93.745173 -224.356386)
			(xy 93.722483 -224.400918) (xy 93.693107 -224.441351) (xy 93.657767 -224.476691) (xy 93.617334 -224.506067)
			(xy 93.572802 -224.528757) (xy 93.52527 -224.544201) (xy 93.475907 -224.55202) (xy 93.425929 -224.55202)
			(xy 93.376566 -224.544201) (xy 93.329034 -224.528757) (xy 93.284502 -224.506067) (xy 93.244069 -224.476691)
			(xy 93.208729 -224.441351) (xy 93.179353 -224.400918) (xy 93.156663 -224.356386) (xy 93.141219 -224.308854)
			(xy 93.1334 -224.259491) (xy 91.888582 -224.259491) (xy 91.880763 -224.308854) (xy 91.865319 -224.356386)
			(xy 91.842629 -224.400918) (xy 91.813253 -224.441351) (xy 91.777913 -224.476691) (xy 91.73748 -224.506067)
			(xy 91.692948 -224.528757) (xy 91.645416 -224.544201) (xy 91.596053 -224.55202) (xy 91.546075 -224.55202)
			(xy 91.496712 -224.544201) (xy 91.44918 -224.528757) (xy 91.404648 -224.506067) (xy 91.364215 -224.476691)
			(xy 91.328875 -224.441351) (xy 91.299499 -224.400918) (xy 91.276809 -224.356386) (xy 91.261365 -224.308854)
			(xy 91.253546 -224.259491) (xy 90.948528 -224.259491) (xy 90.940709 -224.308854) (xy 90.925265 -224.356386)
			(xy 90.902575 -224.400918) (xy 90.873199 -224.441351) (xy 90.837859 -224.476691) (xy 90.797426 -224.506067)
			(xy 90.752894 -224.528757) (xy 90.705362 -224.544201) (xy 90.655999 -224.55202) (xy 90.606021 -224.55202)
			(xy 90.556658 -224.544201) (xy 90.509126 -224.528757) (xy 90.464594 -224.506067) (xy 90.424161 -224.476691)
			(xy 90.388821 -224.441351) (xy 90.359445 -224.400918) (xy 90.336755 -224.356386) (xy 90.321311 -224.308854)
			(xy 90.313492 -224.259491) (xy 90.008474 -224.259491) (xy 90.000655 -224.308854) (xy 89.985211 -224.356386)
			(xy 89.962521 -224.400918) (xy 89.933145 -224.441351) (xy 89.897805 -224.476691) (xy 89.857372 -224.506067)
			(xy 89.81284 -224.528757) (xy 89.765308 -224.544201) (xy 89.715945 -224.55202) (xy 89.665967 -224.55202)
			(xy 89.616604 -224.544201) (xy 89.569072 -224.528757) (xy 89.52454 -224.506067) (xy 89.484107 -224.476691)
			(xy 89.448767 -224.441351) (xy 89.419391 -224.400918) (xy 89.396701 -224.356386) (xy 89.381257 -224.308854)
			(xy 89.373438 -224.259491) (xy 88.890953 -224.259491) (xy 89.67724 -225.045778) (xy 89.685939 -225.053694)
			(xy 89.708189 -225.061228) (xy 89.719912 -225.060256) (xy 89.727278 -225.058986) (xy 89.804494 -225.034856)
			(xy 89.813892 -225.029268) (xy 89.821258 -225.022664) (xy 89.838022 -225.00336) (xy 89.842848 -224.997772)
			(xy 89.848436 -224.98558) (xy 89.849452 -224.981008) (xy 89.849706 -224.979484) (xy 89.855099 -224.955964)
			(xy 89.872025 -224.910778) (xy 89.895576 -224.868664) (xy 89.925212 -224.830585) (xy 89.960254 -224.797414)
			(xy 89.9999 -224.769911) (xy 90.043243 -224.748706) (xy 90.089289 -224.734283) (xy 90.136984 -224.726973)
			(xy 90.16111 -224.7265) (xy 90.186098 -224.726991) (xy 90.23546 -224.734811) (xy 90.28299 -224.750256)
			(xy 90.327519 -224.772946) (xy 90.367951 -224.802323) (xy 90.403289 -224.837663) (xy 90.432663 -224.878096)
			(xy 90.455351 -224.922626) (xy 90.470793 -224.970158) (xy 90.47861 -225.01952) (xy 90.479118 -225.044508)
			(xy 90.784675 -225.044508) (xy 90.78877 -224.99378) (xy 90.800949 -224.944366) (xy 90.820897 -224.897546)
			(xy 90.848098 -224.854532) (xy 90.881846 -224.816438) (xy 90.921268 -224.784251) (xy 90.965342 -224.758805)
			(xy 91.012928 -224.740758) (xy 91.062792 -224.730578) (xy 91.113644 -224.728529) (xy 91.164165 -224.734663)
			(xy 91.213049 -224.748823) (xy 91.259028 -224.77064) (xy 91.300912 -224.79955) (xy 91.337616 -224.834805)
			(xy 91.368189 -224.875491) (xy 91.39184 -224.920554) (xy 91.407956 -224.968828) (xy 91.41612 -225.019062)
			(xy 91.416632 -225.044508) (xy 91.416129 -225.069497) (xy 91.723446 -225.069497) (xy 91.723446 -225.019519)
			(xy 91.731265 -224.970156) (xy 91.746709 -224.922624) (xy 91.769399 -224.878092) (xy 91.798775 -224.837659)
			(xy 91.834115 -224.802319) (xy 91.874548 -224.772943) (xy 91.91908 -224.750253) (xy 91.966612 -224.734809)
			(xy 92.015975 -224.72699) (xy 92.065953 -224.72699) (xy 92.115316 -224.734809) (xy 92.162848 -224.750253)
			(xy 92.20738 -224.772943) (xy 92.247813 -224.802319) (xy 92.283153 -224.837659) (xy 92.312529 -224.878092)
			(xy 92.335219 -224.922624) (xy 92.350663 -224.970156) (xy 92.358482 -225.019519) (xy 92.358972 -225.044508)
			(xy 92.358482 -225.069497) (xy 92.6635 -225.069497) (xy 92.6635 -225.019519) (xy 92.671319 -224.970156)
			(xy 92.686763 -224.922624) (xy 92.709453 -224.878092) (xy 92.738829 -224.837659) (xy 92.774169 -224.802319)
			(xy 92.814602 -224.772943) (xy 92.859134 -224.750253) (xy 92.906666 -224.734809) (xy 92.956029 -224.72699)
			(xy 93.006007 -224.72699) (xy 93.05537 -224.734809) (xy 93.102902 -224.750253) (xy 93.147434 -224.772943)
			(xy 93.187867 -224.802319) (xy 93.223207 -224.837659) (xy 93.252583 -224.878092) (xy 93.275273 -224.922624)
			(xy 93.290717 -224.970156) (xy 93.298536 -225.019519) (xy 93.299026 -225.044508) (xy 93.604837 -225.044508)
			(xy 93.608932 -224.99378) (xy 93.621111 -224.944366) (xy 93.641059 -224.897546) (xy 93.66826 -224.854532)
			(xy 93.702008 -224.816438) (xy 93.74143 -224.784251) (xy 93.785504 -224.758805) (xy 93.83309 -224.740758)
			(xy 93.882954 -224.730578) (xy 93.933806 -224.728529) (xy 93.984327 -224.734663) (xy 94.033211 -224.748823)
			(xy 94.07919 -224.77064) (xy 94.121074 -224.79955) (xy 94.157778 -224.834805) (xy 94.188351 -224.875491)
			(xy 94.212002 -224.920554) (xy 94.228118 -224.968828) (xy 94.236282 -225.019062) (xy 94.236794 -225.044508)
			(xy 94.236291 -225.069497) (xy 94.543608 -225.069497) (xy 94.543608 -225.019519) (xy 94.551427 -224.970156)
			(xy 94.566871 -224.922624) (xy 94.589561 -224.878092) (xy 94.618937 -224.837659) (xy 94.654277 -224.802319)
			(xy 94.69471 -224.772943) (xy 94.739242 -224.750253) (xy 94.786774 -224.734809) (xy 94.836137 -224.72699)
			(xy 94.886115 -224.72699) (xy 94.935478 -224.734809) (xy 94.98301 -224.750253) (xy 95.027542 -224.772943)
			(xy 95.067975 -224.802319) (xy 95.103315 -224.837659) (xy 95.132691 -224.878092) (xy 95.155381 -224.922624)
			(xy 95.170825 -224.970156) (xy 95.178644 -225.019519) (xy 95.179134 -225.044508) (xy 95.178644 -225.069497)
			(xy 95.483408 -225.069497) (xy 95.483408 -225.019519) (xy 95.491227 -224.970156) (xy 95.506671 -224.922624)
			(xy 95.529361 -224.878092) (xy 95.558737 -224.837659) (xy 95.594077 -224.802319) (xy 95.63451 -224.772943)
			(xy 95.679042 -224.750253) (xy 95.726574 -224.734809) (xy 95.775937 -224.72699) (xy 95.825915 -224.72699)
			(xy 95.875278 -224.734809) (xy 95.92281 -224.750253) (xy 95.967342 -224.772943) (xy 96.007775 -224.802319)
			(xy 96.043115 -224.837659) (xy 96.072491 -224.878092) (xy 96.095181 -224.922624) (xy 96.110625 -224.970156)
			(xy 96.118444 -225.019519) (xy 96.118934 -225.044508) (xy 96.118444 -225.069497) (xy 97.363516 -225.069497)
			(xy 97.363516 -225.019519) (xy 97.371335 -224.970156) (xy 97.386779 -224.922624) (xy 97.409469 -224.878092)
			(xy 97.438845 -224.837659) (xy 97.474185 -224.802319) (xy 97.514618 -224.772943) (xy 97.55915 -224.750253)
			(xy 97.606682 -224.734809) (xy 97.656045 -224.72699) (xy 97.706023 -224.72699) (xy 97.755386 -224.734809)
			(xy 97.802918 -224.750253) (xy 97.84745 -224.772943) (xy 97.887883 -224.802319) (xy 97.923223 -224.837659)
			(xy 97.952599 -224.878092) (xy 97.975289 -224.922624) (xy 97.990733 -224.970156) (xy 97.998552 -225.019519)
			(xy 97.999042 -225.044508) (xy 97.998552 -225.069497) (xy 98.30357 -225.069497) (xy 98.30357 -225.019519)
			(xy 98.311389 -224.970156) (xy 98.326833 -224.922624) (xy 98.349523 -224.878092) (xy 98.378899 -224.837659)
			(xy 98.414239 -224.802319) (xy 98.454672 -224.772943) (xy 98.499204 -224.750253) (xy 98.546736 -224.734809)
			(xy 98.596099 -224.72699) (xy 98.646077 -224.72699) (xy 98.69544 -224.734809) (xy 98.742972 -224.750253)
			(xy 98.787504 -224.772943) (xy 98.827937 -224.802319) (xy 98.863277 -224.837659) (xy 98.892653 -224.878092)
			(xy 98.915343 -224.922624) (xy 98.930787 -224.970156) (xy 98.938606 -225.019519) (xy 98.939096 -225.044508)
			(xy 98.938606 -225.069497) (xy 100.183424 -225.069497) (xy 100.183424 -225.019519) (xy 100.191243 -224.970156)
			(xy 100.206687 -224.922624) (xy 100.229377 -224.878092) (xy 100.258753 -224.837659) (xy 100.294093 -224.802319)
			(xy 100.334526 -224.772943) (xy 100.379058 -224.750253) (xy 100.42659 -224.734809) (xy 100.475953 -224.72699)
			(xy 100.525931 -224.72699) (xy 100.575294 -224.734809) (xy 100.622826 -224.750253) (xy 100.667358 -224.772943)
			(xy 100.707791 -224.802319) (xy 100.743131 -224.837659) (xy 100.772507 -224.878092) (xy 100.795197 -224.922624)
			(xy 100.810641 -224.970156) (xy 100.81846 -225.019519) (xy 100.81895 -225.044508) (xy 100.81846 -225.069497)
			(xy 101.123478 -225.069497) (xy 101.123478 -225.019519) (xy 101.131297 -224.970156) (xy 101.146741 -224.922624)
			(xy 101.169431 -224.878092) (xy 101.198807 -224.837659) (xy 101.234147 -224.802319) (xy 101.27458 -224.772943)
			(xy 101.319112 -224.750253) (xy 101.366644 -224.734809) (xy 101.416007 -224.72699) (xy 101.465985 -224.72699)
			(xy 101.515348 -224.734809) (xy 101.56288 -224.750253) (xy 101.607412 -224.772943) (xy 101.647845 -224.802319)
			(xy 101.683185 -224.837659) (xy 101.712561 -224.878092) (xy 101.735251 -224.922624) (xy 101.750695 -224.970156)
			(xy 101.758514 -225.019519) (xy 101.759004 -225.044508) (xy 101.758514 -225.069497) (xy 101.750695 -225.11886)
			(xy 101.735251 -225.166392) (xy 101.712561 -225.210924) (xy 101.683185 -225.251357) (xy 101.647845 -225.286697)
			(xy 101.607412 -225.316073) (xy 101.56288 -225.338763) (xy 101.515348 -225.354207) (xy 101.465985 -225.362026)
			(xy 101.416007 -225.362026) (xy 101.366644 -225.354207) (xy 101.319112 -225.338763) (xy 101.27458 -225.316073)
			(xy 101.234147 -225.286697) (xy 101.198807 -225.251357) (xy 101.169431 -225.210924) (xy 101.146741 -225.166392)
			(xy 101.131297 -225.11886) (xy 101.123478 -225.069497) (xy 100.81846 -225.069497) (xy 100.810641 -225.11886)
			(xy 100.795197 -225.166392) (xy 100.772507 -225.210924) (xy 100.743131 -225.251357) (xy 100.707791 -225.286697)
			(xy 100.667358 -225.316073) (xy 100.622826 -225.338763) (xy 100.575294 -225.354207) (xy 100.525931 -225.362026)
			(xy 100.475953 -225.362026) (xy 100.42659 -225.354207) (xy 100.379058 -225.338763) (xy 100.334526 -225.316073)
			(xy 100.294093 -225.286697) (xy 100.258753 -225.251357) (xy 100.229377 -225.210924) (xy 100.206687 -225.166392)
			(xy 100.191243 -225.11886) (xy 100.183424 -225.069497) (xy 98.938606 -225.069497) (xy 98.930787 -225.11886)
			(xy 98.915343 -225.166392) (xy 98.892653 -225.210924) (xy 98.863277 -225.251357) (xy 98.827937 -225.286697)
			(xy 98.787504 -225.316073) (xy 98.742972 -225.338763) (xy 98.69544 -225.354207) (xy 98.646077 -225.362026)
			(xy 98.596099 -225.362026) (xy 98.546736 -225.354207) (xy 98.499204 -225.338763) (xy 98.454672 -225.316073)
			(xy 98.414239 -225.286697) (xy 98.378899 -225.251357) (xy 98.349523 -225.210924) (xy 98.326833 -225.166392)
			(xy 98.311389 -225.11886) (xy 98.30357 -225.069497) (xy 97.998552 -225.069497) (xy 97.990733 -225.11886)
			(xy 97.975289 -225.166392) (xy 97.952599 -225.210924) (xy 97.923223 -225.251357) (xy 97.887883 -225.286697)
			(xy 97.84745 -225.316073) (xy 97.802918 -225.338763) (xy 97.755386 -225.354207) (xy 97.706023 -225.362026)
			(xy 97.656045 -225.362026) (xy 97.606682 -225.354207) (xy 97.55915 -225.338763) (xy 97.514618 -225.316073)
			(xy 97.474185 -225.286697) (xy 97.438845 -225.251357) (xy 97.409469 -225.210924) (xy 97.386779 -225.166392)
			(xy 97.371335 -225.11886) (xy 97.363516 -225.069497) (xy 96.118444 -225.069497) (xy 96.110625 -225.11886)
			(xy 96.095181 -225.166392) (xy 96.072491 -225.210924) (xy 96.043115 -225.251357) (xy 96.007775 -225.286697)
			(xy 95.967342 -225.316073) (xy 95.92281 -225.338763) (xy 95.875278 -225.354207) (xy 95.825915 -225.362026)
			(xy 95.775937 -225.362026) (xy 95.726574 -225.354207) (xy 95.679042 -225.338763) (xy 95.63451 -225.316073)
			(xy 95.594077 -225.286697) (xy 95.558737 -225.251357) (xy 95.529361 -225.210924) (xy 95.506671 -225.166392)
			(xy 95.491227 -225.11886) (xy 95.483408 -225.069497) (xy 95.178644 -225.069497) (xy 95.170825 -225.11886)
			(xy 95.155381 -225.166392) (xy 95.132691 -225.210924) (xy 95.103315 -225.251357) (xy 95.067975 -225.286697)
			(xy 95.027542 -225.316073) (xy 94.98301 -225.338763) (xy 94.935478 -225.354207) (xy 94.886115 -225.362026)
			(xy 94.836137 -225.362026) (xy 94.786774 -225.354207) (xy 94.739242 -225.338763) (xy 94.69471 -225.316073)
			(xy 94.654277 -225.286697) (xy 94.618937 -225.251357) (xy 94.589561 -225.210924) (xy 94.566871 -225.166392)
			(xy 94.551427 -225.11886) (xy 94.543608 -225.069497) (xy 94.236291 -225.069497) (xy 94.236282 -225.069954)
			(xy 94.228118 -225.120188) (xy 94.212002 -225.168462) (xy 94.188351 -225.213525) (xy 94.157778 -225.254211)
			(xy 94.121074 -225.289466) (xy 94.07919 -225.318376) (xy 94.033211 -225.340193) (xy 93.984327 -225.354353)
			(xy 93.933806 -225.360487) (xy 93.882954 -225.358438) (xy 93.83309 -225.348258) (xy 93.785504 -225.330211)
			(xy 93.74143 -225.304765) (xy 93.702008 -225.272578) (xy 93.66826 -225.234484) (xy 93.641059 -225.19147)
			(xy 93.621111 -225.14465) (xy 93.608932 -225.095236) (xy 93.604837 -225.044508) (xy 93.299026 -225.044508)
			(xy 93.298536 -225.069497) (xy 93.290717 -225.11886) (xy 93.275273 -225.166392) (xy 93.252583 -225.210924)
			(xy 93.223207 -225.251357) (xy 93.187867 -225.286697) (xy 93.147434 -225.316073) (xy 93.102902 -225.338763)
			(xy 93.05537 -225.354207) (xy 93.006007 -225.362026) (xy 92.956029 -225.362026) (xy 92.906666 -225.354207)
			(xy 92.859134 -225.338763) (xy 92.814602 -225.316073) (xy 92.774169 -225.286697) (xy 92.738829 -225.251357)
			(xy 92.709453 -225.210924) (xy 92.686763 -225.166392) (xy 92.671319 -225.11886) (xy 92.6635 -225.069497)
			(xy 92.358482 -225.069497) (xy 92.350663 -225.11886) (xy 92.335219 -225.166392) (xy 92.312529 -225.210924)
			(xy 92.283153 -225.251357) (xy 92.247813 -225.286697) (xy 92.20738 -225.316073) (xy 92.162848 -225.338763)
			(xy 92.115316 -225.354207) (xy 92.065953 -225.362026) (xy 92.015975 -225.362026) (xy 91.966612 -225.354207)
			(xy 91.91908 -225.338763) (xy 91.874548 -225.316073) (xy 91.834115 -225.286697) (xy 91.798775 -225.251357)
			(xy 91.769399 -225.210924) (xy 91.746709 -225.166392) (xy 91.731265 -225.11886) (xy 91.723446 -225.069497)
			(xy 91.416129 -225.069497) (xy 91.41612 -225.069954) (xy 91.407956 -225.120188) (xy 91.39184 -225.168462)
			(xy 91.368189 -225.213525) (xy 91.337616 -225.254211) (xy 91.300912 -225.289466) (xy 91.259028 -225.318376)
			(xy 91.213049 -225.340193) (xy 91.164165 -225.354353) (xy 91.113644 -225.360487) (xy 91.062792 -225.358438)
			(xy 91.012928 -225.348258) (xy 90.965342 -225.330211) (xy 90.921268 -225.304765) (xy 90.881846 -225.272578)
			(xy 90.848098 -225.234484) (xy 90.820897 -225.19147) (xy 90.800949 -225.14465) (xy 90.78877 -225.095236)
			(xy 90.784675 -225.044508) (xy 90.479118 -225.044508) (xy 90.47864 -225.069341) (xy 90.47092 -225.118403)
			(xy 90.45567 -225.165669) (xy 90.433259 -225.209991) (xy 90.404232 -225.250292) (xy 90.369296 -225.285592)
			(xy 90.329297 -225.315034) (xy 90.285209 -225.337901) (xy 90.238103 -225.35364) (xy 90.213688 -225.358198)
			(xy 90.206322 -225.359468) (xy 90.193876 -225.36531) (xy 90.192098 -225.366834) (xy 90.18651 -225.371914)
			(xy 90.182289 -225.376335) (xy 90.17587 -225.386733) (xy 90.17381 -225.392488) (xy 90.172032 -225.397822)
			(xy 90.146378 -225.480118) (xy 90.144639 -225.488642) (xy 90.146352 -225.505943) (xy 90.153737 -225.521683)
			(xy 90.159586 -225.528124) (xy 90.26017 -225.628708) (xy 90.262456 -225.63074) (xy 90.27414 -225.640392)
			(xy 90.283538 -225.64344) (xy 90.291666 -225.646234) (xy 90.361516 -225.645726) (xy 90.36551 -225.64524)
			(xy 90.37329 -225.643195) (xy 90.37701 -225.641662) (xy 90.386154 -225.637598) (xy 90.388694 -225.635058)
			(xy 90.39352 -225.629978) (xy 90.412167 -225.610992) (xy 90.454488 -225.578734) (xy 90.501478 -225.553764)
			(xy 90.551894 -225.536741) (xy 90.604404 -225.528116) (xy 90.63101 -225.527616) (xy 90.656696 -225.52812)
			(xy 90.707436 -225.536158) (xy 90.756293 -225.552034) (xy 90.802066 -225.575358) (xy 90.843627 -225.605555)
			(xy 90.879952 -225.641881) (xy 90.910147 -225.683442) (xy 90.933469 -225.729216) (xy 90.949344 -225.778074)
			(xy 90.95738 -225.828814) (xy 90.95738 -225.879503) (xy 91.253546 -225.879503) (xy 91.253546 -225.829525)
			(xy 91.261365 -225.780162) (xy 91.276809 -225.73263) (xy 91.299499 -225.688098) (xy 91.328875 -225.647665)
			(xy 91.364215 -225.612325) (xy 91.404648 -225.582949) (xy 91.44918 -225.560259) (xy 91.496712 -225.544815)
			(xy 91.546075 -225.536996) (xy 91.596053 -225.536996) (xy 91.645416 -225.544815) (xy 91.692948 -225.560259)
			(xy 91.73748 -225.582949) (xy 91.777913 -225.612325) (xy 91.813253 -225.647665) (xy 91.842629 -225.688098)
			(xy 91.865319 -225.73263) (xy 91.880763 -225.780162) (xy 91.888582 -225.829525) (xy 91.889072 -225.854514)
			(xy 92.194883 -225.854514) (xy 92.198978 -225.803786) (xy 92.211157 -225.754372) (xy 92.231105 -225.707552)
			(xy 92.258306 -225.664538) (xy 92.292054 -225.626444) (xy 92.331476 -225.594257) (xy 92.37555 -225.568811)
			(xy 92.423136 -225.550764) (xy 92.473 -225.540584) (xy 92.523852 -225.538535) (xy 92.574373 -225.544669)
			(xy 92.623257 -225.558829) (xy 92.669236 -225.580646) (xy 92.71112 -225.609556) (xy 92.747824 -225.644811)
			(xy 92.778397 -225.685497) (xy 92.802048 -225.73056) (xy 92.818164 -225.778834) (xy 92.826328 -225.829068)
			(xy 92.82684 -225.854514) (xy 92.826337 -225.879503) (xy 93.1334 -225.879503) (xy 93.1334 -225.829525)
			(xy 93.141219 -225.780162) (xy 93.156663 -225.73263) (xy 93.179353 -225.688098) (xy 93.208729 -225.647665)
			(xy 93.244069 -225.612325) (xy 93.284502 -225.582949) (xy 93.329034 -225.560259) (xy 93.376566 -225.544815)
			(xy 93.425929 -225.536996) (xy 93.475907 -225.536996) (xy 93.52527 -225.544815) (xy 93.572802 -225.560259)
			(xy 93.617334 -225.582949) (xy 93.657767 -225.612325) (xy 93.693107 -225.647665) (xy 93.722483 -225.688098)
			(xy 93.745173 -225.73263) (xy 93.760617 -225.780162) (xy 93.768436 -225.829525) (xy 93.768926 -225.854514)
			(xy 94.074737 -225.854514) (xy 94.078832 -225.803786) (xy 94.091011 -225.754372) (xy 94.110959 -225.707552)
			(xy 94.13816 -225.664538) (xy 94.171908 -225.626444) (xy 94.21133 -225.594257) (xy 94.255404 -225.568811)
			(xy 94.30299 -225.550764) (xy 94.352854 -225.540584) (xy 94.403706 -225.538535) (xy 94.454227 -225.544669)
			(xy 94.503111 -225.558829) (xy 94.54909 -225.580646) (xy 94.590974 -225.609556) (xy 94.627678 -225.644811)
			(xy 94.658251 -225.685497) (xy 94.681902 -225.73056) (xy 94.698018 -225.778834) (xy 94.706182 -225.829068)
			(xy 94.706694 -225.854514) (xy 95.014791 -225.854514) (xy 95.018886 -225.803786) (xy 95.031065 -225.754372)
			(xy 95.051013 -225.707552) (xy 95.078214 -225.664538) (xy 95.111962 -225.626444) (xy 95.151384 -225.594257)
			(xy 95.195458 -225.568811) (xy 95.243044 -225.550764) (xy 95.292908 -225.540584) (xy 95.34376 -225.538535)
			(xy 95.394281 -225.544669) (xy 95.443165 -225.558829) (xy 95.489144 -225.580646) (xy 95.531028 -225.609556)
			(xy 95.567732 -225.644811) (xy 95.598305 -225.685497) (xy 95.621956 -225.73056) (xy 95.638072 -225.778834)
			(xy 95.646236 -225.829068) (xy 95.646748 -225.854514) (xy 95.646245 -225.879503) (xy 96.893616 -225.879503)
			(xy 96.893616 -225.829525) (xy 96.901435 -225.780162) (xy 96.916879 -225.73263) (xy 96.939569 -225.688098)
			(xy 96.968945 -225.647665) (xy 97.004285 -225.612325) (xy 97.044718 -225.582949) (xy 97.08925 -225.560259)
			(xy 97.136782 -225.544815) (xy 97.186145 -225.536996) (xy 97.236123 -225.536996) (xy 97.285486 -225.544815)
			(xy 97.333018 -225.560259) (xy 97.37755 -225.582949) (xy 97.417983 -225.612325) (xy 97.453323 -225.647665)
			(xy 97.482699 -225.688098) (xy 97.505389 -225.73263) (xy 97.520833 -225.780162) (xy 97.528652 -225.829525)
			(xy 97.529142 -225.854514) (xy 97.528652 -225.879503) (xy 97.833416 -225.879503) (xy 97.833416 -225.829525)
			(xy 97.841235 -225.780162) (xy 97.856679 -225.73263) (xy 97.879369 -225.688098) (xy 97.908745 -225.647665)
			(xy 97.944085 -225.612325) (xy 97.984518 -225.582949) (xy 98.02905 -225.560259) (xy 98.076582 -225.544815)
			(xy 98.125945 -225.536996) (xy 98.175923 -225.536996) (xy 98.225286 -225.544815) (xy 98.272818 -225.560259)
			(xy 98.31735 -225.582949) (xy 98.357783 -225.612325) (xy 98.393123 -225.647665) (xy 98.422499 -225.688098)
			(xy 98.445189 -225.73263) (xy 98.460633 -225.780162) (xy 98.468452 -225.829525) (xy 98.468942 -225.854514)
			(xy 98.468452 -225.879503) (xy 99.713524 -225.879503) (xy 99.713524 -225.829525) (xy 99.721343 -225.780162)
			(xy 99.736787 -225.73263) (xy 99.759477 -225.688098) (xy 99.788853 -225.647665) (xy 99.824193 -225.612325)
			(xy 99.864626 -225.582949) (xy 99.909158 -225.560259) (xy 99.95669 -225.544815) (xy 100.006053 -225.536996)
			(xy 100.056031 -225.536996) (xy 100.105394 -225.544815) (xy 100.152926 -225.560259) (xy 100.197458 -225.582949)
			(xy 100.237891 -225.612325) (xy 100.273231 -225.647665) (xy 100.302607 -225.688098) (xy 100.325297 -225.73263)
			(xy 100.340741 -225.780162) (xy 100.34856 -225.829525) (xy 100.34905 -225.854514) (xy 100.34856 -225.879503)
			(xy 100.653578 -225.879503) (xy 100.653578 -225.829525) (xy 100.661397 -225.780162) (xy 100.676841 -225.73263)
			(xy 100.699531 -225.688098) (xy 100.728907 -225.647665) (xy 100.764247 -225.612325) (xy 100.80468 -225.582949)
			(xy 100.849212 -225.560259) (xy 100.896744 -225.544815) (xy 100.946107 -225.536996) (xy 100.996085 -225.536996)
			(xy 101.045448 -225.544815) (xy 101.09298 -225.560259) (xy 101.137512 -225.582949) (xy 101.177945 -225.612325)
			(xy 101.213285 -225.647665) (xy 101.242661 -225.688098) (xy 101.265351 -225.73263) (xy 101.280795 -225.780162)
			(xy 101.288614 -225.829525) (xy 101.289104 -225.854514) (xy 101.288614 -225.879503) (xy 101.280795 -225.928866)
			(xy 101.265351 -225.976398) (xy 101.242661 -226.02093) (xy 101.213285 -226.061363) (xy 101.177945 -226.096703)
			(xy 101.137512 -226.126079) (xy 101.09298 -226.148769) (xy 101.045448 -226.164213) (xy 100.996085 -226.172032)
			(xy 100.946107 -226.172032) (xy 100.896744 -226.164213) (xy 100.849212 -226.148769) (xy 100.80468 -226.126079)
			(xy 100.764247 -226.096703) (xy 100.728907 -226.061363) (xy 100.699531 -226.02093) (xy 100.676841 -225.976398)
			(xy 100.661397 -225.928866) (xy 100.653578 -225.879503) (xy 100.34856 -225.879503) (xy 100.340741 -225.928866)
			(xy 100.325297 -225.976398) (xy 100.302607 -226.02093) (xy 100.273231 -226.061363) (xy 100.237891 -226.096703)
			(xy 100.197458 -226.126079) (xy 100.152926 -226.148769) (xy 100.105394 -226.164213) (xy 100.056031 -226.172032)
			(xy 100.006053 -226.172032) (xy 99.95669 -226.164213) (xy 99.909158 -226.148769) (xy 99.864626 -226.126079)
			(xy 99.824193 -226.096703) (xy 99.788853 -226.061363) (xy 99.759477 -226.02093) (xy 99.736787 -225.976398)
			(xy 99.721343 -225.928866) (xy 99.713524 -225.879503) (xy 98.468452 -225.879503) (xy 98.460633 -225.928866)
			(xy 98.445189 -225.976398) (xy 98.422499 -226.02093) (xy 98.393123 -226.061363) (xy 98.357783 -226.096703)
			(xy 98.31735 -226.126079) (xy 98.272818 -226.148769) (xy 98.225286 -226.164213) (xy 98.175923 -226.172032)
			(xy 98.125945 -226.172032) (xy 98.076582 -226.164213) (xy 98.02905 -226.148769) (xy 97.984518 -226.126079)
			(xy 97.944085 -226.096703) (xy 97.908745 -226.061363) (xy 97.879369 -226.02093) (xy 97.856679 -225.976398)
			(xy 97.841235 -225.928866) (xy 97.833416 -225.879503) (xy 97.528652 -225.879503) (xy 97.520833 -225.928866)
			(xy 97.505389 -225.976398) (xy 97.482699 -226.02093) (xy 97.453323 -226.061363) (xy 97.417983 -226.096703)
			(xy 97.37755 -226.126079) (xy 97.333018 -226.148769) (xy 97.285486 -226.164213) (xy 97.236123 -226.172032)
			(xy 97.186145 -226.172032) (xy 97.136782 -226.164213) (xy 97.08925 -226.148769) (xy 97.044718 -226.126079)
			(xy 97.004285 -226.096703) (xy 96.968945 -226.061363) (xy 96.939569 -226.02093) (xy 96.916879 -225.976398)
			(xy 96.901435 -225.928866) (xy 96.893616 -225.879503) (xy 95.646245 -225.879503) (xy 95.646236 -225.87996)
			(xy 95.638072 -225.930194) (xy 95.621956 -225.978468) (xy 95.598305 -226.023531) (xy 95.567732 -226.064217)
			(xy 95.531028 -226.099472) (xy 95.489144 -226.128382) (xy 95.443165 -226.150199) (xy 95.394281 -226.164359)
			(xy 95.34376 -226.170493) (xy 95.292908 -226.168444) (xy 95.243044 -226.158264) (xy 95.195458 -226.140217)
			(xy 95.151384 -226.114771) (xy 95.111962 -226.082584) (xy 95.078214 -226.04449) (xy 95.051013 -226.001476)
			(xy 95.031065 -225.954656) (xy 95.018886 -225.905242) (xy 95.014791 -225.854514) (xy 94.706694 -225.854514)
			(xy 94.706182 -225.87996) (xy 94.698018 -225.930194) (xy 94.681902 -225.978468) (xy 94.658251 -226.023531)
			(xy 94.627678 -226.064217) (xy 94.590974 -226.099472) (xy 94.54909 -226.128382) (xy 94.503111 -226.150199)
			(xy 94.454227 -226.164359) (xy 94.403706 -226.170493) (xy 94.352854 -226.168444) (xy 94.30299 -226.158264)
			(xy 94.255404 -226.140217) (xy 94.21133 -226.114771) (xy 94.171908 -226.082584) (xy 94.13816 -226.04449)
			(xy 94.110959 -226.001476) (xy 94.091011 -225.954656) (xy 94.078832 -225.905242) (xy 94.074737 -225.854514)
			(xy 93.768926 -225.854514) (xy 93.768436 -225.879503) (xy 93.760617 -225.928866) (xy 93.745173 -225.976398)
			(xy 93.722483 -226.02093) (xy 93.693107 -226.061363) (xy 93.657767 -226.096703) (xy 93.617334 -226.126079)
			(xy 93.572802 -226.148769) (xy 93.52527 -226.164213) (xy 93.475907 -226.172032) (xy 93.425929 -226.172032)
			(xy 93.376566 -226.164213) (xy 93.329034 -226.148769) (xy 93.284502 -226.126079) (xy 93.244069 -226.096703)
			(xy 93.208729 -226.061363) (xy 93.179353 -226.02093) (xy 93.156663 -225.976398) (xy 93.141219 -225.928866)
			(xy 93.1334 -225.879503) (xy 92.826337 -225.879503) (xy 92.826328 -225.87996) (xy 92.818164 -225.930194)
			(xy 92.802048 -225.978468) (xy 92.778397 -226.023531) (xy 92.747824 -226.064217) (xy 92.71112 -226.099472)
			(xy 92.669236 -226.128382) (xy 92.623257 -226.150199) (xy 92.574373 -226.164359) (xy 92.523852 -226.170493)
			(xy 92.473 -226.168444) (xy 92.423136 -226.158264) (xy 92.37555 -226.140217) (xy 92.331476 -226.114771)
			(xy 92.292054 -226.082584) (xy 92.258306 -226.04449) (xy 92.231105 -226.001476) (xy 92.211157 -225.954656)
			(xy 92.198978 -225.905242) (xy 92.194883 -225.854514) (xy 91.889072 -225.854514) (xy 91.888582 -225.879503)
			(xy 91.880763 -225.928866) (xy 91.865319 -225.976398) (xy 91.842629 -226.02093) (xy 91.813253 -226.061363)
			(xy 91.777913 -226.096703) (xy 91.73748 -226.126079) (xy 91.692948 -226.148769) (xy 91.645416 -226.164213)
			(xy 91.596053 -226.172032) (xy 91.546075 -226.172032) (xy 91.496712 -226.164213) (xy 91.44918 -226.148769)
			(xy 91.404648 -226.126079) (xy 91.364215 -226.096703) (xy 91.328875 -226.061363) (xy 91.299499 -226.02093)
			(xy 91.276809 -225.976398) (xy 91.261365 -225.928866) (xy 91.253546 -225.879503) (xy 90.95738 -225.879503)
			(xy 90.95738 -225.880186) (xy 90.949344 -225.930926) (xy 90.933469 -225.979784) (xy 90.910147 -226.025558)
			(xy 90.879952 -226.067119) (xy 90.843627 -226.103445) (xy 90.802066 -226.133642) (xy 90.756293 -226.156966)
			(xy 90.707436 -226.172842) (xy 90.656696 -226.18088) (xy 90.63101 -226.181412) (xy 90.630502 -226.181412)
			(xy 90.615103 -226.181223) (xy 90.584445 -226.178297) (xy 90.569288 -226.17557) (xy 90.567256 -226.175062)
			(xy 90.556841 -226.173043) (xy 90.535975 -226.176728) (xy 90.52687 -226.182174) (xy 90.522044 -226.185222)
			(xy 90.487754 -226.21367) (xy 90.486738 -226.214432) (xy 90.470482 -226.22764) (xy 90.463172 -226.23472)
			(xy 90.454405 -226.253066) (xy 90.453464 -226.2632) (xy 90.453464 -226.528884) (xy 90.455496 -226.539044)
			(xy 90.456766 -226.54641) (xy 90.458544 -226.551236) (xy 90.462354 -226.562158) (xy 90.462608 -226.563174)
			(xy 90.463624 -226.566222) (xy 90.466418 -226.575112) (xy 90.466418 -226.575874) (xy 90.46845 -226.582732)
			(xy 90.470228 -226.589336) (xy 90.470736 -226.591368) (xy 90.476832 -226.625912) (xy 90.478864 -226.642168)
			(xy 90.479118 -226.647248) (xy 90.479118 -226.66452) (xy 90.784675 -226.66452) (xy 90.78877 -226.613792)
			(xy 90.800949 -226.564378) (xy 90.820897 -226.517558) (xy 90.848098 -226.474544) (xy 90.881846 -226.43645)
			(xy 90.921268 -226.404263) (xy 90.965342 -226.378817) (xy 91.012928 -226.36077) (xy 91.062792 -226.35059)
			(xy 91.113644 -226.348541) (xy 91.164165 -226.354675) (xy 91.213049 -226.368835) (xy 91.259028 -226.390652)
			(xy 91.300912 -226.419562) (xy 91.337616 -226.454817) (xy 91.368189 -226.495503) (xy 91.39184 -226.540566)
			(xy 91.407956 -226.58884) (xy 91.41612 -226.639074) (xy 91.416632 -226.66452) (xy 91.724729 -226.66452)
			(xy 91.728824 -226.613792) (xy 91.741003 -226.564378) (xy 91.760951 -226.517558) (xy 91.788152 -226.474544)
			(xy 91.8219 -226.43645) (xy 91.861322 -226.404263) (xy 91.905396 -226.378817) (xy 91.952982 -226.36077)
			(xy 92.002846 -226.35059) (xy 92.053698 -226.348541) (xy 92.104219 -226.354675) (xy 92.153103 -226.368835)
			(xy 92.199082 -226.390652) (xy 92.240966 -226.419562) (xy 92.27767 -226.454817) (xy 92.308243 -226.495503)
			(xy 92.331894 -226.540566) (xy 92.34801 -226.58884) (xy 92.356174 -226.639074) (xy 92.356686 -226.66452)
			(xy 92.356183 -226.689509) (xy 92.6635 -226.689509) (xy 92.6635 -226.639531) (xy 92.671319 -226.590168)
			(xy 92.686763 -226.542636) (xy 92.709453 -226.498104) (xy 92.738829 -226.457671) (xy 92.774169 -226.422331)
			(xy 92.814602 -226.392955) (xy 92.859134 -226.370265) (xy 92.906666 -226.354821) (xy 92.956029 -226.347002)
			(xy 93.006007 -226.347002) (xy 93.05537 -226.354821) (xy 93.102902 -226.370265) (xy 93.147434 -226.392955)
			(xy 93.187867 -226.422331) (xy 93.223207 -226.457671) (xy 93.252583 -226.498104) (xy 93.275273 -226.542636)
			(xy 93.290717 -226.590168) (xy 93.298536 -226.639531) (xy 93.299026 -226.66452) (xy 93.604837 -226.66452)
			(xy 93.608932 -226.613792) (xy 93.621111 -226.564378) (xy 93.641059 -226.517558) (xy 93.66826 -226.474544)
			(xy 93.702008 -226.43645) (xy 93.74143 -226.404263) (xy 93.785504 -226.378817) (xy 93.83309 -226.36077)
			(xy 93.882954 -226.35059) (xy 93.933806 -226.348541) (xy 93.984327 -226.354675) (xy 94.033211 -226.368835)
			(xy 94.07919 -226.390652) (xy 94.121074 -226.419562) (xy 94.157778 -226.454817) (xy 94.188351 -226.495503)
			(xy 94.212002 -226.540566) (xy 94.228118 -226.58884) (xy 94.236282 -226.639074) (xy 94.236794 -226.66452)
			(xy 94.236291 -226.689509) (xy 94.543608 -226.689509) (xy 94.543608 -226.639531) (xy 94.551427 -226.590168)
			(xy 94.566871 -226.542636) (xy 94.589561 -226.498104) (xy 94.618937 -226.457671) (xy 94.654277 -226.422331)
			(xy 94.69471 -226.392955) (xy 94.739242 -226.370265) (xy 94.786774 -226.354821) (xy 94.836137 -226.347002)
			(xy 94.886115 -226.347002) (xy 94.935478 -226.354821) (xy 94.98301 -226.370265) (xy 95.027542 -226.392955)
			(xy 95.067975 -226.422331) (xy 95.103315 -226.457671) (xy 95.132691 -226.498104) (xy 95.155381 -226.542636)
			(xy 95.170825 -226.590168) (xy 95.178644 -226.639531) (xy 95.179134 -226.66452) (xy 95.484691 -226.66452)
			(xy 95.488786 -226.613792) (xy 95.500965 -226.564378) (xy 95.520913 -226.517558) (xy 95.548114 -226.474544)
			(xy 95.581862 -226.43645) (xy 95.621284 -226.404263) (xy 95.665358 -226.378817) (xy 95.712944 -226.36077)
			(xy 95.762808 -226.35059) (xy 95.81366 -226.348541) (xy 95.864181 -226.354675) (xy 95.913065 -226.368835)
			(xy 95.959044 -226.390652) (xy 96.000928 -226.419562) (xy 96.037632 -226.454817) (xy 96.068205 -226.495503)
			(xy 96.091856 -226.540566) (xy 96.107972 -226.58884) (xy 96.116136 -226.639074) (xy 96.116648 -226.66452)
			(xy 96.116145 -226.689509) (xy 96.423462 -226.689509) (xy 96.423462 -226.639531) (xy 96.431281 -226.590168)
			(xy 96.446725 -226.542636) (xy 96.469415 -226.498104) (xy 96.498791 -226.457671) (xy 96.534131 -226.422331)
			(xy 96.574564 -226.392955) (xy 96.619096 -226.370265) (xy 96.666628 -226.354821) (xy 96.715991 -226.347002)
			(xy 96.765969 -226.347002) (xy 96.815332 -226.354821) (xy 96.862864 -226.370265) (xy 96.907396 -226.392955)
			(xy 96.947829 -226.422331) (xy 96.983169 -226.457671) (xy 97.012545 -226.498104) (xy 97.035235 -226.542636)
			(xy 97.050679 -226.590168) (xy 97.058498 -226.639531) (xy 97.058988 -226.66452) (xy 97.364799 -226.66452)
			(xy 97.368894 -226.613792) (xy 97.381073 -226.564378) (xy 97.401021 -226.517558) (xy 97.428222 -226.474544)
			(xy 97.46197 -226.43645) (xy 97.501392 -226.404263) (xy 97.545466 -226.378817) (xy 97.593052 -226.36077)
			(xy 97.642916 -226.35059) (xy 97.693768 -226.348541) (xy 97.744289 -226.354675) (xy 97.793173 -226.368835)
			(xy 97.839152 -226.390652) (xy 97.881036 -226.419562) (xy 97.91774 -226.454817) (xy 97.948313 -226.495503)
			(xy 97.971964 -226.540566) (xy 97.98808 -226.58884) (xy 97.996244 -226.639074) (xy 97.996756 -226.66452)
			(xy 98.304853 -226.66452) (xy 98.308948 -226.613792) (xy 98.321127 -226.564378) (xy 98.341075 -226.517558)
			(xy 98.368276 -226.474544) (xy 98.402024 -226.43645) (xy 98.441446 -226.404263) (xy 98.48552 -226.378817)
			(xy 98.533106 -226.36077) (xy 98.58297 -226.35059) (xy 98.633822 -226.348541) (xy 98.684343 -226.354675)
			(xy 98.733227 -226.368835) (xy 98.779206 -226.390652) (xy 98.82109 -226.419562) (xy 98.857794 -226.454817)
			(xy 98.888367 -226.495503) (xy 98.912018 -226.540566) (xy 98.928134 -226.58884) (xy 98.936298 -226.639074)
			(xy 98.93681 -226.66452) (xy 98.936307 -226.689509) (xy 99.243624 -226.689509) (xy 99.243624 -226.639531)
			(xy 99.251443 -226.590168) (xy 99.266887 -226.542636) (xy 99.289577 -226.498104) (xy 99.318953 -226.457671)
			(xy 99.354293 -226.422331) (xy 99.394726 -226.392955) (xy 99.439258 -226.370265) (xy 99.48679 -226.354821)
			(xy 99.536153 -226.347002) (xy 99.586131 -226.347002) (xy 99.635494 -226.354821) (xy 99.683026 -226.370265)
			(xy 99.727558 -226.392955) (xy 99.767991 -226.422331) (xy 99.803331 -226.457671) (xy 99.832707 -226.498104)
			(xy 99.855397 -226.542636) (xy 99.870841 -226.590168) (xy 99.87866 -226.639531) (xy 99.87915 -226.66452)
			(xy 100.184707 -226.66452) (xy 100.188802 -226.613792) (xy 100.200981 -226.564378) (xy 100.220929 -226.517558)
			(xy 100.24813 -226.474544) (xy 100.281878 -226.43645) (xy 100.3213 -226.404263) (xy 100.365374 -226.378817)
			(xy 100.41296 -226.36077) (xy 100.462824 -226.35059) (xy 100.513676 -226.348541) (xy 100.564197 -226.354675)
			(xy 100.613081 -226.368835) (xy 100.65906 -226.390652) (xy 100.700944 -226.419562) (xy 100.737648 -226.454817)
			(xy 100.768221 -226.495503) (xy 100.791872 -226.540566) (xy 100.807988 -226.58884) (xy 100.816152 -226.639074)
			(xy 100.816664 -226.66452) (xy 101.124761 -226.66452) (xy 101.128856 -226.613792) (xy 101.141035 -226.564378)
			(xy 101.160983 -226.517558) (xy 101.188184 -226.474544) (xy 101.221932 -226.43645) (xy 101.261354 -226.404263)
			(xy 101.305428 -226.378817) (xy 101.353014 -226.36077) (xy 101.402878 -226.35059) (xy 101.45373 -226.348541)
			(xy 101.504251 -226.354675) (xy 101.553135 -226.368835) (xy 101.599114 -226.390652) (xy 101.640998 -226.419562)
			(xy 101.677702 -226.454817) (xy 101.708275 -226.495503) (xy 101.731926 -226.540566) (xy 101.748042 -226.58884)
			(xy 101.756206 -226.639074) (xy 101.756718 -226.66452) (xy 101.756215 -226.689509) (xy 102.063532 -226.689509)
			(xy 102.063532 -226.639531) (xy 102.071351 -226.590168) (xy 102.086795 -226.542636) (xy 102.109485 -226.498104)
			(xy 102.138861 -226.457671) (xy 102.174201 -226.422331) (xy 102.214634 -226.392955) (xy 102.259166 -226.370265)
			(xy 102.306698 -226.354821) (xy 102.356061 -226.347002) (xy 102.406039 -226.347002) (xy 102.455402 -226.354821)
			(xy 102.502934 -226.370265) (xy 102.547466 -226.392955) (xy 102.587899 -226.422331) (xy 102.623239 -226.457671)
			(xy 102.652615 -226.498104) (xy 102.675305 -226.542636) (xy 102.690749 -226.590168) (xy 102.698568 -226.639531)
			(xy 102.699058 -226.66452) (xy 103.004869 -226.66452) (xy 103.008964 -226.613792) (xy 103.021143 -226.564378)
			(xy 103.041091 -226.517558) (xy 103.068292 -226.474544) (xy 103.10204 -226.43645) (xy 103.141462 -226.404263)
			(xy 103.185536 -226.378817) (xy 103.233122 -226.36077) (xy 103.282986 -226.35059) (xy 103.333838 -226.348541)
			(xy 103.384359 -226.354675) (xy 103.433243 -226.368835) (xy 103.479222 -226.390652) (xy 103.521106 -226.419562)
			(xy 103.55781 -226.454817) (xy 103.588383 -226.495503) (xy 103.612034 -226.540566) (xy 103.62815 -226.58884)
			(xy 103.636314 -226.639074) (xy 103.636826 -226.66452) (xy 103.944923 -226.66452) (xy 103.949018 -226.613792)
			(xy 103.961197 -226.564378) (xy 103.981145 -226.517558) (xy 104.008346 -226.474544) (xy 104.042094 -226.43645)
			(xy 104.081516 -226.404263) (xy 104.12559 -226.378817) (xy 104.173176 -226.36077) (xy 104.22304 -226.35059)
			(xy 104.273892 -226.348541) (xy 104.324413 -226.354675) (xy 104.373297 -226.368835) (xy 104.419276 -226.390652)
			(xy 104.46116 -226.419562) (xy 104.497864 -226.454817) (xy 104.528437 -226.495503) (xy 104.552088 -226.540566)
			(xy 104.568204 -226.58884) (xy 104.576368 -226.639074) (xy 104.57688 -226.66452) (xy 104.576377 -226.689509)
			(xy 104.88344 -226.689509) (xy 104.88344 -226.639531) (xy 104.891259 -226.590168) (xy 104.906703 -226.542636)
			(xy 104.929393 -226.498104) (xy 104.958769 -226.457671) (xy 104.994109 -226.422331) (xy 105.034542 -226.392955)
			(xy 105.079074 -226.370265) (xy 105.126606 -226.354821) (xy 105.175969 -226.347002) (xy 105.225947 -226.347002)
			(xy 105.27531 -226.354821) (xy 105.322842 -226.370265) (xy 105.367374 -226.392955) (xy 105.407807 -226.422331)
			(xy 105.443147 -226.457671) (xy 105.472523 -226.498104) (xy 105.495213 -226.542636) (xy 105.510657 -226.590168)
			(xy 105.518476 -226.639531) (xy 105.518966 -226.66452) (xy 105.824777 -226.66452) (xy 105.828872 -226.613792)
			(xy 105.841051 -226.564378) (xy 105.860999 -226.517558) (xy 105.8882 -226.474544) (xy 105.921948 -226.43645)
			(xy 105.96137 -226.404263) (xy 106.005444 -226.378817) (xy 106.05303 -226.36077) (xy 106.102894 -226.35059)
			(xy 106.153746 -226.348541) (xy 106.204267 -226.354675) (xy 106.253151 -226.368835) (xy 106.29913 -226.390652)
			(xy 106.341014 -226.419562) (xy 106.377718 -226.454817) (xy 106.408291 -226.495503) (xy 106.431942 -226.540566)
			(xy 106.448058 -226.58884) (xy 106.456222 -226.639074) (xy 106.456734 -226.66452) (xy 106.764831 -226.66452)
			(xy 106.768926 -226.613792) (xy 106.781105 -226.564378) (xy 106.801053 -226.517558) (xy 106.828254 -226.474544)
			(xy 106.862002 -226.43645) (xy 106.901424 -226.404263) (xy 106.945498 -226.378817) (xy 106.993084 -226.36077)
			(xy 107.042948 -226.35059) (xy 107.0938 -226.348541) (xy 107.144321 -226.354675) (xy 107.193205 -226.368835)
			(xy 107.239184 -226.390652) (xy 107.281068 -226.419562) (xy 107.317772 -226.454817) (xy 107.348345 -226.495503)
			(xy 107.371996 -226.540566) (xy 107.388112 -226.58884) (xy 107.396276 -226.639074) (xy 107.396788 -226.66452)
			(xy 107.396285 -226.689509) (xy 107.703602 -226.689509) (xy 107.703602 -226.639531) (xy 107.711421 -226.590168)
			(xy 107.726865 -226.542636) (xy 107.749555 -226.498104) (xy 107.778931 -226.457671) (xy 107.814271 -226.422331)
			(xy 107.854704 -226.392955) (xy 107.899236 -226.370265) (xy 107.946768 -226.354821) (xy 107.996131 -226.347002)
			(xy 108.046109 -226.347002) (xy 108.095472 -226.354821) (xy 108.143004 -226.370265) (xy 108.187536 -226.392955)
			(xy 108.227969 -226.422331) (xy 108.263309 -226.457671) (xy 108.292685 -226.498104) (xy 108.315375 -226.542636)
			(xy 108.330819 -226.590168) (xy 108.338638 -226.639531) (xy 108.339128 -226.66452) (xy 108.338638 -226.689509)
			(xy 115.217176 -226.689509) (xy 115.217176 -226.639531) (xy 115.224995 -226.590168) (xy 115.240439 -226.542636)
			(xy 115.263129 -226.498104) (xy 115.292505 -226.457671) (xy 115.327845 -226.422331) (xy 115.368278 -226.392955)
			(xy 115.41281 -226.370265) (xy 115.460342 -226.354821) (xy 115.509705 -226.347002) (xy 115.559683 -226.347002)
			(xy 115.609046 -226.354821) (xy 115.656578 -226.370265) (xy 115.70111 -226.392955) (xy 115.741543 -226.422331)
			(xy 115.776883 -226.457671) (xy 115.806259 -226.498104) (xy 115.828949 -226.542636) (xy 115.844393 -226.590168)
			(xy 115.852212 -226.639531) (xy 115.852702 -226.66452) (xy 116.158513 -226.66452) (xy 116.162608 -226.613792)
			(xy 116.174787 -226.564378) (xy 116.194735 -226.517558) (xy 116.221936 -226.474544) (xy 116.255684 -226.43645)
			(xy 116.295106 -226.404263) (xy 116.33918 -226.378817) (xy 116.386766 -226.36077) (xy 116.43663 -226.35059)
			(xy 116.487482 -226.348541) (xy 116.538003 -226.354675) (xy 116.586887 -226.368835) (xy 116.632866 -226.390652)
			(xy 116.67475 -226.419562) (xy 116.711454 -226.454817) (xy 116.742027 -226.495503) (xy 116.765678 -226.540566)
			(xy 116.781794 -226.58884) (xy 116.789958 -226.639074) (xy 116.79047 -226.66452) (xy 117.098567 -226.66452)
			(xy 117.102662 -226.613792) (xy 117.114841 -226.564378) (xy 117.134789 -226.517558) (xy 117.16199 -226.474544)
			(xy 117.195738 -226.43645) (xy 117.23516 -226.404263) (xy 117.279234 -226.378817) (xy 117.32682 -226.36077)
			(xy 117.376684 -226.35059) (xy 117.427536 -226.348541) (xy 117.478057 -226.354675) (xy 117.526941 -226.368835)
			(xy 117.57292 -226.390652) (xy 117.614804 -226.419562) (xy 117.651508 -226.454817) (xy 117.682081 -226.495503)
			(xy 117.705732 -226.540566) (xy 117.721848 -226.58884) (xy 117.730012 -226.639074) (xy 117.730524 -226.66452)
			(xy 117.730021 -226.689509) (xy 118.037338 -226.689509) (xy 118.037338 -226.639531) (xy 118.045157 -226.590168)
			(xy 118.060601 -226.542636) (xy 118.083291 -226.498104) (xy 118.112667 -226.457671) (xy 118.148007 -226.422331)
			(xy 118.18844 -226.392955) (xy 118.232972 -226.370265) (xy 118.280504 -226.354821) (xy 118.329867 -226.347002)
			(xy 118.379845 -226.347002) (xy 118.429208 -226.354821) (xy 118.47674 -226.370265) (xy 118.521272 -226.392955)
			(xy 118.561705 -226.422331) (xy 118.597045 -226.457671) (xy 118.626421 -226.498104) (xy 118.649111 -226.542636)
			(xy 118.664555 -226.590168) (xy 118.672374 -226.639531) (xy 118.672864 -226.66452) (xy 118.978421 -226.66452)
			(xy 118.982516 -226.613792) (xy 118.994695 -226.564378) (xy 119.014643 -226.517558) (xy 119.041844 -226.474544)
			(xy 119.075592 -226.43645) (xy 119.115014 -226.404263) (xy 119.159088 -226.378817) (xy 119.206674 -226.36077)
			(xy 119.256538 -226.35059) (xy 119.30739 -226.348541) (xy 119.357911 -226.354675) (xy 119.406795 -226.368835)
			(xy 119.452774 -226.390652) (xy 119.494658 -226.419562) (xy 119.531362 -226.454817) (xy 119.561935 -226.495503)
			(xy 119.585586 -226.540566) (xy 119.601702 -226.58884) (xy 119.609866 -226.639074) (xy 119.610378 -226.66452)
			(xy 119.918475 -226.66452) (xy 119.92257 -226.613792) (xy 119.934749 -226.564378) (xy 119.954697 -226.517558)
			(xy 119.981898 -226.474544) (xy 120.015646 -226.43645) (xy 120.055068 -226.404263) (xy 120.099142 -226.378817)
			(xy 120.146728 -226.36077) (xy 120.196592 -226.35059) (xy 120.247444 -226.348541) (xy 120.297965 -226.354675)
			(xy 120.346849 -226.368835) (xy 120.392828 -226.390652) (xy 120.434712 -226.419562) (xy 120.471416 -226.454817)
			(xy 120.501989 -226.495503) (xy 120.52564 -226.540566) (xy 120.541756 -226.58884) (xy 120.54992 -226.639074)
			(xy 120.550432 -226.66452) (xy 120.549929 -226.689509) (xy 120.857246 -226.689509) (xy 120.857246 -226.639531)
			(xy 120.865065 -226.590168) (xy 120.880509 -226.542636) (xy 120.903199 -226.498104) (xy 120.932575 -226.457671)
			(xy 120.967915 -226.422331) (xy 121.008348 -226.392955) (xy 121.05288 -226.370265) (xy 121.100412 -226.354821)
			(xy 121.149775 -226.347002) (xy 121.199753 -226.347002) (xy 121.249116 -226.354821) (xy 121.296648 -226.370265)
			(xy 121.34118 -226.392955) (xy 121.381613 -226.422331) (xy 121.416953 -226.457671) (xy 121.446329 -226.498104)
			(xy 121.469019 -226.542636) (xy 121.484463 -226.590168) (xy 121.492282 -226.639531) (xy 121.492772 -226.66452)
			(xy 121.798583 -226.66452) (xy 121.802678 -226.613792) (xy 121.814857 -226.564378) (xy 121.834805 -226.517558)
			(xy 121.862006 -226.474544) (xy 121.895754 -226.43645) (xy 121.935176 -226.404263) (xy 121.97925 -226.378817)
			(xy 122.026836 -226.36077) (xy 122.0767 -226.35059) (xy 122.127552 -226.348541) (xy 122.178073 -226.354675)
			(xy 122.226957 -226.368835) (xy 122.272936 -226.390652) (xy 122.31482 -226.419562) (xy 122.351524 -226.454817)
			(xy 122.382097 -226.495503) (xy 122.405748 -226.540566) (xy 122.421864 -226.58884) (xy 122.430028 -226.639074)
			(xy 122.43054 -226.66452) (xy 122.738383 -226.66452) (xy 122.742478 -226.613792) (xy 122.754657 -226.564378)
			(xy 122.774605 -226.517558) (xy 122.801806 -226.474544) (xy 122.835554 -226.43645) (xy 122.874976 -226.404263)
			(xy 122.91905 -226.378817) (xy 122.966636 -226.36077) (xy 123.0165 -226.35059) (xy 123.067352 -226.348541)
			(xy 123.117873 -226.354675) (xy 123.166757 -226.368835) (xy 123.212736 -226.390652) (xy 123.25462 -226.419562)
			(xy 123.291324 -226.454817) (xy 123.321897 -226.495503) (xy 123.345548 -226.540566) (xy 123.361664 -226.58884)
			(xy 123.369828 -226.639074) (xy 123.37034 -226.66452) (xy 123.369837 -226.689509) (xy 123.677154 -226.689509)
			(xy 123.677154 -226.639531) (xy 123.684973 -226.590168) (xy 123.700417 -226.542636) (xy 123.723107 -226.498104)
			(xy 123.752483 -226.457671) (xy 123.787823 -226.422331) (xy 123.828256 -226.392955) (xy 123.872788 -226.370265)
			(xy 123.92032 -226.354821) (xy 123.969683 -226.347002) (xy 124.019661 -226.347002) (xy 124.069024 -226.354821)
			(xy 124.116556 -226.370265) (xy 124.161088 -226.392955) (xy 124.201521 -226.422331) (xy 124.236861 -226.457671)
			(xy 124.266237 -226.498104) (xy 124.288927 -226.542636) (xy 124.304371 -226.590168) (xy 124.31219 -226.639531)
			(xy 124.31268 -226.66452) (xy 124.618491 -226.66452) (xy 124.622586 -226.613792) (xy 124.634765 -226.564378)
			(xy 124.654713 -226.517558) (xy 124.681914 -226.474544) (xy 124.715662 -226.43645) (xy 124.755084 -226.404263)
			(xy 124.799158 -226.378817) (xy 124.846744 -226.36077) (xy 124.896608 -226.35059) (xy 124.94746 -226.348541)
			(xy 124.997981 -226.354675) (xy 125.046865 -226.368835) (xy 125.092844 -226.390652) (xy 125.134728 -226.419562)
			(xy 125.171432 -226.454817) (xy 125.202005 -226.495503) (xy 125.225656 -226.540566) (xy 125.241772 -226.58884)
			(xy 125.249936 -226.639074) (xy 125.250448 -226.66452) (xy 125.558545 -226.66452) (xy 125.56264 -226.613792)
			(xy 125.574819 -226.564378) (xy 125.594767 -226.517558) (xy 125.621968 -226.474544) (xy 125.655716 -226.43645)
			(xy 125.695138 -226.404263) (xy 125.739212 -226.378817) (xy 125.786798 -226.36077) (xy 125.836662 -226.35059)
			(xy 125.887514 -226.348541) (xy 125.938035 -226.354675) (xy 125.986919 -226.368835) (xy 126.032898 -226.390652)
			(xy 126.074782 -226.419562) (xy 126.111486 -226.454817) (xy 126.142059 -226.495503) (xy 126.16571 -226.540566)
			(xy 126.181826 -226.58884) (xy 126.18999 -226.639074) (xy 126.190502 -226.66452) (xy 126.18999 -226.689966)
			(xy 126.181826 -226.7402) (xy 126.16571 -226.788474) (xy 126.142059 -226.833537) (xy 126.111486 -226.874223)
			(xy 126.074782 -226.909478) (xy 126.032898 -226.938388) (xy 125.986919 -226.960205) (xy 125.938035 -226.974365)
			(xy 125.887514 -226.980499) (xy 125.836662 -226.97845) (xy 125.786798 -226.96827) (xy 125.739212 -226.950223)
			(xy 125.695138 -226.924777) (xy 125.655716 -226.89259) (xy 125.621968 -226.854496) (xy 125.594767 -226.811482)
			(xy 125.574819 -226.764662) (xy 125.56264 -226.715248) (xy 125.558545 -226.66452) (xy 125.250448 -226.66452)
			(xy 125.249936 -226.689966) (xy 125.241772 -226.7402) (xy 125.225656 -226.788474) (xy 125.202005 -226.833537)
			(xy 125.171432 -226.874223) (xy 125.134728 -226.909478) (xy 125.092844 -226.938388) (xy 125.046865 -226.960205)
			(xy 124.997981 -226.974365) (xy 124.94746 -226.980499) (xy 124.896608 -226.97845) (xy 124.846744 -226.96827)
			(xy 124.799158 -226.950223) (xy 124.755084 -226.924777) (xy 124.715662 -226.89259) (xy 124.681914 -226.854496)
			(xy 124.654713 -226.811482) (xy 124.634765 -226.764662) (xy 124.622586 -226.715248) (xy 124.618491 -226.66452)
			(xy 124.31268 -226.66452) (xy 124.31219 -226.689509) (xy 124.304371 -226.738872) (xy 124.288927 -226.786404)
			(xy 124.266237 -226.830936) (xy 124.236861 -226.871369) (xy 124.201521 -226.906709) (xy 124.161088 -226.936085)
			(xy 124.116556 -226.958775) (xy 124.069024 -226.974219) (xy 124.019661 -226.982038) (xy 123.969683 -226.982038)
			(xy 123.92032 -226.974219) (xy 123.872788 -226.958775) (xy 123.828256 -226.936085) (xy 123.787823 -226.906709)
			(xy 123.752483 -226.871369) (xy 123.723107 -226.830936) (xy 123.700417 -226.786404) (xy 123.684973 -226.738872)
			(xy 123.677154 -226.689509) (xy 123.369837 -226.689509) (xy 123.369828 -226.689966) (xy 123.361664 -226.7402)
			(xy 123.345548 -226.788474) (xy 123.321897 -226.833537) (xy 123.291324 -226.874223) (xy 123.25462 -226.909478)
			(xy 123.212736 -226.938388) (xy 123.166757 -226.960205) (xy 123.117873 -226.974365) (xy 123.067352 -226.980499)
			(xy 123.0165 -226.97845) (xy 122.966636 -226.96827) (xy 122.91905 -226.950223) (xy 122.874976 -226.924777)
			(xy 122.835554 -226.89259) (xy 122.801806 -226.854496) (xy 122.774605 -226.811482) (xy 122.754657 -226.764662)
			(xy 122.742478 -226.715248) (xy 122.738383 -226.66452) (xy 122.43054 -226.66452) (xy 122.430028 -226.689966)
			(xy 122.421864 -226.7402) (xy 122.405748 -226.788474) (xy 122.382097 -226.833537) (xy 122.351524 -226.874223)
			(xy 122.31482 -226.909478) (xy 122.272936 -226.938388) (xy 122.226957 -226.960205) (xy 122.178073 -226.974365)
			(xy 122.127552 -226.980499) (xy 122.0767 -226.97845) (xy 122.026836 -226.96827) (xy 121.97925 -226.950223)
			(xy 121.935176 -226.924777) (xy 121.895754 -226.89259) (xy 121.862006 -226.854496) (xy 121.834805 -226.811482)
			(xy 121.814857 -226.764662) (xy 121.802678 -226.715248) (xy 121.798583 -226.66452) (xy 121.492772 -226.66452)
			(xy 121.492282 -226.689509) (xy 121.484463 -226.738872) (xy 121.469019 -226.786404) (xy 121.446329 -226.830936)
			(xy 121.416953 -226.871369) (xy 121.381613 -226.906709) (xy 121.34118 -226.936085) (xy 121.296648 -226.958775)
			(xy 121.249116 -226.974219) (xy 121.199753 -226.982038) (xy 121.149775 -226.982038) (xy 121.100412 -226.974219)
			(xy 121.05288 -226.958775) (xy 121.008348 -226.936085) (xy 120.967915 -226.906709) (xy 120.932575 -226.871369)
			(xy 120.903199 -226.830936) (xy 120.880509 -226.786404) (xy 120.865065 -226.738872) (xy 120.857246 -226.689509)
			(xy 120.549929 -226.689509) (xy 120.54992 -226.689966) (xy 120.541756 -226.7402) (xy 120.52564 -226.788474)
			(xy 120.501989 -226.833537) (xy 120.471416 -226.874223) (xy 120.434712 -226.909478) (xy 120.392828 -226.938388)
			(xy 120.346849 -226.960205) (xy 120.297965 -226.974365) (xy 120.247444 -226.980499) (xy 120.196592 -226.97845)
			(xy 120.146728 -226.96827) (xy 120.099142 -226.950223) (xy 120.055068 -226.924777) (xy 120.015646 -226.89259)
			(xy 119.981898 -226.854496) (xy 119.954697 -226.811482) (xy 119.934749 -226.764662) (xy 119.92257 -226.715248)
			(xy 119.918475 -226.66452) (xy 119.610378 -226.66452) (xy 119.609866 -226.689966) (xy 119.601702 -226.7402)
			(xy 119.585586 -226.788474) (xy 119.561935 -226.833537) (xy 119.531362 -226.874223) (xy 119.494658 -226.909478)
			(xy 119.452774 -226.938388) (xy 119.406795 -226.960205) (xy 119.357911 -226.974365) (xy 119.30739 -226.980499)
			(xy 119.256538 -226.97845) (xy 119.206674 -226.96827) (xy 119.159088 -226.950223) (xy 119.115014 -226.924777)
			(xy 119.075592 -226.89259) (xy 119.041844 -226.854496) (xy 119.014643 -226.811482) (xy 118.994695 -226.764662)
			(xy 118.982516 -226.715248) (xy 118.978421 -226.66452) (xy 118.672864 -226.66452) (xy 118.672374 -226.689509)
			(xy 118.664555 -226.738872) (xy 118.649111 -226.786404) (xy 118.626421 -226.830936) (xy 118.597045 -226.871369)
			(xy 118.561705 -226.906709) (xy 118.521272 -226.936085) (xy 118.47674 -226.958775) (xy 118.429208 -226.974219)
			(xy 118.379845 -226.982038) (xy 118.329867 -226.982038) (xy 118.280504 -226.974219) (xy 118.232972 -226.958775)
			(xy 118.18844 -226.936085) (xy 118.148007 -226.906709) (xy 118.112667 -226.871369) (xy 118.083291 -226.830936)
			(xy 118.060601 -226.786404) (xy 118.045157 -226.738872) (xy 118.037338 -226.689509) (xy 117.730021 -226.689509)
			(xy 117.730012 -226.689966) (xy 117.721848 -226.7402) (xy 117.705732 -226.788474) (xy 117.682081 -226.833537)
			(xy 117.651508 -226.874223) (xy 117.614804 -226.909478) (xy 117.57292 -226.938388) (xy 117.526941 -226.960205)
			(xy 117.478057 -226.974365) (xy 117.427536 -226.980499) (xy 117.376684 -226.97845) (xy 117.32682 -226.96827)
			(xy 117.279234 -226.950223) (xy 117.23516 -226.924777) (xy 117.195738 -226.89259) (xy 117.16199 -226.854496)
			(xy 117.134789 -226.811482) (xy 117.114841 -226.764662) (xy 117.102662 -226.715248) (xy 117.098567 -226.66452)
			(xy 116.79047 -226.66452) (xy 116.789958 -226.689966) (xy 116.781794 -226.7402) (xy 116.765678 -226.788474)
			(xy 116.742027 -226.833537) (xy 116.711454 -226.874223) (xy 116.67475 -226.909478) (xy 116.632866 -226.938388)
			(xy 116.586887 -226.960205) (xy 116.538003 -226.974365) (xy 116.487482 -226.980499) (xy 116.43663 -226.97845)
			(xy 116.386766 -226.96827) (xy 116.33918 -226.950223) (xy 116.295106 -226.924777) (xy 116.255684 -226.89259)
			(xy 116.221936 -226.854496) (xy 116.194735 -226.811482) (xy 116.174787 -226.764662) (xy 116.162608 -226.715248)
			(xy 116.158513 -226.66452) (xy 115.852702 -226.66452) (xy 115.852212 -226.689509) (xy 115.844393 -226.738872)
			(xy 115.828949 -226.786404) (xy 115.806259 -226.830936) (xy 115.776883 -226.871369) (xy 115.741543 -226.906709)
			(xy 115.70111 -226.936085) (xy 115.656578 -226.958775) (xy 115.609046 -226.974219) (xy 115.559683 -226.982038)
			(xy 115.509705 -226.982038) (xy 115.460342 -226.974219) (xy 115.41281 -226.958775) (xy 115.368278 -226.936085)
			(xy 115.327845 -226.906709) (xy 115.292505 -226.871369) (xy 115.263129 -226.830936) (xy 115.240439 -226.786404)
			(xy 115.224995 -226.738872) (xy 115.217176 -226.689509) (xy 108.338638 -226.689509) (xy 108.330819 -226.738872)
			(xy 108.315375 -226.786404) (xy 108.292685 -226.830936) (xy 108.263309 -226.871369) (xy 108.227969 -226.906709)
			(xy 108.187536 -226.936085) (xy 108.143004 -226.958775) (xy 108.095472 -226.974219) (xy 108.046109 -226.982038)
			(xy 107.996131 -226.982038) (xy 107.946768 -226.974219) (xy 107.899236 -226.958775) (xy 107.854704 -226.936085)
			(xy 107.814271 -226.906709) (xy 107.778931 -226.871369) (xy 107.749555 -226.830936) (xy 107.726865 -226.786404)
			(xy 107.711421 -226.738872) (xy 107.703602 -226.689509) (xy 107.396285 -226.689509) (xy 107.396276 -226.689966)
			(xy 107.388112 -226.7402) (xy 107.371996 -226.788474) (xy 107.348345 -226.833537) (xy 107.317772 -226.874223)
			(xy 107.281068 -226.909478) (xy 107.239184 -226.938388) (xy 107.193205 -226.960205) (xy 107.144321 -226.974365)
			(xy 107.0938 -226.980499) (xy 107.042948 -226.97845) (xy 106.993084 -226.96827) (xy 106.945498 -226.950223)
			(xy 106.901424 -226.924777) (xy 106.862002 -226.89259) (xy 106.828254 -226.854496) (xy 106.801053 -226.811482)
			(xy 106.781105 -226.764662) (xy 106.768926 -226.715248) (xy 106.764831 -226.66452) (xy 106.456734 -226.66452)
			(xy 106.456222 -226.689966) (xy 106.448058 -226.7402) (xy 106.431942 -226.788474) (xy 106.408291 -226.833537)
			(xy 106.377718 -226.874223) (xy 106.341014 -226.909478) (xy 106.29913 -226.938388) (xy 106.253151 -226.960205)
			(xy 106.204267 -226.974365) (xy 106.153746 -226.980499) (xy 106.102894 -226.97845) (xy 106.05303 -226.96827)
			(xy 106.005444 -226.950223) (xy 105.96137 -226.924777) (xy 105.921948 -226.89259) (xy 105.8882 -226.854496)
			(xy 105.860999 -226.811482) (xy 105.841051 -226.764662) (xy 105.828872 -226.715248) (xy 105.824777 -226.66452)
			(xy 105.518966 -226.66452) (xy 105.518476 -226.689509) (xy 105.510657 -226.738872) (xy 105.495213 -226.786404)
			(xy 105.472523 -226.830936) (xy 105.443147 -226.871369) (xy 105.407807 -226.906709) (xy 105.367374 -226.936085)
			(xy 105.322842 -226.958775) (xy 105.27531 -226.974219) (xy 105.225947 -226.982038) (xy 105.175969 -226.982038)
			(xy 105.126606 -226.974219) (xy 105.079074 -226.958775) (xy 105.034542 -226.936085) (xy 104.994109 -226.906709)
			(xy 104.958769 -226.871369) (xy 104.929393 -226.830936) (xy 104.906703 -226.786404) (xy 104.891259 -226.738872)
			(xy 104.88344 -226.689509) (xy 104.576377 -226.689509) (xy 104.576368 -226.689966) (xy 104.568204 -226.7402)
			(xy 104.552088 -226.788474) (xy 104.528437 -226.833537) (xy 104.497864 -226.874223) (xy 104.46116 -226.909478)
			(xy 104.419276 -226.938388) (xy 104.373297 -226.960205) (xy 104.324413 -226.974365) (xy 104.273892 -226.980499)
			(xy 104.22304 -226.97845) (xy 104.173176 -226.96827) (xy 104.12559 -226.950223) (xy 104.081516 -226.924777)
			(xy 104.042094 -226.89259) (xy 104.008346 -226.854496) (xy 103.981145 -226.811482) (xy 103.961197 -226.764662)
			(xy 103.949018 -226.715248) (xy 103.944923 -226.66452) (xy 103.636826 -226.66452) (xy 103.636314 -226.689966)
			(xy 103.62815 -226.7402) (xy 103.612034 -226.788474) (xy 103.588383 -226.833537) (xy 103.55781 -226.874223)
			(xy 103.521106 -226.909478) (xy 103.479222 -226.938388) (xy 103.433243 -226.960205) (xy 103.384359 -226.974365)
			(xy 103.333838 -226.980499) (xy 103.282986 -226.97845) (xy 103.233122 -226.96827) (xy 103.185536 -226.950223)
			(xy 103.141462 -226.924777) (xy 103.10204 -226.89259) (xy 103.068292 -226.854496) (xy 103.041091 -226.811482)
			(xy 103.021143 -226.764662) (xy 103.008964 -226.715248) (xy 103.004869 -226.66452) (xy 102.699058 -226.66452)
			(xy 102.698568 -226.689509) (xy 102.690749 -226.738872) (xy 102.675305 -226.786404) (xy 102.652615 -226.830936)
			(xy 102.623239 -226.871369) (xy 102.587899 -226.906709) (xy 102.547466 -226.936085) (xy 102.502934 -226.958775)
			(xy 102.455402 -226.974219) (xy 102.406039 -226.982038) (xy 102.356061 -226.982038) (xy 102.306698 -226.974219)
			(xy 102.259166 -226.958775) (xy 102.214634 -226.936085) (xy 102.174201 -226.906709) (xy 102.138861 -226.871369)
			(xy 102.109485 -226.830936) (xy 102.086795 -226.786404) (xy 102.071351 -226.738872) (xy 102.063532 -226.689509)
			(xy 101.756215 -226.689509) (xy 101.756206 -226.689966) (xy 101.748042 -226.7402) (xy 101.731926 -226.788474)
			(xy 101.708275 -226.833537) (xy 101.677702 -226.874223) (xy 101.640998 -226.909478) (xy 101.599114 -226.938388)
			(xy 101.553135 -226.960205) (xy 101.504251 -226.974365) (xy 101.45373 -226.980499) (xy 101.402878 -226.97845)
			(xy 101.353014 -226.96827) (xy 101.305428 -226.950223) (xy 101.261354 -226.924777) (xy 101.221932 -226.89259)
			(xy 101.188184 -226.854496) (xy 101.160983 -226.811482) (xy 101.141035 -226.764662) (xy 101.128856 -226.715248)
			(xy 101.124761 -226.66452) (xy 100.816664 -226.66452) (xy 100.816152 -226.689966) (xy 100.807988 -226.7402)
			(xy 100.791872 -226.788474) (xy 100.768221 -226.833537) (xy 100.737648 -226.874223) (xy 100.700944 -226.909478)
			(xy 100.65906 -226.938388) (xy 100.613081 -226.960205) (xy 100.564197 -226.974365) (xy 100.513676 -226.980499)
			(xy 100.462824 -226.97845) (xy 100.41296 -226.96827) (xy 100.365374 -226.950223) (xy 100.3213 -226.924777)
			(xy 100.281878 -226.89259) (xy 100.24813 -226.854496) (xy 100.220929 -226.811482) (xy 100.200981 -226.764662)
			(xy 100.188802 -226.715248) (xy 100.184707 -226.66452) (xy 99.87915 -226.66452) (xy 99.87866 -226.689509)
			(xy 99.870841 -226.738872) (xy 99.855397 -226.786404) (xy 99.832707 -226.830936) (xy 99.803331 -226.871369)
			(xy 99.767991 -226.906709) (xy 99.727558 -226.936085) (xy 99.683026 -226.958775) (xy 99.635494 -226.974219)
			(xy 99.586131 -226.982038) (xy 99.536153 -226.982038) (xy 99.48679 -226.974219) (xy 99.439258 -226.958775)
			(xy 99.394726 -226.936085) (xy 99.354293 -226.906709) (xy 99.318953 -226.871369) (xy 99.289577 -226.830936)
			(xy 99.266887 -226.786404) (xy 99.251443 -226.738872) (xy 99.243624 -226.689509) (xy 98.936307 -226.689509)
			(xy 98.936298 -226.689966) (xy 98.928134 -226.7402) (xy 98.912018 -226.788474) (xy 98.888367 -226.833537)
			(xy 98.857794 -226.874223) (xy 98.82109 -226.909478) (xy 98.779206 -226.938388) (xy 98.733227 -226.960205)
			(xy 98.684343 -226.974365) (xy 98.633822 -226.980499) (xy 98.58297 -226.97845) (xy 98.533106 -226.96827)
			(xy 98.48552 -226.950223) (xy 98.441446 -226.924777) (xy 98.402024 -226.89259) (xy 98.368276 -226.854496)
			(xy 98.341075 -226.811482) (xy 98.321127 -226.764662) (xy 98.308948 -226.715248) (xy 98.304853 -226.66452)
			(xy 97.996756 -226.66452) (xy 97.996244 -226.689966) (xy 97.98808 -226.7402) (xy 97.971964 -226.788474)
			(xy 97.948313 -226.833537) (xy 97.91774 -226.874223) (xy 97.881036 -226.909478) (xy 97.839152 -226.938388)
			(xy 97.793173 -226.960205) (xy 97.744289 -226.974365) (xy 97.693768 -226.980499) (xy 97.642916 -226.97845)
			(xy 97.593052 -226.96827) (xy 97.545466 -226.950223) (xy 97.501392 -226.924777) (xy 97.46197 -226.89259)
			(xy 97.428222 -226.854496) (xy 97.401021 -226.811482) (xy 97.381073 -226.764662) (xy 97.368894 -226.715248)
			(xy 97.364799 -226.66452) (xy 97.058988 -226.66452) (xy 97.058498 -226.689509) (xy 97.050679 -226.738872)
			(xy 97.035235 -226.786404) (xy 97.012545 -226.830936) (xy 96.983169 -226.871369) (xy 96.947829 -226.906709)
			(xy 96.907396 -226.936085) (xy 96.862864 -226.958775) (xy 96.815332 -226.974219) (xy 96.765969 -226.982038)
			(xy 96.715991 -226.982038) (xy 96.666628 -226.974219) (xy 96.619096 -226.958775) (xy 96.574564 -226.936085)
			(xy 96.534131 -226.906709) (xy 96.498791 -226.871369) (xy 96.469415 -226.830936) (xy 96.446725 -226.786404)
			(xy 96.431281 -226.738872) (xy 96.423462 -226.689509) (xy 96.116145 -226.689509) (xy 96.116136 -226.689966)
			(xy 96.107972 -226.7402) (xy 96.091856 -226.788474) (xy 96.068205 -226.833537) (xy 96.037632 -226.874223)
			(xy 96.000928 -226.909478) (xy 95.959044 -226.938388) (xy 95.913065 -226.960205) (xy 95.864181 -226.974365)
			(xy 95.81366 -226.980499) (xy 95.762808 -226.97845) (xy 95.712944 -226.96827) (xy 95.665358 -226.950223)
			(xy 95.621284 -226.924777) (xy 95.581862 -226.89259) (xy 95.548114 -226.854496) (xy 95.520913 -226.811482)
			(xy 95.500965 -226.764662) (xy 95.488786 -226.715248) (xy 95.484691 -226.66452) (xy 95.179134 -226.66452)
			(xy 95.178644 -226.689509) (xy 95.170825 -226.738872) (xy 95.155381 -226.786404) (xy 95.132691 -226.830936)
			(xy 95.103315 -226.871369) (xy 95.067975 -226.906709) (xy 95.027542 -226.936085) (xy 94.98301 -226.958775)
			(xy 94.935478 -226.974219) (xy 94.886115 -226.982038) (xy 94.836137 -226.982038) (xy 94.786774 -226.974219)
			(xy 94.739242 -226.958775) (xy 94.69471 -226.936085) (xy 94.654277 -226.906709) (xy 94.618937 -226.871369)
			(xy 94.589561 -226.830936) (xy 94.566871 -226.786404) (xy 94.551427 -226.738872) (xy 94.543608 -226.689509)
			(xy 94.236291 -226.689509) (xy 94.236282 -226.689966) (xy 94.228118 -226.7402) (xy 94.212002 -226.788474)
			(xy 94.188351 -226.833537) (xy 94.157778 -226.874223) (xy 94.121074 -226.909478) (xy 94.07919 -226.938388)
			(xy 94.033211 -226.960205) (xy 93.984327 -226.974365) (xy 93.933806 -226.980499) (xy 93.882954 -226.97845)
			(xy 93.83309 -226.96827) (xy 93.785504 -226.950223) (xy 93.74143 -226.924777) (xy 93.702008 -226.89259)
			(xy 93.66826 -226.854496) (xy 93.641059 -226.811482) (xy 93.621111 -226.764662) (xy 93.608932 -226.715248)
			(xy 93.604837 -226.66452) (xy 93.299026 -226.66452) (xy 93.298536 -226.689509) (xy 93.290717 -226.738872)
			(xy 93.275273 -226.786404) (xy 93.252583 -226.830936) (xy 93.223207 -226.871369) (xy 93.187867 -226.906709)
			(xy 93.147434 -226.936085) (xy 93.102902 -226.958775) (xy 93.05537 -226.974219) (xy 93.006007 -226.982038)
			(xy 92.956029 -226.982038) (xy 92.906666 -226.974219) (xy 92.859134 -226.958775) (xy 92.814602 -226.936085)
			(xy 92.774169 -226.906709) (xy 92.738829 -226.871369) (xy 92.709453 -226.830936) (xy 92.686763 -226.786404)
			(xy 92.671319 -226.738872) (xy 92.6635 -226.689509) (xy 92.356183 -226.689509) (xy 92.356174 -226.689966)
			(xy 92.34801 -226.7402) (xy 92.331894 -226.788474) (xy 92.308243 -226.833537) (xy 92.27767 -226.874223)
			(xy 92.240966 -226.909478) (xy 92.199082 -226.938388) (xy 92.153103 -226.960205) (xy 92.104219 -226.974365)
			(xy 92.053698 -226.980499) (xy 92.002846 -226.97845) (xy 91.952982 -226.96827) (xy 91.905396 -226.950223)
			(xy 91.861322 -226.924777) (xy 91.8219 -226.89259) (xy 91.788152 -226.854496) (xy 91.760951 -226.811482)
			(xy 91.741003 -226.764662) (xy 91.728824 -226.715248) (xy 91.724729 -226.66452) (xy 91.416632 -226.66452)
			(xy 91.41612 -226.689966) (xy 91.407956 -226.7402) (xy 91.39184 -226.788474) (xy 91.368189 -226.833537)
			(xy 91.337616 -226.874223) (xy 91.300912 -226.909478) (xy 91.259028 -226.938388) (xy 91.213049 -226.960205)
			(xy 91.164165 -226.974365) (xy 91.113644 -226.980499) (xy 91.062792 -226.97845) (xy 91.012928 -226.96827)
			(xy 90.965342 -226.950223) (xy 90.921268 -226.924777) (xy 90.881846 -226.89259) (xy 90.848098 -226.854496)
			(xy 90.820897 -226.811482) (xy 90.800949 -226.764662) (xy 90.78877 -226.715248) (xy 90.784675 -226.66452)
			(xy 90.479118 -226.66452) (xy 90.478915 -226.682714) (xy 90.474846 -226.718874) (xy 90.47099 -226.736656)
			(xy 90.469212 -226.74453) (xy 90.469212 -226.75723) (xy 90.469674 -226.767106) (xy 90.477122 -226.7854)
			(xy 90.48369 -226.79279) (xy 90.819986 -227.129086) (xy 90.825662 -227.134284) (xy 90.839367 -227.141274)
			(xy 90.84691 -227.142802) (xy 90.847418 -227.142802) (xy 90.855546 -227.143564) (xy 96.65589 -227.143564)
			(xy 96.665727 -227.144103) (xy 96.683886 -227.151691) (xy 96.691196 -227.158296) (xy 97.032415 -227.499515)
			(xy 98.77347 -227.499515) (xy 98.77347 -227.449537) (xy 98.781289 -227.400174) (xy 98.796733 -227.352642)
			(xy 98.819423 -227.30811) (xy 98.848799 -227.267677) (xy 98.884139 -227.232337) (xy 98.924572 -227.202961)
			(xy 98.969104 -227.180271) (xy 99.016636 -227.164827) (xy 99.065999 -227.157008) (xy 99.115977 -227.157008)
			(xy 99.16534 -227.164827) (xy 99.212872 -227.180271) (xy 99.257404 -227.202961) (xy 99.297837 -227.232337)
			(xy 99.333177 -227.267677) (xy 99.362553 -227.30811) (xy 99.385243 -227.352642) (xy 99.400687 -227.400174)
			(xy 99.408506 -227.449537) (xy 99.408996 -227.474526) (xy 99.408506 -227.499515) (xy 101.593632 -227.499515)
			(xy 101.593632 -227.449537) (xy 101.601451 -227.400174) (xy 101.616895 -227.352642) (xy 101.639585 -227.30811)
			(xy 101.668961 -227.267677) (xy 101.704301 -227.232337) (xy 101.744734 -227.202961) (xy 101.789266 -227.180271)
			(xy 101.836798 -227.164827) (xy 101.886161 -227.157008) (xy 101.936139 -227.157008) (xy 101.985502 -227.164827)
			(xy 102.033034 -227.180271) (xy 102.077566 -227.202961) (xy 102.117999 -227.232337) (xy 102.153339 -227.267677)
			(xy 102.182715 -227.30811) (xy 102.205405 -227.352642) (xy 102.220849 -227.400174) (xy 102.228668 -227.449537)
			(xy 102.229158 -227.474526) (xy 102.228668 -227.499515) (xy 104.41354 -227.499515) (xy 104.41354 -227.449537)
			(xy 104.421359 -227.400174) (xy 104.436803 -227.352642) (xy 104.459493 -227.30811) (xy 104.488869 -227.267677)
			(xy 104.524209 -227.232337) (xy 104.564642 -227.202961) (xy 104.609174 -227.180271) (xy 104.656706 -227.164827)
			(xy 104.706069 -227.157008) (xy 104.756047 -227.157008) (xy 104.80541 -227.164827) (xy 104.852942 -227.180271)
			(xy 104.897474 -227.202961) (xy 104.937907 -227.232337) (xy 104.973247 -227.267677) (xy 105.002623 -227.30811)
			(xy 105.025313 -227.352642) (xy 105.040757 -227.400174) (xy 105.048576 -227.449537) (xy 105.049066 -227.474526)
			(xy 105.048576 -227.499515) (xy 107.233448 -227.499515) (xy 107.233448 -227.449537) (xy 107.241267 -227.400174)
			(xy 107.256711 -227.352642) (xy 107.279401 -227.30811) (xy 107.308777 -227.267677) (xy 107.344117 -227.232337)
			(xy 107.38455 -227.202961) (xy 107.429082 -227.180271) (xy 107.476614 -227.164827) (xy 107.525977 -227.157008)
			(xy 107.575955 -227.157008) (xy 107.625318 -227.164827) (xy 107.67285 -227.180271) (xy 107.717382 -227.202961)
			(xy 107.757815 -227.232337) (xy 107.793155 -227.267677) (xy 107.822531 -227.30811) (xy 107.845221 -227.352642)
			(xy 107.860665 -227.400174) (xy 107.868484 -227.449537) (xy 107.868974 -227.474526) (xy 108.174785 -227.474526)
			(xy 108.17888 -227.423798) (xy 108.191059 -227.374384) (xy 108.211007 -227.327564) (xy 108.238208 -227.28455)
			(xy 108.271956 -227.246456) (xy 108.311378 -227.214269) (xy 108.355452 -227.188823) (xy 108.403038 -227.170776)
			(xy 108.452902 -227.160596) (xy 108.503754 -227.158547) (xy 108.554275 -227.164681) (xy 108.603159 -227.178841)
			(xy 108.649138 -227.200658) (xy 108.691022 -227.229568) (xy 108.727726 -227.264823) (xy 108.758299 -227.305509)
			(xy 108.78195 -227.350572) (xy 108.798066 -227.398846) (xy 108.80623 -227.44908) (xy 108.806742 -227.474526)
			(xy 109.114839 -227.474526) (xy 109.118934 -227.423798) (xy 109.131113 -227.374384) (xy 109.151061 -227.327564)
			(xy 109.178262 -227.28455) (xy 109.21201 -227.246456) (xy 109.251432 -227.214269) (xy 109.295506 -227.188823)
			(xy 109.343092 -227.170776) (xy 109.392956 -227.160596) (xy 109.443808 -227.158547) (xy 109.494329 -227.164681)
			(xy 109.543213 -227.178841) (xy 109.589192 -227.200658) (xy 109.631076 -227.229568) (xy 109.66778 -227.264823)
			(xy 109.698353 -227.305509) (xy 109.722004 -227.350572) (xy 109.73812 -227.398846) (xy 109.746284 -227.44908)
			(xy 109.746796 -227.474526) (xy 109.746293 -227.499515) (xy 110.05361 -227.499515) (xy 110.05361 -227.449537)
			(xy 110.061429 -227.400174) (xy 110.076873 -227.352642) (xy 110.099563 -227.30811) (xy 110.128939 -227.267677)
			(xy 110.164279 -227.232337) (xy 110.204712 -227.202961) (xy 110.249244 -227.180271) (xy 110.296776 -227.164827)
			(xy 110.346139 -227.157008) (xy 110.396117 -227.157008) (xy 110.44548 -227.164827) (xy 110.493012 -227.180271)
			(xy 110.537544 -227.202961) (xy 110.577977 -227.232337) (xy 110.613317 -227.267677) (xy 110.642693 -227.30811)
			(xy 110.665383 -227.352642) (xy 110.680827 -227.400174) (xy 110.688646 -227.449537) (xy 110.689136 -227.474526)
			(xy 110.688646 -227.499515) (xy 112.867168 -227.499515) (xy 112.867168 -227.449537) (xy 112.874987 -227.400174)
			(xy 112.890431 -227.352642) (xy 112.913121 -227.30811) (xy 112.942497 -227.267677) (xy 112.977837 -227.232337)
			(xy 113.01827 -227.202961) (xy 113.062802 -227.180271) (xy 113.110334 -227.164827) (xy 113.159697 -227.157008)
			(xy 113.209675 -227.157008) (xy 113.259038 -227.164827) (xy 113.30657 -227.180271) (xy 113.351102 -227.202961)
			(xy 113.391535 -227.232337) (xy 113.426875 -227.267677) (xy 113.456251 -227.30811) (xy 113.478941 -227.352642)
			(xy 113.494385 -227.400174) (xy 113.502204 -227.449537) (xy 113.502694 -227.474526) (xy 113.808505 -227.474526)
			(xy 113.8126 -227.423798) (xy 113.824779 -227.374384) (xy 113.844727 -227.327564) (xy 113.871928 -227.28455)
			(xy 113.905676 -227.246456) (xy 113.945098 -227.214269) (xy 113.989172 -227.188823) (xy 114.036758 -227.170776)
			(xy 114.086622 -227.160596) (xy 114.137474 -227.158547) (xy 114.187995 -227.164681) (xy 114.236879 -227.178841)
			(xy 114.282858 -227.200658) (xy 114.324742 -227.229568) (xy 114.361446 -227.264823) (xy 114.392019 -227.305509)
			(xy 114.41567 -227.350572) (xy 114.431786 -227.398846) (xy 114.43995 -227.44908) (xy 114.440462 -227.474526)
			(xy 114.748559 -227.474526) (xy 114.752654 -227.423798) (xy 114.764833 -227.374384) (xy 114.784781 -227.327564)
			(xy 114.811982 -227.28455) (xy 114.84573 -227.246456) (xy 114.885152 -227.214269) (xy 114.929226 -227.188823)
			(xy 114.976812 -227.170776) (xy 115.026676 -227.160596) (xy 115.077528 -227.158547) (xy 115.128049 -227.164681)
			(xy 115.176933 -227.178841) (xy 115.222912 -227.200658) (xy 115.264796 -227.229568) (xy 115.3015 -227.264823)
			(xy 115.332073 -227.305509) (xy 115.355724 -227.350572) (xy 115.37184 -227.398846) (xy 115.380004 -227.44908)
			(xy 115.380516 -227.474526) (xy 115.380013 -227.499515) (xy 115.68733 -227.499515) (xy 115.68733 -227.449537)
			(xy 115.695149 -227.400174) (xy 115.710593 -227.352642) (xy 115.733283 -227.30811) (xy 115.762659 -227.267677)
			(xy 115.797999 -227.232337) (xy 115.838432 -227.202961) (xy 115.882964 -227.180271) (xy 115.930496 -227.164827)
			(xy 115.979859 -227.157008) (xy 116.029837 -227.157008) (xy 116.0792 -227.164827) (xy 116.126732 -227.180271)
			(xy 116.171264 -227.202961) (xy 116.211697 -227.232337) (xy 116.247037 -227.267677) (xy 116.276413 -227.30811)
			(xy 116.299103 -227.352642) (xy 116.314547 -227.400174) (xy 116.322366 -227.449537) (xy 116.322856 -227.474526)
			(xy 116.322366 -227.499515) (xy 118.507238 -227.499515) (xy 118.507238 -227.449537) (xy 118.515057 -227.400174)
			(xy 118.530501 -227.352642) (xy 118.553191 -227.30811) (xy 118.582567 -227.267677) (xy 118.617907 -227.232337)
			(xy 118.65834 -227.202961) (xy 118.702872 -227.180271) (xy 118.750404 -227.164827) (xy 118.799767 -227.157008)
			(xy 118.849745 -227.157008) (xy 118.899108 -227.164827) (xy 118.94664 -227.180271) (xy 118.991172 -227.202961)
			(xy 119.031605 -227.232337) (xy 119.066945 -227.267677) (xy 119.096321 -227.30811) (xy 119.119011 -227.352642)
			(xy 119.134455 -227.400174) (xy 119.142274 -227.449537) (xy 119.142764 -227.474526) (xy 119.142274 -227.499515)
			(xy 121.327146 -227.499515) (xy 121.327146 -227.449537) (xy 121.334965 -227.400174) (xy 121.350409 -227.352642)
			(xy 121.373099 -227.30811) (xy 121.402475 -227.267677) (xy 121.437815 -227.232337) (xy 121.478248 -227.202961)
			(xy 121.52278 -227.180271) (xy 121.570312 -227.164827) (xy 121.619675 -227.157008) (xy 121.669653 -227.157008)
			(xy 121.719016 -227.164827) (xy 121.766548 -227.180271) (xy 121.81108 -227.202961) (xy 121.851513 -227.232337)
			(xy 121.886853 -227.267677) (xy 121.916229 -227.30811) (xy 121.938919 -227.352642) (xy 121.954363 -227.400174)
			(xy 121.962182 -227.449537) (xy 121.962672 -227.474526) (xy 121.962182 -227.499515) (xy 124.147308 -227.499515)
			(xy 124.147308 -227.449537) (xy 124.155127 -227.400174) (xy 124.170571 -227.352642) (xy 124.193261 -227.30811)
			(xy 124.222637 -227.267677) (xy 124.257977 -227.232337) (xy 124.29841 -227.202961) (xy 124.342942 -227.180271)
			(xy 124.390474 -227.164827) (xy 124.439837 -227.157008) (xy 124.489815 -227.157008) (xy 124.539178 -227.164827)
			(xy 124.58671 -227.180271) (xy 124.631242 -227.202961) (xy 124.671675 -227.232337) (xy 124.707015 -227.267677)
			(xy 124.736391 -227.30811) (xy 124.759081 -227.352642) (xy 124.774525 -227.400174) (xy 124.782344 -227.449537)
			(xy 124.782834 -227.474526) (xy 124.782344 -227.499515) (xy 124.774525 -227.548878) (xy 124.759081 -227.59641)
			(xy 124.736391 -227.640942) (xy 124.707015 -227.681375) (xy 124.671675 -227.716715) (xy 124.631242 -227.746091)
			(xy 124.58671 -227.768781) (xy 124.539178 -227.784225) (xy 124.489815 -227.792044) (xy 124.439837 -227.792044)
			(xy 124.390474 -227.784225) (xy 124.342942 -227.768781) (xy 124.29841 -227.746091) (xy 124.257977 -227.716715)
			(xy 124.222637 -227.681375) (xy 124.193261 -227.640942) (xy 124.170571 -227.59641) (xy 124.155127 -227.548878)
			(xy 124.147308 -227.499515) (xy 121.962182 -227.499515) (xy 121.954363 -227.548878) (xy 121.938919 -227.59641)
			(xy 121.916229 -227.640942) (xy 121.886853 -227.681375) (xy 121.851513 -227.716715) (xy 121.81108 -227.746091)
			(xy 121.766548 -227.768781) (xy 121.719016 -227.784225) (xy 121.669653 -227.792044) (xy 121.619675 -227.792044)
			(xy 121.570312 -227.784225) (xy 121.52278 -227.768781) (xy 121.478248 -227.746091) (xy 121.437815 -227.716715)
			(xy 121.402475 -227.681375) (xy 121.373099 -227.640942) (xy 121.350409 -227.59641) (xy 121.334965 -227.548878)
			(xy 121.327146 -227.499515) (xy 119.142274 -227.499515) (xy 119.134455 -227.548878) (xy 119.119011 -227.59641)
			(xy 119.096321 -227.640942) (xy 119.066945 -227.681375) (xy 119.031605 -227.716715) (xy 118.991172 -227.746091)
			(xy 118.94664 -227.768781) (xy 118.899108 -227.784225) (xy 118.849745 -227.792044) (xy 118.799767 -227.792044)
			(xy 118.750404 -227.784225) (xy 118.702872 -227.768781) (xy 118.65834 -227.746091) (xy 118.617907 -227.716715)
			(xy 118.582567 -227.681375) (xy 118.553191 -227.640942) (xy 118.530501 -227.59641) (xy 118.515057 -227.548878)
			(xy 118.507238 -227.499515) (xy 116.322366 -227.499515) (xy 116.314547 -227.548878) (xy 116.299103 -227.59641)
			(xy 116.276413 -227.640942) (xy 116.247037 -227.681375) (xy 116.211697 -227.716715) (xy 116.171264 -227.746091)
			(xy 116.126732 -227.768781) (xy 116.0792 -227.784225) (xy 116.029837 -227.792044) (xy 115.979859 -227.792044)
			(xy 115.930496 -227.784225) (xy 115.882964 -227.768781) (xy 115.838432 -227.746091) (xy 115.797999 -227.716715)
			(xy 115.762659 -227.681375) (xy 115.733283 -227.640942) (xy 115.710593 -227.59641) (xy 115.695149 -227.548878)
			(xy 115.68733 -227.499515) (xy 115.380013 -227.499515) (xy 115.380004 -227.499972) (xy 115.37184 -227.550206)
			(xy 115.355724 -227.59848) (xy 115.332073 -227.643543) (xy 115.3015 -227.684229) (xy 115.264796 -227.719484)
			(xy 115.222912 -227.748394) (xy 115.176933 -227.770211) (xy 115.128049 -227.784371) (xy 115.077528 -227.790505)
			(xy 115.026676 -227.788456) (xy 114.976812 -227.778276) (xy 114.929226 -227.760229) (xy 114.885152 -227.734783)
			(xy 114.84573 -227.702596) (xy 114.811982 -227.664502) (xy 114.784781 -227.621488) (xy 114.764833 -227.574668)
			(xy 114.752654 -227.525254) (xy 114.748559 -227.474526) (xy 114.440462 -227.474526) (xy 114.43995 -227.499972)
			(xy 114.431786 -227.550206) (xy 114.41567 -227.59848) (xy 114.392019 -227.643543) (xy 114.361446 -227.684229)
			(xy 114.324742 -227.719484) (xy 114.282858 -227.748394) (xy 114.236879 -227.770211) (xy 114.187995 -227.784371)
			(xy 114.137474 -227.790505) (xy 114.086622 -227.788456) (xy 114.036758 -227.778276) (xy 113.989172 -227.760229)
			(xy 113.945098 -227.734783) (xy 113.905676 -227.702596) (xy 113.871928 -227.664502) (xy 113.844727 -227.621488)
			(xy 113.824779 -227.574668) (xy 113.8126 -227.525254) (xy 113.808505 -227.474526) (xy 113.502694 -227.474526)
			(xy 113.502204 -227.499515) (xy 113.494385 -227.548878) (xy 113.478941 -227.59641) (xy 113.456251 -227.640942)
			(xy 113.426875 -227.681375) (xy 113.391535 -227.716715) (xy 113.351102 -227.746091) (xy 113.30657 -227.768781)
			(xy 113.259038 -227.784225) (xy 113.209675 -227.792044) (xy 113.159697 -227.792044) (xy 113.110334 -227.784225)
			(xy 113.062802 -227.768781) (xy 113.01827 -227.746091) (xy 112.977837 -227.716715) (xy 112.942497 -227.681375)
			(xy 112.913121 -227.640942) (xy 112.890431 -227.59641) (xy 112.874987 -227.548878) (xy 112.867168 -227.499515)
			(xy 110.688646 -227.499515) (xy 110.680827 -227.548878) (xy 110.665383 -227.59641) (xy 110.642693 -227.640942)
			(xy 110.613317 -227.681375) (xy 110.577977 -227.716715) (xy 110.537544 -227.746091) (xy 110.493012 -227.768781)
			(xy 110.44548 -227.784225) (xy 110.396117 -227.792044) (xy 110.346139 -227.792044) (xy 110.296776 -227.784225)
			(xy 110.249244 -227.768781) (xy 110.204712 -227.746091) (xy 110.164279 -227.716715) (xy 110.128939 -227.681375)
			(xy 110.099563 -227.640942) (xy 110.076873 -227.59641) (xy 110.061429 -227.548878) (xy 110.05361 -227.499515)
			(xy 109.746293 -227.499515) (xy 109.746284 -227.499972) (xy 109.73812 -227.550206) (xy 109.722004 -227.59848)
			(xy 109.698353 -227.643543) (xy 109.66778 -227.684229) (xy 109.631076 -227.719484) (xy 109.589192 -227.748394)
			(xy 109.543213 -227.770211) (xy 109.494329 -227.784371) (xy 109.443808 -227.790505) (xy 109.392956 -227.788456)
			(xy 109.343092 -227.778276) (xy 109.295506 -227.760229) (xy 109.251432 -227.734783) (xy 109.21201 -227.702596)
			(xy 109.178262 -227.664502) (xy 109.151061 -227.621488) (xy 109.131113 -227.574668) (xy 109.118934 -227.525254)
			(xy 109.114839 -227.474526) (xy 108.806742 -227.474526) (xy 108.80623 -227.499972) (xy 108.798066 -227.550206)
			(xy 108.78195 -227.59848) (xy 108.758299 -227.643543) (xy 108.727726 -227.684229) (xy 108.691022 -227.719484)
			(xy 108.649138 -227.748394) (xy 108.603159 -227.770211) (xy 108.554275 -227.784371) (xy 108.503754 -227.790505)
			(xy 108.452902 -227.788456) (xy 108.403038 -227.778276) (xy 108.355452 -227.760229) (xy 108.311378 -227.734783)
			(xy 108.271956 -227.702596) (xy 108.238208 -227.664502) (xy 108.211007 -227.621488) (xy 108.191059 -227.574668)
			(xy 108.17888 -227.525254) (xy 108.174785 -227.474526) (xy 107.868974 -227.474526) (xy 107.868484 -227.499515)
			(xy 107.860665 -227.548878) (xy 107.845221 -227.59641) (xy 107.822531 -227.640942) (xy 107.793155 -227.681375)
			(xy 107.757815 -227.716715) (xy 107.717382 -227.746091) (xy 107.67285 -227.768781) (xy 107.625318 -227.784225)
			(xy 107.575955 -227.792044) (xy 107.525977 -227.792044) (xy 107.476614 -227.784225) (xy 107.429082 -227.768781)
			(xy 107.38455 -227.746091) (xy 107.344117 -227.716715) (xy 107.308777 -227.681375) (xy 107.279401 -227.640942)
			(xy 107.256711 -227.59641) (xy 107.241267 -227.548878) (xy 107.233448 -227.499515) (xy 105.048576 -227.499515)
			(xy 105.040757 -227.548878) (xy 105.025313 -227.59641) (xy 105.002623 -227.640942) (xy 104.973247 -227.681375)
			(xy 104.937907 -227.716715) (xy 104.897474 -227.746091) (xy 104.852942 -227.768781) (xy 104.80541 -227.784225)
			(xy 104.756047 -227.792044) (xy 104.706069 -227.792044) (xy 104.656706 -227.784225) (xy 104.609174 -227.768781)
			(xy 104.564642 -227.746091) (xy 104.524209 -227.716715) (xy 104.488869 -227.681375) (xy 104.459493 -227.640942)
			(xy 104.436803 -227.59641) (xy 104.421359 -227.548878) (xy 104.41354 -227.499515) (xy 102.228668 -227.499515)
			(xy 102.220849 -227.548878) (xy 102.205405 -227.59641) (xy 102.182715 -227.640942) (xy 102.153339 -227.681375)
			(xy 102.117999 -227.716715) (xy 102.077566 -227.746091) (xy 102.033034 -227.768781) (xy 101.985502 -227.784225)
			(xy 101.936139 -227.792044) (xy 101.886161 -227.792044) (xy 101.836798 -227.784225) (xy 101.789266 -227.768781)
			(xy 101.744734 -227.746091) (xy 101.704301 -227.716715) (xy 101.668961 -227.681375) (xy 101.639585 -227.640942)
			(xy 101.616895 -227.59641) (xy 101.601451 -227.548878) (xy 101.593632 -227.499515) (xy 99.408506 -227.499515)
			(xy 99.400687 -227.548878) (xy 99.385243 -227.59641) (xy 99.362553 -227.640942) (xy 99.333177 -227.681375)
			(xy 99.297837 -227.716715) (xy 99.257404 -227.746091) (xy 99.212872 -227.768781) (xy 99.16534 -227.784225)
			(xy 99.115977 -227.792044) (xy 99.065999 -227.792044) (xy 99.016636 -227.784225) (xy 98.969104 -227.768781)
			(xy 98.924572 -227.746091) (xy 98.884139 -227.716715) (xy 98.848799 -227.681375) (xy 98.819423 -227.640942)
			(xy 98.796733 -227.59641) (xy 98.781289 -227.548878) (xy 98.77347 -227.499515) (xy 97.032415 -227.499515)
			(xy 97.042732 -227.509832) (xy 97.04944 -227.517072) (xy 97.057023 -227.535277) (xy 97.057464 -227.545138)
			(xy 97.057464 -228.24694) (xy 97.057718 -228.251512) (xy 97.058988 -228.281992) (xy 97.058988 -228.284532)
			(xy 97.364799 -228.284532) (xy 97.368894 -228.233804) (xy 97.381073 -228.18439) (xy 97.401021 -228.13757)
			(xy 97.428222 -228.094556) (xy 97.46197 -228.056462) (xy 97.501392 -228.024275) (xy 97.545466 -227.998829)
			(xy 97.593052 -227.980782) (xy 97.642916 -227.970602) (xy 97.693768 -227.968553) (xy 97.744289 -227.974687)
			(xy 97.793173 -227.988847) (xy 97.839152 -228.010664) (xy 97.881036 -228.039574) (xy 97.91774 -228.074829)
			(xy 97.948313 -228.115515) (xy 97.971964 -228.160578) (xy 97.98808 -228.208852) (xy 97.996244 -228.259086)
			(xy 97.996756 -228.284532) (xy 98.304853 -228.284532) (xy 98.308948 -228.233804) (xy 98.321127 -228.18439)
			(xy 98.341075 -228.13757) (xy 98.368276 -228.094556) (xy 98.402024 -228.056462) (xy 98.441446 -228.024275)
			(xy 98.48552 -227.998829) (xy 98.533106 -227.980782) (xy 98.58297 -227.970602) (xy 98.633822 -227.968553)
			(xy 98.684343 -227.974687) (xy 98.733227 -227.988847) (xy 98.779206 -228.010664) (xy 98.82109 -228.039574)
			(xy 98.857794 -228.074829) (xy 98.888367 -228.115515) (xy 98.912018 -228.160578) (xy 98.928134 -228.208852)
			(xy 98.936298 -228.259086) (xy 98.93681 -228.284532) (xy 98.936307 -228.309521) (xy 99.243624 -228.309521)
			(xy 99.243624 -228.259543) (xy 99.251443 -228.21018) (xy 99.266887 -228.162648) (xy 99.289577 -228.118116)
			(xy 99.318953 -228.077683) (xy 99.354293 -228.042343) (xy 99.394726 -228.012967) (xy 99.439258 -227.990277)
			(xy 99.48679 -227.974833) (xy 99.536153 -227.967014) (xy 99.586131 -227.967014) (xy 99.635494 -227.974833)
			(xy 99.683026 -227.990277) (xy 99.727558 -228.012967) (xy 99.767991 -228.042343) (xy 99.803331 -228.077683)
			(xy 99.832707 -228.118116) (xy 99.855397 -228.162648) (xy 99.870841 -228.21018) (xy 99.87866 -228.259543)
			(xy 99.87915 -228.284532) (xy 100.184707 -228.284532) (xy 100.188802 -228.233804) (xy 100.200981 -228.18439)
			(xy 100.220929 -228.13757) (xy 100.24813 -228.094556) (xy 100.281878 -228.056462) (xy 100.3213 -228.024275)
			(xy 100.365374 -227.998829) (xy 100.41296 -227.980782) (xy 100.462824 -227.970602) (xy 100.513676 -227.968553)
			(xy 100.564197 -227.974687) (xy 100.613081 -227.988847) (xy 100.65906 -228.010664) (xy 100.700944 -228.039574)
			(xy 100.737648 -228.074829) (xy 100.768221 -228.115515) (xy 100.791872 -228.160578) (xy 100.807988 -228.208852)
			(xy 100.816152 -228.259086) (xy 100.816664 -228.284532) (xy 101.124761 -228.284532) (xy 101.128856 -228.233804)
			(xy 101.141035 -228.18439) (xy 101.160983 -228.13757) (xy 101.188184 -228.094556) (xy 101.221932 -228.056462)
			(xy 101.261354 -228.024275) (xy 101.305428 -227.998829) (xy 101.353014 -227.980782) (xy 101.402878 -227.970602)
			(xy 101.45373 -227.968553) (xy 101.504251 -227.974687) (xy 101.553135 -227.988847) (xy 101.599114 -228.010664)
			(xy 101.640998 -228.039574) (xy 101.677702 -228.074829) (xy 101.708275 -228.115515) (xy 101.731926 -228.160578)
			(xy 101.748042 -228.208852) (xy 101.756206 -228.259086) (xy 101.756718 -228.284532) (xy 101.756215 -228.309521)
			(xy 102.063532 -228.309521) (xy 102.063532 -228.259543) (xy 102.071351 -228.21018) (xy 102.086795 -228.162648)
			(xy 102.109485 -228.118116) (xy 102.138861 -228.077683) (xy 102.174201 -228.042343) (xy 102.214634 -228.012967)
			(xy 102.259166 -227.990277) (xy 102.306698 -227.974833) (xy 102.356061 -227.967014) (xy 102.406039 -227.967014)
			(xy 102.455402 -227.974833) (xy 102.502934 -227.990277) (xy 102.547466 -228.012967) (xy 102.587899 -228.042343)
			(xy 102.623239 -228.077683) (xy 102.652615 -228.118116) (xy 102.675305 -228.162648) (xy 102.690749 -228.21018)
			(xy 102.698568 -228.259543) (xy 102.699058 -228.284532) (xy 103.004869 -228.284532) (xy 103.008964 -228.233804)
			(xy 103.021143 -228.18439) (xy 103.041091 -228.13757) (xy 103.068292 -228.094556) (xy 103.10204 -228.056462)
			(xy 103.141462 -228.024275) (xy 103.185536 -227.998829) (xy 103.233122 -227.980782) (xy 103.282986 -227.970602)
			(xy 103.333838 -227.968553) (xy 103.384359 -227.974687) (xy 103.433243 -227.988847) (xy 103.479222 -228.010664)
			(xy 103.521106 -228.039574) (xy 103.55781 -228.074829) (xy 103.588383 -228.115515) (xy 103.612034 -228.160578)
			(xy 103.62815 -228.208852) (xy 103.636314 -228.259086) (xy 103.636826 -228.284532) (xy 103.944923 -228.284532)
			(xy 103.949018 -228.233804) (xy 103.961197 -228.18439) (xy 103.981145 -228.13757) (xy 104.008346 -228.094556)
			(xy 104.042094 -228.056462) (xy 104.081516 -228.024275) (xy 104.12559 -227.998829) (xy 104.173176 -227.980782)
			(xy 104.22304 -227.970602) (xy 104.273892 -227.968553) (xy 104.324413 -227.974687) (xy 104.373297 -227.988847)
			(xy 104.419276 -228.010664) (xy 104.46116 -228.039574) (xy 104.497864 -228.074829) (xy 104.528437 -228.115515)
			(xy 104.552088 -228.160578) (xy 104.568204 -228.208852) (xy 104.576368 -228.259086) (xy 104.57688 -228.284532)
			(xy 104.576377 -228.309521) (xy 104.88344 -228.309521) (xy 104.88344 -228.259543) (xy 104.891259 -228.21018)
			(xy 104.906703 -228.162648) (xy 104.929393 -228.118116) (xy 104.958769 -228.077683) (xy 104.994109 -228.042343)
			(xy 105.034542 -228.012967) (xy 105.079074 -227.990277) (xy 105.126606 -227.974833) (xy 105.175969 -227.967014)
			(xy 105.225947 -227.967014) (xy 105.27531 -227.974833) (xy 105.322842 -227.990277) (xy 105.367374 -228.012967)
			(xy 105.407807 -228.042343) (xy 105.443147 -228.077683) (xy 105.472523 -228.118116) (xy 105.495213 -228.162648)
			(xy 105.510657 -228.21018) (xy 105.518476 -228.259543) (xy 105.518966 -228.284532) (xy 105.824777 -228.284532)
			(xy 105.828872 -228.233804) (xy 105.841051 -228.18439) (xy 105.860999 -228.13757) (xy 105.8882 -228.094556)
			(xy 105.921948 -228.056462) (xy 105.96137 -228.024275) (xy 106.005444 -227.998829) (xy 106.05303 -227.980782)
			(xy 106.102894 -227.970602) (xy 106.153746 -227.968553) (xy 106.204267 -227.974687) (xy 106.253151 -227.988847)
			(xy 106.29913 -228.010664) (xy 106.341014 -228.039574) (xy 106.377718 -228.074829) (xy 106.408291 -228.115515)
			(xy 106.431942 -228.160578) (xy 106.448058 -228.208852) (xy 106.456222 -228.259086) (xy 106.456734 -228.284532)
			(xy 106.764831 -228.284532) (xy 106.768926 -228.233804) (xy 106.781105 -228.18439) (xy 106.801053 -228.13757)
			(xy 106.828254 -228.094556) (xy 106.862002 -228.056462) (xy 106.901424 -228.024275) (xy 106.945498 -227.998829)
			(xy 106.993084 -227.980782) (xy 107.042948 -227.970602) (xy 107.0938 -227.968553) (xy 107.144321 -227.974687)
			(xy 107.193205 -227.988847) (xy 107.239184 -228.010664) (xy 107.281068 -228.039574) (xy 107.317772 -228.074829)
			(xy 107.348345 -228.115515) (xy 107.371996 -228.160578) (xy 107.388112 -228.208852) (xy 107.396276 -228.259086)
			(xy 107.396788 -228.284532) (xy 107.396285 -228.309521) (xy 107.703602 -228.309521) (xy 107.703602 -228.259543)
			(xy 107.711421 -228.21018) (xy 107.726865 -228.162648) (xy 107.749555 -228.118116) (xy 107.778931 -228.077683)
			(xy 107.814271 -228.042343) (xy 107.854704 -228.012967) (xy 107.899236 -227.990277) (xy 107.946768 -227.974833)
			(xy 107.996131 -227.967014) (xy 108.046109 -227.967014) (xy 108.095472 -227.974833) (xy 108.143004 -227.990277)
			(xy 108.187536 -228.012967) (xy 108.227969 -228.042343) (xy 108.263309 -228.077683) (xy 108.292685 -228.118116)
			(xy 108.315375 -228.162648) (xy 108.330819 -228.21018) (xy 108.338638 -228.259543) (xy 108.339128 -228.284532)
			(xy 108.338638 -228.309521) (xy 115.217176 -228.309521) (xy 115.217176 -228.259543) (xy 115.224995 -228.21018)
			(xy 115.240439 -228.162648) (xy 115.263129 -228.118116) (xy 115.292505 -228.077683) (xy 115.327845 -228.042343)
			(xy 115.368278 -228.012967) (xy 115.41281 -227.990277) (xy 115.460342 -227.974833) (xy 115.509705 -227.967014)
			(xy 115.559683 -227.967014) (xy 115.609046 -227.974833) (xy 115.656578 -227.990277) (xy 115.70111 -228.012967)
			(xy 115.741543 -228.042343) (xy 115.776883 -228.077683) (xy 115.806259 -228.118116) (xy 115.828949 -228.162648)
			(xy 115.844393 -228.21018) (xy 115.852212 -228.259543) (xy 115.852702 -228.284532) (xy 116.158513 -228.284532)
			(xy 116.162608 -228.233804) (xy 116.174787 -228.18439) (xy 116.194735 -228.13757) (xy 116.221936 -228.094556)
			(xy 116.255684 -228.056462) (xy 116.295106 -228.024275) (xy 116.33918 -227.998829) (xy 116.386766 -227.980782)
			(xy 116.43663 -227.970602) (xy 116.487482 -227.968553) (xy 116.538003 -227.974687) (xy 116.586887 -227.988847)
			(xy 116.632866 -228.010664) (xy 116.67475 -228.039574) (xy 116.711454 -228.074829) (xy 116.742027 -228.115515)
			(xy 116.765678 -228.160578) (xy 116.781794 -228.208852) (xy 116.789958 -228.259086) (xy 116.79047 -228.284532)
			(xy 117.098567 -228.284532) (xy 117.102662 -228.233804) (xy 117.114841 -228.18439) (xy 117.134789 -228.13757)
			(xy 117.16199 -228.094556) (xy 117.195738 -228.056462) (xy 117.23516 -228.024275) (xy 117.279234 -227.998829)
			(xy 117.32682 -227.980782) (xy 117.376684 -227.970602) (xy 117.427536 -227.968553) (xy 117.478057 -227.974687)
			(xy 117.526941 -227.988847) (xy 117.57292 -228.010664) (xy 117.614804 -228.039574) (xy 117.651508 -228.074829)
			(xy 117.682081 -228.115515) (xy 117.705732 -228.160578) (xy 117.721848 -228.208852) (xy 117.730012 -228.259086)
			(xy 117.730524 -228.284532) (xy 117.730021 -228.309521) (xy 118.037338 -228.309521) (xy 118.037338 -228.259543)
			(xy 118.045157 -228.21018) (xy 118.060601 -228.162648) (xy 118.083291 -228.118116) (xy 118.112667 -228.077683)
			(xy 118.148007 -228.042343) (xy 118.18844 -228.012967) (xy 118.232972 -227.990277) (xy 118.280504 -227.974833)
			(xy 118.329867 -227.967014) (xy 118.379845 -227.967014) (xy 118.429208 -227.974833) (xy 118.47674 -227.990277)
			(xy 118.521272 -228.012967) (xy 118.561705 -228.042343) (xy 118.597045 -228.077683) (xy 118.626421 -228.118116)
			(xy 118.649111 -228.162648) (xy 118.664555 -228.21018) (xy 118.672374 -228.259543) (xy 118.672864 -228.284532)
			(xy 118.978421 -228.284532) (xy 118.982516 -228.233804) (xy 118.994695 -228.18439) (xy 119.014643 -228.13757)
			(xy 119.041844 -228.094556) (xy 119.075592 -228.056462) (xy 119.115014 -228.024275) (xy 119.159088 -227.998829)
			(xy 119.206674 -227.980782) (xy 119.256538 -227.970602) (xy 119.30739 -227.968553) (xy 119.357911 -227.974687)
			(xy 119.406795 -227.988847) (xy 119.452774 -228.010664) (xy 119.494658 -228.039574) (xy 119.531362 -228.074829)
			(xy 119.561935 -228.115515) (xy 119.585586 -228.160578) (xy 119.601702 -228.208852) (xy 119.609866 -228.259086)
			(xy 119.610378 -228.284532) (xy 119.918475 -228.284532) (xy 119.92257 -228.233804) (xy 119.934749 -228.18439)
			(xy 119.954697 -228.13757) (xy 119.981898 -228.094556) (xy 120.015646 -228.056462) (xy 120.055068 -228.024275)
			(xy 120.099142 -227.998829) (xy 120.146728 -227.980782) (xy 120.196592 -227.970602) (xy 120.247444 -227.968553)
			(xy 120.297965 -227.974687) (xy 120.346849 -227.988847) (xy 120.392828 -228.010664) (xy 120.434712 -228.039574)
			(xy 120.471416 -228.074829) (xy 120.501989 -228.115515) (xy 120.52564 -228.160578) (xy 120.541756 -228.208852)
			(xy 120.54992 -228.259086) (xy 120.550432 -228.284532) (xy 120.549929 -228.309521) (xy 120.857246 -228.309521)
			(xy 120.857246 -228.259543) (xy 120.865065 -228.21018) (xy 120.880509 -228.162648) (xy 120.903199 -228.118116)
			(xy 120.932575 -228.077683) (xy 120.967915 -228.042343) (xy 121.008348 -228.012967) (xy 121.05288 -227.990277)
			(xy 121.100412 -227.974833) (xy 121.149775 -227.967014) (xy 121.199753 -227.967014) (xy 121.249116 -227.974833)
			(xy 121.296648 -227.990277) (xy 121.34118 -228.012967) (xy 121.381613 -228.042343) (xy 121.416953 -228.077683)
			(xy 121.446329 -228.118116) (xy 121.469019 -228.162648) (xy 121.484463 -228.21018) (xy 121.492282 -228.259543)
			(xy 121.492772 -228.284532) (xy 121.798583 -228.284532) (xy 121.802678 -228.233804) (xy 121.814857 -228.18439)
			(xy 121.834805 -228.13757) (xy 121.862006 -228.094556) (xy 121.895754 -228.056462) (xy 121.935176 -228.024275)
			(xy 121.97925 -227.998829) (xy 122.026836 -227.980782) (xy 122.0767 -227.970602) (xy 122.127552 -227.968553)
			(xy 122.178073 -227.974687) (xy 122.226957 -227.988847) (xy 122.272936 -228.010664) (xy 122.31482 -228.039574)
			(xy 122.351524 -228.074829) (xy 122.382097 -228.115515) (xy 122.405748 -228.160578) (xy 122.421864 -228.208852)
			(xy 122.430028 -228.259086) (xy 122.43054 -228.284532) (xy 122.738383 -228.284532) (xy 122.742478 -228.233804)
			(xy 122.754657 -228.18439) (xy 122.774605 -228.13757) (xy 122.801806 -228.094556) (xy 122.835554 -228.056462)
			(xy 122.874976 -228.024275) (xy 122.91905 -227.998829) (xy 122.966636 -227.980782) (xy 123.0165 -227.970602)
			(xy 123.067352 -227.968553) (xy 123.117873 -227.974687) (xy 123.166757 -227.988847) (xy 123.212736 -228.010664)
			(xy 123.25462 -228.039574) (xy 123.291324 -228.074829) (xy 123.321897 -228.115515) (xy 123.345548 -228.160578)
			(xy 123.361664 -228.208852) (xy 123.369828 -228.259086) (xy 123.37034 -228.284532) (xy 123.369837 -228.309521)
			(xy 123.677154 -228.309521) (xy 123.677154 -228.259543) (xy 123.684973 -228.21018) (xy 123.700417 -228.162648)
			(xy 123.723107 -228.118116) (xy 123.752483 -228.077683) (xy 123.787823 -228.042343) (xy 123.828256 -228.012967)
			(xy 123.872788 -227.990277) (xy 123.92032 -227.974833) (xy 123.969683 -227.967014) (xy 124.019661 -227.967014)
			(xy 124.069024 -227.974833) (xy 124.116556 -227.990277) (xy 124.161088 -228.012967) (xy 124.201521 -228.042343)
			(xy 124.236861 -228.077683) (xy 124.266237 -228.118116) (xy 124.288927 -228.162648) (xy 124.304371 -228.21018)
			(xy 124.31219 -228.259543) (xy 124.31268 -228.284532) (xy 124.618491 -228.284532) (xy 124.622586 -228.233804)
			(xy 124.634765 -228.18439) (xy 124.654713 -228.13757) (xy 124.681914 -228.094556) (xy 124.715662 -228.056462)
			(xy 124.755084 -228.024275) (xy 124.799158 -227.998829) (xy 124.846744 -227.980782) (xy 124.896608 -227.970602)
			(xy 124.94746 -227.968553) (xy 124.997981 -227.974687) (xy 125.046865 -227.988847) (xy 125.092844 -228.010664)
			(xy 125.134728 -228.039574) (xy 125.171432 -228.074829) (xy 125.202005 -228.115515) (xy 125.225656 -228.160578)
			(xy 125.241772 -228.208852) (xy 125.249936 -228.259086) (xy 125.250448 -228.284532) (xy 125.558545 -228.284532)
			(xy 125.56264 -228.233804) (xy 125.574819 -228.18439) (xy 125.594767 -228.13757) (xy 125.621968 -228.094556)
			(xy 125.655716 -228.056462) (xy 125.695138 -228.024275) (xy 125.739212 -227.998829) (xy 125.786798 -227.980782)
			(xy 125.836662 -227.970602) (xy 125.887514 -227.968553) (xy 125.938035 -227.974687) (xy 125.986919 -227.988847)
			(xy 126.032898 -228.010664) (xy 126.074782 -228.039574) (xy 126.111486 -228.074829) (xy 126.142059 -228.115515)
			(xy 126.16571 -228.160578) (xy 126.181826 -228.208852) (xy 126.18999 -228.259086) (xy 126.190502 -228.284532)
			(xy 126.18999 -228.309978) (xy 126.181826 -228.360212) (xy 126.16571 -228.408486) (xy 126.142059 -228.453549)
			(xy 126.111486 -228.494235) (xy 126.074782 -228.52949) (xy 126.032898 -228.5584) (xy 125.986919 -228.580217)
			(xy 125.938035 -228.594377) (xy 125.887514 -228.600511) (xy 125.836662 -228.598462) (xy 125.786798 -228.588282)
			(xy 125.739212 -228.570235) (xy 125.695138 -228.544789) (xy 125.655716 -228.512602) (xy 125.621968 -228.474508)
			(xy 125.594767 -228.431494) (xy 125.574819 -228.384674) (xy 125.56264 -228.33526) (xy 125.558545 -228.284532)
			(xy 125.250448 -228.284532) (xy 125.249936 -228.309978) (xy 125.241772 -228.360212) (xy 125.225656 -228.408486)
			(xy 125.202005 -228.453549) (xy 125.171432 -228.494235) (xy 125.134728 -228.52949) (xy 125.092844 -228.5584)
			(xy 125.046865 -228.580217) (xy 124.997981 -228.594377) (xy 124.94746 -228.600511) (xy 124.896608 -228.598462)
			(xy 124.846744 -228.588282) (xy 124.799158 -228.570235) (xy 124.755084 -228.544789) (xy 124.715662 -228.512602)
			(xy 124.681914 -228.474508) (xy 124.654713 -228.431494) (xy 124.634765 -228.384674) (xy 124.622586 -228.33526)
			(xy 124.618491 -228.284532) (xy 124.31268 -228.284532) (xy 124.31219 -228.309521) (xy 124.304371 -228.358884)
			(xy 124.288927 -228.406416) (xy 124.266237 -228.450948) (xy 124.236861 -228.491381) (xy 124.201521 -228.526721)
			(xy 124.161088 -228.556097) (xy 124.116556 -228.578787) (xy 124.069024 -228.594231) (xy 124.019661 -228.60205)
			(xy 123.969683 -228.60205) (xy 123.92032 -228.594231) (xy 123.872788 -228.578787) (xy 123.828256 -228.556097)
			(xy 123.787823 -228.526721) (xy 123.752483 -228.491381) (xy 123.723107 -228.450948) (xy 123.700417 -228.406416)
			(xy 123.684973 -228.358884) (xy 123.677154 -228.309521) (xy 123.369837 -228.309521) (xy 123.369828 -228.309978)
			(xy 123.361664 -228.360212) (xy 123.345548 -228.408486) (xy 123.321897 -228.453549) (xy 123.291324 -228.494235)
			(xy 123.25462 -228.52949) (xy 123.212736 -228.5584) (xy 123.166757 -228.580217) (xy 123.117873 -228.594377)
			(xy 123.067352 -228.600511) (xy 123.0165 -228.598462) (xy 122.966636 -228.588282) (xy 122.91905 -228.570235)
			(xy 122.874976 -228.544789) (xy 122.835554 -228.512602) (xy 122.801806 -228.474508) (xy 122.774605 -228.431494)
			(xy 122.754657 -228.384674) (xy 122.742478 -228.33526) (xy 122.738383 -228.284532) (xy 122.43054 -228.284532)
			(xy 122.430028 -228.309978) (xy 122.421864 -228.360212) (xy 122.405748 -228.408486) (xy 122.382097 -228.453549)
			(xy 122.351524 -228.494235) (xy 122.31482 -228.52949) (xy 122.272936 -228.5584) (xy 122.226957 -228.580217)
			(xy 122.178073 -228.594377) (xy 122.127552 -228.600511) (xy 122.0767 -228.598462) (xy 122.026836 -228.588282)
			(xy 121.97925 -228.570235) (xy 121.935176 -228.544789) (xy 121.895754 -228.512602) (xy 121.862006 -228.474508)
			(xy 121.834805 -228.431494) (xy 121.814857 -228.384674) (xy 121.802678 -228.33526) (xy 121.798583 -228.284532)
			(xy 121.492772 -228.284532) (xy 121.492282 -228.309521) (xy 121.484463 -228.358884) (xy 121.469019 -228.406416)
			(xy 121.446329 -228.450948) (xy 121.416953 -228.491381) (xy 121.381613 -228.526721) (xy 121.34118 -228.556097)
			(xy 121.296648 -228.578787) (xy 121.249116 -228.594231) (xy 121.199753 -228.60205) (xy 121.149775 -228.60205)
			(xy 121.100412 -228.594231) (xy 121.05288 -228.578787) (xy 121.008348 -228.556097) (xy 120.967915 -228.526721)
			(xy 120.932575 -228.491381) (xy 120.903199 -228.450948) (xy 120.880509 -228.406416) (xy 120.865065 -228.358884)
			(xy 120.857246 -228.309521) (xy 120.549929 -228.309521) (xy 120.54992 -228.309978) (xy 120.541756 -228.360212)
			(xy 120.52564 -228.408486) (xy 120.501989 -228.453549) (xy 120.471416 -228.494235) (xy 120.434712 -228.52949)
			(xy 120.392828 -228.5584) (xy 120.346849 -228.580217) (xy 120.297965 -228.594377) (xy 120.247444 -228.600511)
			(xy 120.196592 -228.598462) (xy 120.146728 -228.588282) (xy 120.099142 -228.570235) (xy 120.055068 -228.544789)
			(xy 120.015646 -228.512602) (xy 119.981898 -228.474508) (xy 119.954697 -228.431494) (xy 119.934749 -228.384674)
			(xy 119.92257 -228.33526) (xy 119.918475 -228.284532) (xy 119.610378 -228.284532) (xy 119.609866 -228.309978)
			(xy 119.601702 -228.360212) (xy 119.585586 -228.408486) (xy 119.561935 -228.453549) (xy 119.531362 -228.494235)
			(xy 119.494658 -228.52949) (xy 119.452774 -228.5584) (xy 119.406795 -228.580217) (xy 119.357911 -228.594377)
			(xy 119.30739 -228.600511) (xy 119.256538 -228.598462) (xy 119.206674 -228.588282) (xy 119.159088 -228.570235)
			(xy 119.115014 -228.544789) (xy 119.075592 -228.512602) (xy 119.041844 -228.474508) (xy 119.014643 -228.431494)
			(xy 118.994695 -228.384674) (xy 118.982516 -228.33526) (xy 118.978421 -228.284532) (xy 118.672864 -228.284532)
			(xy 118.672374 -228.309521) (xy 118.664555 -228.358884) (xy 118.649111 -228.406416) (xy 118.626421 -228.450948)
			(xy 118.597045 -228.491381) (xy 118.561705 -228.526721) (xy 118.521272 -228.556097) (xy 118.47674 -228.578787)
			(xy 118.429208 -228.594231) (xy 118.379845 -228.60205) (xy 118.329867 -228.60205) (xy 118.280504 -228.594231)
			(xy 118.232972 -228.578787) (xy 118.18844 -228.556097) (xy 118.148007 -228.526721) (xy 118.112667 -228.491381)
			(xy 118.083291 -228.450948) (xy 118.060601 -228.406416) (xy 118.045157 -228.358884) (xy 118.037338 -228.309521)
			(xy 117.730021 -228.309521) (xy 117.730012 -228.309978) (xy 117.721848 -228.360212) (xy 117.705732 -228.408486)
			(xy 117.682081 -228.453549) (xy 117.651508 -228.494235) (xy 117.614804 -228.52949) (xy 117.57292 -228.5584)
			(xy 117.526941 -228.580217) (xy 117.478057 -228.594377) (xy 117.427536 -228.600511) (xy 117.376684 -228.598462)
			(xy 117.32682 -228.588282) (xy 117.279234 -228.570235) (xy 117.23516 -228.544789) (xy 117.195738 -228.512602)
			(xy 117.16199 -228.474508) (xy 117.134789 -228.431494) (xy 117.114841 -228.384674) (xy 117.102662 -228.33526)
			(xy 117.098567 -228.284532) (xy 116.79047 -228.284532) (xy 116.789958 -228.309978) (xy 116.781794 -228.360212)
			(xy 116.765678 -228.408486) (xy 116.742027 -228.453549) (xy 116.711454 -228.494235) (xy 116.67475 -228.52949)
			(xy 116.632866 -228.5584) (xy 116.586887 -228.580217) (xy 116.538003 -228.594377) (xy 116.487482 -228.600511)
			(xy 116.43663 -228.598462) (xy 116.386766 -228.588282) (xy 116.33918 -228.570235) (xy 116.295106 -228.544789)
			(xy 116.255684 -228.512602) (xy 116.221936 -228.474508) (xy 116.194735 -228.431494) (xy 116.174787 -228.384674)
			(xy 116.162608 -228.33526) (xy 116.158513 -228.284532) (xy 115.852702 -228.284532) (xy 115.852212 -228.309521)
			(xy 115.844393 -228.358884) (xy 115.828949 -228.406416) (xy 115.806259 -228.450948) (xy 115.776883 -228.491381)
			(xy 115.741543 -228.526721) (xy 115.70111 -228.556097) (xy 115.656578 -228.578787) (xy 115.609046 -228.594231)
			(xy 115.559683 -228.60205) (xy 115.509705 -228.60205) (xy 115.460342 -228.594231) (xy 115.41281 -228.578787)
			(xy 115.368278 -228.556097) (xy 115.327845 -228.526721) (xy 115.292505 -228.491381) (xy 115.263129 -228.450948)
			(xy 115.240439 -228.406416) (xy 115.224995 -228.358884) (xy 115.217176 -228.309521) (xy 108.338638 -228.309521)
			(xy 108.330819 -228.358884) (xy 108.315375 -228.406416) (xy 108.292685 -228.450948) (xy 108.263309 -228.491381)
			(xy 108.227969 -228.526721) (xy 108.187536 -228.556097) (xy 108.143004 -228.578787) (xy 108.095472 -228.594231)
			(xy 108.046109 -228.60205) (xy 107.996131 -228.60205) (xy 107.946768 -228.594231) (xy 107.899236 -228.578787)
			(xy 107.854704 -228.556097) (xy 107.814271 -228.526721) (xy 107.778931 -228.491381) (xy 107.749555 -228.450948)
			(xy 107.726865 -228.406416) (xy 107.711421 -228.358884) (xy 107.703602 -228.309521) (xy 107.396285 -228.309521)
			(xy 107.396276 -228.309978) (xy 107.388112 -228.360212) (xy 107.371996 -228.408486) (xy 107.348345 -228.453549)
			(xy 107.317772 -228.494235) (xy 107.281068 -228.52949) (xy 107.239184 -228.5584) (xy 107.193205 -228.580217)
			(xy 107.144321 -228.594377) (xy 107.0938 -228.600511) (xy 107.042948 -228.598462) (xy 106.993084 -228.588282)
			(xy 106.945498 -228.570235) (xy 106.901424 -228.544789) (xy 106.862002 -228.512602) (xy 106.828254 -228.474508)
			(xy 106.801053 -228.431494) (xy 106.781105 -228.384674) (xy 106.768926 -228.33526) (xy 106.764831 -228.284532)
			(xy 106.456734 -228.284532) (xy 106.456222 -228.309978) (xy 106.448058 -228.360212) (xy 106.431942 -228.408486)
			(xy 106.408291 -228.453549) (xy 106.377718 -228.494235) (xy 106.341014 -228.52949) (xy 106.29913 -228.5584)
			(xy 106.253151 -228.580217) (xy 106.204267 -228.594377) (xy 106.153746 -228.600511) (xy 106.102894 -228.598462)
			(xy 106.05303 -228.588282) (xy 106.005444 -228.570235) (xy 105.96137 -228.544789) (xy 105.921948 -228.512602)
			(xy 105.8882 -228.474508) (xy 105.860999 -228.431494) (xy 105.841051 -228.384674) (xy 105.828872 -228.33526)
			(xy 105.824777 -228.284532) (xy 105.518966 -228.284532) (xy 105.518476 -228.309521) (xy 105.510657 -228.358884)
			(xy 105.495213 -228.406416) (xy 105.472523 -228.450948) (xy 105.443147 -228.491381) (xy 105.407807 -228.526721)
			(xy 105.367374 -228.556097) (xy 105.322842 -228.578787) (xy 105.27531 -228.594231) (xy 105.225947 -228.60205)
			(xy 105.175969 -228.60205) (xy 105.126606 -228.594231) (xy 105.079074 -228.578787) (xy 105.034542 -228.556097)
			(xy 104.994109 -228.526721) (xy 104.958769 -228.491381) (xy 104.929393 -228.450948) (xy 104.906703 -228.406416)
			(xy 104.891259 -228.358884) (xy 104.88344 -228.309521) (xy 104.576377 -228.309521) (xy 104.576368 -228.309978)
			(xy 104.568204 -228.360212) (xy 104.552088 -228.408486) (xy 104.528437 -228.453549) (xy 104.497864 -228.494235)
			(xy 104.46116 -228.52949) (xy 104.419276 -228.5584) (xy 104.373297 -228.580217) (xy 104.324413 -228.594377)
			(xy 104.273892 -228.600511) (xy 104.22304 -228.598462) (xy 104.173176 -228.588282) (xy 104.12559 -228.570235)
			(xy 104.081516 -228.544789) (xy 104.042094 -228.512602) (xy 104.008346 -228.474508) (xy 103.981145 -228.431494)
			(xy 103.961197 -228.384674) (xy 103.949018 -228.33526) (xy 103.944923 -228.284532) (xy 103.636826 -228.284532)
			(xy 103.636314 -228.309978) (xy 103.62815 -228.360212) (xy 103.612034 -228.408486) (xy 103.588383 -228.453549)
			(xy 103.55781 -228.494235) (xy 103.521106 -228.52949) (xy 103.479222 -228.5584) (xy 103.433243 -228.580217)
			(xy 103.384359 -228.594377) (xy 103.333838 -228.600511) (xy 103.282986 -228.598462) (xy 103.233122 -228.588282)
			(xy 103.185536 -228.570235) (xy 103.141462 -228.544789) (xy 103.10204 -228.512602) (xy 103.068292 -228.474508)
			(xy 103.041091 -228.431494) (xy 103.021143 -228.384674) (xy 103.008964 -228.33526) (xy 103.004869 -228.284532)
			(xy 102.699058 -228.284532) (xy 102.698568 -228.309521) (xy 102.690749 -228.358884) (xy 102.675305 -228.406416)
			(xy 102.652615 -228.450948) (xy 102.623239 -228.491381) (xy 102.587899 -228.526721) (xy 102.547466 -228.556097)
			(xy 102.502934 -228.578787) (xy 102.455402 -228.594231) (xy 102.406039 -228.60205) (xy 102.356061 -228.60205)
			(xy 102.306698 -228.594231) (xy 102.259166 -228.578787) (xy 102.214634 -228.556097) (xy 102.174201 -228.526721)
			(xy 102.138861 -228.491381) (xy 102.109485 -228.450948) (xy 102.086795 -228.406416) (xy 102.071351 -228.358884)
			(xy 102.063532 -228.309521) (xy 101.756215 -228.309521) (xy 101.756206 -228.309978) (xy 101.748042 -228.360212)
			(xy 101.731926 -228.408486) (xy 101.708275 -228.453549) (xy 101.677702 -228.494235) (xy 101.640998 -228.52949)
			(xy 101.599114 -228.5584) (xy 101.553135 -228.580217) (xy 101.504251 -228.594377) (xy 101.45373 -228.600511)
			(xy 101.402878 -228.598462) (xy 101.353014 -228.588282) (xy 101.305428 -228.570235) (xy 101.261354 -228.544789)
			(xy 101.221932 -228.512602) (xy 101.188184 -228.474508) (xy 101.160983 -228.431494) (xy 101.141035 -228.384674)
			(xy 101.128856 -228.33526) (xy 101.124761 -228.284532) (xy 100.816664 -228.284532) (xy 100.816152 -228.309978)
			(xy 100.807988 -228.360212) (xy 100.791872 -228.408486) (xy 100.768221 -228.453549) (xy 100.737648 -228.494235)
			(xy 100.700944 -228.52949) (xy 100.65906 -228.5584) (xy 100.613081 -228.580217) (xy 100.564197 -228.594377)
			(xy 100.513676 -228.600511) (xy 100.462824 -228.598462) (xy 100.41296 -228.588282) (xy 100.365374 -228.570235)
			(xy 100.3213 -228.544789) (xy 100.281878 -228.512602) (xy 100.24813 -228.474508) (xy 100.220929 -228.431494)
			(xy 100.200981 -228.384674) (xy 100.188802 -228.33526) (xy 100.184707 -228.284532) (xy 99.87915 -228.284532)
			(xy 99.87866 -228.309521) (xy 99.870841 -228.358884) (xy 99.855397 -228.406416) (xy 99.832707 -228.450948)
			(xy 99.803331 -228.491381) (xy 99.767991 -228.526721) (xy 99.727558 -228.556097) (xy 99.683026 -228.578787)
			(xy 99.635494 -228.594231) (xy 99.586131 -228.60205) (xy 99.536153 -228.60205) (xy 99.48679 -228.594231)
			(xy 99.439258 -228.578787) (xy 99.394726 -228.556097) (xy 99.354293 -228.526721) (xy 99.318953 -228.491381)
			(xy 99.289577 -228.450948) (xy 99.266887 -228.406416) (xy 99.251443 -228.358884) (xy 99.243624 -228.309521)
			(xy 98.936307 -228.309521) (xy 98.936298 -228.309978) (xy 98.928134 -228.360212) (xy 98.912018 -228.408486)
			(xy 98.888367 -228.453549) (xy 98.857794 -228.494235) (xy 98.82109 -228.52949) (xy 98.779206 -228.5584)
			(xy 98.733227 -228.580217) (xy 98.684343 -228.594377) (xy 98.633822 -228.600511) (xy 98.58297 -228.598462)
			(xy 98.533106 -228.588282) (xy 98.48552 -228.570235) (xy 98.441446 -228.544789) (xy 98.402024 -228.512602)
			(xy 98.368276 -228.474508) (xy 98.341075 -228.431494) (xy 98.321127 -228.384674) (xy 98.308948 -228.33526)
			(xy 98.304853 -228.284532) (xy 97.996756 -228.284532) (xy 97.996244 -228.309978) (xy 97.98808 -228.360212)
			(xy 97.971964 -228.408486) (xy 97.948313 -228.453549) (xy 97.91774 -228.494235) (xy 97.881036 -228.52949)
			(xy 97.839152 -228.5584) (xy 97.793173 -228.580217) (xy 97.744289 -228.594377) (xy 97.693768 -228.600511)
			(xy 97.642916 -228.598462) (xy 97.593052 -228.588282) (xy 97.545466 -228.570235) (xy 97.501392 -228.544789)
			(xy 97.46197 -228.512602) (xy 97.428222 -228.474508) (xy 97.401021 -228.431494) (xy 97.381073 -228.384674)
			(xy 97.368894 -228.33526) (xy 97.364799 -228.284532) (xy 97.058988 -228.284532) (xy 97.058988 -228.288088)
			(xy 97.057718 -228.31806) (xy 97.057464 -228.319584) (xy 97.057464 -228.679248) (xy 97.057948 -228.689995)
			(xy 97.066768 -228.709595) (xy 97.074482 -228.717094) (xy 97.130362 -228.766624) (xy 97.13087 -228.766624)
			(xy 97.138236 -228.773482) (xy 97.159318 -228.78034) (xy 97.171002 -228.77907) (xy 97.17151 -228.77907)
			(xy 97.18049 -228.777984) (xy 97.198535 -228.776714) (xy 97.207578 -228.77653) (xy 97.211134 -228.77653)
			(xy 97.236122 -228.776997) (xy 97.285483 -228.784821) (xy 97.333012 -228.80027) (xy 97.377539 -228.822964)
			(xy 97.417968 -228.852344) (xy 97.453303 -228.887687) (xy 97.482674 -228.928122) (xy 97.505358 -228.972655)
			(xy 97.520796 -229.020187) (xy 97.528608 -229.06955) (xy 97.529142 -229.094538) (xy 97.52865 -229.119514)
			(xy 97.528648 -229.119527) (xy 97.833416 -229.119527) (xy 97.833416 -229.069549) (xy 97.841235 -229.020186)
			(xy 97.856679 -228.972654) (xy 97.879369 -228.928122) (xy 97.908745 -228.887689) (xy 97.944085 -228.852349)
			(xy 97.984518 -228.822973) (xy 98.02905 -228.800283) (xy 98.076582 -228.784839) (xy 98.125945 -228.77702)
			(xy 98.175923 -228.77702) (xy 98.225286 -228.784839) (xy 98.272818 -228.800283) (xy 98.31735 -228.822973)
			(xy 98.357783 -228.852349) (xy 98.393123 -228.887689) (xy 98.422499 -228.928122) (xy 98.445189 -228.972654)
			(xy 98.460633 -229.020186) (xy 98.468452 -229.069549) (xy 98.468942 -229.094538) (xy 98.468452 -229.119527)
			(xy 98.77347 -229.119527) (xy 98.77347 -229.069549) (xy 98.781289 -229.020186) (xy 98.796733 -228.972654)
			(xy 98.819423 -228.928122) (xy 98.848799 -228.887689) (xy 98.884139 -228.852349) (xy 98.924572 -228.822973)
			(xy 98.969104 -228.800283) (xy 99.016636 -228.784839) (xy 99.065999 -228.77702) (xy 99.115977 -228.77702)
			(xy 99.16534 -228.784839) (xy 99.212872 -228.800283) (xy 99.257404 -228.822973) (xy 99.297837 -228.852349)
			(xy 99.333177 -228.887689) (xy 99.362553 -228.928122) (xy 99.385243 -228.972654) (xy 99.400687 -229.020186)
			(xy 99.408506 -229.069549) (xy 99.408996 -229.094538) (xy 99.408506 -229.119527) (xy 99.713524 -229.119527)
			(xy 99.713524 -229.069549) (xy 99.721343 -229.020186) (xy 99.736787 -228.972654) (xy 99.759477 -228.928122)
			(xy 99.788853 -228.887689) (xy 99.824193 -228.852349) (xy 99.864626 -228.822973) (xy 99.909158 -228.800283)
			(xy 99.95669 -228.784839) (xy 100.006053 -228.77702) (xy 100.056031 -228.77702) (xy 100.105394 -228.784839)
			(xy 100.152926 -228.800283) (xy 100.197458 -228.822973) (xy 100.237891 -228.852349) (xy 100.273231 -228.887689)
			(xy 100.302607 -228.928122) (xy 100.325297 -228.972654) (xy 100.340741 -229.020186) (xy 100.34856 -229.069549)
			(xy 100.34905 -229.094538) (xy 100.34856 -229.119527) (xy 100.653578 -229.119527) (xy 100.653578 -229.069549)
			(xy 100.661397 -229.020186) (xy 100.676841 -228.972654) (xy 100.699531 -228.928122) (xy 100.728907 -228.887689)
			(xy 100.764247 -228.852349) (xy 100.80468 -228.822973) (xy 100.849212 -228.800283) (xy 100.896744 -228.784839)
			(xy 100.946107 -228.77702) (xy 100.996085 -228.77702) (xy 101.045448 -228.784839) (xy 101.09298 -228.800283)
			(xy 101.137512 -228.822973) (xy 101.177945 -228.852349) (xy 101.213285 -228.887689) (xy 101.242661 -228.928122)
			(xy 101.265351 -228.972654) (xy 101.280795 -229.020186) (xy 101.288614 -229.069549) (xy 101.289104 -229.094538)
			(xy 101.288614 -229.119527) (xy 101.593632 -229.119527) (xy 101.593632 -229.069549) (xy 101.601451 -229.020186)
			(xy 101.616895 -228.972654) (xy 101.639585 -228.928122) (xy 101.668961 -228.887689) (xy 101.704301 -228.852349)
			(xy 101.744734 -228.822973) (xy 101.789266 -228.800283) (xy 101.836798 -228.784839) (xy 101.886161 -228.77702)
			(xy 101.936139 -228.77702) (xy 101.985502 -228.784839) (xy 102.033034 -228.800283) (xy 102.077566 -228.822973)
			(xy 102.117999 -228.852349) (xy 102.153339 -228.887689) (xy 102.182715 -228.928122) (xy 102.205405 -228.972654)
			(xy 102.220849 -229.020186) (xy 102.228668 -229.069549) (xy 102.229158 -229.094538) (xy 102.228668 -229.119527)
			(xy 102.533432 -229.119527) (xy 102.533432 -229.069549) (xy 102.541251 -229.020186) (xy 102.556695 -228.972654)
			(xy 102.579385 -228.928122) (xy 102.608761 -228.887689) (xy 102.644101 -228.852349) (xy 102.684534 -228.822973)
			(xy 102.729066 -228.800283) (xy 102.776598 -228.784839) (xy 102.825961 -228.77702) (xy 102.875939 -228.77702)
			(xy 102.925302 -228.784839) (xy 102.972834 -228.800283) (xy 103.017366 -228.822973) (xy 103.057799 -228.852349)
			(xy 103.093139 -228.887689) (xy 103.122515 -228.928122) (xy 103.145205 -228.972654) (xy 103.160649 -229.020186)
			(xy 103.168468 -229.069549) (xy 103.168958 -229.094538) (xy 103.168468 -229.119527) (xy 103.473486 -229.119527)
			(xy 103.473486 -229.069549) (xy 103.481305 -229.020186) (xy 103.496749 -228.972654) (xy 103.519439 -228.928122)
			(xy 103.548815 -228.887689) (xy 103.584155 -228.852349) (xy 103.624588 -228.822973) (xy 103.66912 -228.800283)
			(xy 103.716652 -228.784839) (xy 103.766015 -228.77702) (xy 103.815993 -228.77702) (xy 103.865356 -228.784839)
			(xy 103.912888 -228.800283) (xy 103.95742 -228.822973) (xy 103.997853 -228.852349) (xy 104.033193 -228.887689)
			(xy 104.062569 -228.928122) (xy 104.085259 -228.972654) (xy 104.100703 -229.020186) (xy 104.108522 -229.069549)
			(xy 104.109012 -229.094538) (xy 104.108522 -229.119527) (xy 104.41354 -229.119527) (xy 104.41354 -229.069549)
			(xy 104.421359 -229.020186) (xy 104.436803 -228.972654) (xy 104.459493 -228.928122) (xy 104.488869 -228.887689)
			(xy 104.524209 -228.852349) (xy 104.564642 -228.822973) (xy 104.609174 -228.800283) (xy 104.656706 -228.784839)
			(xy 104.706069 -228.77702) (xy 104.756047 -228.77702) (xy 104.80541 -228.784839) (xy 104.852942 -228.800283)
			(xy 104.897474 -228.822973) (xy 104.937907 -228.852349) (xy 104.973247 -228.887689) (xy 105.002623 -228.928122)
			(xy 105.025313 -228.972654) (xy 105.040757 -229.020186) (xy 105.048576 -229.069549) (xy 105.049066 -229.094538)
			(xy 105.048576 -229.119527) (xy 105.353594 -229.119527) (xy 105.353594 -229.069549) (xy 105.361413 -229.020186)
			(xy 105.376857 -228.972654) (xy 105.399547 -228.928122) (xy 105.428923 -228.887689) (xy 105.464263 -228.852349)
			(xy 105.504696 -228.822973) (xy 105.549228 -228.800283) (xy 105.59676 -228.784839) (xy 105.646123 -228.77702)
			(xy 105.696101 -228.77702) (xy 105.745464 -228.784839) (xy 105.792996 -228.800283) (xy 105.837528 -228.822973)
			(xy 105.877961 -228.852349) (xy 105.913301 -228.887689) (xy 105.942677 -228.928122) (xy 105.965367 -228.972654)
			(xy 105.980811 -229.020186) (xy 105.98863 -229.069549) (xy 105.98912 -229.094538) (xy 105.98863 -229.119527)
			(xy 106.293648 -229.119527) (xy 106.293648 -229.069549) (xy 106.301467 -229.020186) (xy 106.316911 -228.972654)
			(xy 106.339601 -228.928122) (xy 106.368977 -228.887689) (xy 106.404317 -228.852349) (xy 106.44475 -228.822973)
			(xy 106.489282 -228.800283) (xy 106.536814 -228.784839) (xy 106.586177 -228.77702) (xy 106.636155 -228.77702)
			(xy 106.685518 -228.784839) (xy 106.73305 -228.800283) (xy 106.777582 -228.822973) (xy 106.818015 -228.852349)
			(xy 106.853355 -228.887689) (xy 106.882731 -228.928122) (xy 106.905421 -228.972654) (xy 106.920865 -229.020186)
			(xy 106.928684 -229.069549) (xy 106.929174 -229.094538) (xy 106.928684 -229.119527) (xy 107.233448 -229.119527)
			(xy 107.233448 -229.069549) (xy 107.241267 -229.020186) (xy 107.256711 -228.972654) (xy 107.279401 -228.928122)
			(xy 107.308777 -228.887689) (xy 107.344117 -228.852349) (xy 107.38455 -228.822973) (xy 107.429082 -228.800283)
			(xy 107.476614 -228.784839) (xy 107.525977 -228.77702) (xy 107.575955 -228.77702) (xy 107.625318 -228.784839)
			(xy 107.67285 -228.800283) (xy 107.717382 -228.822973) (xy 107.757815 -228.852349) (xy 107.793155 -228.887689)
			(xy 107.822531 -228.928122) (xy 107.845221 -228.972654) (xy 107.860665 -229.020186) (xy 107.868484 -229.069549)
			(xy 107.868974 -229.094538) (xy 108.174785 -229.094538) (xy 108.17888 -229.04381) (xy 108.191059 -228.994396)
			(xy 108.211007 -228.947576) (xy 108.238208 -228.904562) (xy 108.271956 -228.866468) (xy 108.311378 -228.834281)
			(xy 108.355452 -228.808835) (xy 108.403038 -228.790788) (xy 108.452902 -228.780608) (xy 108.503754 -228.778559)
			(xy 108.554275 -228.784693) (xy 108.603159 -228.798853) (xy 108.649138 -228.82067) (xy 108.691022 -228.84958)
			(xy 108.727726 -228.884835) (xy 108.758299 -228.925521) (xy 108.78195 -228.970584) (xy 108.798066 -229.018858)
			(xy 108.80623 -229.069092) (xy 108.806742 -229.094538) (xy 109.114839 -229.094538) (xy 109.118934 -229.04381)
			(xy 109.131113 -228.994396) (xy 109.151061 -228.947576) (xy 109.178262 -228.904562) (xy 109.21201 -228.866468)
			(xy 109.251432 -228.834281) (xy 109.295506 -228.808835) (xy 109.343092 -228.790788) (xy 109.392956 -228.780608)
			(xy 109.443808 -228.778559) (xy 109.494329 -228.784693) (xy 109.543213 -228.798853) (xy 109.589192 -228.82067)
			(xy 109.631076 -228.84958) (xy 109.66778 -228.884835) (xy 109.698353 -228.925521) (xy 109.722004 -228.970584)
			(xy 109.73812 -229.018858) (xy 109.746284 -229.069092) (xy 109.746796 -229.094538) (xy 109.746293 -229.119527)
			(xy 110.05361 -229.119527) (xy 110.05361 -229.069549) (xy 110.061429 -229.020186) (xy 110.076873 -228.972654)
			(xy 110.099563 -228.928122) (xy 110.128939 -228.887689) (xy 110.164279 -228.852349) (xy 110.204712 -228.822973)
			(xy 110.249244 -228.800283) (xy 110.296776 -228.784839) (xy 110.346139 -228.77702) (xy 110.396117 -228.77702)
			(xy 110.44548 -228.784839) (xy 110.493012 -228.800283) (xy 110.537544 -228.822973) (xy 110.577977 -228.852349)
			(xy 110.613317 -228.887689) (xy 110.642693 -228.928122) (xy 110.665383 -228.972654) (xy 110.680827 -229.020186)
			(xy 110.688646 -229.069549) (xy 110.689136 -229.094538) (xy 110.688646 -229.119527) (xy 112.867168 -229.119527)
			(xy 112.867168 -229.069549) (xy 112.874987 -229.020186) (xy 112.890431 -228.972654) (xy 112.913121 -228.928122)
			(xy 112.942497 -228.887689) (xy 112.977837 -228.852349) (xy 113.01827 -228.822973) (xy 113.062802 -228.800283)
			(xy 113.110334 -228.784839) (xy 113.159697 -228.77702) (xy 113.209675 -228.77702) (xy 113.259038 -228.784839)
			(xy 113.30657 -228.800283) (xy 113.351102 -228.822973) (xy 113.391535 -228.852349) (xy 113.426875 -228.887689)
			(xy 113.456251 -228.928122) (xy 113.478941 -228.972654) (xy 113.494385 -229.020186) (xy 113.502204 -229.069549)
			(xy 113.502694 -229.094538) (xy 113.808505 -229.094538) (xy 113.8126 -229.04381) (xy 113.824779 -228.994396)
			(xy 113.844727 -228.947576) (xy 113.871928 -228.904562) (xy 113.905676 -228.866468) (xy 113.945098 -228.834281)
			(xy 113.989172 -228.808835) (xy 114.036758 -228.790788) (xy 114.086622 -228.780608) (xy 114.137474 -228.778559)
			(xy 114.187995 -228.784693) (xy 114.236879 -228.798853) (xy 114.282858 -228.82067) (xy 114.324742 -228.84958)
			(xy 114.361446 -228.884835) (xy 114.392019 -228.925521) (xy 114.41567 -228.970584) (xy 114.431786 -229.018858)
			(xy 114.43995 -229.069092) (xy 114.440462 -229.094538) (xy 114.748559 -229.094538) (xy 114.752654 -229.04381)
			(xy 114.764833 -228.994396) (xy 114.784781 -228.947576) (xy 114.811982 -228.904562) (xy 114.84573 -228.866468)
			(xy 114.885152 -228.834281) (xy 114.929226 -228.808835) (xy 114.976812 -228.790788) (xy 115.026676 -228.780608)
			(xy 115.077528 -228.778559) (xy 115.128049 -228.784693) (xy 115.176933 -228.798853) (xy 115.222912 -228.82067)
			(xy 115.264796 -228.84958) (xy 115.3015 -228.884835) (xy 115.332073 -228.925521) (xy 115.355724 -228.970584)
			(xy 115.37184 -229.018858) (xy 115.380004 -229.069092) (xy 115.380516 -229.094538) (xy 115.380013 -229.119527)
			(xy 115.68733 -229.119527) (xy 115.68733 -229.069549) (xy 115.695149 -229.020186) (xy 115.710593 -228.972654)
			(xy 115.733283 -228.928122) (xy 115.762659 -228.887689) (xy 115.797999 -228.852349) (xy 115.838432 -228.822973)
			(xy 115.882964 -228.800283) (xy 115.930496 -228.784839) (xy 115.979859 -228.77702) (xy 116.029837 -228.77702)
			(xy 116.0792 -228.784839) (xy 116.126732 -228.800283) (xy 116.171264 -228.822973) (xy 116.211697 -228.852349)
			(xy 116.247037 -228.887689) (xy 116.276413 -228.928122) (xy 116.299103 -228.972654) (xy 116.314547 -229.020186)
			(xy 116.322366 -229.069549) (xy 116.322856 -229.094538) (xy 116.322366 -229.119527) (xy 116.62713 -229.119527)
			(xy 116.62713 -229.069549) (xy 116.634949 -229.020186) (xy 116.650393 -228.972654) (xy 116.673083 -228.928122)
			(xy 116.702459 -228.887689) (xy 116.737799 -228.852349) (xy 116.778232 -228.822973) (xy 116.822764 -228.800283)
			(xy 116.870296 -228.784839) (xy 116.919659 -228.77702) (xy 116.969637 -228.77702) (xy 117.019 -228.784839)
			(xy 117.066532 -228.800283) (xy 117.111064 -228.822973) (xy 117.151497 -228.852349) (xy 117.186837 -228.887689)
			(xy 117.216213 -228.928122) (xy 117.238903 -228.972654) (xy 117.254347 -229.020186) (xy 117.262166 -229.069549)
			(xy 117.262656 -229.094538) (xy 117.262166 -229.119527) (xy 117.567184 -229.119527) (xy 117.567184 -229.069549)
			(xy 117.575003 -229.020186) (xy 117.590447 -228.972654) (xy 117.613137 -228.928122) (xy 117.642513 -228.887689)
			(xy 117.677853 -228.852349) (xy 117.718286 -228.822973) (xy 117.762818 -228.800283) (xy 117.81035 -228.784839)
			(xy 117.859713 -228.77702) (xy 117.909691 -228.77702) (xy 117.959054 -228.784839) (xy 118.006586 -228.800283)
			(xy 118.051118 -228.822973) (xy 118.091551 -228.852349) (xy 118.126891 -228.887689) (xy 118.156267 -228.928122)
			(xy 118.178957 -228.972654) (xy 118.194401 -229.020186) (xy 118.20222 -229.069549) (xy 118.20271 -229.094538)
			(xy 118.20222 -229.119527) (xy 118.507238 -229.119527) (xy 118.507238 -229.069549) (xy 118.515057 -229.020186)
			(xy 118.530501 -228.972654) (xy 118.553191 -228.928122) (xy 118.582567 -228.887689) (xy 118.617907 -228.852349)
			(xy 118.65834 -228.822973) (xy 118.702872 -228.800283) (xy 118.750404 -228.784839) (xy 118.799767 -228.77702)
			(xy 118.849745 -228.77702) (xy 118.899108 -228.784839) (xy 118.94664 -228.800283) (xy 118.991172 -228.822973)
			(xy 119.031605 -228.852349) (xy 119.066945 -228.887689) (xy 119.096321 -228.928122) (xy 119.119011 -228.972654)
			(xy 119.134455 -229.020186) (xy 119.142274 -229.069549) (xy 119.142764 -229.094538) (xy 119.142274 -229.119527)
			(xy 119.447292 -229.119527) (xy 119.447292 -229.069549) (xy 119.455111 -229.020186) (xy 119.470555 -228.972654)
			(xy 119.493245 -228.928122) (xy 119.522621 -228.887689) (xy 119.557961 -228.852349) (xy 119.598394 -228.822973)
			(xy 119.642926 -228.800283) (xy 119.690458 -228.784839) (xy 119.739821 -228.77702) (xy 119.789799 -228.77702)
			(xy 119.839162 -228.784839) (xy 119.886694 -228.800283) (xy 119.931226 -228.822973) (xy 119.971659 -228.852349)
			(xy 120.006999 -228.887689) (xy 120.036375 -228.928122) (xy 120.059065 -228.972654) (xy 120.074509 -229.020186)
			(xy 120.082328 -229.069549) (xy 120.082818 -229.094538) (xy 120.082328 -229.119527) (xy 120.387092 -229.119527)
			(xy 120.387092 -229.069549) (xy 120.394911 -229.020186) (xy 120.410355 -228.972654) (xy 120.433045 -228.928122)
			(xy 120.462421 -228.887689) (xy 120.497761 -228.852349) (xy 120.538194 -228.822973) (xy 120.582726 -228.800283)
			(xy 120.630258 -228.784839) (xy 120.679621 -228.77702) (xy 120.729599 -228.77702) (xy 120.778962 -228.784839)
			(xy 120.826494 -228.800283) (xy 120.871026 -228.822973) (xy 120.911459 -228.852349) (xy 120.946799 -228.887689)
			(xy 120.976175 -228.928122) (xy 120.998865 -228.972654) (xy 121.014309 -229.020186) (xy 121.022128 -229.069549)
			(xy 121.022618 -229.094538) (xy 121.022128 -229.119527) (xy 121.327146 -229.119527) (xy 121.327146 -229.069549)
			(xy 121.334965 -229.020186) (xy 121.350409 -228.972654) (xy 121.373099 -228.928122) (xy 121.402475 -228.887689)
			(xy 121.437815 -228.852349) (xy 121.478248 -228.822973) (xy 121.52278 -228.800283) (xy 121.570312 -228.784839)
			(xy 121.619675 -228.77702) (xy 121.669653 -228.77702) (xy 121.719016 -228.784839) (xy 121.766548 -228.800283)
			(xy 121.81108 -228.822973) (xy 121.851513 -228.852349) (xy 121.886853 -228.887689) (xy 121.916229 -228.928122)
			(xy 121.938919 -228.972654) (xy 121.954363 -229.020186) (xy 121.962182 -229.069549) (xy 121.962672 -229.094538)
			(xy 121.962182 -229.119527) (xy 122.2672 -229.119527) (xy 122.2672 -229.069549) (xy 122.275019 -229.020186)
			(xy 122.290463 -228.972654) (xy 122.313153 -228.928122) (xy 122.342529 -228.887689) (xy 122.377869 -228.852349)
			(xy 122.418302 -228.822973) (xy 122.462834 -228.800283) (xy 122.510366 -228.784839) (xy 122.559729 -228.77702)
			(xy 122.609707 -228.77702) (xy 122.65907 -228.784839) (xy 122.706602 -228.800283) (xy 122.751134 -228.822973)
			(xy 122.791567 -228.852349) (xy 122.826907 -228.887689) (xy 122.856283 -228.928122) (xy 122.878973 -228.972654)
			(xy 122.894417 -229.020186) (xy 122.902236 -229.069549) (xy 122.902726 -229.094538) (xy 122.902236 -229.119527)
			(xy 123.207254 -229.119527) (xy 123.207254 -229.069549) (xy 123.215073 -229.020186) (xy 123.230517 -228.972654)
			(xy 123.253207 -228.928122) (xy 123.282583 -228.887689) (xy 123.317923 -228.852349) (xy 123.358356 -228.822973)
			(xy 123.402888 -228.800283) (xy 123.45042 -228.784839) (xy 123.499783 -228.77702) (xy 123.549761 -228.77702)
			(xy 123.599124 -228.784839) (xy 123.646656 -228.800283) (xy 123.691188 -228.822973) (xy 123.731621 -228.852349)
			(xy 123.766961 -228.887689) (xy 123.796337 -228.928122) (xy 123.819027 -228.972654) (xy 123.834471 -229.020186)
			(xy 123.84229 -229.069549) (xy 123.84278 -229.094538) (xy 123.84229 -229.119527) (xy 124.147308 -229.119527)
			(xy 124.147308 -229.069549) (xy 124.155127 -229.020186) (xy 124.170571 -228.972654) (xy 124.193261 -228.928122)
			(xy 124.222637 -228.887689) (xy 124.257977 -228.852349) (xy 124.29841 -228.822973) (xy 124.342942 -228.800283)
			(xy 124.390474 -228.784839) (xy 124.439837 -228.77702) (xy 124.489815 -228.77702) (xy 124.539178 -228.784839)
			(xy 124.58671 -228.800283) (xy 124.631242 -228.822973) (xy 124.671675 -228.852349) (xy 124.707015 -228.887689)
			(xy 124.736391 -228.928122) (xy 124.759081 -228.972654) (xy 124.774525 -229.020186) (xy 124.782344 -229.069549)
			(xy 124.782834 -229.094538) (xy 124.782344 -229.119527) (xy 125.087108 -229.119527) (xy 125.087108 -229.069549)
			(xy 125.094927 -229.020186) (xy 125.110371 -228.972654) (xy 125.133061 -228.928122) (xy 125.162437 -228.887689)
			(xy 125.197777 -228.852349) (xy 125.23821 -228.822973) (xy 125.282742 -228.800283) (xy 125.330274 -228.784839)
			(xy 125.379637 -228.77702) (xy 125.429615 -228.77702) (xy 125.478978 -228.784839) (xy 125.52651 -228.800283)
			(xy 125.571042 -228.822973) (xy 125.611475 -228.852349) (xy 125.646815 -228.887689) (xy 125.676191 -228.928122)
			(xy 125.698881 -228.972654) (xy 125.714325 -229.020186) (xy 125.722144 -229.069549) (xy 125.722634 -229.094538)
			(xy 125.722144 -229.119527) (xy 125.714325 -229.16889) (xy 125.698881 -229.216422) (xy 125.676191 -229.260954)
			(xy 125.646815 -229.301387) (xy 125.611475 -229.336727) (xy 125.571042 -229.366103) (xy 125.52651 -229.388793)
			(xy 125.478978 -229.404237) (xy 125.429615 -229.412056) (xy 125.379637 -229.412056) (xy 125.330274 -229.404237)
			(xy 125.282742 -229.388793) (xy 125.23821 -229.366103) (xy 125.197777 -229.336727) (xy 125.162437 -229.301387)
			(xy 125.133061 -229.260954) (xy 125.110371 -229.216422) (xy 125.094927 -229.16889) (xy 125.087108 -229.119527)
			(xy 124.782344 -229.119527) (xy 124.774525 -229.16889) (xy 124.759081 -229.216422) (xy 124.736391 -229.260954)
			(xy 124.707015 -229.301387) (xy 124.671675 -229.336727) (xy 124.631242 -229.366103) (xy 124.58671 -229.388793)
			(xy 124.539178 -229.404237) (xy 124.489815 -229.412056) (xy 124.439837 -229.412056) (xy 124.390474 -229.404237)
			(xy 124.342942 -229.388793) (xy 124.29841 -229.366103) (xy 124.257977 -229.336727) (xy 124.222637 -229.301387)
			(xy 124.193261 -229.260954) (xy 124.170571 -229.216422) (xy 124.155127 -229.16889) (xy 124.147308 -229.119527)
			(xy 123.84229 -229.119527) (xy 123.834471 -229.16889) (xy 123.819027 -229.216422) (xy 123.796337 -229.260954)
			(xy 123.766961 -229.301387) (xy 123.731621 -229.336727) (xy 123.691188 -229.366103) (xy 123.646656 -229.388793)
			(xy 123.599124 -229.404237) (xy 123.549761 -229.412056) (xy 123.499783 -229.412056) (xy 123.45042 -229.404237)
			(xy 123.402888 -229.388793) (xy 123.358356 -229.366103) (xy 123.317923 -229.336727) (xy 123.282583 -229.301387)
			(xy 123.253207 -229.260954) (xy 123.230517 -229.216422) (xy 123.215073 -229.16889) (xy 123.207254 -229.119527)
			(xy 122.902236 -229.119527) (xy 122.894417 -229.16889) (xy 122.878973 -229.216422) (xy 122.856283 -229.260954)
			(xy 122.826907 -229.301387) (xy 122.791567 -229.336727) (xy 122.751134 -229.366103) (xy 122.706602 -229.388793)
			(xy 122.65907 -229.404237) (xy 122.609707 -229.412056) (xy 122.559729 -229.412056) (xy 122.510366 -229.404237)
			(xy 122.462834 -229.388793) (xy 122.418302 -229.366103) (xy 122.377869 -229.336727) (xy 122.342529 -229.301387)
			(xy 122.313153 -229.260954) (xy 122.290463 -229.216422) (xy 122.275019 -229.16889) (xy 122.2672 -229.119527)
			(xy 121.962182 -229.119527) (xy 121.954363 -229.16889) (xy 121.938919 -229.216422) (xy 121.916229 -229.260954)
			(xy 121.886853 -229.301387) (xy 121.851513 -229.336727) (xy 121.81108 -229.366103) (xy 121.766548 -229.388793)
			(xy 121.719016 -229.404237) (xy 121.669653 -229.412056) (xy 121.619675 -229.412056) (xy 121.570312 -229.404237)
			(xy 121.52278 -229.388793) (xy 121.478248 -229.366103) (xy 121.437815 -229.336727) (xy 121.402475 -229.301387)
			(xy 121.373099 -229.260954) (xy 121.350409 -229.216422) (xy 121.334965 -229.16889) (xy 121.327146 -229.119527)
			(xy 121.022128 -229.119527) (xy 121.014309 -229.16889) (xy 120.998865 -229.216422) (xy 120.976175 -229.260954)
			(xy 120.946799 -229.301387) (xy 120.911459 -229.336727) (xy 120.871026 -229.366103) (xy 120.826494 -229.388793)
			(xy 120.778962 -229.404237) (xy 120.729599 -229.412056) (xy 120.679621 -229.412056) (xy 120.630258 -229.404237)
			(xy 120.582726 -229.388793) (xy 120.538194 -229.366103) (xy 120.497761 -229.336727) (xy 120.462421 -229.301387)
			(xy 120.433045 -229.260954) (xy 120.410355 -229.216422) (xy 120.394911 -229.16889) (xy 120.387092 -229.119527)
			(xy 120.082328 -229.119527) (xy 120.074509 -229.16889) (xy 120.059065 -229.216422) (xy 120.036375 -229.260954)
			(xy 120.006999 -229.301387) (xy 119.971659 -229.336727) (xy 119.931226 -229.366103) (xy 119.886694 -229.388793)
			(xy 119.839162 -229.404237) (xy 119.789799 -229.412056) (xy 119.739821 -229.412056) (xy 119.690458 -229.404237)
			(xy 119.642926 -229.388793) (xy 119.598394 -229.366103) (xy 119.557961 -229.336727) (xy 119.522621 -229.301387)
			(xy 119.493245 -229.260954) (xy 119.470555 -229.216422) (xy 119.455111 -229.16889) (xy 119.447292 -229.119527)
			(xy 119.142274 -229.119527) (xy 119.134455 -229.16889) (xy 119.119011 -229.216422) (xy 119.096321 -229.260954)
			(xy 119.066945 -229.301387) (xy 119.031605 -229.336727) (xy 118.991172 -229.366103) (xy 118.94664 -229.388793)
			(xy 118.899108 -229.404237) (xy 118.849745 -229.412056) (xy 118.799767 -229.412056) (xy 118.750404 -229.404237)
			(xy 118.702872 -229.388793) (xy 118.65834 -229.366103) (xy 118.617907 -229.336727) (xy 118.582567 -229.301387)
			(xy 118.553191 -229.260954) (xy 118.530501 -229.216422) (xy 118.515057 -229.16889) (xy 118.507238 -229.119527)
			(xy 118.20222 -229.119527) (xy 118.194401 -229.16889) (xy 118.178957 -229.216422) (xy 118.156267 -229.260954)
			(xy 118.126891 -229.301387) (xy 118.091551 -229.336727) (xy 118.051118 -229.366103) (xy 118.006586 -229.388793)
			(xy 117.959054 -229.404237) (xy 117.909691 -229.412056) (xy 117.859713 -229.412056) (xy 117.81035 -229.404237)
			(xy 117.762818 -229.388793) (xy 117.718286 -229.366103) (xy 117.677853 -229.336727) (xy 117.642513 -229.301387)
			(xy 117.613137 -229.260954) (xy 117.590447 -229.216422) (xy 117.575003 -229.16889) (xy 117.567184 -229.119527)
			(xy 117.262166 -229.119527) (xy 117.254347 -229.16889) (xy 117.238903 -229.216422) (xy 117.216213 -229.260954)
			(xy 117.186837 -229.301387) (xy 117.151497 -229.336727) (xy 117.111064 -229.366103) (xy 117.066532 -229.388793)
			(xy 117.019 -229.404237) (xy 116.969637 -229.412056) (xy 116.919659 -229.412056) (xy 116.870296 -229.404237)
			(xy 116.822764 -229.388793) (xy 116.778232 -229.366103) (xy 116.737799 -229.336727) (xy 116.702459 -229.301387)
			(xy 116.673083 -229.260954) (xy 116.650393 -229.216422) (xy 116.634949 -229.16889) (xy 116.62713 -229.119527)
			(xy 116.322366 -229.119527) (xy 116.314547 -229.16889) (xy 116.299103 -229.216422) (xy 116.276413 -229.260954)
			(xy 116.247037 -229.301387) (xy 116.211697 -229.336727) (xy 116.171264 -229.366103) (xy 116.126732 -229.388793)
			(xy 116.0792 -229.404237) (xy 116.029837 -229.412056) (xy 115.979859 -229.412056) (xy 115.930496 -229.404237)
			(xy 115.882964 -229.388793) (xy 115.838432 -229.366103) (xy 115.797999 -229.336727) (xy 115.762659 -229.301387)
			(xy 115.733283 -229.260954) (xy 115.710593 -229.216422) (xy 115.695149 -229.16889) (xy 115.68733 -229.119527)
			(xy 115.380013 -229.119527) (xy 115.380004 -229.119984) (xy 115.37184 -229.170218) (xy 115.355724 -229.218492)
			(xy 115.332073 -229.263555) (xy 115.3015 -229.304241) (xy 115.264796 -229.339496) (xy 115.222912 -229.368406)
			(xy 115.176933 -229.390223) (xy 115.128049 -229.404383) (xy 115.077528 -229.410517) (xy 115.026676 -229.408468)
			(xy 114.976812 -229.398288) (xy 114.929226 -229.380241) (xy 114.885152 -229.354795) (xy 114.84573 -229.322608)
			(xy 114.811982 -229.284514) (xy 114.784781 -229.2415) (xy 114.764833 -229.19468) (xy 114.752654 -229.145266)
			(xy 114.748559 -229.094538) (xy 114.440462 -229.094538) (xy 114.43995 -229.119984) (xy 114.431786 -229.170218)
			(xy 114.41567 -229.218492) (xy 114.392019 -229.263555) (xy 114.361446 -229.304241) (xy 114.324742 -229.339496)
			(xy 114.282858 -229.368406) (xy 114.236879 -229.390223) (xy 114.187995 -229.404383) (xy 114.137474 -229.410517)
			(xy 114.086622 -229.408468) (xy 114.036758 -229.398288) (xy 113.989172 -229.380241) (xy 113.945098 -229.354795)
			(xy 113.905676 -229.322608) (xy 113.871928 -229.284514) (xy 113.844727 -229.2415) (xy 113.824779 -229.19468)
			(xy 113.8126 -229.145266) (xy 113.808505 -229.094538) (xy 113.502694 -229.094538) (xy 113.502204 -229.119527)
			(xy 113.494385 -229.16889) (xy 113.478941 -229.216422) (xy 113.456251 -229.260954) (xy 113.426875 -229.301387)
			(xy 113.391535 -229.336727) (xy 113.351102 -229.366103) (xy 113.30657 -229.388793) (xy 113.259038 -229.404237)
			(xy 113.209675 -229.412056) (xy 113.159697 -229.412056) (xy 113.110334 -229.404237) (xy 113.062802 -229.388793)
			(xy 113.01827 -229.366103) (xy 112.977837 -229.336727) (xy 112.942497 -229.301387) (xy 112.913121 -229.260954)
			(xy 112.890431 -229.216422) (xy 112.874987 -229.16889) (xy 112.867168 -229.119527) (xy 110.688646 -229.119527)
			(xy 110.680827 -229.16889) (xy 110.665383 -229.216422) (xy 110.642693 -229.260954) (xy 110.613317 -229.301387)
			(xy 110.577977 -229.336727) (xy 110.537544 -229.366103) (xy 110.493012 -229.388793) (xy 110.44548 -229.404237)
			(xy 110.396117 -229.412056) (xy 110.346139 -229.412056) (xy 110.296776 -229.404237) (xy 110.249244 -229.388793)
			(xy 110.204712 -229.366103) (xy 110.164279 -229.336727) (xy 110.128939 -229.301387) (xy 110.099563 -229.260954)
			(xy 110.076873 -229.216422) (xy 110.061429 -229.16889) (xy 110.05361 -229.119527) (xy 109.746293 -229.119527)
			(xy 109.746284 -229.119984) (xy 109.73812 -229.170218) (xy 109.722004 -229.218492) (xy 109.698353 -229.263555)
			(xy 109.66778 -229.304241) (xy 109.631076 -229.339496) (xy 109.589192 -229.368406) (xy 109.543213 -229.390223)
			(xy 109.494329 -229.404383) (xy 109.443808 -229.410517) (xy 109.392956 -229.408468) (xy 109.343092 -229.398288)
			(xy 109.295506 -229.380241) (xy 109.251432 -229.354795) (xy 109.21201 -229.322608) (xy 109.178262 -229.284514)
			(xy 109.151061 -229.2415) (xy 109.131113 -229.19468) (xy 109.118934 -229.145266) (xy 109.114839 -229.094538)
			(xy 108.806742 -229.094538) (xy 108.80623 -229.119984) (xy 108.798066 -229.170218) (xy 108.78195 -229.218492)
			(xy 108.758299 -229.263555) (xy 108.727726 -229.304241) (xy 108.691022 -229.339496) (xy 108.649138 -229.368406)
			(xy 108.603159 -229.390223) (xy 108.554275 -229.404383) (xy 108.503754 -229.410517) (xy 108.452902 -229.408468)
			(xy 108.403038 -229.398288) (xy 108.355452 -229.380241) (xy 108.311378 -229.354795) (xy 108.271956 -229.322608)
			(xy 108.238208 -229.284514) (xy 108.211007 -229.2415) (xy 108.191059 -229.19468) (xy 108.17888 -229.145266)
			(xy 108.174785 -229.094538) (xy 107.868974 -229.094538) (xy 107.868484 -229.119527) (xy 107.860665 -229.16889)
			(xy 107.845221 -229.216422) (xy 107.822531 -229.260954) (xy 107.793155 -229.301387) (xy 107.757815 -229.336727)
			(xy 107.717382 -229.366103) (xy 107.67285 -229.388793) (xy 107.625318 -229.404237) (xy 107.575955 -229.412056)
			(xy 107.525977 -229.412056) (xy 107.476614 -229.404237) (xy 107.429082 -229.388793) (xy 107.38455 -229.366103)
			(xy 107.344117 -229.336727) (xy 107.308777 -229.301387) (xy 107.279401 -229.260954) (xy 107.256711 -229.216422)
			(xy 107.241267 -229.16889) (xy 107.233448 -229.119527) (xy 106.928684 -229.119527) (xy 106.920865 -229.16889)
			(xy 106.905421 -229.216422) (xy 106.882731 -229.260954) (xy 106.853355 -229.301387) (xy 106.818015 -229.336727)
			(xy 106.777582 -229.366103) (xy 106.73305 -229.388793) (xy 106.685518 -229.404237) (xy 106.636155 -229.412056)
			(xy 106.586177 -229.412056) (xy 106.536814 -229.404237) (xy 106.489282 -229.388793) (xy 106.44475 -229.366103)
			(xy 106.404317 -229.336727) (xy 106.368977 -229.301387) (xy 106.339601 -229.260954) (xy 106.316911 -229.216422)
			(xy 106.301467 -229.16889) (xy 106.293648 -229.119527) (xy 105.98863 -229.119527) (xy 105.980811 -229.16889)
			(xy 105.965367 -229.216422) (xy 105.942677 -229.260954) (xy 105.913301 -229.301387) (xy 105.877961 -229.336727)
			(xy 105.837528 -229.366103) (xy 105.792996 -229.388793) (xy 105.745464 -229.404237) (xy 105.696101 -229.412056)
			(xy 105.646123 -229.412056) (xy 105.59676 -229.404237) (xy 105.549228 -229.388793) (xy 105.504696 -229.366103)
			(xy 105.464263 -229.336727) (xy 105.428923 -229.301387) (xy 105.399547 -229.260954) (xy 105.376857 -229.216422)
			(xy 105.361413 -229.16889) (xy 105.353594 -229.119527) (xy 105.048576 -229.119527) (xy 105.040757 -229.16889)
			(xy 105.025313 -229.216422) (xy 105.002623 -229.260954) (xy 104.973247 -229.301387) (xy 104.937907 -229.336727)
			(xy 104.897474 -229.366103) (xy 104.852942 -229.388793) (xy 104.80541 -229.404237) (xy 104.756047 -229.412056)
			(xy 104.706069 -229.412056) (xy 104.656706 -229.404237) (xy 104.609174 -229.388793) (xy 104.564642 -229.366103)
			(xy 104.524209 -229.336727) (xy 104.488869 -229.301387) (xy 104.459493 -229.260954) (xy 104.436803 -229.216422)
			(xy 104.421359 -229.16889) (xy 104.41354 -229.119527) (xy 104.108522 -229.119527) (xy 104.100703 -229.16889)
			(xy 104.085259 -229.216422) (xy 104.062569 -229.260954) (xy 104.033193 -229.301387) (xy 103.997853 -229.336727)
			(xy 103.95742 -229.366103) (xy 103.912888 -229.388793) (xy 103.865356 -229.404237) (xy 103.815993 -229.412056)
			(xy 103.766015 -229.412056) (xy 103.716652 -229.404237) (xy 103.66912 -229.388793) (xy 103.624588 -229.366103)
			(xy 103.584155 -229.336727) (xy 103.548815 -229.301387) (xy 103.519439 -229.260954) (xy 103.496749 -229.216422)
			(xy 103.481305 -229.16889) (xy 103.473486 -229.119527) (xy 103.168468 -229.119527) (xy 103.160649 -229.16889)
			(xy 103.145205 -229.216422) (xy 103.122515 -229.260954) (xy 103.093139 -229.301387) (xy 103.057799 -229.336727)
			(xy 103.017366 -229.366103) (xy 102.972834 -229.388793) (xy 102.925302 -229.404237) (xy 102.875939 -229.412056)
			(xy 102.825961 -229.412056) (xy 102.776598 -229.404237) (xy 102.729066 -229.388793) (xy 102.684534 -229.366103)
			(xy 102.644101 -229.336727) (xy 102.608761 -229.301387) (xy 102.579385 -229.260954) (xy 102.556695 -229.216422)
			(xy 102.541251 -229.16889) (xy 102.533432 -229.119527) (xy 102.228668 -229.119527) (xy 102.220849 -229.16889)
			(xy 102.205405 -229.216422) (xy 102.182715 -229.260954) (xy 102.153339 -229.301387) (xy 102.117999 -229.336727)
			(xy 102.077566 -229.366103) (xy 102.033034 -229.388793) (xy 101.985502 -229.404237) (xy 101.936139 -229.412056)
			(xy 101.886161 -229.412056) (xy 101.836798 -229.404237) (xy 101.789266 -229.388793) (xy 101.744734 -229.366103)
			(xy 101.704301 -229.336727) (xy 101.668961 -229.301387) (xy 101.639585 -229.260954) (xy 101.616895 -229.216422)
			(xy 101.601451 -229.16889) (xy 101.593632 -229.119527) (xy 101.288614 -229.119527) (xy 101.280795 -229.16889)
			(xy 101.265351 -229.216422) (xy 101.242661 -229.260954) (xy 101.213285 -229.301387) (xy 101.177945 -229.336727)
			(xy 101.137512 -229.366103) (xy 101.09298 -229.388793) (xy 101.045448 -229.404237) (xy 100.996085 -229.412056)
			(xy 100.946107 -229.412056) (xy 100.896744 -229.404237) (xy 100.849212 -229.388793) (xy 100.80468 -229.366103)
			(xy 100.764247 -229.336727) (xy 100.728907 -229.301387) (xy 100.699531 -229.260954) (xy 100.676841 -229.216422)
			(xy 100.661397 -229.16889) (xy 100.653578 -229.119527) (xy 100.34856 -229.119527) (xy 100.340741 -229.16889)
			(xy 100.325297 -229.216422) (xy 100.302607 -229.260954) (xy 100.273231 -229.301387) (xy 100.237891 -229.336727)
			(xy 100.197458 -229.366103) (xy 100.152926 -229.388793) (xy 100.105394 -229.404237) (xy 100.056031 -229.412056)
			(xy 100.006053 -229.412056) (xy 99.95669 -229.404237) (xy 99.909158 -229.388793) (xy 99.864626 -229.366103)
			(xy 99.824193 -229.336727) (xy 99.788853 -229.301387) (xy 99.759477 -229.260954) (xy 99.736787 -229.216422)
			(xy 99.721343 -229.16889) (xy 99.713524 -229.119527) (xy 99.408506 -229.119527) (xy 99.400687 -229.16889)
			(xy 99.385243 -229.216422) (xy 99.362553 -229.260954) (xy 99.333177 -229.301387) (xy 99.297837 -229.336727)
			(xy 99.257404 -229.366103) (xy 99.212872 -229.388793) (xy 99.16534 -229.404237) (xy 99.115977 -229.412056)
			(xy 99.065999 -229.412056) (xy 99.016636 -229.404237) (xy 98.969104 -229.388793) (xy 98.924572 -229.366103)
			(xy 98.884139 -229.336727) (xy 98.848799 -229.301387) (xy 98.819423 -229.260954) (xy 98.796733 -229.216422)
			(xy 98.781289 -229.16889) (xy 98.77347 -229.119527) (xy 98.468452 -229.119527) (xy 98.460633 -229.16889)
			(xy 98.445189 -229.216422) (xy 98.422499 -229.260954) (xy 98.393123 -229.301387) (xy 98.357783 -229.336727)
			(xy 98.31735 -229.366103) (xy 98.272818 -229.388793) (xy 98.225286 -229.404237) (xy 98.175923 -229.412056)
			(xy 98.125945 -229.412056) (xy 98.076582 -229.404237) (xy 98.02905 -229.388793) (xy 97.984518 -229.366103)
			(xy 97.944085 -229.336727) (xy 97.908745 -229.301387) (xy 97.879369 -229.260954) (xy 97.856679 -229.216422)
			(xy 97.841235 -229.16889) (xy 97.833416 -229.119527) (xy 97.528648 -229.119527) (xy 97.520835 -229.16885)
			(xy 97.505403 -229.216357) (xy 97.482734 -229.260868) (xy 97.453385 -229.301288) (xy 97.418079 -229.336623)
			(xy 97.377682 -229.366003) (xy 97.333189 -229.388707) (xy 97.285693 -229.404176) (xy 97.236363 -229.41203)
			(xy 97.211388 -229.412546) (xy 97.211134 -229.412546) (xy 97.201776 -229.412455) (xy 97.183095 -229.411312)
			(xy 97.173796 -229.41026) (xy 97.171002 -229.410006) (xy 97.170494 -229.410006) (xy 97.160588 -229.408736)
			(xy 97.148396 -229.412292) (xy 97.137474 -229.416356) (xy 97.073212 -229.472744) (xy 97.066395 -229.479838)
			(xy 97.058273 -229.497738) (xy 97.057464 -229.507542) (xy 97.057464 -229.866698) (xy 97.057718 -229.87127)
			(xy 97.058988 -229.90175) (xy 97.058988 -229.90429) (xy 97.364799 -229.90429) (xy 97.368894 -229.853562)
			(xy 97.381073 -229.804148) (xy 97.401021 -229.757328) (xy 97.428222 -229.714314) (xy 97.46197 -229.67622)
			(xy 97.501392 -229.644033) (xy 97.545466 -229.618587) (xy 97.593052 -229.60054) (xy 97.642916 -229.59036)
			(xy 97.693768 -229.588311) (xy 97.744289 -229.594445) (xy 97.793173 -229.608605) (xy 97.839152 -229.630422)
			(xy 97.881036 -229.659332) (xy 97.91774 -229.694587) (xy 97.948313 -229.735273) (xy 97.971964 -229.780336)
			(xy 97.98808 -229.82861) (xy 97.996244 -229.878844) (xy 97.996756 -229.90429) (xy 98.304853 -229.90429)
			(xy 98.308948 -229.853562) (xy 98.321127 -229.804148) (xy 98.341075 -229.757328) (xy 98.368276 -229.714314)
			(xy 98.402024 -229.67622) (xy 98.441446 -229.644033) (xy 98.48552 -229.618587) (xy 98.533106 -229.60054)
			(xy 98.58297 -229.59036) (xy 98.633822 -229.588311) (xy 98.684343 -229.594445) (xy 98.733227 -229.608605)
			(xy 98.779206 -229.630422) (xy 98.82109 -229.659332) (xy 98.857794 -229.694587) (xy 98.888367 -229.735273)
			(xy 98.912018 -229.780336) (xy 98.928134 -229.82861) (xy 98.936298 -229.878844) (xy 98.93681 -229.90429)
			(xy 98.936307 -229.929279) (xy 99.243624 -229.929279) (xy 99.243624 -229.879301) (xy 99.251443 -229.829938)
			(xy 99.266887 -229.782406) (xy 99.289577 -229.737874) (xy 99.318953 -229.697441) (xy 99.354293 -229.662101)
			(xy 99.394726 -229.632725) (xy 99.439258 -229.610035) (xy 99.48679 -229.594591) (xy 99.536153 -229.586772)
			(xy 99.586131 -229.586772) (xy 99.635494 -229.594591) (xy 99.683026 -229.610035) (xy 99.727558 -229.632725)
			(xy 99.767991 -229.662101) (xy 99.803331 -229.697441) (xy 99.832707 -229.737874) (xy 99.855397 -229.782406)
			(xy 99.870841 -229.829938) (xy 99.87866 -229.879301) (xy 99.87915 -229.90429) (xy 100.184707 -229.90429)
			(xy 100.188802 -229.853562) (xy 100.200981 -229.804148) (xy 100.220929 -229.757328) (xy 100.24813 -229.714314)
			(xy 100.281878 -229.67622) (xy 100.3213 -229.644033) (xy 100.365374 -229.618587) (xy 100.41296 -229.60054)
			(xy 100.462824 -229.59036) (xy 100.513676 -229.588311) (xy 100.564197 -229.594445) (xy 100.613081 -229.608605)
			(xy 100.65906 -229.630422) (xy 100.700944 -229.659332) (xy 100.737648 -229.694587) (xy 100.768221 -229.735273)
			(xy 100.791872 -229.780336) (xy 100.807988 -229.82861) (xy 100.816152 -229.878844) (xy 100.816664 -229.90429)
			(xy 101.124761 -229.90429) (xy 101.128856 -229.853562) (xy 101.141035 -229.804148) (xy 101.160983 -229.757328)
			(xy 101.188184 -229.714314) (xy 101.221932 -229.67622) (xy 101.261354 -229.644033) (xy 101.305428 -229.618587)
			(xy 101.353014 -229.60054) (xy 101.402878 -229.59036) (xy 101.45373 -229.588311) (xy 101.504251 -229.594445)
			(xy 101.553135 -229.608605) (xy 101.599114 -229.630422) (xy 101.640998 -229.659332) (xy 101.677702 -229.694587)
			(xy 101.708275 -229.735273) (xy 101.731926 -229.780336) (xy 101.748042 -229.82861) (xy 101.756206 -229.878844)
			(xy 101.756718 -229.90429) (xy 101.756215 -229.929279) (xy 102.063532 -229.929279) (xy 102.063532 -229.879301)
			(xy 102.071351 -229.829938) (xy 102.086795 -229.782406) (xy 102.109485 -229.737874) (xy 102.138861 -229.697441)
			(xy 102.174201 -229.662101) (xy 102.214634 -229.632725) (xy 102.259166 -229.610035) (xy 102.306698 -229.594591)
			(xy 102.356061 -229.586772) (xy 102.406039 -229.586772) (xy 102.455402 -229.594591) (xy 102.502934 -229.610035)
			(xy 102.547466 -229.632725) (xy 102.587899 -229.662101) (xy 102.623239 -229.697441) (xy 102.652615 -229.737874)
			(xy 102.675305 -229.782406) (xy 102.690749 -229.829938) (xy 102.698568 -229.879301) (xy 102.699058 -229.90429)
			(xy 103.004869 -229.90429) (xy 103.008964 -229.853562) (xy 103.021143 -229.804148) (xy 103.041091 -229.757328)
			(xy 103.068292 -229.714314) (xy 103.10204 -229.67622) (xy 103.141462 -229.644033) (xy 103.185536 -229.618587)
			(xy 103.233122 -229.60054) (xy 103.282986 -229.59036) (xy 103.333838 -229.588311) (xy 103.384359 -229.594445)
			(xy 103.433243 -229.608605) (xy 103.479222 -229.630422) (xy 103.521106 -229.659332) (xy 103.55781 -229.694587)
			(xy 103.588383 -229.735273) (xy 103.612034 -229.780336) (xy 103.62815 -229.82861) (xy 103.636314 -229.878844)
			(xy 103.636826 -229.90429) (xy 103.944923 -229.90429) (xy 103.949018 -229.853562) (xy 103.961197 -229.804148)
			(xy 103.981145 -229.757328) (xy 104.008346 -229.714314) (xy 104.042094 -229.67622) (xy 104.081516 -229.644033)
			(xy 104.12559 -229.618587) (xy 104.173176 -229.60054) (xy 104.22304 -229.59036) (xy 104.273892 -229.588311)
			(xy 104.324413 -229.594445) (xy 104.373297 -229.608605) (xy 104.419276 -229.630422) (xy 104.46116 -229.659332)
			(xy 104.497864 -229.694587) (xy 104.528437 -229.735273) (xy 104.552088 -229.780336) (xy 104.568204 -229.82861)
			(xy 104.576368 -229.878844) (xy 104.57688 -229.90429) (xy 104.576377 -229.929279) (xy 104.88344 -229.929279)
			(xy 104.88344 -229.879301) (xy 104.891259 -229.829938) (xy 104.906703 -229.782406) (xy 104.929393 -229.737874)
			(xy 104.958769 -229.697441) (xy 104.994109 -229.662101) (xy 105.034542 -229.632725) (xy 105.079074 -229.610035)
			(xy 105.126606 -229.594591) (xy 105.175969 -229.586772) (xy 105.225947 -229.586772) (xy 105.27531 -229.594591)
			(xy 105.322842 -229.610035) (xy 105.367374 -229.632725) (xy 105.407807 -229.662101) (xy 105.443147 -229.697441)
			(xy 105.472523 -229.737874) (xy 105.495213 -229.782406) (xy 105.510657 -229.829938) (xy 105.518476 -229.879301)
			(xy 105.518966 -229.90429) (xy 105.824777 -229.90429) (xy 105.828872 -229.853562) (xy 105.841051 -229.804148)
			(xy 105.860999 -229.757328) (xy 105.8882 -229.714314) (xy 105.921948 -229.67622) (xy 105.96137 -229.644033)
			(xy 106.005444 -229.618587) (xy 106.05303 -229.60054) (xy 106.102894 -229.59036) (xy 106.153746 -229.588311)
			(xy 106.204267 -229.594445) (xy 106.253151 -229.608605) (xy 106.29913 -229.630422) (xy 106.341014 -229.659332)
			(xy 106.377718 -229.694587) (xy 106.408291 -229.735273) (xy 106.431942 -229.780336) (xy 106.448058 -229.82861)
			(xy 106.456222 -229.878844) (xy 106.456734 -229.90429) (xy 106.764831 -229.90429) (xy 106.768926 -229.853562)
			(xy 106.781105 -229.804148) (xy 106.801053 -229.757328) (xy 106.828254 -229.714314) (xy 106.862002 -229.67622)
			(xy 106.901424 -229.644033) (xy 106.945498 -229.618587) (xy 106.993084 -229.60054) (xy 107.042948 -229.59036)
			(xy 107.0938 -229.588311) (xy 107.144321 -229.594445) (xy 107.193205 -229.608605) (xy 107.239184 -229.630422)
			(xy 107.281068 -229.659332) (xy 107.317772 -229.694587) (xy 107.348345 -229.735273) (xy 107.371996 -229.780336)
			(xy 107.388112 -229.82861) (xy 107.396276 -229.878844) (xy 107.396788 -229.90429) (xy 107.396285 -229.929279)
			(xy 107.703602 -229.929279) (xy 107.703602 -229.879301) (xy 107.711421 -229.829938) (xy 107.726865 -229.782406)
			(xy 107.749555 -229.737874) (xy 107.778931 -229.697441) (xy 107.814271 -229.662101) (xy 107.854704 -229.632725)
			(xy 107.899236 -229.610035) (xy 107.946768 -229.594591) (xy 107.996131 -229.586772) (xy 108.046109 -229.586772)
			(xy 108.095472 -229.594591) (xy 108.143004 -229.610035) (xy 108.187536 -229.632725) (xy 108.227969 -229.662101)
			(xy 108.263309 -229.697441) (xy 108.292685 -229.737874) (xy 108.315375 -229.782406) (xy 108.330819 -229.829938)
			(xy 108.338638 -229.879301) (xy 108.339128 -229.90429) (xy 108.338638 -229.929279) (xy 108.643656 -229.929279)
			(xy 108.643656 -229.879301) (xy 108.651475 -229.829938) (xy 108.666919 -229.782406) (xy 108.689609 -229.737874)
			(xy 108.718985 -229.697441) (xy 108.754325 -229.662101) (xy 108.794758 -229.632725) (xy 108.83929 -229.610035)
			(xy 108.886822 -229.594591) (xy 108.936185 -229.586772) (xy 108.986163 -229.586772) (xy 109.035526 -229.594591)
			(xy 109.083058 -229.610035) (xy 109.12759 -229.632725) (xy 109.168023 -229.662101) (xy 109.203363 -229.697441)
			(xy 109.232739 -229.737874) (xy 109.255429 -229.782406) (xy 109.270873 -229.829938) (xy 109.278692 -229.879301)
			(xy 109.279182 -229.90429) (xy 109.278692 -229.929279) (xy 109.583456 -229.929279) (xy 109.583456 -229.879301)
			(xy 109.591275 -229.829938) (xy 109.606719 -229.782406) (xy 109.629409 -229.737874) (xy 109.658785 -229.697441)
			(xy 109.694125 -229.662101) (xy 109.734558 -229.632725) (xy 109.77909 -229.610035) (xy 109.826622 -229.594591)
			(xy 109.875985 -229.586772) (xy 109.925963 -229.586772) (xy 109.975326 -229.594591) (xy 110.022858 -229.610035)
			(xy 110.06739 -229.632725) (xy 110.107823 -229.662101) (xy 110.143163 -229.697441) (xy 110.172539 -229.737874)
			(xy 110.195229 -229.782406) (xy 110.210673 -229.829938) (xy 110.218492 -229.879301) (xy 110.218982 -229.90429)
			(xy 110.218492 -229.929279) (xy 113.337322 -229.929279) (xy 113.337322 -229.879301) (xy 113.345141 -229.829938)
			(xy 113.360585 -229.782406) (xy 113.383275 -229.737874) (xy 113.412651 -229.697441) (xy 113.447991 -229.662101)
			(xy 113.488424 -229.632725) (xy 113.532956 -229.610035) (xy 113.580488 -229.594591) (xy 113.629851 -229.586772)
			(xy 113.679829 -229.586772) (xy 113.729192 -229.594591) (xy 113.776724 -229.610035) (xy 113.821256 -229.632725)
			(xy 113.861689 -229.662101) (xy 113.897029 -229.697441) (xy 113.926405 -229.737874) (xy 113.949095 -229.782406)
			(xy 113.964539 -229.829938) (xy 113.972358 -229.879301) (xy 113.972848 -229.90429) (xy 113.972358 -229.929279)
			(xy 114.277122 -229.929279) (xy 114.277122 -229.879301) (xy 114.284941 -229.829938) (xy 114.300385 -229.782406)
			(xy 114.323075 -229.737874) (xy 114.352451 -229.697441) (xy 114.387791 -229.662101) (xy 114.428224 -229.632725)
			(xy 114.472756 -229.610035) (xy 114.520288 -229.594591) (xy 114.569651 -229.586772) (xy 114.619629 -229.586772)
			(xy 114.668992 -229.594591) (xy 114.716524 -229.610035) (xy 114.761056 -229.632725) (xy 114.801489 -229.662101)
			(xy 114.836829 -229.697441) (xy 114.866205 -229.737874) (xy 114.888895 -229.782406) (xy 114.904339 -229.829938)
			(xy 114.912158 -229.879301) (xy 114.912648 -229.90429) (xy 114.912158 -229.929279) (xy 115.217176 -229.929279)
			(xy 115.217176 -229.879301) (xy 115.224995 -229.829938) (xy 115.240439 -229.782406) (xy 115.263129 -229.737874)
			(xy 115.292505 -229.697441) (xy 115.327845 -229.662101) (xy 115.368278 -229.632725) (xy 115.41281 -229.610035)
			(xy 115.460342 -229.594591) (xy 115.509705 -229.586772) (xy 115.559683 -229.586772) (xy 115.609046 -229.594591)
			(xy 115.656578 -229.610035) (xy 115.70111 -229.632725) (xy 115.741543 -229.662101) (xy 115.776883 -229.697441)
			(xy 115.806259 -229.737874) (xy 115.828949 -229.782406) (xy 115.844393 -229.829938) (xy 115.852212 -229.879301)
			(xy 115.852702 -229.90429) (xy 116.158513 -229.90429) (xy 116.162608 -229.853562) (xy 116.174787 -229.804148)
			(xy 116.194735 -229.757328) (xy 116.221936 -229.714314) (xy 116.255684 -229.67622) (xy 116.295106 -229.644033)
			(xy 116.33918 -229.618587) (xy 116.386766 -229.60054) (xy 116.43663 -229.59036) (xy 116.487482 -229.588311)
			(xy 116.538003 -229.594445) (xy 116.586887 -229.608605) (xy 116.632866 -229.630422) (xy 116.67475 -229.659332)
			(xy 116.711454 -229.694587) (xy 116.742027 -229.735273) (xy 116.765678 -229.780336) (xy 116.781794 -229.82861)
			(xy 116.789958 -229.878844) (xy 116.79047 -229.90429) (xy 117.098567 -229.90429) (xy 117.102662 -229.853562)
			(xy 117.114841 -229.804148) (xy 117.134789 -229.757328) (xy 117.16199 -229.714314) (xy 117.195738 -229.67622)
			(xy 117.23516 -229.644033) (xy 117.279234 -229.618587) (xy 117.32682 -229.60054) (xy 117.376684 -229.59036)
			(xy 117.427536 -229.588311) (xy 117.478057 -229.594445) (xy 117.526941 -229.608605) (xy 117.57292 -229.630422)
			(xy 117.614804 -229.659332) (xy 117.651508 -229.694587) (xy 117.682081 -229.735273) (xy 117.705732 -229.780336)
			(xy 117.721848 -229.82861) (xy 117.730012 -229.878844) (xy 117.730524 -229.90429) (xy 117.730021 -229.929279)
			(xy 118.037338 -229.929279) (xy 118.037338 -229.879301) (xy 118.045157 -229.829938) (xy 118.060601 -229.782406)
			(xy 118.083291 -229.737874) (xy 118.112667 -229.697441) (xy 118.148007 -229.662101) (xy 118.18844 -229.632725)
			(xy 118.232972 -229.610035) (xy 118.280504 -229.594591) (xy 118.329867 -229.586772) (xy 118.379845 -229.586772)
			(xy 118.429208 -229.594591) (xy 118.47674 -229.610035) (xy 118.521272 -229.632725) (xy 118.561705 -229.662101)
			(xy 118.597045 -229.697441) (xy 118.626421 -229.737874) (xy 118.649111 -229.782406) (xy 118.664555 -229.829938)
			(xy 118.672374 -229.879301) (xy 118.672864 -229.90429) (xy 118.978421 -229.90429) (xy 118.982516 -229.853562)
			(xy 118.994695 -229.804148) (xy 119.014643 -229.757328) (xy 119.041844 -229.714314) (xy 119.075592 -229.67622)
			(xy 119.115014 -229.644033) (xy 119.159088 -229.618587) (xy 119.206674 -229.60054) (xy 119.256538 -229.59036)
			(xy 119.30739 -229.588311) (xy 119.357911 -229.594445) (xy 119.406795 -229.608605) (xy 119.452774 -229.630422)
			(xy 119.494658 -229.659332) (xy 119.531362 -229.694587) (xy 119.561935 -229.735273) (xy 119.585586 -229.780336)
			(xy 119.601702 -229.82861) (xy 119.609866 -229.878844) (xy 119.610378 -229.90429) (xy 119.918475 -229.90429)
			(xy 119.92257 -229.853562) (xy 119.934749 -229.804148) (xy 119.954697 -229.757328) (xy 119.981898 -229.714314)
			(xy 120.015646 -229.67622) (xy 120.055068 -229.644033) (xy 120.099142 -229.618587) (xy 120.146728 -229.60054)
			(xy 120.196592 -229.59036) (xy 120.247444 -229.588311) (xy 120.297965 -229.594445) (xy 120.346849 -229.608605)
			(xy 120.392828 -229.630422) (xy 120.434712 -229.659332) (xy 120.471416 -229.694587) (xy 120.501989 -229.735273)
			(xy 120.52564 -229.780336) (xy 120.541756 -229.82861) (xy 120.54992 -229.878844) (xy 120.550432 -229.90429)
			(xy 120.549929 -229.929279) (xy 120.857246 -229.929279) (xy 120.857246 -229.879301) (xy 120.865065 -229.829938)
			(xy 120.880509 -229.782406) (xy 120.903199 -229.737874) (xy 120.932575 -229.697441) (xy 120.967915 -229.662101)
			(xy 121.008348 -229.632725) (xy 121.05288 -229.610035) (xy 121.100412 -229.594591) (xy 121.149775 -229.586772)
			(xy 121.199753 -229.586772) (xy 121.249116 -229.594591) (xy 121.296648 -229.610035) (xy 121.34118 -229.632725)
			(xy 121.381613 -229.662101) (xy 121.416953 -229.697441) (xy 121.446329 -229.737874) (xy 121.469019 -229.782406)
			(xy 121.484463 -229.829938) (xy 121.492282 -229.879301) (xy 121.492772 -229.90429) (xy 121.798583 -229.90429)
			(xy 121.802678 -229.853562) (xy 121.814857 -229.804148) (xy 121.834805 -229.757328) (xy 121.862006 -229.714314)
			(xy 121.895754 -229.67622) (xy 121.935176 -229.644033) (xy 121.97925 -229.618587) (xy 122.026836 -229.60054)
			(xy 122.0767 -229.59036) (xy 122.127552 -229.588311) (xy 122.178073 -229.594445) (xy 122.226957 -229.608605)
			(xy 122.272936 -229.630422) (xy 122.31482 -229.659332) (xy 122.351524 -229.694587) (xy 122.382097 -229.735273)
			(xy 122.405748 -229.780336) (xy 122.421864 -229.82861) (xy 122.430028 -229.878844) (xy 122.43054 -229.90429)
			(xy 122.738383 -229.90429) (xy 122.742478 -229.853562) (xy 122.754657 -229.804148) (xy 122.774605 -229.757328)
			(xy 122.801806 -229.714314) (xy 122.835554 -229.67622) (xy 122.874976 -229.644033) (xy 122.91905 -229.618587)
			(xy 122.966636 -229.60054) (xy 123.0165 -229.59036) (xy 123.067352 -229.588311) (xy 123.117873 -229.594445)
			(xy 123.166757 -229.608605) (xy 123.212736 -229.630422) (xy 123.25462 -229.659332) (xy 123.291324 -229.694587)
			(xy 123.321897 -229.735273) (xy 123.345548 -229.780336) (xy 123.361664 -229.82861) (xy 123.369828 -229.878844)
			(xy 123.37034 -229.90429) (xy 123.369837 -229.929279) (xy 123.677154 -229.929279) (xy 123.677154 -229.879301)
			(xy 123.684973 -229.829938) (xy 123.700417 -229.782406) (xy 123.723107 -229.737874) (xy 123.752483 -229.697441)
			(xy 123.787823 -229.662101) (xy 123.828256 -229.632725) (xy 123.872788 -229.610035) (xy 123.92032 -229.594591)
			(xy 123.969683 -229.586772) (xy 124.019661 -229.586772) (xy 124.069024 -229.594591) (xy 124.116556 -229.610035)
			(xy 124.161088 -229.632725) (xy 124.201521 -229.662101) (xy 124.236861 -229.697441) (xy 124.266237 -229.737874)
			(xy 124.288927 -229.782406) (xy 124.304371 -229.829938) (xy 124.31219 -229.879301) (xy 124.31268 -229.90429)
			(xy 124.618491 -229.90429) (xy 124.622586 -229.853562) (xy 124.634765 -229.804148) (xy 124.654713 -229.757328)
			(xy 124.681914 -229.714314) (xy 124.715662 -229.67622) (xy 124.755084 -229.644033) (xy 124.799158 -229.618587)
			(xy 124.846744 -229.60054) (xy 124.896608 -229.59036) (xy 124.94746 -229.588311) (xy 124.997981 -229.594445)
			(xy 125.046865 -229.608605) (xy 125.092844 -229.630422) (xy 125.134728 -229.659332) (xy 125.171432 -229.694587)
			(xy 125.202005 -229.735273) (xy 125.225656 -229.780336) (xy 125.241772 -229.82861) (xy 125.249936 -229.878844)
			(xy 125.250448 -229.90429) (xy 125.558545 -229.90429) (xy 125.56264 -229.853562) (xy 125.574819 -229.804148)
			(xy 125.594767 -229.757328) (xy 125.621968 -229.714314) (xy 125.655716 -229.67622) (xy 125.695138 -229.644033)
			(xy 125.739212 -229.618587) (xy 125.786798 -229.60054) (xy 125.836662 -229.59036) (xy 125.887514 -229.588311)
			(xy 125.938035 -229.594445) (xy 125.986919 -229.608605) (xy 126.032898 -229.630422) (xy 126.074782 -229.659332)
			(xy 126.111486 -229.694587) (xy 126.142059 -229.735273) (xy 126.16571 -229.780336) (xy 126.181826 -229.82861)
			(xy 126.18999 -229.878844) (xy 126.190502 -229.90429) (xy 126.18999 -229.929736) (xy 126.181826 -229.97997)
			(xy 126.16571 -230.028244) (xy 126.142059 -230.073307) (xy 126.111486 -230.113993) (xy 126.074782 -230.149248)
			(xy 126.032898 -230.178158) (xy 125.986919 -230.199975) (xy 125.938035 -230.214135) (xy 125.887514 -230.220269)
			(xy 125.836662 -230.21822) (xy 125.786798 -230.20804) (xy 125.739212 -230.189993) (xy 125.695138 -230.164547)
			(xy 125.655716 -230.13236) (xy 125.621968 -230.094266) (xy 125.594767 -230.051252) (xy 125.574819 -230.004432)
			(xy 125.56264 -229.955018) (xy 125.558545 -229.90429) (xy 125.250448 -229.90429) (xy 125.249936 -229.929736)
			(xy 125.241772 -229.97997) (xy 125.225656 -230.028244) (xy 125.202005 -230.073307) (xy 125.171432 -230.113993)
			(xy 125.134728 -230.149248) (xy 125.092844 -230.178158) (xy 125.046865 -230.199975) (xy 124.997981 -230.214135)
			(xy 124.94746 -230.220269) (xy 124.896608 -230.21822) (xy 124.846744 -230.20804) (xy 124.799158 -230.189993)
			(xy 124.755084 -230.164547) (xy 124.715662 -230.13236) (xy 124.681914 -230.094266) (xy 124.654713 -230.051252)
			(xy 124.634765 -230.004432) (xy 124.622586 -229.955018) (xy 124.618491 -229.90429) (xy 124.31268 -229.90429)
			(xy 124.31219 -229.929279) (xy 124.304371 -229.978642) (xy 124.288927 -230.026174) (xy 124.266237 -230.070706)
			(xy 124.236861 -230.111139) (xy 124.201521 -230.146479) (xy 124.161088 -230.175855) (xy 124.116556 -230.198545)
			(xy 124.069024 -230.213989) (xy 124.019661 -230.221808) (xy 123.969683 -230.221808) (xy 123.92032 -230.213989)
			(xy 123.872788 -230.198545) (xy 123.828256 -230.175855) (xy 123.787823 -230.146479) (xy 123.752483 -230.111139)
			(xy 123.723107 -230.070706) (xy 123.700417 -230.026174) (xy 123.684973 -229.978642) (xy 123.677154 -229.929279)
			(xy 123.369837 -229.929279) (xy 123.369828 -229.929736) (xy 123.361664 -229.97997) (xy 123.345548 -230.028244)
			(xy 123.321897 -230.073307) (xy 123.291324 -230.113993) (xy 123.25462 -230.149248) (xy 123.212736 -230.178158)
			(xy 123.166757 -230.199975) (xy 123.117873 -230.214135) (xy 123.067352 -230.220269) (xy 123.0165 -230.21822)
			(xy 122.966636 -230.20804) (xy 122.91905 -230.189993) (xy 122.874976 -230.164547) (xy 122.835554 -230.13236)
			(xy 122.801806 -230.094266) (xy 122.774605 -230.051252) (xy 122.754657 -230.004432) (xy 122.742478 -229.955018)
			(xy 122.738383 -229.90429) (xy 122.43054 -229.90429) (xy 122.430028 -229.929736) (xy 122.421864 -229.97997)
			(xy 122.405748 -230.028244) (xy 122.382097 -230.073307) (xy 122.351524 -230.113993) (xy 122.31482 -230.149248)
			(xy 122.272936 -230.178158) (xy 122.226957 -230.199975) (xy 122.178073 -230.214135) (xy 122.127552 -230.220269)
			(xy 122.0767 -230.21822) (xy 122.026836 -230.20804) (xy 121.97925 -230.189993) (xy 121.935176 -230.164547)
			(xy 121.895754 -230.13236) (xy 121.862006 -230.094266) (xy 121.834805 -230.051252) (xy 121.814857 -230.004432)
			(xy 121.802678 -229.955018) (xy 121.798583 -229.90429) (xy 121.492772 -229.90429) (xy 121.492282 -229.929279)
			(xy 121.484463 -229.978642) (xy 121.469019 -230.026174) (xy 121.446329 -230.070706) (xy 121.416953 -230.111139)
			(xy 121.381613 -230.146479) (xy 121.34118 -230.175855) (xy 121.296648 -230.198545) (xy 121.249116 -230.213989)
			(xy 121.199753 -230.221808) (xy 121.149775 -230.221808) (xy 121.100412 -230.213989) (xy 121.05288 -230.198545)
			(xy 121.008348 -230.175855) (xy 120.967915 -230.146479) (xy 120.932575 -230.111139) (xy 120.903199 -230.070706)
			(xy 120.880509 -230.026174) (xy 120.865065 -229.978642) (xy 120.857246 -229.929279) (xy 120.549929 -229.929279)
			(xy 120.54992 -229.929736) (xy 120.541756 -229.97997) (xy 120.52564 -230.028244) (xy 120.501989 -230.073307)
			(xy 120.471416 -230.113993) (xy 120.434712 -230.149248) (xy 120.392828 -230.178158) (xy 120.346849 -230.199975)
			(xy 120.297965 -230.214135) (xy 120.247444 -230.220269) (xy 120.196592 -230.21822) (xy 120.146728 -230.20804)
			(xy 120.099142 -230.189993) (xy 120.055068 -230.164547) (xy 120.015646 -230.13236) (xy 119.981898 -230.094266)
			(xy 119.954697 -230.051252) (xy 119.934749 -230.004432) (xy 119.92257 -229.955018) (xy 119.918475 -229.90429)
			(xy 119.610378 -229.90429) (xy 119.609866 -229.929736) (xy 119.601702 -229.97997) (xy 119.585586 -230.028244)
			(xy 119.561935 -230.073307) (xy 119.531362 -230.113993) (xy 119.494658 -230.149248) (xy 119.452774 -230.178158)
			(xy 119.406795 -230.199975) (xy 119.357911 -230.214135) (xy 119.30739 -230.220269) (xy 119.256538 -230.21822)
			(xy 119.206674 -230.20804) (xy 119.159088 -230.189993) (xy 119.115014 -230.164547) (xy 119.075592 -230.13236)
			(xy 119.041844 -230.094266) (xy 119.014643 -230.051252) (xy 118.994695 -230.004432) (xy 118.982516 -229.955018)
			(xy 118.978421 -229.90429) (xy 118.672864 -229.90429) (xy 118.672374 -229.929279) (xy 118.664555 -229.978642)
			(xy 118.649111 -230.026174) (xy 118.626421 -230.070706) (xy 118.597045 -230.111139) (xy 118.561705 -230.146479)
			(xy 118.521272 -230.175855) (xy 118.47674 -230.198545) (xy 118.429208 -230.213989) (xy 118.379845 -230.221808)
			(xy 118.329867 -230.221808) (xy 118.280504 -230.213989) (xy 118.232972 -230.198545) (xy 118.18844 -230.175855)
			(xy 118.148007 -230.146479) (xy 118.112667 -230.111139) (xy 118.083291 -230.070706) (xy 118.060601 -230.026174)
			(xy 118.045157 -229.978642) (xy 118.037338 -229.929279) (xy 117.730021 -229.929279) (xy 117.730012 -229.929736)
			(xy 117.721848 -229.97997) (xy 117.705732 -230.028244) (xy 117.682081 -230.073307) (xy 117.651508 -230.113993)
			(xy 117.614804 -230.149248) (xy 117.57292 -230.178158) (xy 117.526941 -230.199975) (xy 117.478057 -230.214135)
			(xy 117.427536 -230.220269) (xy 117.376684 -230.21822) (xy 117.32682 -230.20804) (xy 117.279234 -230.189993)
			(xy 117.23516 -230.164547) (xy 117.195738 -230.13236) (xy 117.16199 -230.094266) (xy 117.134789 -230.051252)
			(xy 117.114841 -230.004432) (xy 117.102662 -229.955018) (xy 117.098567 -229.90429) (xy 116.79047 -229.90429)
			(xy 116.789958 -229.929736) (xy 116.781794 -229.97997) (xy 116.765678 -230.028244) (xy 116.742027 -230.073307)
			(xy 116.711454 -230.113993) (xy 116.67475 -230.149248) (xy 116.632866 -230.178158) (xy 116.586887 -230.199975)
			(xy 116.538003 -230.214135) (xy 116.487482 -230.220269) (xy 116.43663 -230.21822) (xy 116.386766 -230.20804)
			(xy 116.33918 -230.189993) (xy 116.295106 -230.164547) (xy 116.255684 -230.13236) (xy 116.221936 -230.094266)
			(xy 116.194735 -230.051252) (xy 116.174787 -230.004432) (xy 116.162608 -229.955018) (xy 116.158513 -229.90429)
			(xy 115.852702 -229.90429) (xy 115.852212 -229.929279) (xy 115.844393 -229.978642) (xy 115.828949 -230.026174)
			(xy 115.806259 -230.070706) (xy 115.776883 -230.111139) (xy 115.741543 -230.146479) (xy 115.70111 -230.175855)
			(xy 115.656578 -230.198545) (xy 115.609046 -230.213989) (xy 115.559683 -230.221808) (xy 115.509705 -230.221808)
			(xy 115.460342 -230.213989) (xy 115.41281 -230.198545) (xy 115.368278 -230.175855) (xy 115.327845 -230.146479)
			(xy 115.292505 -230.111139) (xy 115.263129 -230.070706) (xy 115.240439 -230.026174) (xy 115.224995 -229.978642)
			(xy 115.217176 -229.929279) (xy 114.912158 -229.929279) (xy 114.904339 -229.978642) (xy 114.888895 -230.026174)
			(xy 114.866205 -230.070706) (xy 114.836829 -230.111139) (xy 114.801489 -230.146479) (xy 114.761056 -230.175855)
			(xy 114.716524 -230.198545) (xy 114.668992 -230.213989) (xy 114.619629 -230.221808) (xy 114.569651 -230.221808)
			(xy 114.520288 -230.213989) (xy 114.472756 -230.198545) (xy 114.428224 -230.175855) (xy 114.387791 -230.146479)
			(xy 114.352451 -230.111139) (xy 114.323075 -230.070706) (xy 114.300385 -230.026174) (xy 114.284941 -229.978642)
			(xy 114.277122 -229.929279) (xy 113.972358 -229.929279) (xy 113.964539 -229.978642) (xy 113.949095 -230.026174)
			(xy 113.926405 -230.070706) (xy 113.897029 -230.111139) (xy 113.861689 -230.146479) (xy 113.821256 -230.175855)
			(xy 113.776724 -230.198545) (xy 113.729192 -230.213989) (xy 113.679829 -230.221808) (xy 113.629851 -230.221808)
			(xy 113.580488 -230.213989) (xy 113.532956 -230.198545) (xy 113.488424 -230.175855) (xy 113.447991 -230.146479)
			(xy 113.412651 -230.111139) (xy 113.383275 -230.070706) (xy 113.360585 -230.026174) (xy 113.345141 -229.978642)
			(xy 113.337322 -229.929279) (xy 110.218492 -229.929279) (xy 110.210673 -229.978642) (xy 110.195229 -230.026174)
			(xy 110.172539 -230.070706) (xy 110.143163 -230.111139) (xy 110.107823 -230.146479) (xy 110.06739 -230.175855)
			(xy 110.022858 -230.198545) (xy 109.975326 -230.213989) (xy 109.925963 -230.221808) (xy 109.875985 -230.221808)
			(xy 109.826622 -230.213989) (xy 109.77909 -230.198545) (xy 109.734558 -230.175855) (xy 109.694125 -230.146479)
			(xy 109.658785 -230.111139) (xy 109.629409 -230.070706) (xy 109.606719 -230.026174) (xy 109.591275 -229.978642)
			(xy 109.583456 -229.929279) (xy 109.278692 -229.929279) (xy 109.270873 -229.978642) (xy 109.255429 -230.026174)
			(xy 109.232739 -230.070706) (xy 109.203363 -230.111139) (xy 109.168023 -230.146479) (xy 109.12759 -230.175855)
			(xy 109.083058 -230.198545) (xy 109.035526 -230.213989) (xy 108.986163 -230.221808) (xy 108.936185 -230.221808)
			(xy 108.886822 -230.213989) (xy 108.83929 -230.198545) (xy 108.794758 -230.175855) (xy 108.754325 -230.146479)
			(xy 108.718985 -230.111139) (xy 108.689609 -230.070706) (xy 108.666919 -230.026174) (xy 108.651475 -229.978642)
			(xy 108.643656 -229.929279) (xy 108.338638 -229.929279) (xy 108.330819 -229.978642) (xy 108.315375 -230.026174)
			(xy 108.292685 -230.070706) (xy 108.263309 -230.111139) (xy 108.227969 -230.146479) (xy 108.187536 -230.175855)
			(xy 108.143004 -230.198545) (xy 108.095472 -230.213989) (xy 108.046109 -230.221808) (xy 107.996131 -230.221808)
			(xy 107.946768 -230.213989) (xy 107.899236 -230.198545) (xy 107.854704 -230.175855) (xy 107.814271 -230.146479)
			(xy 107.778931 -230.111139) (xy 107.749555 -230.070706) (xy 107.726865 -230.026174) (xy 107.711421 -229.978642)
			(xy 107.703602 -229.929279) (xy 107.396285 -229.929279) (xy 107.396276 -229.929736) (xy 107.388112 -229.97997)
			(xy 107.371996 -230.028244) (xy 107.348345 -230.073307) (xy 107.317772 -230.113993) (xy 107.281068 -230.149248)
			(xy 107.239184 -230.178158) (xy 107.193205 -230.199975) (xy 107.144321 -230.214135) (xy 107.0938 -230.220269)
			(xy 107.042948 -230.21822) (xy 106.993084 -230.20804) (xy 106.945498 -230.189993) (xy 106.901424 -230.164547)
			(xy 106.862002 -230.13236) (xy 106.828254 -230.094266) (xy 106.801053 -230.051252) (xy 106.781105 -230.004432)
			(xy 106.768926 -229.955018) (xy 106.764831 -229.90429) (xy 106.456734 -229.90429) (xy 106.456222 -229.929736)
			(xy 106.448058 -229.97997) (xy 106.431942 -230.028244) (xy 106.408291 -230.073307) (xy 106.377718 -230.113993)
			(xy 106.341014 -230.149248) (xy 106.29913 -230.178158) (xy 106.253151 -230.199975) (xy 106.204267 -230.214135)
			(xy 106.153746 -230.220269) (xy 106.102894 -230.21822) (xy 106.05303 -230.20804) (xy 106.005444 -230.189993)
			(xy 105.96137 -230.164547) (xy 105.921948 -230.13236) (xy 105.8882 -230.094266) (xy 105.860999 -230.051252)
			(xy 105.841051 -230.004432) (xy 105.828872 -229.955018) (xy 105.824777 -229.90429) (xy 105.518966 -229.90429)
			(xy 105.518476 -229.929279) (xy 105.510657 -229.978642) (xy 105.495213 -230.026174) (xy 105.472523 -230.070706)
			(xy 105.443147 -230.111139) (xy 105.407807 -230.146479) (xy 105.367374 -230.175855) (xy 105.322842 -230.198545)
			(xy 105.27531 -230.213989) (xy 105.225947 -230.221808) (xy 105.175969 -230.221808) (xy 105.126606 -230.213989)
			(xy 105.079074 -230.198545) (xy 105.034542 -230.175855) (xy 104.994109 -230.146479) (xy 104.958769 -230.111139)
			(xy 104.929393 -230.070706) (xy 104.906703 -230.026174) (xy 104.891259 -229.978642) (xy 104.88344 -229.929279)
			(xy 104.576377 -229.929279) (xy 104.576368 -229.929736) (xy 104.568204 -229.97997) (xy 104.552088 -230.028244)
			(xy 104.528437 -230.073307) (xy 104.497864 -230.113993) (xy 104.46116 -230.149248) (xy 104.419276 -230.178158)
			(xy 104.373297 -230.199975) (xy 104.324413 -230.214135) (xy 104.273892 -230.220269) (xy 104.22304 -230.21822)
			(xy 104.173176 -230.20804) (xy 104.12559 -230.189993) (xy 104.081516 -230.164547) (xy 104.042094 -230.13236)
			(xy 104.008346 -230.094266) (xy 103.981145 -230.051252) (xy 103.961197 -230.004432) (xy 103.949018 -229.955018)
			(xy 103.944923 -229.90429) (xy 103.636826 -229.90429) (xy 103.636314 -229.929736) (xy 103.62815 -229.97997)
			(xy 103.612034 -230.028244) (xy 103.588383 -230.073307) (xy 103.55781 -230.113993) (xy 103.521106 -230.149248)
			(xy 103.479222 -230.178158) (xy 103.433243 -230.199975) (xy 103.384359 -230.214135) (xy 103.333838 -230.220269)
			(xy 103.282986 -230.21822) (xy 103.233122 -230.20804) (xy 103.185536 -230.189993) (xy 103.141462 -230.164547)
			(xy 103.10204 -230.13236) (xy 103.068292 -230.094266) (xy 103.041091 -230.051252) (xy 103.021143 -230.004432)
			(xy 103.008964 -229.955018) (xy 103.004869 -229.90429) (xy 102.699058 -229.90429) (xy 102.698568 -229.929279)
			(xy 102.690749 -229.978642) (xy 102.675305 -230.026174) (xy 102.652615 -230.070706) (xy 102.623239 -230.111139)
			(xy 102.587899 -230.146479) (xy 102.547466 -230.175855) (xy 102.502934 -230.198545) (xy 102.455402 -230.213989)
			(xy 102.406039 -230.221808) (xy 102.356061 -230.221808) (xy 102.306698 -230.213989) (xy 102.259166 -230.198545)
			(xy 102.214634 -230.175855) (xy 102.174201 -230.146479) (xy 102.138861 -230.111139) (xy 102.109485 -230.070706)
			(xy 102.086795 -230.026174) (xy 102.071351 -229.978642) (xy 102.063532 -229.929279) (xy 101.756215 -229.929279)
			(xy 101.756206 -229.929736) (xy 101.748042 -229.97997) (xy 101.731926 -230.028244) (xy 101.708275 -230.073307)
			(xy 101.677702 -230.113993) (xy 101.640998 -230.149248) (xy 101.599114 -230.178158) (xy 101.553135 -230.199975)
			(xy 101.504251 -230.214135) (xy 101.45373 -230.220269) (xy 101.402878 -230.21822) (xy 101.353014 -230.20804)
			(xy 101.305428 -230.189993) (xy 101.261354 -230.164547) (xy 101.221932 -230.13236) (xy 101.188184 -230.094266)
			(xy 101.160983 -230.051252) (xy 101.141035 -230.004432) (xy 101.128856 -229.955018) (xy 101.124761 -229.90429)
			(xy 100.816664 -229.90429) (xy 100.816152 -229.929736) (xy 100.807988 -229.97997) (xy 100.791872 -230.028244)
			(xy 100.768221 -230.073307) (xy 100.737648 -230.113993) (xy 100.700944 -230.149248) (xy 100.65906 -230.178158)
			(xy 100.613081 -230.199975) (xy 100.564197 -230.214135) (xy 100.513676 -230.220269) (xy 100.462824 -230.21822)
			(xy 100.41296 -230.20804) (xy 100.365374 -230.189993) (xy 100.3213 -230.164547) (xy 100.281878 -230.13236)
			(xy 100.24813 -230.094266) (xy 100.220929 -230.051252) (xy 100.200981 -230.004432) (xy 100.188802 -229.955018)
			(xy 100.184707 -229.90429) (xy 99.87915 -229.90429) (xy 99.87866 -229.929279) (xy 99.870841 -229.978642)
			(xy 99.855397 -230.026174) (xy 99.832707 -230.070706) (xy 99.803331 -230.111139) (xy 99.767991 -230.146479)
			(xy 99.727558 -230.175855) (xy 99.683026 -230.198545) (xy 99.635494 -230.213989) (xy 99.586131 -230.221808)
			(xy 99.536153 -230.221808) (xy 99.48679 -230.213989) (xy 99.439258 -230.198545) (xy 99.394726 -230.175855)
			(xy 99.354293 -230.146479) (xy 99.318953 -230.111139) (xy 99.289577 -230.070706) (xy 99.266887 -230.026174)
			(xy 99.251443 -229.978642) (xy 99.243624 -229.929279) (xy 98.936307 -229.929279) (xy 98.936298 -229.929736)
			(xy 98.928134 -229.97997) (xy 98.912018 -230.028244) (xy 98.888367 -230.073307) (xy 98.857794 -230.113993)
			(xy 98.82109 -230.149248) (xy 98.779206 -230.178158) (xy 98.733227 -230.199975) (xy 98.684343 -230.214135)
			(xy 98.633822 -230.220269) (xy 98.58297 -230.21822) (xy 98.533106 -230.20804) (xy 98.48552 -230.189993)
			(xy 98.441446 -230.164547) (xy 98.402024 -230.13236) (xy 98.368276 -230.094266) (xy 98.341075 -230.051252)
			(xy 98.321127 -230.004432) (xy 98.308948 -229.955018) (xy 98.304853 -229.90429) (xy 97.996756 -229.90429)
			(xy 97.996244 -229.929736) (xy 97.98808 -229.97997) (xy 97.971964 -230.028244) (xy 97.948313 -230.073307)
			(xy 97.91774 -230.113993) (xy 97.881036 -230.149248) (xy 97.839152 -230.178158) (xy 97.793173 -230.199975)
			(xy 97.744289 -230.214135) (xy 97.693768 -230.220269) (xy 97.642916 -230.21822) (xy 97.593052 -230.20804)
			(xy 97.545466 -230.189993) (xy 97.501392 -230.164547) (xy 97.46197 -230.13236) (xy 97.428222 -230.094266)
			(xy 97.401021 -230.051252) (xy 97.381073 -230.004432) (xy 97.368894 -229.955018) (xy 97.364799 -229.90429)
			(xy 97.058988 -229.90429) (xy 97.058988 -229.907846) (xy 97.057718 -229.937818) (xy 97.057464 -229.939342)
			(xy 97.057464 -230.739539) (xy 98.77347 -230.739539) (xy 98.77347 -230.689561) (xy 98.781289 -230.640198)
			(xy 98.796733 -230.592666) (xy 98.819423 -230.548134) (xy 98.848799 -230.507701) (xy 98.884139 -230.472361)
			(xy 98.924572 -230.442985) (xy 98.969104 -230.420295) (xy 99.016636 -230.404851) (xy 99.065999 -230.397032)
			(xy 99.115977 -230.397032) (xy 99.16534 -230.404851) (xy 99.212872 -230.420295) (xy 99.257404 -230.442985)
			(xy 99.297837 -230.472361) (xy 99.333177 -230.507701) (xy 99.362553 -230.548134) (xy 99.385243 -230.592666)
			(xy 99.400687 -230.640198) (xy 99.408506 -230.689561) (xy 99.408996 -230.71455) (xy 99.408511 -230.739285)
			(xy 101.593632 -230.739285) (xy 101.593632 -230.689307) (xy 101.601451 -230.639944) (xy 101.616895 -230.592412)
			(xy 101.639585 -230.54788) (xy 101.668961 -230.507447) (xy 101.704301 -230.472107) (xy 101.744734 -230.442731)
			(xy 101.789266 -230.420041) (xy 101.836798 -230.404597) (xy 101.886161 -230.396778) (xy 101.936139 -230.396778)
			(xy 101.985502 -230.404597) (xy 102.033034 -230.420041) (xy 102.077566 -230.442731) (xy 102.117999 -230.472107)
			(xy 102.153339 -230.507447) (xy 102.182715 -230.54788) (xy 102.205405 -230.592412) (xy 102.220849 -230.639944)
			(xy 102.228668 -230.689307) (xy 102.229158 -230.714296) (xy 102.228668 -230.739285) (xy 102.228628 -230.739539)
			(xy 104.41354 -230.739539) (xy 104.41354 -230.689561) (xy 104.421359 -230.640198) (xy 104.436803 -230.592666)
			(xy 104.459493 -230.548134) (xy 104.488869 -230.507701) (xy 104.524209 -230.472361) (xy 104.564642 -230.442985)
			(xy 104.609174 -230.420295) (xy 104.656706 -230.404851) (xy 104.706069 -230.397032) (xy 104.756047 -230.397032)
			(xy 104.80541 -230.404851) (xy 104.852942 -230.420295) (xy 104.897474 -230.442985) (xy 104.937907 -230.472361)
			(xy 104.973247 -230.507701) (xy 105.002623 -230.548134) (xy 105.025313 -230.592666) (xy 105.040757 -230.640198)
			(xy 105.048576 -230.689561) (xy 105.049066 -230.71455) (xy 105.048581 -230.739285) (xy 107.233448 -230.739285)
			(xy 107.233448 -230.689307) (xy 107.241267 -230.639944) (xy 107.256711 -230.592412) (xy 107.279401 -230.54788)
			(xy 107.308777 -230.507447) (xy 107.344117 -230.472107) (xy 107.38455 -230.442731) (xy 107.429082 -230.420041)
			(xy 107.476614 -230.404597) (xy 107.525977 -230.396778) (xy 107.575955 -230.396778) (xy 107.625318 -230.404597)
			(xy 107.67285 -230.420041) (xy 107.717382 -230.442731) (xy 107.757815 -230.472107) (xy 107.793155 -230.507447)
			(xy 107.822531 -230.54788) (xy 107.845221 -230.592412) (xy 107.860665 -230.639944) (xy 107.868484 -230.689307)
			(xy 107.868974 -230.714296) (xy 107.868969 -230.71455) (xy 108.174785 -230.71455) (xy 108.17888 -230.663822)
			(xy 108.191059 -230.614408) (xy 108.211007 -230.567588) (xy 108.238208 -230.524574) (xy 108.271956 -230.48648)
			(xy 108.311378 -230.454293) (xy 108.355452 -230.428847) (xy 108.403038 -230.4108) (xy 108.452902 -230.40062)
			(xy 108.503754 -230.398571) (xy 108.554275 -230.404705) (xy 108.603159 -230.418865) (xy 108.649138 -230.440682)
			(xy 108.691022 -230.469592) (xy 108.727726 -230.504847) (xy 108.758299 -230.545533) (xy 108.78195 -230.590596)
			(xy 108.798066 -230.63887) (xy 108.80623 -230.689104) (xy 108.806742 -230.71455) (xy 109.114839 -230.71455)
			(xy 109.118934 -230.663822) (xy 109.131113 -230.614408) (xy 109.151061 -230.567588) (xy 109.178262 -230.524574)
			(xy 109.21201 -230.48648) (xy 109.251432 -230.454293) (xy 109.295506 -230.428847) (xy 109.343092 -230.4108)
			(xy 109.392956 -230.40062) (xy 109.443808 -230.398571) (xy 109.494329 -230.404705) (xy 109.543213 -230.418865)
			(xy 109.589192 -230.440682) (xy 109.631076 -230.469592) (xy 109.66778 -230.504847) (xy 109.698353 -230.545533)
			(xy 109.722004 -230.590596) (xy 109.73812 -230.63887) (xy 109.746284 -230.689104) (xy 109.746796 -230.71455)
			(xy 109.746293 -230.739539) (xy 110.05361 -230.739539) (xy 110.05361 -230.689561) (xy 110.061429 -230.640198)
			(xy 110.076873 -230.592666) (xy 110.099563 -230.548134) (xy 110.128939 -230.507701) (xy 110.164279 -230.472361)
			(xy 110.204712 -230.442985) (xy 110.249244 -230.420295) (xy 110.296776 -230.404851) (xy 110.346139 -230.397032)
			(xy 110.396117 -230.397032) (xy 110.44548 -230.404851) (xy 110.493012 -230.420295) (xy 110.537544 -230.442985)
			(xy 110.577977 -230.472361) (xy 110.613317 -230.507701) (xy 110.642693 -230.548134) (xy 110.665383 -230.592666)
			(xy 110.680827 -230.640198) (xy 110.688646 -230.689561) (xy 110.689136 -230.71455) (xy 110.688646 -230.739539)
			(xy 112.867168 -230.739539) (xy 112.867168 -230.689561) (xy 112.874987 -230.640198) (xy 112.890431 -230.592666)
			(xy 112.913121 -230.548134) (xy 112.942497 -230.507701) (xy 112.977837 -230.472361) (xy 113.01827 -230.442985)
			(xy 113.062802 -230.420295) (xy 113.110334 -230.404851) (xy 113.159697 -230.397032) (xy 113.209675 -230.397032)
			(xy 113.259038 -230.404851) (xy 113.30657 -230.420295) (xy 113.351102 -230.442985) (xy 113.391535 -230.472361)
			(xy 113.426875 -230.507701) (xy 113.456251 -230.548134) (xy 113.478941 -230.592666) (xy 113.494385 -230.640198)
			(xy 113.502204 -230.689561) (xy 113.502694 -230.71455) (xy 113.808505 -230.71455) (xy 113.8126 -230.663822)
			(xy 113.824779 -230.614408) (xy 113.844727 -230.567588) (xy 113.871928 -230.524574) (xy 113.905676 -230.48648)
			(xy 113.945098 -230.454293) (xy 113.989172 -230.428847) (xy 114.036758 -230.4108) (xy 114.086622 -230.40062)
			(xy 114.137474 -230.398571) (xy 114.187995 -230.404705) (xy 114.236879 -230.418865) (xy 114.282858 -230.440682)
			(xy 114.324742 -230.469592) (xy 114.361446 -230.504847) (xy 114.392019 -230.545533) (xy 114.41567 -230.590596)
			(xy 114.431786 -230.63887) (xy 114.43995 -230.689104) (xy 114.440462 -230.71455) (xy 114.748559 -230.71455)
			(xy 114.752654 -230.663822) (xy 114.764833 -230.614408) (xy 114.784781 -230.567588) (xy 114.811982 -230.524574)
			(xy 114.84573 -230.48648) (xy 114.885152 -230.454293) (xy 114.929226 -230.428847) (xy 114.976812 -230.4108)
			(xy 115.026676 -230.40062) (xy 115.077528 -230.398571) (xy 115.128049 -230.404705) (xy 115.176933 -230.418865)
			(xy 115.222912 -230.440682) (xy 115.264796 -230.469592) (xy 115.3015 -230.504847) (xy 115.332073 -230.545533)
			(xy 115.355724 -230.590596) (xy 115.37184 -230.63887) (xy 115.380004 -230.689104) (xy 115.380516 -230.71455)
			(xy 115.380018 -230.739285) (xy 115.68733 -230.739285) (xy 115.68733 -230.689307) (xy 115.695149 -230.639944)
			(xy 115.710593 -230.592412) (xy 115.733283 -230.54788) (xy 115.762659 -230.507447) (xy 115.797999 -230.472107)
			(xy 115.838432 -230.442731) (xy 115.882964 -230.420041) (xy 115.930496 -230.404597) (xy 115.979859 -230.396778)
			(xy 116.029837 -230.396778) (xy 116.0792 -230.404597) (xy 116.126732 -230.420041) (xy 116.171264 -230.442731)
			(xy 116.211697 -230.472107) (xy 116.247037 -230.507447) (xy 116.276413 -230.54788) (xy 116.299103 -230.592412)
			(xy 116.314547 -230.639944) (xy 116.322366 -230.689307) (xy 116.322856 -230.714296) (xy 116.322366 -230.739285)
			(xy 116.322326 -230.739539) (xy 118.507238 -230.739539) (xy 118.507238 -230.689561) (xy 118.515057 -230.640198)
			(xy 118.530501 -230.592666) (xy 118.553191 -230.548134) (xy 118.582567 -230.507701) (xy 118.617907 -230.472361)
			(xy 118.65834 -230.442985) (xy 118.702872 -230.420295) (xy 118.750404 -230.404851) (xy 118.799767 -230.397032)
			(xy 118.849745 -230.397032) (xy 118.899108 -230.404851) (xy 118.94664 -230.420295) (xy 118.991172 -230.442985)
			(xy 119.031605 -230.472361) (xy 119.066945 -230.507701) (xy 119.096321 -230.548134) (xy 119.119011 -230.592666)
			(xy 119.134455 -230.640198) (xy 119.142274 -230.689561) (xy 119.142764 -230.71455) (xy 119.142274 -230.739539)
			(xy 121.327146 -230.739539) (xy 121.327146 -230.689561) (xy 121.334965 -230.640198) (xy 121.350409 -230.592666)
			(xy 121.373099 -230.548134) (xy 121.402475 -230.507701) (xy 121.437815 -230.472361) (xy 121.478248 -230.442985)
			(xy 121.52278 -230.420295) (xy 121.570312 -230.404851) (xy 121.619675 -230.397032) (xy 121.669653 -230.397032)
			(xy 121.719016 -230.404851) (xy 121.766548 -230.420295) (xy 121.81108 -230.442985) (xy 121.851513 -230.472361)
			(xy 121.886853 -230.507701) (xy 121.916229 -230.548134) (xy 121.938919 -230.592666) (xy 121.954363 -230.640198)
			(xy 121.962182 -230.689561) (xy 121.962672 -230.71455) (xy 121.962187 -230.739285) (xy 124.147308 -230.739285)
			(xy 124.147308 -230.689307) (xy 124.155127 -230.639944) (xy 124.170571 -230.592412) (xy 124.193261 -230.54788)
			(xy 124.222637 -230.507447) (xy 124.257977 -230.472107) (xy 124.29841 -230.442731) (xy 124.342942 -230.420041)
			(xy 124.390474 -230.404597) (xy 124.439837 -230.396778) (xy 124.489815 -230.396778) (xy 124.539178 -230.404597)
			(xy 124.58671 -230.420041) (xy 124.631242 -230.442731) (xy 124.671675 -230.472107) (xy 124.707015 -230.507447)
			(xy 124.736391 -230.54788) (xy 124.759081 -230.592412) (xy 124.774525 -230.639944) (xy 124.782344 -230.689307)
			(xy 124.782834 -230.714296) (xy 124.782344 -230.739285) (xy 124.774525 -230.788648) (xy 124.759081 -230.83618)
			(xy 124.736391 -230.880712) (xy 124.707015 -230.921145) (xy 124.671675 -230.956485) (xy 124.631242 -230.985861)
			(xy 124.58671 -231.008551) (xy 124.539178 -231.023995) (xy 124.489815 -231.031814) (xy 124.439837 -231.031814)
			(xy 124.390474 -231.023995) (xy 124.342942 -231.008551) (xy 124.29841 -230.985861) (xy 124.257977 -230.956485)
			(xy 124.222637 -230.921145) (xy 124.193261 -230.880712) (xy 124.170571 -230.83618) (xy 124.155127 -230.788648)
			(xy 124.147308 -230.739285) (xy 121.962187 -230.739285) (xy 121.962182 -230.739539) (xy 121.954363 -230.788902)
			(xy 121.938919 -230.836434) (xy 121.916229 -230.880966) (xy 121.886853 -230.921399) (xy 121.851513 -230.956739)
			(xy 121.81108 -230.986115) (xy 121.766548 -231.008805) (xy 121.719016 -231.024249) (xy 121.669653 -231.032068)
			(xy 121.619675 -231.032068) (xy 121.570312 -231.024249) (xy 121.52278 -231.008805) (xy 121.478248 -230.986115)
			(xy 121.437815 -230.956739) (xy 121.402475 -230.921399) (xy 121.373099 -230.880966) (xy 121.350409 -230.836434)
			(xy 121.334965 -230.788902) (xy 121.327146 -230.739539) (xy 119.142274 -230.739539) (xy 119.134455 -230.788902)
			(xy 119.119011 -230.836434) (xy 119.096321 -230.880966) (xy 119.066945 -230.921399) (xy 119.031605 -230.956739)
			(xy 118.991172 -230.986115) (xy 118.94664 -231.008805) (xy 118.899108 -231.024249) (xy 118.849745 -231.032068)
			(xy 118.799767 -231.032068) (xy 118.750404 -231.024249) (xy 118.702872 -231.008805) (xy 118.65834 -230.986115)
			(xy 118.617907 -230.956739) (xy 118.582567 -230.921399) (xy 118.553191 -230.880966) (xy 118.530501 -230.836434)
			(xy 118.515057 -230.788902) (xy 118.507238 -230.739539) (xy 116.322326 -230.739539) (xy 116.314547 -230.788648)
			(xy 116.299103 -230.83618) (xy 116.276413 -230.880712) (xy 116.247037 -230.921145) (xy 116.211697 -230.956485)
			(xy 116.171264 -230.985861) (xy 116.126732 -231.008551) (xy 116.0792 -231.023995) (xy 116.029837 -231.031814)
			(xy 115.979859 -231.031814) (xy 115.930496 -231.023995) (xy 115.882964 -231.008551) (xy 115.838432 -230.985861)
			(xy 115.797999 -230.956485) (xy 115.762659 -230.921145) (xy 115.733283 -230.880712) (xy 115.710593 -230.83618)
			(xy 115.695149 -230.788648) (xy 115.68733 -230.739285) (xy 115.380018 -230.739285) (xy 115.380004 -230.739996)
			(xy 115.37184 -230.79023) (xy 115.355724 -230.838504) (xy 115.332073 -230.883567) (xy 115.3015 -230.924253)
			(xy 115.264796 -230.959508) (xy 115.222912 -230.988418) (xy 115.176933 -231.010235) (xy 115.128049 -231.024395)
			(xy 115.077528 -231.030529) (xy 115.026676 -231.02848) (xy 114.976812 -231.0183) (xy 114.929226 -231.000253)
			(xy 114.885152 -230.974807) (xy 114.84573 -230.94262) (xy 114.811982 -230.904526) (xy 114.784781 -230.861512)
			(xy 114.764833 -230.814692) (xy 114.752654 -230.765278) (xy 114.748559 -230.71455) (xy 114.440462 -230.71455)
			(xy 114.43995 -230.739996) (xy 114.431786 -230.79023) (xy 114.41567 -230.838504) (xy 114.392019 -230.883567)
			(xy 114.361446 -230.924253) (xy 114.324742 -230.959508) (xy 114.282858 -230.988418) (xy 114.236879 -231.010235)
			(xy 114.187995 -231.024395) (xy 114.137474 -231.030529) (xy 114.086622 -231.02848) (xy 114.036758 -231.0183)
			(xy 113.989172 -231.000253) (xy 113.945098 -230.974807) (xy 113.905676 -230.94262) (xy 113.871928 -230.904526)
			(xy 113.844727 -230.861512) (xy 113.824779 -230.814692) (xy 113.8126 -230.765278) (xy 113.808505 -230.71455)
			(xy 113.502694 -230.71455) (xy 113.502204 -230.739539) (xy 113.494385 -230.788902) (xy 113.478941 -230.836434)
			(xy 113.456251 -230.880966) (xy 113.426875 -230.921399) (xy 113.391535 -230.956739) (xy 113.351102 -230.986115)
			(xy 113.30657 -231.008805) (xy 113.259038 -231.024249) (xy 113.209675 -231.032068) (xy 113.159697 -231.032068)
			(xy 113.110334 -231.024249) (xy 113.062802 -231.008805) (xy 113.01827 -230.986115) (xy 112.977837 -230.956739)
			(xy 112.942497 -230.921399) (xy 112.913121 -230.880966) (xy 112.890431 -230.836434) (xy 112.874987 -230.788902)
			(xy 112.867168 -230.739539) (xy 110.688646 -230.739539) (xy 110.680827 -230.788902) (xy 110.665383 -230.836434)
			(xy 110.642693 -230.880966) (xy 110.613317 -230.921399) (xy 110.577977 -230.956739) (xy 110.537544 -230.986115)
			(xy 110.493012 -231.008805) (xy 110.44548 -231.024249) (xy 110.396117 -231.032068) (xy 110.346139 -231.032068)
			(xy 110.296776 -231.024249) (xy 110.249244 -231.008805) (xy 110.204712 -230.986115) (xy 110.164279 -230.956739)
			(xy 110.128939 -230.921399) (xy 110.099563 -230.880966) (xy 110.076873 -230.836434) (xy 110.061429 -230.788902)
			(xy 110.05361 -230.739539) (xy 109.746293 -230.739539) (xy 109.746284 -230.739996) (xy 109.73812 -230.79023)
			(xy 109.722004 -230.838504) (xy 109.698353 -230.883567) (xy 109.66778 -230.924253) (xy 109.631076 -230.959508)
			(xy 109.589192 -230.988418) (xy 109.543213 -231.010235) (xy 109.494329 -231.024395) (xy 109.443808 -231.030529)
			(xy 109.392956 -231.02848) (xy 109.343092 -231.0183) (xy 109.295506 -231.000253) (xy 109.251432 -230.974807)
			(xy 109.21201 -230.94262) (xy 109.178262 -230.904526) (xy 109.151061 -230.861512) (xy 109.131113 -230.814692)
			(xy 109.118934 -230.765278) (xy 109.114839 -230.71455) (xy 108.806742 -230.71455) (xy 108.80623 -230.739996)
			(xy 108.798066 -230.79023) (xy 108.78195 -230.838504) (xy 108.758299 -230.883567) (xy 108.727726 -230.924253)
			(xy 108.691022 -230.959508) (xy 108.649138 -230.988418) (xy 108.603159 -231.010235) (xy 108.554275 -231.024395)
			(xy 108.503754 -231.030529) (xy 108.452902 -231.02848) (xy 108.403038 -231.0183) (xy 108.355452 -231.000253)
			(xy 108.311378 -230.974807) (xy 108.271956 -230.94262) (xy 108.238208 -230.904526) (xy 108.211007 -230.861512)
			(xy 108.191059 -230.814692) (xy 108.17888 -230.765278) (xy 108.174785 -230.71455) (xy 107.868969 -230.71455)
			(xy 107.868484 -230.739285) (xy 107.860665 -230.788648) (xy 107.845221 -230.83618) (xy 107.822531 -230.880712)
			(xy 107.793155 -230.921145) (xy 107.757815 -230.956485) (xy 107.717382 -230.985861) (xy 107.67285 -231.008551)
			(xy 107.625318 -231.023995) (xy 107.575955 -231.031814) (xy 107.525977 -231.031814) (xy 107.476614 -231.023995)
			(xy 107.429082 -231.008551) (xy 107.38455 -230.985861) (xy 107.344117 -230.956485) (xy 107.308777 -230.921145)
			(xy 107.279401 -230.880712) (xy 107.256711 -230.83618) (xy 107.241267 -230.788648) (xy 107.233448 -230.739285)
			(xy 105.048581 -230.739285) (xy 105.048576 -230.739539) (xy 105.040757 -230.788902) (xy 105.025313 -230.836434)
			(xy 105.002623 -230.880966) (xy 104.973247 -230.921399) (xy 104.937907 -230.956739) (xy 104.897474 -230.986115)
			(xy 104.852942 -231.008805) (xy 104.80541 -231.024249) (xy 104.756047 -231.032068) (xy 104.706069 -231.032068)
			(xy 104.656706 -231.024249) (xy 104.609174 -231.008805) (xy 104.564642 -230.986115) (xy 104.524209 -230.956739)
			(xy 104.488869 -230.921399) (xy 104.459493 -230.880966) (xy 104.436803 -230.836434) (xy 104.421359 -230.788902)
			(xy 104.41354 -230.739539) (xy 102.228628 -230.739539) (xy 102.220849 -230.788648) (xy 102.205405 -230.83618)
			(xy 102.182715 -230.880712) (xy 102.153339 -230.921145) (xy 102.117999 -230.956485) (xy 102.077566 -230.985861)
			(xy 102.033034 -231.008551) (xy 101.985502 -231.023995) (xy 101.936139 -231.031814) (xy 101.886161 -231.031814)
			(xy 101.836798 -231.023995) (xy 101.789266 -231.008551) (xy 101.744734 -230.985861) (xy 101.704301 -230.956485)
			(xy 101.668961 -230.921145) (xy 101.639585 -230.880712) (xy 101.616895 -230.83618) (xy 101.601451 -230.788648)
			(xy 101.593632 -230.739285) (xy 99.408511 -230.739285) (xy 99.408506 -230.739539) (xy 99.400687 -230.788902)
			(xy 99.385243 -230.836434) (xy 99.362553 -230.880966) (xy 99.333177 -230.921399) (xy 99.297837 -230.956739)
			(xy 99.257404 -230.986115) (xy 99.212872 -231.008805) (xy 99.16534 -231.024249) (xy 99.115977 -231.032068)
			(xy 99.065999 -231.032068) (xy 99.016636 -231.024249) (xy 98.969104 -231.008805) (xy 98.924572 -230.986115)
			(xy 98.884139 -230.956739) (xy 98.848799 -230.921399) (xy 98.819423 -230.880966) (xy 98.796733 -230.836434)
			(xy 98.781289 -230.788902) (xy 98.77347 -230.739539) (xy 97.057464 -230.739539) (xy 97.057464 -231.48671)
			(xy 97.057718 -231.491282) (xy 97.058988 -231.521762) (xy 97.058988 -231.524302) (xy 97.364799 -231.524302)
			(xy 97.368894 -231.473574) (xy 97.381073 -231.42416) (xy 97.401021 -231.37734) (xy 97.428222 -231.334326)
			(xy 97.46197 -231.296232) (xy 97.501392 -231.264045) (xy 97.545466 -231.238599) (xy 97.593052 -231.220552)
			(xy 97.642916 -231.210372) (xy 97.693768 -231.208323) (xy 97.744289 -231.214457) (xy 97.793173 -231.228617)
			(xy 97.839152 -231.250434) (xy 97.881036 -231.279344) (xy 97.91774 -231.314599) (xy 97.948313 -231.355285)
			(xy 97.971964 -231.400348) (xy 97.98808 -231.448622) (xy 97.996244 -231.498856) (xy 97.996756 -231.524302)
			(xy 98.304853 -231.524302) (xy 98.308948 -231.473574) (xy 98.321127 -231.42416) (xy 98.341075 -231.37734)
			(xy 98.368276 -231.334326) (xy 98.402024 -231.296232) (xy 98.441446 -231.264045) (xy 98.48552 -231.238599)
			(xy 98.533106 -231.220552) (xy 98.58297 -231.210372) (xy 98.633822 -231.208323) (xy 98.684343 -231.214457)
			(xy 98.733227 -231.228617) (xy 98.779206 -231.250434) (xy 98.82109 -231.279344) (xy 98.857794 -231.314599)
			(xy 98.888367 -231.355285) (xy 98.912018 -231.400348) (xy 98.928134 -231.448622) (xy 98.936298 -231.498856)
			(xy 98.93681 -231.524302) (xy 98.936307 -231.549291) (xy 99.243624 -231.549291) (xy 99.243624 -231.499313)
			(xy 99.251443 -231.44995) (xy 99.266887 -231.402418) (xy 99.289577 -231.357886) (xy 99.318953 -231.317453)
			(xy 99.354293 -231.282113) (xy 99.394726 -231.252737) (xy 99.439258 -231.230047) (xy 99.48679 -231.214603)
			(xy 99.536153 -231.206784) (xy 99.586131 -231.206784) (xy 99.635494 -231.214603) (xy 99.683026 -231.230047)
			(xy 99.727558 -231.252737) (xy 99.767991 -231.282113) (xy 99.803331 -231.317453) (xy 99.832707 -231.357886)
			(xy 99.855397 -231.402418) (xy 99.870841 -231.44995) (xy 99.87866 -231.499313) (xy 99.87915 -231.524302)
			(xy 100.184707 -231.524302) (xy 100.188802 -231.473574) (xy 100.200981 -231.42416) (xy 100.220929 -231.37734)
			(xy 100.24813 -231.334326) (xy 100.281878 -231.296232) (xy 100.3213 -231.264045) (xy 100.365374 -231.238599)
			(xy 100.41296 -231.220552) (xy 100.462824 -231.210372) (xy 100.513676 -231.208323) (xy 100.564197 -231.214457)
			(xy 100.613081 -231.228617) (xy 100.65906 -231.250434) (xy 100.700944 -231.279344) (xy 100.737648 -231.314599)
			(xy 100.768221 -231.355285) (xy 100.791872 -231.400348) (xy 100.807988 -231.448622) (xy 100.816152 -231.498856)
			(xy 100.816664 -231.524302) (xy 101.124761 -231.524302) (xy 101.128856 -231.473574) (xy 101.141035 -231.42416)
			(xy 101.160983 -231.37734) (xy 101.188184 -231.334326) (xy 101.221932 -231.296232) (xy 101.261354 -231.264045)
			(xy 101.305428 -231.238599) (xy 101.353014 -231.220552) (xy 101.402878 -231.210372) (xy 101.45373 -231.208323)
			(xy 101.504251 -231.214457) (xy 101.553135 -231.228617) (xy 101.599114 -231.250434) (xy 101.640998 -231.279344)
			(xy 101.677702 -231.314599) (xy 101.708275 -231.355285) (xy 101.731926 -231.400348) (xy 101.748042 -231.448622)
			(xy 101.756206 -231.498856) (xy 101.756718 -231.524302) (xy 101.756215 -231.549291) (xy 102.063532 -231.549291)
			(xy 102.063532 -231.499313) (xy 102.071351 -231.44995) (xy 102.086795 -231.402418) (xy 102.109485 -231.357886)
			(xy 102.138861 -231.317453) (xy 102.174201 -231.282113) (xy 102.214634 -231.252737) (xy 102.259166 -231.230047)
			(xy 102.306698 -231.214603) (xy 102.356061 -231.206784) (xy 102.406039 -231.206784) (xy 102.455402 -231.214603)
			(xy 102.502934 -231.230047) (xy 102.547466 -231.252737) (xy 102.587899 -231.282113) (xy 102.623239 -231.317453)
			(xy 102.652615 -231.357886) (xy 102.675305 -231.402418) (xy 102.690749 -231.44995) (xy 102.698568 -231.499313)
			(xy 102.699058 -231.524302) (xy 103.004869 -231.524302) (xy 103.008964 -231.473574) (xy 103.021143 -231.42416)
			(xy 103.041091 -231.37734) (xy 103.068292 -231.334326) (xy 103.10204 -231.296232) (xy 103.141462 -231.264045)
			(xy 103.185536 -231.238599) (xy 103.233122 -231.220552) (xy 103.282986 -231.210372) (xy 103.333838 -231.208323)
			(xy 103.384359 -231.214457) (xy 103.433243 -231.228617) (xy 103.479222 -231.250434) (xy 103.521106 -231.279344)
			(xy 103.55781 -231.314599) (xy 103.588383 -231.355285) (xy 103.612034 -231.400348) (xy 103.62815 -231.448622)
			(xy 103.636314 -231.498856) (xy 103.636826 -231.524302) (xy 103.944923 -231.524302) (xy 103.949018 -231.473574)
			(xy 103.961197 -231.42416) (xy 103.981145 -231.37734) (xy 104.008346 -231.334326) (xy 104.042094 -231.296232)
			(xy 104.081516 -231.264045) (xy 104.12559 -231.238599) (xy 104.173176 -231.220552) (xy 104.22304 -231.210372)
			(xy 104.273892 -231.208323) (xy 104.324413 -231.214457) (xy 104.373297 -231.228617) (xy 104.419276 -231.250434)
			(xy 104.46116 -231.279344) (xy 104.497864 -231.314599) (xy 104.528437 -231.355285) (xy 104.552088 -231.400348)
			(xy 104.568204 -231.448622) (xy 104.576368 -231.498856) (xy 104.57688 -231.524302) (xy 104.576377 -231.549291)
			(xy 104.88344 -231.549291) (xy 104.88344 -231.499313) (xy 104.891259 -231.44995) (xy 104.906703 -231.402418)
			(xy 104.929393 -231.357886) (xy 104.958769 -231.317453) (xy 104.994109 -231.282113) (xy 105.034542 -231.252737)
			(xy 105.079074 -231.230047) (xy 105.126606 -231.214603) (xy 105.175969 -231.206784) (xy 105.225947 -231.206784)
			(xy 105.27531 -231.214603) (xy 105.322842 -231.230047) (xy 105.367374 -231.252737) (xy 105.407807 -231.282113)
			(xy 105.443147 -231.317453) (xy 105.472523 -231.357886) (xy 105.495213 -231.402418) (xy 105.510657 -231.44995)
			(xy 105.518476 -231.499313) (xy 105.518966 -231.524302) (xy 105.824777 -231.524302) (xy 105.828872 -231.473574)
			(xy 105.841051 -231.42416) (xy 105.860999 -231.37734) (xy 105.8882 -231.334326) (xy 105.921948 -231.296232)
			(xy 105.96137 -231.264045) (xy 106.005444 -231.238599) (xy 106.05303 -231.220552) (xy 106.102894 -231.210372)
			(xy 106.153746 -231.208323) (xy 106.204267 -231.214457) (xy 106.253151 -231.228617) (xy 106.29913 -231.250434)
			(xy 106.341014 -231.279344) (xy 106.377718 -231.314599) (xy 106.408291 -231.355285) (xy 106.431942 -231.400348)
			(xy 106.448058 -231.448622) (xy 106.456222 -231.498856) (xy 106.456734 -231.524302) (xy 106.764831 -231.524302)
			(xy 106.768926 -231.473574) (xy 106.781105 -231.42416) (xy 106.801053 -231.37734) (xy 106.828254 -231.334326)
			(xy 106.862002 -231.296232) (xy 106.901424 -231.264045) (xy 106.945498 -231.238599) (xy 106.993084 -231.220552)
			(xy 107.042948 -231.210372) (xy 107.0938 -231.208323) (xy 107.144321 -231.214457) (xy 107.193205 -231.228617)
			(xy 107.239184 -231.250434) (xy 107.281068 -231.279344) (xy 107.317772 -231.314599) (xy 107.348345 -231.355285)
			(xy 107.371996 -231.400348) (xy 107.388112 -231.448622) (xy 107.396276 -231.498856) (xy 107.396788 -231.524302)
			(xy 107.396285 -231.549291) (xy 107.703602 -231.549291) (xy 107.703602 -231.499313) (xy 107.711421 -231.44995)
			(xy 107.726865 -231.402418) (xy 107.749555 -231.357886) (xy 107.778931 -231.317453) (xy 107.814271 -231.282113)
			(xy 107.854704 -231.252737) (xy 107.899236 -231.230047) (xy 107.946768 -231.214603) (xy 107.996131 -231.206784)
			(xy 108.046109 -231.206784) (xy 108.095472 -231.214603) (xy 108.143004 -231.230047) (xy 108.187536 -231.252737)
			(xy 108.227969 -231.282113) (xy 108.263309 -231.317453) (xy 108.292685 -231.357886) (xy 108.315375 -231.402418)
			(xy 108.330819 -231.44995) (xy 108.338638 -231.499313) (xy 108.339128 -231.524302) (xy 108.338638 -231.549291)
			(xy 115.217176 -231.549291) (xy 115.217176 -231.499313) (xy 115.224995 -231.44995) (xy 115.240439 -231.402418)
			(xy 115.263129 -231.357886) (xy 115.292505 -231.317453) (xy 115.327845 -231.282113) (xy 115.368278 -231.252737)
			(xy 115.41281 -231.230047) (xy 115.460342 -231.214603) (xy 115.509705 -231.206784) (xy 115.559683 -231.206784)
			(xy 115.609046 -231.214603) (xy 115.656578 -231.230047) (xy 115.70111 -231.252737) (xy 115.741543 -231.282113)
			(xy 115.776883 -231.317453) (xy 115.806259 -231.357886) (xy 115.828949 -231.402418) (xy 115.844393 -231.44995)
			(xy 115.852212 -231.499313) (xy 115.852702 -231.524302) (xy 116.158513 -231.524302) (xy 116.162608 -231.473574)
			(xy 116.174787 -231.42416) (xy 116.194735 -231.37734) (xy 116.221936 -231.334326) (xy 116.255684 -231.296232)
			(xy 116.295106 -231.264045) (xy 116.33918 -231.238599) (xy 116.386766 -231.220552) (xy 116.43663 -231.210372)
			(xy 116.487482 -231.208323) (xy 116.538003 -231.214457) (xy 116.586887 -231.228617) (xy 116.632866 -231.250434)
			(xy 116.67475 -231.279344) (xy 116.711454 -231.314599) (xy 116.742027 -231.355285) (xy 116.765678 -231.400348)
			(xy 116.781794 -231.448622) (xy 116.789958 -231.498856) (xy 116.79047 -231.524302) (xy 117.098567 -231.524302)
			(xy 117.102662 -231.473574) (xy 117.114841 -231.42416) (xy 117.134789 -231.37734) (xy 117.16199 -231.334326)
			(xy 117.195738 -231.296232) (xy 117.23516 -231.264045) (xy 117.279234 -231.238599) (xy 117.32682 -231.220552)
			(xy 117.376684 -231.210372) (xy 117.427536 -231.208323) (xy 117.478057 -231.214457) (xy 117.526941 -231.228617)
			(xy 117.57292 -231.250434) (xy 117.614804 -231.279344) (xy 117.651508 -231.314599) (xy 117.682081 -231.355285)
			(xy 117.705732 -231.400348) (xy 117.721848 -231.448622) (xy 117.730012 -231.498856) (xy 117.730524 -231.524302)
			(xy 117.730021 -231.549291) (xy 118.037338 -231.549291) (xy 118.037338 -231.499313) (xy 118.045157 -231.44995)
			(xy 118.060601 -231.402418) (xy 118.083291 -231.357886) (xy 118.112667 -231.317453) (xy 118.148007 -231.282113)
			(xy 118.18844 -231.252737) (xy 118.232972 -231.230047) (xy 118.280504 -231.214603) (xy 118.329867 -231.206784)
			(xy 118.379845 -231.206784) (xy 118.429208 -231.214603) (xy 118.47674 -231.230047) (xy 118.521272 -231.252737)
			(xy 118.561705 -231.282113) (xy 118.597045 -231.317453) (xy 118.626421 -231.357886) (xy 118.649111 -231.402418)
			(xy 118.664555 -231.44995) (xy 118.672374 -231.499313) (xy 118.672864 -231.524302) (xy 118.978421 -231.524302)
			(xy 118.982516 -231.473574) (xy 118.994695 -231.42416) (xy 119.014643 -231.37734) (xy 119.041844 -231.334326)
			(xy 119.075592 -231.296232) (xy 119.115014 -231.264045) (xy 119.159088 -231.238599) (xy 119.206674 -231.220552)
			(xy 119.256538 -231.210372) (xy 119.30739 -231.208323) (xy 119.357911 -231.214457) (xy 119.406795 -231.228617)
			(xy 119.452774 -231.250434) (xy 119.494658 -231.279344) (xy 119.531362 -231.314599) (xy 119.561935 -231.355285)
			(xy 119.585586 -231.400348) (xy 119.601702 -231.448622) (xy 119.609866 -231.498856) (xy 119.610378 -231.524302)
			(xy 119.918475 -231.524302) (xy 119.92257 -231.473574) (xy 119.934749 -231.42416) (xy 119.954697 -231.37734)
			(xy 119.981898 -231.334326) (xy 120.015646 -231.296232) (xy 120.055068 -231.264045) (xy 120.099142 -231.238599)
			(xy 120.146728 -231.220552) (xy 120.196592 -231.210372) (xy 120.247444 -231.208323) (xy 120.297965 -231.214457)
			(xy 120.346849 -231.228617) (xy 120.392828 -231.250434) (xy 120.434712 -231.279344) (xy 120.471416 -231.314599)
			(xy 120.501989 -231.355285) (xy 120.52564 -231.400348) (xy 120.541756 -231.448622) (xy 120.54992 -231.498856)
			(xy 120.550432 -231.524302) (xy 120.549929 -231.549291) (xy 120.857246 -231.549291) (xy 120.857246 -231.499313)
			(xy 120.865065 -231.44995) (xy 120.880509 -231.402418) (xy 120.903199 -231.357886) (xy 120.932575 -231.317453)
			(xy 120.967915 -231.282113) (xy 121.008348 -231.252737) (xy 121.05288 -231.230047) (xy 121.100412 -231.214603)
			(xy 121.149775 -231.206784) (xy 121.199753 -231.206784) (xy 121.249116 -231.214603) (xy 121.296648 -231.230047)
			(xy 121.34118 -231.252737) (xy 121.381613 -231.282113) (xy 121.416953 -231.317453) (xy 121.446329 -231.357886)
			(xy 121.469019 -231.402418) (xy 121.484463 -231.44995) (xy 121.492282 -231.499313) (xy 121.492772 -231.524302)
			(xy 121.798583 -231.524302) (xy 121.802678 -231.473574) (xy 121.814857 -231.42416) (xy 121.834805 -231.37734)
			(xy 121.862006 -231.334326) (xy 121.895754 -231.296232) (xy 121.935176 -231.264045) (xy 121.97925 -231.238599)
			(xy 122.026836 -231.220552) (xy 122.0767 -231.210372) (xy 122.127552 -231.208323) (xy 122.178073 -231.214457)
			(xy 122.226957 -231.228617) (xy 122.272936 -231.250434) (xy 122.31482 -231.279344) (xy 122.351524 -231.314599)
			(xy 122.382097 -231.355285) (xy 122.405748 -231.400348) (xy 122.421864 -231.448622) (xy 122.430028 -231.498856)
			(xy 122.43054 -231.524302) (xy 122.738383 -231.524302) (xy 122.742478 -231.473574) (xy 122.754657 -231.42416)
			(xy 122.774605 -231.37734) (xy 122.801806 -231.334326) (xy 122.835554 -231.296232) (xy 122.874976 -231.264045)
			(xy 122.91905 -231.238599) (xy 122.966636 -231.220552) (xy 123.0165 -231.210372) (xy 123.067352 -231.208323)
			(xy 123.117873 -231.214457) (xy 123.166757 -231.228617) (xy 123.212736 -231.250434) (xy 123.25462 -231.279344)
			(xy 123.291324 -231.314599) (xy 123.321897 -231.355285) (xy 123.345548 -231.400348) (xy 123.361664 -231.448622)
			(xy 123.369828 -231.498856) (xy 123.37034 -231.524302) (xy 123.369837 -231.549291) (xy 123.677154 -231.549291)
			(xy 123.677154 -231.499313) (xy 123.684973 -231.44995) (xy 123.700417 -231.402418) (xy 123.723107 -231.357886)
			(xy 123.752483 -231.317453) (xy 123.787823 -231.282113) (xy 123.828256 -231.252737) (xy 123.872788 -231.230047)
			(xy 123.92032 -231.214603) (xy 123.969683 -231.206784) (xy 124.019661 -231.206784) (xy 124.069024 -231.214603)
			(xy 124.116556 -231.230047) (xy 124.161088 -231.252737) (xy 124.201521 -231.282113) (xy 124.236861 -231.317453)
			(xy 124.266237 -231.357886) (xy 124.288927 -231.402418) (xy 124.304371 -231.44995) (xy 124.31219 -231.499313)
			(xy 124.31268 -231.524302) (xy 124.618491 -231.524302) (xy 124.622586 -231.473574) (xy 124.634765 -231.42416)
			(xy 124.654713 -231.37734) (xy 124.681914 -231.334326) (xy 124.715662 -231.296232) (xy 124.755084 -231.264045)
			(xy 124.799158 -231.238599) (xy 124.846744 -231.220552) (xy 124.896608 -231.210372) (xy 124.94746 -231.208323)
			(xy 124.997981 -231.214457) (xy 125.046865 -231.228617) (xy 125.092844 -231.250434) (xy 125.134728 -231.279344)
			(xy 125.171432 -231.314599) (xy 125.202005 -231.355285) (xy 125.225656 -231.400348) (xy 125.241772 -231.448622)
			(xy 125.249936 -231.498856) (xy 125.250448 -231.524302) (xy 125.558545 -231.524302) (xy 125.56264 -231.473574)
			(xy 125.574819 -231.42416) (xy 125.594767 -231.37734) (xy 125.621968 -231.334326) (xy 125.655716 -231.296232)
			(xy 125.695138 -231.264045) (xy 125.739212 -231.238599) (xy 125.786798 -231.220552) (xy 125.836662 -231.210372)
			(xy 125.887514 -231.208323) (xy 125.938035 -231.214457) (xy 125.986919 -231.228617) (xy 126.032898 -231.250434)
			(xy 126.074782 -231.279344) (xy 126.111486 -231.314599) (xy 126.142059 -231.355285) (xy 126.16571 -231.400348)
			(xy 126.181826 -231.448622) (xy 126.18999 -231.498856) (xy 126.190502 -231.524302) (xy 126.18999 -231.549748)
			(xy 126.181826 -231.599982) (xy 126.16571 -231.648256) (xy 126.142059 -231.693319) (xy 126.111486 -231.734005)
			(xy 126.074782 -231.76926) (xy 126.032898 -231.79817) (xy 125.986919 -231.819987) (xy 125.938035 -231.834147)
			(xy 125.887514 -231.840281) (xy 125.836662 -231.838232) (xy 125.786798 -231.828052) (xy 125.739212 -231.810005)
			(xy 125.695138 -231.784559) (xy 125.655716 -231.752372) (xy 125.621968 -231.714278) (xy 125.594767 -231.671264)
			(xy 125.574819 -231.624444) (xy 125.56264 -231.57503) (xy 125.558545 -231.524302) (xy 125.250448 -231.524302)
			(xy 125.249936 -231.549748) (xy 125.241772 -231.599982) (xy 125.225656 -231.648256) (xy 125.202005 -231.693319)
			(xy 125.171432 -231.734005) (xy 125.134728 -231.76926) (xy 125.092844 -231.79817) (xy 125.046865 -231.819987)
			(xy 124.997981 -231.834147) (xy 124.94746 -231.840281) (xy 124.896608 -231.838232) (xy 124.846744 -231.828052)
			(xy 124.799158 -231.810005) (xy 124.755084 -231.784559) (xy 124.715662 -231.752372) (xy 124.681914 -231.714278)
			(xy 124.654713 -231.671264) (xy 124.634765 -231.624444) (xy 124.622586 -231.57503) (xy 124.618491 -231.524302)
			(xy 124.31268 -231.524302) (xy 124.31219 -231.549291) (xy 124.304371 -231.598654) (xy 124.288927 -231.646186)
			(xy 124.266237 -231.690718) (xy 124.236861 -231.731151) (xy 124.201521 -231.766491) (xy 124.161088 -231.795867)
			(xy 124.116556 -231.818557) (xy 124.069024 -231.834001) (xy 124.019661 -231.84182) (xy 123.969683 -231.84182)
			(xy 123.92032 -231.834001) (xy 123.872788 -231.818557) (xy 123.828256 -231.795867) (xy 123.787823 -231.766491)
			(xy 123.752483 -231.731151) (xy 123.723107 -231.690718) (xy 123.700417 -231.646186) (xy 123.684973 -231.598654)
			(xy 123.677154 -231.549291) (xy 123.369837 -231.549291) (xy 123.369828 -231.549748) (xy 123.361664 -231.599982)
			(xy 123.345548 -231.648256) (xy 123.321897 -231.693319) (xy 123.291324 -231.734005) (xy 123.25462 -231.76926)
			(xy 123.212736 -231.79817) (xy 123.166757 -231.819987) (xy 123.117873 -231.834147) (xy 123.067352 -231.840281)
			(xy 123.0165 -231.838232) (xy 122.966636 -231.828052) (xy 122.91905 -231.810005) (xy 122.874976 -231.784559)
			(xy 122.835554 -231.752372) (xy 122.801806 -231.714278) (xy 122.774605 -231.671264) (xy 122.754657 -231.624444)
			(xy 122.742478 -231.57503) (xy 122.738383 -231.524302) (xy 122.43054 -231.524302) (xy 122.430028 -231.549748)
			(xy 122.421864 -231.599982) (xy 122.405748 -231.648256) (xy 122.382097 -231.693319) (xy 122.351524 -231.734005)
			(xy 122.31482 -231.76926) (xy 122.272936 -231.79817) (xy 122.226957 -231.819987) (xy 122.178073 -231.834147)
			(xy 122.127552 -231.840281) (xy 122.0767 -231.838232) (xy 122.026836 -231.828052) (xy 121.97925 -231.810005)
			(xy 121.935176 -231.784559) (xy 121.895754 -231.752372) (xy 121.862006 -231.714278) (xy 121.834805 -231.671264)
			(xy 121.814857 -231.624444) (xy 121.802678 -231.57503) (xy 121.798583 -231.524302) (xy 121.492772 -231.524302)
			(xy 121.492282 -231.549291) (xy 121.484463 -231.598654) (xy 121.469019 -231.646186) (xy 121.446329 -231.690718)
			(xy 121.416953 -231.731151) (xy 121.381613 -231.766491) (xy 121.34118 -231.795867) (xy 121.296648 -231.818557)
			(xy 121.249116 -231.834001) (xy 121.199753 -231.84182) (xy 121.149775 -231.84182) (xy 121.100412 -231.834001)
			(xy 121.05288 -231.818557) (xy 121.008348 -231.795867) (xy 120.967915 -231.766491) (xy 120.932575 -231.731151)
			(xy 120.903199 -231.690718) (xy 120.880509 -231.646186) (xy 120.865065 -231.598654) (xy 120.857246 -231.549291)
			(xy 120.549929 -231.549291) (xy 120.54992 -231.549748) (xy 120.541756 -231.599982) (xy 120.52564 -231.648256)
			(xy 120.501989 -231.693319) (xy 120.471416 -231.734005) (xy 120.434712 -231.76926) (xy 120.392828 -231.79817)
			(xy 120.346849 -231.819987) (xy 120.297965 -231.834147) (xy 120.247444 -231.840281) (xy 120.196592 -231.838232)
			(xy 120.146728 -231.828052) (xy 120.099142 -231.810005) (xy 120.055068 -231.784559) (xy 120.015646 -231.752372)
			(xy 119.981898 -231.714278) (xy 119.954697 -231.671264) (xy 119.934749 -231.624444) (xy 119.92257 -231.57503)
			(xy 119.918475 -231.524302) (xy 119.610378 -231.524302) (xy 119.609866 -231.549748) (xy 119.601702 -231.599982)
			(xy 119.585586 -231.648256) (xy 119.561935 -231.693319) (xy 119.531362 -231.734005) (xy 119.494658 -231.76926)
			(xy 119.452774 -231.79817) (xy 119.406795 -231.819987) (xy 119.357911 -231.834147) (xy 119.30739 -231.840281)
			(xy 119.256538 -231.838232) (xy 119.206674 -231.828052) (xy 119.159088 -231.810005) (xy 119.115014 -231.784559)
			(xy 119.075592 -231.752372) (xy 119.041844 -231.714278) (xy 119.014643 -231.671264) (xy 118.994695 -231.624444)
			(xy 118.982516 -231.57503) (xy 118.978421 -231.524302) (xy 118.672864 -231.524302) (xy 118.672374 -231.549291)
			(xy 118.664555 -231.598654) (xy 118.649111 -231.646186) (xy 118.626421 -231.690718) (xy 118.597045 -231.731151)
			(xy 118.561705 -231.766491) (xy 118.521272 -231.795867) (xy 118.47674 -231.818557) (xy 118.429208 -231.834001)
			(xy 118.379845 -231.84182) (xy 118.329867 -231.84182) (xy 118.280504 -231.834001) (xy 118.232972 -231.818557)
			(xy 118.18844 -231.795867) (xy 118.148007 -231.766491) (xy 118.112667 -231.731151) (xy 118.083291 -231.690718)
			(xy 118.060601 -231.646186) (xy 118.045157 -231.598654) (xy 118.037338 -231.549291) (xy 117.730021 -231.549291)
			(xy 117.730012 -231.549748) (xy 117.721848 -231.599982) (xy 117.705732 -231.648256) (xy 117.682081 -231.693319)
			(xy 117.651508 -231.734005) (xy 117.614804 -231.76926) (xy 117.57292 -231.79817) (xy 117.526941 -231.819987)
			(xy 117.478057 -231.834147) (xy 117.427536 -231.840281) (xy 117.376684 -231.838232) (xy 117.32682 -231.828052)
			(xy 117.279234 -231.810005) (xy 117.23516 -231.784559) (xy 117.195738 -231.752372) (xy 117.16199 -231.714278)
			(xy 117.134789 -231.671264) (xy 117.114841 -231.624444) (xy 117.102662 -231.57503) (xy 117.098567 -231.524302)
			(xy 116.79047 -231.524302) (xy 116.789958 -231.549748) (xy 116.781794 -231.599982) (xy 116.765678 -231.648256)
			(xy 116.742027 -231.693319) (xy 116.711454 -231.734005) (xy 116.67475 -231.76926) (xy 116.632866 -231.79817)
			(xy 116.586887 -231.819987) (xy 116.538003 -231.834147) (xy 116.487482 -231.840281) (xy 116.43663 -231.838232)
			(xy 116.386766 -231.828052) (xy 116.33918 -231.810005) (xy 116.295106 -231.784559) (xy 116.255684 -231.752372)
			(xy 116.221936 -231.714278) (xy 116.194735 -231.671264) (xy 116.174787 -231.624444) (xy 116.162608 -231.57503)
			(xy 116.158513 -231.524302) (xy 115.852702 -231.524302) (xy 115.852212 -231.549291) (xy 115.844393 -231.598654)
			(xy 115.828949 -231.646186) (xy 115.806259 -231.690718) (xy 115.776883 -231.731151) (xy 115.741543 -231.766491)
			(xy 115.70111 -231.795867) (xy 115.656578 -231.818557) (xy 115.609046 -231.834001) (xy 115.559683 -231.84182)
			(xy 115.509705 -231.84182) (xy 115.460342 -231.834001) (xy 115.41281 -231.818557) (xy 115.368278 -231.795867)
			(xy 115.327845 -231.766491) (xy 115.292505 -231.731151) (xy 115.263129 -231.690718) (xy 115.240439 -231.646186)
			(xy 115.224995 -231.598654) (xy 115.217176 -231.549291) (xy 108.338638 -231.549291) (xy 108.330819 -231.598654)
			(xy 108.315375 -231.646186) (xy 108.292685 -231.690718) (xy 108.263309 -231.731151) (xy 108.227969 -231.766491)
			(xy 108.187536 -231.795867) (xy 108.143004 -231.818557) (xy 108.095472 -231.834001) (xy 108.046109 -231.84182)
			(xy 107.996131 -231.84182) (xy 107.946768 -231.834001) (xy 107.899236 -231.818557) (xy 107.854704 -231.795867)
			(xy 107.814271 -231.766491) (xy 107.778931 -231.731151) (xy 107.749555 -231.690718) (xy 107.726865 -231.646186)
			(xy 107.711421 -231.598654) (xy 107.703602 -231.549291) (xy 107.396285 -231.549291) (xy 107.396276 -231.549748)
			(xy 107.388112 -231.599982) (xy 107.371996 -231.648256) (xy 107.348345 -231.693319) (xy 107.317772 -231.734005)
			(xy 107.281068 -231.76926) (xy 107.239184 -231.79817) (xy 107.193205 -231.819987) (xy 107.144321 -231.834147)
			(xy 107.0938 -231.840281) (xy 107.042948 -231.838232) (xy 106.993084 -231.828052) (xy 106.945498 -231.810005)
			(xy 106.901424 -231.784559) (xy 106.862002 -231.752372) (xy 106.828254 -231.714278) (xy 106.801053 -231.671264)
			(xy 106.781105 -231.624444) (xy 106.768926 -231.57503) (xy 106.764831 -231.524302) (xy 106.456734 -231.524302)
			(xy 106.456222 -231.549748) (xy 106.448058 -231.599982) (xy 106.431942 -231.648256) (xy 106.408291 -231.693319)
			(xy 106.377718 -231.734005) (xy 106.341014 -231.76926) (xy 106.29913 -231.79817) (xy 106.253151 -231.819987)
			(xy 106.204267 -231.834147) (xy 106.153746 -231.840281) (xy 106.102894 -231.838232) (xy 106.05303 -231.828052)
			(xy 106.005444 -231.810005) (xy 105.96137 -231.784559) (xy 105.921948 -231.752372) (xy 105.8882 -231.714278)
			(xy 105.860999 -231.671264) (xy 105.841051 -231.624444) (xy 105.828872 -231.57503) (xy 105.824777 -231.524302)
			(xy 105.518966 -231.524302) (xy 105.518476 -231.549291) (xy 105.510657 -231.598654) (xy 105.495213 -231.646186)
			(xy 105.472523 -231.690718) (xy 105.443147 -231.731151) (xy 105.407807 -231.766491) (xy 105.367374 -231.795867)
			(xy 105.322842 -231.818557) (xy 105.27531 -231.834001) (xy 105.225947 -231.84182) (xy 105.175969 -231.84182)
			(xy 105.126606 -231.834001) (xy 105.079074 -231.818557) (xy 105.034542 -231.795867) (xy 104.994109 -231.766491)
			(xy 104.958769 -231.731151) (xy 104.929393 -231.690718) (xy 104.906703 -231.646186) (xy 104.891259 -231.598654)
			(xy 104.88344 -231.549291) (xy 104.576377 -231.549291) (xy 104.576368 -231.549748) (xy 104.568204 -231.599982)
			(xy 104.552088 -231.648256) (xy 104.528437 -231.693319) (xy 104.497864 -231.734005) (xy 104.46116 -231.76926)
			(xy 104.419276 -231.79817) (xy 104.373297 -231.819987) (xy 104.324413 -231.834147) (xy 104.273892 -231.840281)
			(xy 104.22304 -231.838232) (xy 104.173176 -231.828052) (xy 104.12559 -231.810005) (xy 104.081516 -231.784559)
			(xy 104.042094 -231.752372) (xy 104.008346 -231.714278) (xy 103.981145 -231.671264) (xy 103.961197 -231.624444)
			(xy 103.949018 -231.57503) (xy 103.944923 -231.524302) (xy 103.636826 -231.524302) (xy 103.636314 -231.549748)
			(xy 103.62815 -231.599982) (xy 103.612034 -231.648256) (xy 103.588383 -231.693319) (xy 103.55781 -231.734005)
			(xy 103.521106 -231.76926) (xy 103.479222 -231.79817) (xy 103.433243 -231.819987) (xy 103.384359 -231.834147)
			(xy 103.333838 -231.840281) (xy 103.282986 -231.838232) (xy 103.233122 -231.828052) (xy 103.185536 -231.810005)
			(xy 103.141462 -231.784559) (xy 103.10204 -231.752372) (xy 103.068292 -231.714278) (xy 103.041091 -231.671264)
			(xy 103.021143 -231.624444) (xy 103.008964 -231.57503) (xy 103.004869 -231.524302) (xy 102.699058 -231.524302)
			(xy 102.698568 -231.549291) (xy 102.690749 -231.598654) (xy 102.675305 -231.646186) (xy 102.652615 -231.690718)
			(xy 102.623239 -231.731151) (xy 102.587899 -231.766491) (xy 102.547466 -231.795867) (xy 102.502934 -231.818557)
			(xy 102.455402 -231.834001) (xy 102.406039 -231.84182) (xy 102.356061 -231.84182) (xy 102.306698 -231.834001)
			(xy 102.259166 -231.818557) (xy 102.214634 -231.795867) (xy 102.174201 -231.766491) (xy 102.138861 -231.731151)
			(xy 102.109485 -231.690718) (xy 102.086795 -231.646186) (xy 102.071351 -231.598654) (xy 102.063532 -231.549291)
			(xy 101.756215 -231.549291) (xy 101.756206 -231.549748) (xy 101.748042 -231.599982) (xy 101.731926 -231.648256)
			(xy 101.708275 -231.693319) (xy 101.677702 -231.734005) (xy 101.640998 -231.76926) (xy 101.599114 -231.79817)
			(xy 101.553135 -231.819987) (xy 101.504251 -231.834147) (xy 101.45373 -231.840281) (xy 101.402878 -231.838232)
			(xy 101.353014 -231.828052) (xy 101.305428 -231.810005) (xy 101.261354 -231.784559) (xy 101.221932 -231.752372)
			(xy 101.188184 -231.714278) (xy 101.160983 -231.671264) (xy 101.141035 -231.624444) (xy 101.128856 -231.57503)
			(xy 101.124761 -231.524302) (xy 100.816664 -231.524302) (xy 100.816152 -231.549748) (xy 100.807988 -231.599982)
			(xy 100.791872 -231.648256) (xy 100.768221 -231.693319) (xy 100.737648 -231.734005) (xy 100.700944 -231.76926)
			(xy 100.65906 -231.79817) (xy 100.613081 -231.819987) (xy 100.564197 -231.834147) (xy 100.513676 -231.840281)
			(xy 100.462824 -231.838232) (xy 100.41296 -231.828052) (xy 100.365374 -231.810005) (xy 100.3213 -231.784559)
			(xy 100.281878 -231.752372) (xy 100.24813 -231.714278) (xy 100.220929 -231.671264) (xy 100.200981 -231.624444)
			(xy 100.188802 -231.57503) (xy 100.184707 -231.524302) (xy 99.87915 -231.524302) (xy 99.87866 -231.549291)
			(xy 99.870841 -231.598654) (xy 99.855397 -231.646186) (xy 99.832707 -231.690718) (xy 99.803331 -231.731151)
			(xy 99.767991 -231.766491) (xy 99.727558 -231.795867) (xy 99.683026 -231.818557) (xy 99.635494 -231.834001)
			(xy 99.586131 -231.84182) (xy 99.536153 -231.84182) (xy 99.48679 -231.834001) (xy 99.439258 -231.818557)
			(xy 99.394726 -231.795867) (xy 99.354293 -231.766491) (xy 99.318953 -231.731151) (xy 99.289577 -231.690718)
			(xy 99.266887 -231.646186) (xy 99.251443 -231.598654) (xy 99.243624 -231.549291) (xy 98.936307 -231.549291)
			(xy 98.936298 -231.549748) (xy 98.928134 -231.599982) (xy 98.912018 -231.648256) (xy 98.888367 -231.693319)
			(xy 98.857794 -231.734005) (xy 98.82109 -231.76926) (xy 98.779206 -231.79817) (xy 98.733227 -231.819987)
			(xy 98.684343 -231.834147) (xy 98.633822 -231.840281) (xy 98.58297 -231.838232) (xy 98.533106 -231.828052)
			(xy 98.48552 -231.810005) (xy 98.441446 -231.784559) (xy 98.402024 -231.752372) (xy 98.368276 -231.714278)
			(xy 98.341075 -231.671264) (xy 98.321127 -231.624444) (xy 98.308948 -231.57503) (xy 98.304853 -231.524302)
			(xy 97.996756 -231.524302) (xy 97.996244 -231.549748) (xy 97.98808 -231.599982) (xy 97.971964 -231.648256)
			(xy 97.948313 -231.693319) (xy 97.91774 -231.734005) (xy 97.881036 -231.76926) (xy 97.839152 -231.79817)
			(xy 97.793173 -231.819987) (xy 97.744289 -231.834147) (xy 97.693768 -231.840281) (xy 97.642916 -231.838232)
			(xy 97.593052 -231.828052) (xy 97.545466 -231.810005) (xy 97.501392 -231.784559) (xy 97.46197 -231.752372)
			(xy 97.428222 -231.714278) (xy 97.401021 -231.671264) (xy 97.381073 -231.624444) (xy 97.368894 -231.57503)
			(xy 97.364799 -231.524302) (xy 97.058988 -231.524302) (xy 97.058988 -231.527858) (xy 97.057718 -231.55783)
			(xy 97.057464 -231.559354) (xy 97.057464 -231.919018) (xy 97.057942 -231.929768) (xy 97.066754 -231.949377)
			(xy 97.074482 -231.956864) (xy 97.130362 -232.006394) (xy 97.13087 -232.006394) (xy 97.138236 -232.013252)
			(xy 97.159318 -232.02011) (xy 97.171002 -232.01884) (xy 97.17151 -232.01884) (xy 97.18049 -232.017754)
			(xy 97.198535 -232.016484) (xy 97.207578 -232.0163) (xy 97.211134 -232.0163) (xy 97.236121 -232.016793)
			(xy 97.28548 -232.024615) (xy 97.333007 -232.040063) (xy 97.377533 -232.062754) (xy 97.417961 -232.092132)
			(xy 97.453296 -232.127471) (xy 97.482668 -232.167903) (xy 97.505353 -232.212432) (xy 97.520794 -232.259961)
			(xy 97.52861 -232.309321) (xy 97.529142 -232.334308) (xy 97.528652 -232.359285) (xy 97.52865 -232.359297)
			(xy 97.833416 -232.359297) (xy 97.833416 -232.309319) (xy 97.841235 -232.259956) (xy 97.856679 -232.212424)
			(xy 97.879369 -232.167892) (xy 97.908745 -232.127459) (xy 97.944085 -232.092119) (xy 97.984518 -232.062743)
			(xy 98.02905 -232.040053) (xy 98.076582 -232.024609) (xy 98.125945 -232.01679) (xy 98.175923 -232.01679)
			(xy 98.225286 -232.024609) (xy 98.272818 -232.040053) (xy 98.31735 -232.062743) (xy 98.357783 -232.092119)
			(xy 98.393123 -232.127459) (xy 98.422499 -232.167892) (xy 98.445189 -232.212424) (xy 98.460633 -232.259956)
			(xy 98.468452 -232.309319) (xy 98.468942 -232.334308) (xy 98.468452 -232.359297) (xy 98.77347 -232.359297)
			(xy 98.77347 -232.309319) (xy 98.781289 -232.259956) (xy 98.796733 -232.212424) (xy 98.819423 -232.167892)
			(xy 98.848799 -232.127459) (xy 98.884139 -232.092119) (xy 98.924572 -232.062743) (xy 98.969104 -232.040053)
			(xy 99.016636 -232.024609) (xy 99.065999 -232.01679) (xy 99.115977 -232.01679) (xy 99.16534 -232.024609)
			(xy 99.212872 -232.040053) (xy 99.257404 -232.062743) (xy 99.297837 -232.092119) (xy 99.333177 -232.127459)
			(xy 99.362553 -232.167892) (xy 99.385243 -232.212424) (xy 99.400687 -232.259956) (xy 99.408506 -232.309319)
			(xy 99.408996 -232.334308) (xy 99.408506 -232.359297) (xy 99.713524 -232.359297) (xy 99.713524 -232.309319)
			(xy 99.721343 -232.259956) (xy 99.736787 -232.212424) (xy 99.759477 -232.167892) (xy 99.788853 -232.127459)
			(xy 99.824193 -232.092119) (xy 99.864626 -232.062743) (xy 99.909158 -232.040053) (xy 99.95669 -232.024609)
			(xy 100.006053 -232.01679) (xy 100.056031 -232.01679) (xy 100.105394 -232.024609) (xy 100.152926 -232.040053)
			(xy 100.197458 -232.062743) (xy 100.237891 -232.092119) (xy 100.273231 -232.127459) (xy 100.302607 -232.167892)
			(xy 100.325297 -232.212424) (xy 100.340741 -232.259956) (xy 100.34856 -232.309319) (xy 100.34905 -232.334308)
			(xy 100.34856 -232.359297) (xy 100.653578 -232.359297) (xy 100.653578 -232.309319) (xy 100.661397 -232.259956)
			(xy 100.676841 -232.212424) (xy 100.699531 -232.167892) (xy 100.728907 -232.127459) (xy 100.764247 -232.092119)
			(xy 100.80468 -232.062743) (xy 100.849212 -232.040053) (xy 100.896744 -232.024609) (xy 100.946107 -232.01679)
			(xy 100.996085 -232.01679) (xy 101.045448 -232.024609) (xy 101.09298 -232.040053) (xy 101.137512 -232.062743)
			(xy 101.177945 -232.092119) (xy 101.213285 -232.127459) (xy 101.242661 -232.167892) (xy 101.265351 -232.212424)
			(xy 101.280795 -232.259956) (xy 101.288614 -232.309319) (xy 101.289104 -232.334308) (xy 101.288614 -232.359297)
			(xy 101.593632 -232.359297) (xy 101.593632 -232.309319) (xy 101.601451 -232.259956) (xy 101.616895 -232.212424)
			(xy 101.639585 -232.167892) (xy 101.668961 -232.127459) (xy 101.704301 -232.092119) (xy 101.744734 -232.062743)
			(xy 101.789266 -232.040053) (xy 101.836798 -232.024609) (xy 101.886161 -232.01679) (xy 101.936139 -232.01679)
			(xy 101.985502 -232.024609) (xy 102.033034 -232.040053) (xy 102.077566 -232.062743) (xy 102.117999 -232.092119)
			(xy 102.153339 -232.127459) (xy 102.182715 -232.167892) (xy 102.205405 -232.212424) (xy 102.220849 -232.259956)
			(xy 102.228668 -232.309319) (xy 102.229158 -232.334308) (xy 102.228668 -232.359297) (xy 102.533432 -232.359297)
			(xy 102.533432 -232.309319) (xy 102.541251 -232.259956) (xy 102.556695 -232.212424) (xy 102.579385 -232.167892)
			(xy 102.608761 -232.127459) (xy 102.644101 -232.092119) (xy 102.684534 -232.062743) (xy 102.729066 -232.040053)
			(xy 102.776598 -232.024609) (xy 102.825961 -232.01679) (xy 102.875939 -232.01679) (xy 102.925302 -232.024609)
			(xy 102.972834 -232.040053) (xy 103.017366 -232.062743) (xy 103.057799 -232.092119) (xy 103.093139 -232.127459)
			(xy 103.122515 -232.167892) (xy 103.145205 -232.212424) (xy 103.160649 -232.259956) (xy 103.168468 -232.309319)
			(xy 103.168958 -232.334308) (xy 103.168468 -232.359297) (xy 103.473486 -232.359297) (xy 103.473486 -232.309319)
			(xy 103.481305 -232.259956) (xy 103.496749 -232.212424) (xy 103.519439 -232.167892) (xy 103.548815 -232.127459)
			(xy 103.584155 -232.092119) (xy 103.624588 -232.062743) (xy 103.66912 -232.040053) (xy 103.716652 -232.024609)
			(xy 103.766015 -232.01679) (xy 103.815993 -232.01679) (xy 103.865356 -232.024609) (xy 103.912888 -232.040053)
			(xy 103.95742 -232.062743) (xy 103.997853 -232.092119) (xy 104.033193 -232.127459) (xy 104.062569 -232.167892)
			(xy 104.085259 -232.212424) (xy 104.100703 -232.259956) (xy 104.108522 -232.309319) (xy 104.109012 -232.334308)
			(xy 104.108522 -232.359297) (xy 104.41354 -232.359297) (xy 104.41354 -232.309319) (xy 104.421359 -232.259956)
			(xy 104.436803 -232.212424) (xy 104.459493 -232.167892) (xy 104.488869 -232.127459) (xy 104.524209 -232.092119)
			(xy 104.564642 -232.062743) (xy 104.609174 -232.040053) (xy 104.656706 -232.024609) (xy 104.706069 -232.01679)
			(xy 104.756047 -232.01679) (xy 104.80541 -232.024609) (xy 104.852942 -232.040053) (xy 104.897474 -232.062743)
			(xy 104.937907 -232.092119) (xy 104.973247 -232.127459) (xy 105.002623 -232.167892) (xy 105.025313 -232.212424)
			(xy 105.040757 -232.259956) (xy 105.048576 -232.309319) (xy 105.049066 -232.334308) (xy 105.048576 -232.359297)
			(xy 105.353594 -232.359297) (xy 105.353594 -232.309319) (xy 105.361413 -232.259956) (xy 105.376857 -232.212424)
			(xy 105.399547 -232.167892) (xy 105.428923 -232.127459) (xy 105.464263 -232.092119) (xy 105.504696 -232.062743)
			(xy 105.549228 -232.040053) (xy 105.59676 -232.024609) (xy 105.646123 -232.01679) (xy 105.696101 -232.01679)
			(xy 105.745464 -232.024609) (xy 105.792996 -232.040053) (xy 105.837528 -232.062743) (xy 105.877961 -232.092119)
			(xy 105.913301 -232.127459) (xy 105.942677 -232.167892) (xy 105.965367 -232.212424) (xy 105.980811 -232.259956)
			(xy 105.98863 -232.309319) (xy 105.98912 -232.334308) (xy 105.98863 -232.359297) (xy 106.293648 -232.359297)
			(xy 106.293648 -232.309319) (xy 106.301467 -232.259956) (xy 106.316911 -232.212424) (xy 106.339601 -232.167892)
			(xy 106.368977 -232.127459) (xy 106.404317 -232.092119) (xy 106.44475 -232.062743) (xy 106.489282 -232.040053)
			(xy 106.536814 -232.024609) (xy 106.586177 -232.01679) (xy 106.636155 -232.01679) (xy 106.685518 -232.024609)
			(xy 106.73305 -232.040053) (xy 106.777582 -232.062743) (xy 106.818015 -232.092119) (xy 106.853355 -232.127459)
			(xy 106.882731 -232.167892) (xy 106.905421 -232.212424) (xy 106.920865 -232.259956) (xy 106.928684 -232.309319)
			(xy 106.929174 -232.334308) (xy 106.928684 -232.359297) (xy 107.233448 -232.359297) (xy 107.233448 -232.309319)
			(xy 107.241267 -232.259956) (xy 107.256711 -232.212424) (xy 107.279401 -232.167892) (xy 107.308777 -232.127459)
			(xy 107.344117 -232.092119) (xy 107.38455 -232.062743) (xy 107.429082 -232.040053) (xy 107.476614 -232.024609)
			(xy 107.525977 -232.01679) (xy 107.575955 -232.01679) (xy 107.625318 -232.024609) (xy 107.67285 -232.040053)
			(xy 107.717382 -232.062743) (xy 107.757815 -232.092119) (xy 107.793155 -232.127459) (xy 107.822531 -232.167892)
			(xy 107.845221 -232.212424) (xy 107.860665 -232.259956) (xy 107.868484 -232.309319) (xy 107.868974 -232.334308)
			(xy 108.174785 -232.334308) (xy 108.17888 -232.28358) (xy 108.191059 -232.234166) (xy 108.211007 -232.187346)
			(xy 108.238208 -232.144332) (xy 108.271956 -232.106238) (xy 108.311378 -232.074051) (xy 108.355452 -232.048605)
			(xy 108.403038 -232.030558) (xy 108.452902 -232.020378) (xy 108.503754 -232.018329) (xy 108.554275 -232.024463)
			(xy 108.603159 -232.038623) (xy 108.649138 -232.06044) (xy 108.691022 -232.08935) (xy 108.727726 -232.124605)
			(xy 108.758299 -232.165291) (xy 108.78195 -232.210354) (xy 108.798066 -232.258628) (xy 108.80623 -232.308862)
			(xy 108.806742 -232.334308) (xy 109.114839 -232.334308) (xy 109.118934 -232.28358) (xy 109.131113 -232.234166)
			(xy 109.151061 -232.187346) (xy 109.178262 -232.144332) (xy 109.21201 -232.106238) (xy 109.251432 -232.074051)
			(xy 109.295506 -232.048605) (xy 109.343092 -232.030558) (xy 109.392956 -232.020378) (xy 109.443808 -232.018329)
			(xy 109.494329 -232.024463) (xy 109.543213 -232.038623) (xy 109.589192 -232.06044) (xy 109.631076 -232.08935)
			(xy 109.66778 -232.124605) (xy 109.698353 -232.165291) (xy 109.722004 -232.210354) (xy 109.73812 -232.258628)
			(xy 109.746284 -232.308862) (xy 109.746796 -232.334308) (xy 109.746293 -232.359297) (xy 110.05361 -232.359297)
			(xy 110.05361 -232.309319) (xy 110.061429 -232.259956) (xy 110.076873 -232.212424) (xy 110.099563 -232.167892)
			(xy 110.128939 -232.127459) (xy 110.164279 -232.092119) (xy 110.204712 -232.062743) (xy 110.249244 -232.040053)
			(xy 110.296776 -232.024609) (xy 110.346139 -232.01679) (xy 110.396117 -232.01679) (xy 110.44548 -232.024609)
			(xy 110.493012 -232.040053) (xy 110.537544 -232.062743) (xy 110.577977 -232.092119) (xy 110.613317 -232.127459)
			(xy 110.642693 -232.167892) (xy 110.665383 -232.212424) (xy 110.680827 -232.259956) (xy 110.688646 -232.309319)
			(xy 110.689136 -232.334308) (xy 110.688646 -232.359297) (xy 112.867168 -232.359297) (xy 112.867168 -232.309319)
			(xy 112.874987 -232.259956) (xy 112.890431 -232.212424) (xy 112.913121 -232.167892) (xy 112.942497 -232.127459)
			(xy 112.977837 -232.092119) (xy 113.01827 -232.062743) (xy 113.062802 -232.040053) (xy 113.110334 -232.024609)
			(xy 113.159697 -232.01679) (xy 113.209675 -232.01679) (xy 113.259038 -232.024609) (xy 113.30657 -232.040053)
			(xy 113.351102 -232.062743) (xy 113.391535 -232.092119) (xy 113.426875 -232.127459) (xy 113.456251 -232.167892)
			(xy 113.478941 -232.212424) (xy 113.494385 -232.259956) (xy 113.502204 -232.309319) (xy 113.502694 -232.334308)
			(xy 113.808505 -232.334308) (xy 113.8126 -232.28358) (xy 113.824779 -232.234166) (xy 113.844727 -232.187346)
			(xy 113.871928 -232.144332) (xy 113.905676 -232.106238) (xy 113.945098 -232.074051) (xy 113.989172 -232.048605)
			(xy 114.036758 -232.030558) (xy 114.086622 -232.020378) (xy 114.137474 -232.018329) (xy 114.187995 -232.024463)
			(xy 114.236879 -232.038623) (xy 114.282858 -232.06044) (xy 114.324742 -232.08935) (xy 114.361446 -232.124605)
			(xy 114.392019 -232.165291) (xy 114.41567 -232.210354) (xy 114.431786 -232.258628) (xy 114.43995 -232.308862)
			(xy 114.440462 -232.334308) (xy 114.748559 -232.334308) (xy 114.752654 -232.28358) (xy 114.764833 -232.234166)
			(xy 114.784781 -232.187346) (xy 114.811982 -232.144332) (xy 114.84573 -232.106238) (xy 114.885152 -232.074051)
			(xy 114.929226 -232.048605) (xy 114.976812 -232.030558) (xy 115.026676 -232.020378) (xy 115.077528 -232.018329)
			(xy 115.128049 -232.024463) (xy 115.176933 -232.038623) (xy 115.222912 -232.06044) (xy 115.264796 -232.08935)
			(xy 115.3015 -232.124605) (xy 115.332073 -232.165291) (xy 115.355724 -232.210354) (xy 115.37184 -232.258628)
			(xy 115.380004 -232.308862) (xy 115.380516 -232.334308) (xy 115.380013 -232.359297) (xy 115.68733 -232.359297)
			(xy 115.68733 -232.309319) (xy 115.695149 -232.259956) (xy 115.710593 -232.212424) (xy 115.733283 -232.167892)
			(xy 115.762659 -232.127459) (xy 115.797999 -232.092119) (xy 115.838432 -232.062743) (xy 115.882964 -232.040053)
			(xy 115.930496 -232.024609) (xy 115.979859 -232.01679) (xy 116.029837 -232.01679) (xy 116.0792 -232.024609)
			(xy 116.126732 -232.040053) (xy 116.171264 -232.062743) (xy 116.211697 -232.092119) (xy 116.247037 -232.127459)
			(xy 116.276413 -232.167892) (xy 116.299103 -232.212424) (xy 116.314547 -232.259956) (xy 116.322366 -232.309319)
			(xy 116.322856 -232.334308) (xy 116.322366 -232.359297) (xy 116.62713 -232.359297) (xy 116.62713 -232.309319)
			(xy 116.634949 -232.259956) (xy 116.650393 -232.212424) (xy 116.673083 -232.167892) (xy 116.702459 -232.127459)
			(xy 116.737799 -232.092119) (xy 116.778232 -232.062743) (xy 116.822764 -232.040053) (xy 116.870296 -232.024609)
			(xy 116.919659 -232.01679) (xy 116.969637 -232.01679) (xy 117.019 -232.024609) (xy 117.066532 -232.040053)
			(xy 117.111064 -232.062743) (xy 117.151497 -232.092119) (xy 117.186837 -232.127459) (xy 117.216213 -232.167892)
			(xy 117.238903 -232.212424) (xy 117.254347 -232.259956) (xy 117.262166 -232.309319) (xy 117.262656 -232.334308)
			(xy 117.262166 -232.359297) (xy 117.567184 -232.359297) (xy 117.567184 -232.309319) (xy 117.575003 -232.259956)
			(xy 117.590447 -232.212424) (xy 117.613137 -232.167892) (xy 117.642513 -232.127459) (xy 117.677853 -232.092119)
			(xy 117.718286 -232.062743) (xy 117.762818 -232.040053) (xy 117.81035 -232.024609) (xy 117.859713 -232.01679)
			(xy 117.909691 -232.01679) (xy 117.959054 -232.024609) (xy 118.006586 -232.040053) (xy 118.051118 -232.062743)
			(xy 118.091551 -232.092119) (xy 118.126891 -232.127459) (xy 118.156267 -232.167892) (xy 118.178957 -232.212424)
			(xy 118.194401 -232.259956) (xy 118.20222 -232.309319) (xy 118.20271 -232.334308) (xy 118.20222 -232.359297)
			(xy 118.507238 -232.359297) (xy 118.507238 -232.309319) (xy 118.515057 -232.259956) (xy 118.530501 -232.212424)
			(xy 118.553191 -232.167892) (xy 118.582567 -232.127459) (xy 118.617907 -232.092119) (xy 118.65834 -232.062743)
			(xy 118.702872 -232.040053) (xy 118.750404 -232.024609) (xy 118.799767 -232.01679) (xy 118.849745 -232.01679)
			(xy 118.899108 -232.024609) (xy 118.94664 -232.040053) (xy 118.991172 -232.062743) (xy 119.031605 -232.092119)
			(xy 119.066945 -232.127459) (xy 119.096321 -232.167892) (xy 119.119011 -232.212424) (xy 119.134455 -232.259956)
			(xy 119.142274 -232.309319) (xy 119.142764 -232.334308) (xy 119.142274 -232.359297) (xy 119.447292 -232.359297)
			(xy 119.447292 -232.309319) (xy 119.455111 -232.259956) (xy 119.470555 -232.212424) (xy 119.493245 -232.167892)
			(xy 119.522621 -232.127459) (xy 119.557961 -232.092119) (xy 119.598394 -232.062743) (xy 119.642926 -232.040053)
			(xy 119.690458 -232.024609) (xy 119.739821 -232.01679) (xy 119.789799 -232.01679) (xy 119.839162 -232.024609)
			(xy 119.886694 -232.040053) (xy 119.931226 -232.062743) (xy 119.971659 -232.092119) (xy 120.006999 -232.127459)
			(xy 120.036375 -232.167892) (xy 120.059065 -232.212424) (xy 120.074509 -232.259956) (xy 120.082328 -232.309319)
			(xy 120.082818 -232.334308) (xy 120.082328 -232.359297) (xy 120.387092 -232.359297) (xy 120.387092 -232.309319)
			(xy 120.394911 -232.259956) (xy 120.410355 -232.212424) (xy 120.433045 -232.167892) (xy 120.462421 -232.127459)
			(xy 120.497761 -232.092119) (xy 120.538194 -232.062743) (xy 120.582726 -232.040053) (xy 120.630258 -232.024609)
			(xy 120.679621 -232.01679) (xy 120.729599 -232.01679) (xy 120.778962 -232.024609) (xy 120.826494 -232.040053)
			(xy 120.871026 -232.062743) (xy 120.911459 -232.092119) (xy 120.946799 -232.127459) (xy 120.976175 -232.167892)
			(xy 120.998865 -232.212424) (xy 121.014309 -232.259956) (xy 121.022128 -232.309319) (xy 121.022618 -232.334308)
			(xy 121.022128 -232.359297) (xy 121.327146 -232.359297) (xy 121.327146 -232.309319) (xy 121.334965 -232.259956)
			(xy 121.350409 -232.212424) (xy 121.373099 -232.167892) (xy 121.402475 -232.127459) (xy 121.437815 -232.092119)
			(xy 121.478248 -232.062743) (xy 121.52278 -232.040053) (xy 121.570312 -232.024609) (xy 121.619675 -232.01679)
			(xy 121.669653 -232.01679) (xy 121.719016 -232.024609) (xy 121.766548 -232.040053) (xy 121.81108 -232.062743)
			(xy 121.851513 -232.092119) (xy 121.886853 -232.127459) (xy 121.916229 -232.167892) (xy 121.938919 -232.212424)
			(xy 121.954363 -232.259956) (xy 121.962182 -232.309319) (xy 121.962672 -232.334308) (xy 121.962182 -232.359297)
			(xy 122.2672 -232.359297) (xy 122.2672 -232.309319) (xy 122.275019 -232.259956) (xy 122.290463 -232.212424)
			(xy 122.313153 -232.167892) (xy 122.342529 -232.127459) (xy 122.377869 -232.092119) (xy 122.418302 -232.062743)
			(xy 122.462834 -232.040053) (xy 122.510366 -232.024609) (xy 122.559729 -232.01679) (xy 122.609707 -232.01679)
			(xy 122.65907 -232.024609) (xy 122.706602 -232.040053) (xy 122.751134 -232.062743) (xy 122.791567 -232.092119)
			(xy 122.826907 -232.127459) (xy 122.856283 -232.167892) (xy 122.878973 -232.212424) (xy 122.894417 -232.259956)
			(xy 122.902236 -232.309319) (xy 122.902726 -232.334308) (xy 122.902236 -232.359297) (xy 123.207254 -232.359297)
			(xy 123.207254 -232.309319) (xy 123.215073 -232.259956) (xy 123.230517 -232.212424) (xy 123.253207 -232.167892)
			(xy 123.282583 -232.127459) (xy 123.317923 -232.092119) (xy 123.358356 -232.062743) (xy 123.402888 -232.040053)
			(xy 123.45042 -232.024609) (xy 123.499783 -232.01679) (xy 123.549761 -232.01679) (xy 123.599124 -232.024609)
			(xy 123.646656 -232.040053) (xy 123.691188 -232.062743) (xy 123.731621 -232.092119) (xy 123.766961 -232.127459)
			(xy 123.796337 -232.167892) (xy 123.819027 -232.212424) (xy 123.834471 -232.259956) (xy 123.84229 -232.309319)
			(xy 123.84278 -232.334308) (xy 123.84229 -232.359297) (xy 124.147308 -232.359297) (xy 124.147308 -232.309319)
			(xy 124.155127 -232.259956) (xy 124.170571 -232.212424) (xy 124.193261 -232.167892) (xy 124.222637 -232.127459)
			(xy 124.257977 -232.092119) (xy 124.29841 -232.062743) (xy 124.342942 -232.040053) (xy 124.390474 -232.024609)
			(xy 124.439837 -232.01679) (xy 124.489815 -232.01679) (xy 124.539178 -232.024609) (xy 124.58671 -232.040053)
			(xy 124.631242 -232.062743) (xy 124.671675 -232.092119) (xy 124.707015 -232.127459) (xy 124.736391 -232.167892)
			(xy 124.759081 -232.212424) (xy 124.774525 -232.259956) (xy 124.782344 -232.309319) (xy 124.782834 -232.334308)
			(xy 124.782344 -232.359297) (xy 125.087108 -232.359297) (xy 125.087108 -232.309319) (xy 125.094927 -232.259956)
			(xy 125.110371 -232.212424) (xy 125.133061 -232.167892) (xy 125.162437 -232.127459) (xy 125.197777 -232.092119)
			(xy 125.23821 -232.062743) (xy 125.282742 -232.040053) (xy 125.330274 -232.024609) (xy 125.379637 -232.01679)
			(xy 125.429615 -232.01679) (xy 125.478978 -232.024609) (xy 125.52651 -232.040053) (xy 125.571042 -232.062743)
			(xy 125.611475 -232.092119) (xy 125.646815 -232.127459) (xy 125.676191 -232.167892) (xy 125.698881 -232.212424)
			(xy 125.714325 -232.259956) (xy 125.722144 -232.309319) (xy 125.722634 -232.334308) (xy 125.722144 -232.359297)
			(xy 125.714325 -232.40866) (xy 125.698881 -232.456192) (xy 125.676191 -232.500724) (xy 125.646815 -232.541157)
			(xy 125.611475 -232.576497) (xy 125.571042 -232.605873) (xy 125.52651 -232.628563) (xy 125.478978 -232.644007)
			(xy 125.429615 -232.651826) (xy 125.379637 -232.651826) (xy 125.330274 -232.644007) (xy 125.282742 -232.628563)
			(xy 125.23821 -232.605873) (xy 125.197777 -232.576497) (xy 125.162437 -232.541157) (xy 125.133061 -232.500724)
			(xy 125.110371 -232.456192) (xy 125.094927 -232.40866) (xy 125.087108 -232.359297) (xy 124.782344 -232.359297)
			(xy 124.774525 -232.40866) (xy 124.759081 -232.456192) (xy 124.736391 -232.500724) (xy 124.707015 -232.541157)
			(xy 124.671675 -232.576497) (xy 124.631242 -232.605873) (xy 124.58671 -232.628563) (xy 124.539178 -232.644007)
			(xy 124.489815 -232.651826) (xy 124.439837 -232.651826) (xy 124.390474 -232.644007) (xy 124.342942 -232.628563)
			(xy 124.29841 -232.605873) (xy 124.257977 -232.576497) (xy 124.222637 -232.541157) (xy 124.193261 -232.500724)
			(xy 124.170571 -232.456192) (xy 124.155127 -232.40866) (xy 124.147308 -232.359297) (xy 123.84229 -232.359297)
			(xy 123.834471 -232.40866) (xy 123.819027 -232.456192) (xy 123.796337 -232.500724) (xy 123.766961 -232.541157)
			(xy 123.731621 -232.576497) (xy 123.691188 -232.605873) (xy 123.646656 -232.628563) (xy 123.599124 -232.644007)
			(xy 123.549761 -232.651826) (xy 123.499783 -232.651826) (xy 123.45042 -232.644007) (xy 123.402888 -232.628563)
			(xy 123.358356 -232.605873) (xy 123.317923 -232.576497) (xy 123.282583 -232.541157) (xy 123.253207 -232.500724)
			(xy 123.230517 -232.456192) (xy 123.215073 -232.40866) (xy 123.207254 -232.359297) (xy 122.902236 -232.359297)
			(xy 122.894417 -232.40866) (xy 122.878973 -232.456192) (xy 122.856283 -232.500724) (xy 122.826907 -232.541157)
			(xy 122.791567 -232.576497) (xy 122.751134 -232.605873) (xy 122.706602 -232.628563) (xy 122.65907 -232.644007)
			(xy 122.609707 -232.651826) (xy 122.559729 -232.651826) (xy 122.510366 -232.644007) (xy 122.462834 -232.628563)
			(xy 122.418302 -232.605873) (xy 122.377869 -232.576497) (xy 122.342529 -232.541157) (xy 122.313153 -232.500724)
			(xy 122.290463 -232.456192) (xy 122.275019 -232.40866) (xy 122.2672 -232.359297) (xy 121.962182 -232.359297)
			(xy 121.954363 -232.40866) (xy 121.938919 -232.456192) (xy 121.916229 -232.500724) (xy 121.886853 -232.541157)
			(xy 121.851513 -232.576497) (xy 121.81108 -232.605873) (xy 121.766548 -232.628563) (xy 121.719016 -232.644007)
			(xy 121.669653 -232.651826) (xy 121.619675 -232.651826) (xy 121.570312 -232.644007) (xy 121.52278 -232.628563)
			(xy 121.478248 -232.605873) (xy 121.437815 -232.576497) (xy 121.402475 -232.541157) (xy 121.373099 -232.500724)
			(xy 121.350409 -232.456192) (xy 121.334965 -232.40866) (xy 121.327146 -232.359297) (xy 121.022128 -232.359297)
			(xy 121.014309 -232.40866) (xy 120.998865 -232.456192) (xy 120.976175 -232.500724) (xy 120.946799 -232.541157)
			(xy 120.911459 -232.576497) (xy 120.871026 -232.605873) (xy 120.826494 -232.628563) (xy 120.778962 -232.644007)
			(xy 120.729599 -232.651826) (xy 120.679621 -232.651826) (xy 120.630258 -232.644007) (xy 120.582726 -232.628563)
			(xy 120.538194 -232.605873) (xy 120.497761 -232.576497) (xy 120.462421 -232.541157) (xy 120.433045 -232.500724)
			(xy 120.410355 -232.456192) (xy 120.394911 -232.40866) (xy 120.387092 -232.359297) (xy 120.082328 -232.359297)
			(xy 120.074509 -232.40866) (xy 120.059065 -232.456192) (xy 120.036375 -232.500724) (xy 120.006999 -232.541157)
			(xy 119.971659 -232.576497) (xy 119.931226 -232.605873) (xy 119.886694 -232.628563) (xy 119.839162 -232.644007)
			(xy 119.789799 -232.651826) (xy 119.739821 -232.651826) (xy 119.690458 -232.644007) (xy 119.642926 -232.628563)
			(xy 119.598394 -232.605873) (xy 119.557961 -232.576497) (xy 119.522621 -232.541157) (xy 119.493245 -232.500724)
			(xy 119.470555 -232.456192) (xy 119.455111 -232.40866) (xy 119.447292 -232.359297) (xy 119.142274 -232.359297)
			(xy 119.134455 -232.40866) (xy 119.119011 -232.456192) (xy 119.096321 -232.500724) (xy 119.066945 -232.541157)
			(xy 119.031605 -232.576497) (xy 118.991172 -232.605873) (xy 118.94664 -232.628563) (xy 118.899108 -232.644007)
			(xy 118.849745 -232.651826) (xy 118.799767 -232.651826) (xy 118.750404 -232.644007) (xy 118.702872 -232.628563)
			(xy 118.65834 -232.605873) (xy 118.617907 -232.576497) (xy 118.582567 -232.541157) (xy 118.553191 -232.500724)
			(xy 118.530501 -232.456192) (xy 118.515057 -232.40866) (xy 118.507238 -232.359297) (xy 118.20222 -232.359297)
			(xy 118.194401 -232.40866) (xy 118.178957 -232.456192) (xy 118.156267 -232.500724) (xy 118.126891 -232.541157)
			(xy 118.091551 -232.576497) (xy 118.051118 -232.605873) (xy 118.006586 -232.628563) (xy 117.959054 -232.644007)
			(xy 117.909691 -232.651826) (xy 117.859713 -232.651826) (xy 117.81035 -232.644007) (xy 117.762818 -232.628563)
			(xy 117.718286 -232.605873) (xy 117.677853 -232.576497) (xy 117.642513 -232.541157) (xy 117.613137 -232.500724)
			(xy 117.590447 -232.456192) (xy 117.575003 -232.40866) (xy 117.567184 -232.359297) (xy 117.262166 -232.359297)
			(xy 117.254347 -232.40866) (xy 117.238903 -232.456192) (xy 117.216213 -232.500724) (xy 117.186837 -232.541157)
			(xy 117.151497 -232.576497) (xy 117.111064 -232.605873) (xy 117.066532 -232.628563) (xy 117.019 -232.644007)
			(xy 116.969637 -232.651826) (xy 116.919659 -232.651826) (xy 116.870296 -232.644007) (xy 116.822764 -232.628563)
			(xy 116.778232 -232.605873) (xy 116.737799 -232.576497) (xy 116.702459 -232.541157) (xy 116.673083 -232.500724)
			(xy 116.650393 -232.456192) (xy 116.634949 -232.40866) (xy 116.62713 -232.359297) (xy 116.322366 -232.359297)
			(xy 116.314547 -232.40866) (xy 116.299103 -232.456192) (xy 116.276413 -232.500724) (xy 116.247037 -232.541157)
			(xy 116.211697 -232.576497) (xy 116.171264 -232.605873) (xy 116.126732 -232.628563) (xy 116.0792 -232.644007)
			(xy 116.029837 -232.651826) (xy 115.979859 -232.651826) (xy 115.930496 -232.644007) (xy 115.882964 -232.628563)
			(xy 115.838432 -232.605873) (xy 115.797999 -232.576497) (xy 115.762659 -232.541157) (xy 115.733283 -232.500724)
			(xy 115.710593 -232.456192) (xy 115.695149 -232.40866) (xy 115.68733 -232.359297) (xy 115.380013 -232.359297)
			(xy 115.380004 -232.359754) (xy 115.37184 -232.409988) (xy 115.355724 -232.458262) (xy 115.332073 -232.503325)
			(xy 115.3015 -232.544011) (xy 115.264796 -232.579266) (xy 115.222912 -232.608176) (xy 115.176933 -232.629993)
			(xy 115.128049 -232.644153) (xy 115.077528 -232.650287) (xy 115.026676 -232.648238) (xy 114.976812 -232.638058)
			(xy 114.929226 -232.620011) (xy 114.885152 -232.594565) (xy 114.84573 -232.562378) (xy 114.811982 -232.524284)
			(xy 114.784781 -232.48127) (xy 114.764833 -232.43445) (xy 114.752654 -232.385036) (xy 114.748559 -232.334308)
			(xy 114.440462 -232.334308) (xy 114.43995 -232.359754) (xy 114.431786 -232.409988) (xy 114.41567 -232.458262)
			(xy 114.392019 -232.503325) (xy 114.361446 -232.544011) (xy 114.324742 -232.579266) (xy 114.282858 -232.608176)
			(xy 114.236879 -232.629993) (xy 114.187995 -232.644153) (xy 114.137474 -232.650287) (xy 114.086622 -232.648238)
			(xy 114.036758 -232.638058) (xy 113.989172 -232.620011) (xy 113.945098 -232.594565) (xy 113.905676 -232.562378)
			(xy 113.871928 -232.524284) (xy 113.844727 -232.48127) (xy 113.824779 -232.43445) (xy 113.8126 -232.385036)
			(xy 113.808505 -232.334308) (xy 113.502694 -232.334308) (xy 113.502204 -232.359297) (xy 113.494385 -232.40866)
			(xy 113.478941 -232.456192) (xy 113.456251 -232.500724) (xy 113.426875 -232.541157) (xy 113.391535 -232.576497)
			(xy 113.351102 -232.605873) (xy 113.30657 -232.628563) (xy 113.259038 -232.644007) (xy 113.209675 -232.651826)
			(xy 113.159697 -232.651826) (xy 113.110334 -232.644007) (xy 113.062802 -232.628563) (xy 113.01827 -232.605873)
			(xy 112.977837 -232.576497) (xy 112.942497 -232.541157) (xy 112.913121 -232.500724) (xy 112.890431 -232.456192)
			(xy 112.874987 -232.40866) (xy 112.867168 -232.359297) (xy 110.688646 -232.359297) (xy 110.680827 -232.40866)
			(xy 110.665383 -232.456192) (xy 110.642693 -232.500724) (xy 110.613317 -232.541157) (xy 110.577977 -232.576497)
			(xy 110.537544 -232.605873) (xy 110.493012 -232.628563) (xy 110.44548 -232.644007) (xy 110.396117 -232.651826)
			(xy 110.346139 -232.651826) (xy 110.296776 -232.644007) (xy 110.249244 -232.628563) (xy 110.204712 -232.605873)
			(xy 110.164279 -232.576497) (xy 110.128939 -232.541157) (xy 110.099563 -232.500724) (xy 110.076873 -232.456192)
			(xy 110.061429 -232.40866) (xy 110.05361 -232.359297) (xy 109.746293 -232.359297) (xy 109.746284 -232.359754)
			(xy 109.73812 -232.409988) (xy 109.722004 -232.458262) (xy 109.698353 -232.503325) (xy 109.66778 -232.544011)
			(xy 109.631076 -232.579266) (xy 109.589192 -232.608176) (xy 109.543213 -232.629993) (xy 109.494329 -232.644153)
			(xy 109.443808 -232.650287) (xy 109.392956 -232.648238) (xy 109.343092 -232.638058) (xy 109.295506 -232.620011)
			(xy 109.251432 -232.594565) (xy 109.21201 -232.562378) (xy 109.178262 -232.524284) (xy 109.151061 -232.48127)
			(xy 109.131113 -232.43445) (xy 109.118934 -232.385036) (xy 109.114839 -232.334308) (xy 108.806742 -232.334308)
			(xy 108.80623 -232.359754) (xy 108.798066 -232.409988) (xy 108.78195 -232.458262) (xy 108.758299 -232.503325)
			(xy 108.727726 -232.544011) (xy 108.691022 -232.579266) (xy 108.649138 -232.608176) (xy 108.603159 -232.629993)
			(xy 108.554275 -232.644153) (xy 108.503754 -232.650287) (xy 108.452902 -232.648238) (xy 108.403038 -232.638058)
			(xy 108.355452 -232.620011) (xy 108.311378 -232.594565) (xy 108.271956 -232.562378) (xy 108.238208 -232.524284)
			(xy 108.211007 -232.48127) (xy 108.191059 -232.43445) (xy 108.17888 -232.385036) (xy 108.174785 -232.334308)
			(xy 107.868974 -232.334308) (xy 107.868484 -232.359297) (xy 107.860665 -232.40866) (xy 107.845221 -232.456192)
			(xy 107.822531 -232.500724) (xy 107.793155 -232.541157) (xy 107.757815 -232.576497) (xy 107.717382 -232.605873)
			(xy 107.67285 -232.628563) (xy 107.625318 -232.644007) (xy 107.575955 -232.651826) (xy 107.525977 -232.651826)
			(xy 107.476614 -232.644007) (xy 107.429082 -232.628563) (xy 107.38455 -232.605873) (xy 107.344117 -232.576497)
			(xy 107.308777 -232.541157) (xy 107.279401 -232.500724) (xy 107.256711 -232.456192) (xy 107.241267 -232.40866)
			(xy 107.233448 -232.359297) (xy 106.928684 -232.359297) (xy 106.920865 -232.40866) (xy 106.905421 -232.456192)
			(xy 106.882731 -232.500724) (xy 106.853355 -232.541157) (xy 106.818015 -232.576497) (xy 106.777582 -232.605873)
			(xy 106.73305 -232.628563) (xy 106.685518 -232.644007) (xy 106.636155 -232.651826) (xy 106.586177 -232.651826)
			(xy 106.536814 -232.644007) (xy 106.489282 -232.628563) (xy 106.44475 -232.605873) (xy 106.404317 -232.576497)
			(xy 106.368977 -232.541157) (xy 106.339601 -232.500724) (xy 106.316911 -232.456192) (xy 106.301467 -232.40866)
			(xy 106.293648 -232.359297) (xy 105.98863 -232.359297) (xy 105.980811 -232.40866) (xy 105.965367 -232.456192)
			(xy 105.942677 -232.500724) (xy 105.913301 -232.541157) (xy 105.877961 -232.576497) (xy 105.837528 -232.605873)
			(xy 105.792996 -232.628563) (xy 105.745464 -232.644007) (xy 105.696101 -232.651826) (xy 105.646123 -232.651826)
			(xy 105.59676 -232.644007) (xy 105.549228 -232.628563) (xy 105.504696 -232.605873) (xy 105.464263 -232.576497)
			(xy 105.428923 -232.541157) (xy 105.399547 -232.500724) (xy 105.376857 -232.456192) (xy 105.361413 -232.40866)
			(xy 105.353594 -232.359297) (xy 105.048576 -232.359297) (xy 105.040757 -232.40866) (xy 105.025313 -232.456192)
			(xy 105.002623 -232.500724) (xy 104.973247 -232.541157) (xy 104.937907 -232.576497) (xy 104.897474 -232.605873)
			(xy 104.852942 -232.628563) (xy 104.80541 -232.644007) (xy 104.756047 -232.651826) (xy 104.706069 -232.651826)
			(xy 104.656706 -232.644007) (xy 104.609174 -232.628563) (xy 104.564642 -232.605873) (xy 104.524209 -232.576497)
			(xy 104.488869 -232.541157) (xy 104.459493 -232.500724) (xy 104.436803 -232.456192) (xy 104.421359 -232.40866)
			(xy 104.41354 -232.359297) (xy 104.108522 -232.359297) (xy 104.100703 -232.40866) (xy 104.085259 -232.456192)
			(xy 104.062569 -232.500724) (xy 104.033193 -232.541157) (xy 103.997853 -232.576497) (xy 103.95742 -232.605873)
			(xy 103.912888 -232.628563) (xy 103.865356 -232.644007) (xy 103.815993 -232.651826) (xy 103.766015 -232.651826)
			(xy 103.716652 -232.644007) (xy 103.66912 -232.628563) (xy 103.624588 -232.605873) (xy 103.584155 -232.576497)
			(xy 103.548815 -232.541157) (xy 103.519439 -232.500724) (xy 103.496749 -232.456192) (xy 103.481305 -232.40866)
			(xy 103.473486 -232.359297) (xy 103.168468 -232.359297) (xy 103.160649 -232.40866) (xy 103.145205 -232.456192)
			(xy 103.122515 -232.500724) (xy 103.093139 -232.541157) (xy 103.057799 -232.576497) (xy 103.017366 -232.605873)
			(xy 102.972834 -232.628563) (xy 102.925302 -232.644007) (xy 102.875939 -232.651826) (xy 102.825961 -232.651826)
			(xy 102.776598 -232.644007) (xy 102.729066 -232.628563) (xy 102.684534 -232.605873) (xy 102.644101 -232.576497)
			(xy 102.608761 -232.541157) (xy 102.579385 -232.500724) (xy 102.556695 -232.456192) (xy 102.541251 -232.40866)
			(xy 102.533432 -232.359297) (xy 102.228668 -232.359297) (xy 102.220849 -232.40866) (xy 102.205405 -232.456192)
			(xy 102.182715 -232.500724) (xy 102.153339 -232.541157) (xy 102.117999 -232.576497) (xy 102.077566 -232.605873)
			(xy 102.033034 -232.628563) (xy 101.985502 -232.644007) (xy 101.936139 -232.651826) (xy 101.886161 -232.651826)
			(xy 101.836798 -232.644007) (xy 101.789266 -232.628563) (xy 101.744734 -232.605873) (xy 101.704301 -232.576497)
			(xy 101.668961 -232.541157) (xy 101.639585 -232.500724) (xy 101.616895 -232.456192) (xy 101.601451 -232.40866)
			(xy 101.593632 -232.359297) (xy 101.288614 -232.359297) (xy 101.280795 -232.40866) (xy 101.265351 -232.456192)
			(xy 101.242661 -232.500724) (xy 101.213285 -232.541157) (xy 101.177945 -232.576497) (xy 101.137512 -232.605873)
			(xy 101.09298 -232.628563) (xy 101.045448 -232.644007) (xy 100.996085 -232.651826) (xy 100.946107 -232.651826)
			(xy 100.896744 -232.644007) (xy 100.849212 -232.628563) (xy 100.80468 -232.605873) (xy 100.764247 -232.576497)
			(xy 100.728907 -232.541157) (xy 100.699531 -232.500724) (xy 100.676841 -232.456192) (xy 100.661397 -232.40866)
			(xy 100.653578 -232.359297) (xy 100.34856 -232.359297) (xy 100.340741 -232.40866) (xy 100.325297 -232.456192)
			(xy 100.302607 -232.500724) (xy 100.273231 -232.541157) (xy 100.237891 -232.576497) (xy 100.197458 -232.605873)
			(xy 100.152926 -232.628563) (xy 100.105394 -232.644007) (xy 100.056031 -232.651826) (xy 100.006053 -232.651826)
			(xy 99.95669 -232.644007) (xy 99.909158 -232.628563) (xy 99.864626 -232.605873) (xy 99.824193 -232.576497)
			(xy 99.788853 -232.541157) (xy 99.759477 -232.500724) (xy 99.736787 -232.456192) (xy 99.721343 -232.40866)
			(xy 99.713524 -232.359297) (xy 99.408506 -232.359297) (xy 99.400687 -232.40866) (xy 99.385243 -232.456192)
			(xy 99.362553 -232.500724) (xy 99.333177 -232.541157) (xy 99.297837 -232.576497) (xy 99.257404 -232.605873)
			(xy 99.212872 -232.628563) (xy 99.16534 -232.644007) (xy 99.115977 -232.651826) (xy 99.065999 -232.651826)
			(xy 99.016636 -232.644007) (xy 98.969104 -232.628563) (xy 98.924572 -232.605873) (xy 98.884139 -232.576497)
			(xy 98.848799 -232.541157) (xy 98.819423 -232.500724) (xy 98.796733 -232.456192) (xy 98.781289 -232.40866)
			(xy 98.77347 -232.359297) (xy 98.468452 -232.359297) (xy 98.460633 -232.40866) (xy 98.445189 -232.456192)
			(xy 98.422499 -232.500724) (xy 98.393123 -232.541157) (xy 98.357783 -232.576497) (xy 98.31735 -232.605873)
			(xy 98.272818 -232.628563) (xy 98.225286 -232.644007) (xy 98.175923 -232.651826) (xy 98.125945 -232.651826)
			(xy 98.076582 -232.644007) (xy 98.02905 -232.628563) (xy 97.984518 -232.605873) (xy 97.944085 -232.576497)
			(xy 97.908745 -232.541157) (xy 97.879369 -232.500724) (xy 97.856679 -232.456192) (xy 97.841235 -232.40866)
			(xy 97.833416 -232.359297) (xy 97.52865 -232.359297) (xy 97.520841 -232.408625) (xy 97.505412 -232.456136)
			(xy 97.482744 -232.500652) (xy 97.453396 -232.541076) (xy 97.418089 -232.576414) (xy 97.377691 -232.605798)
			(xy 97.333195 -232.628504) (xy 97.285697 -232.643975) (xy 97.236365 -232.65183) (xy 97.211388 -232.652316)
			(xy 97.211134 -232.652316) (xy 97.201776 -232.652225) (xy 97.183095 -232.651083) (xy 97.173796 -232.65003)
			(xy 97.171002 -232.649776) (xy 97.170494 -232.649776) (xy 97.160588 -232.648506) (xy 97.148396 -232.652062)
			(xy 97.137474 -232.656126) (xy 97.073212 -232.712514) (xy 97.066406 -232.719612) (xy 97.058308 -232.737514)
			(xy 97.057464 -232.747312) (xy 97.057464 -233.106722) (xy 97.057718 -233.111294) (xy 97.058988 -233.141774)
			(xy 97.058988 -233.144314) (xy 97.364799 -233.144314) (xy 97.368894 -233.093586) (xy 97.381073 -233.044172)
			(xy 97.401021 -232.997352) (xy 97.428222 -232.954338) (xy 97.46197 -232.916244) (xy 97.501392 -232.884057)
			(xy 97.545466 -232.858611) (xy 97.593052 -232.840564) (xy 97.642916 -232.830384) (xy 97.693768 -232.828335)
			(xy 97.744289 -232.834469) (xy 97.793173 -232.848629) (xy 97.839152 -232.870446) (xy 97.881036 -232.899356)
			(xy 97.91774 -232.934611) (xy 97.948313 -232.975297) (xy 97.971964 -233.02036) (xy 97.98808 -233.068634)
			(xy 97.996244 -233.118868) (xy 97.996756 -233.144314) (xy 98.304853 -233.144314) (xy 98.308948 -233.093586)
			(xy 98.321127 -233.044172) (xy 98.341075 -232.997352) (xy 98.368276 -232.954338) (xy 98.402024 -232.916244)
			(xy 98.441446 -232.884057) (xy 98.48552 -232.858611) (xy 98.533106 -232.840564) (xy 98.58297 -232.830384)
			(xy 98.633822 -232.828335) (xy 98.684343 -232.834469) (xy 98.733227 -232.848629) (xy 98.779206 -232.870446)
			(xy 98.82109 -232.899356) (xy 98.857794 -232.934611) (xy 98.888367 -232.975297) (xy 98.912018 -233.02036)
			(xy 98.928134 -233.068634) (xy 98.936298 -233.118868) (xy 98.93681 -233.144314) (xy 98.936307 -233.169303)
			(xy 99.243624 -233.169303) (xy 99.243624 -233.119325) (xy 99.251443 -233.069962) (xy 99.266887 -233.02243)
			(xy 99.289577 -232.977898) (xy 99.318953 -232.937465) (xy 99.354293 -232.902125) (xy 99.394726 -232.872749)
			(xy 99.439258 -232.850059) (xy 99.48679 -232.834615) (xy 99.536153 -232.826796) (xy 99.586131 -232.826796)
			(xy 99.635494 -232.834615) (xy 99.683026 -232.850059) (xy 99.727558 -232.872749) (xy 99.767991 -232.902125)
			(xy 99.803331 -232.937465) (xy 99.832707 -232.977898) (xy 99.855397 -233.02243) (xy 99.870841 -233.069962)
			(xy 99.87866 -233.119325) (xy 99.87915 -233.144314) (xy 100.184707 -233.144314) (xy 100.188802 -233.093586)
			(xy 100.200981 -233.044172) (xy 100.220929 -232.997352) (xy 100.24813 -232.954338) (xy 100.281878 -232.916244)
			(xy 100.3213 -232.884057) (xy 100.365374 -232.858611) (xy 100.41296 -232.840564) (xy 100.462824 -232.830384)
			(xy 100.513676 -232.828335) (xy 100.564197 -232.834469) (xy 100.613081 -232.848629) (xy 100.65906 -232.870446)
			(xy 100.700944 -232.899356) (xy 100.737648 -232.934611) (xy 100.768221 -232.975297) (xy 100.791872 -233.02036)
			(xy 100.807988 -233.068634) (xy 100.816152 -233.118868) (xy 100.816664 -233.144314) (xy 101.124761 -233.144314)
			(xy 101.128856 -233.093586) (xy 101.141035 -233.044172) (xy 101.160983 -232.997352) (xy 101.188184 -232.954338)
			(xy 101.221932 -232.916244) (xy 101.261354 -232.884057) (xy 101.305428 -232.858611) (xy 101.353014 -232.840564)
			(xy 101.402878 -232.830384) (xy 101.45373 -232.828335) (xy 101.504251 -232.834469) (xy 101.553135 -232.848629)
			(xy 101.599114 -232.870446) (xy 101.640998 -232.899356) (xy 101.677702 -232.934611) (xy 101.708275 -232.975297)
			(xy 101.731926 -233.02036) (xy 101.748042 -233.068634) (xy 101.756206 -233.118868) (xy 101.756718 -233.144314)
			(xy 101.756215 -233.169303) (xy 102.063532 -233.169303) (xy 102.063532 -233.119325) (xy 102.071351 -233.069962)
			(xy 102.086795 -233.02243) (xy 102.109485 -232.977898) (xy 102.138861 -232.937465) (xy 102.174201 -232.902125)
			(xy 102.214634 -232.872749) (xy 102.259166 -232.850059) (xy 102.306698 -232.834615) (xy 102.356061 -232.826796)
			(xy 102.406039 -232.826796) (xy 102.455402 -232.834615) (xy 102.502934 -232.850059) (xy 102.547466 -232.872749)
			(xy 102.587899 -232.902125) (xy 102.623239 -232.937465) (xy 102.652615 -232.977898) (xy 102.675305 -233.02243)
			(xy 102.690749 -233.069962) (xy 102.698568 -233.119325) (xy 102.699058 -233.144314) (xy 103.004869 -233.144314)
			(xy 103.008964 -233.093586) (xy 103.021143 -233.044172) (xy 103.041091 -232.997352) (xy 103.068292 -232.954338)
			(xy 103.10204 -232.916244) (xy 103.141462 -232.884057) (xy 103.185536 -232.858611) (xy 103.233122 -232.840564)
			(xy 103.282986 -232.830384) (xy 103.333838 -232.828335) (xy 103.384359 -232.834469) (xy 103.433243 -232.848629)
			(xy 103.479222 -232.870446) (xy 103.521106 -232.899356) (xy 103.55781 -232.934611) (xy 103.588383 -232.975297)
			(xy 103.612034 -233.02036) (xy 103.62815 -233.068634) (xy 103.636314 -233.118868) (xy 103.636826 -233.144314)
			(xy 103.944923 -233.144314) (xy 103.949018 -233.093586) (xy 103.961197 -233.044172) (xy 103.981145 -232.997352)
			(xy 104.008346 -232.954338) (xy 104.042094 -232.916244) (xy 104.081516 -232.884057) (xy 104.12559 -232.858611)
			(xy 104.173176 -232.840564) (xy 104.22304 -232.830384) (xy 104.273892 -232.828335) (xy 104.324413 -232.834469)
			(xy 104.373297 -232.848629) (xy 104.419276 -232.870446) (xy 104.46116 -232.899356) (xy 104.497864 -232.934611)
			(xy 104.528437 -232.975297) (xy 104.552088 -233.02036) (xy 104.568204 -233.068634) (xy 104.576368 -233.118868)
			(xy 104.57688 -233.144314) (xy 104.576377 -233.169303) (xy 104.88344 -233.169303) (xy 104.88344 -233.119325)
			(xy 104.891259 -233.069962) (xy 104.906703 -233.02243) (xy 104.929393 -232.977898) (xy 104.958769 -232.937465)
			(xy 104.994109 -232.902125) (xy 105.034542 -232.872749) (xy 105.079074 -232.850059) (xy 105.126606 -232.834615)
			(xy 105.175969 -232.826796) (xy 105.225947 -232.826796) (xy 105.27531 -232.834615) (xy 105.322842 -232.850059)
			(xy 105.367374 -232.872749) (xy 105.407807 -232.902125) (xy 105.443147 -232.937465) (xy 105.472523 -232.977898)
			(xy 105.495213 -233.02243) (xy 105.510657 -233.069962) (xy 105.518476 -233.119325) (xy 105.518966 -233.144314)
			(xy 105.824777 -233.144314) (xy 105.828872 -233.093586) (xy 105.841051 -233.044172) (xy 105.860999 -232.997352)
			(xy 105.8882 -232.954338) (xy 105.921948 -232.916244) (xy 105.96137 -232.884057) (xy 106.005444 -232.858611)
			(xy 106.05303 -232.840564) (xy 106.102894 -232.830384) (xy 106.153746 -232.828335) (xy 106.204267 -232.834469)
			(xy 106.253151 -232.848629) (xy 106.29913 -232.870446) (xy 106.341014 -232.899356) (xy 106.377718 -232.934611)
			(xy 106.408291 -232.975297) (xy 106.431942 -233.02036) (xy 106.448058 -233.068634) (xy 106.456222 -233.118868)
			(xy 106.456734 -233.144314) (xy 106.764831 -233.144314) (xy 106.768926 -233.093586) (xy 106.781105 -233.044172)
			(xy 106.801053 -232.997352) (xy 106.828254 -232.954338) (xy 106.862002 -232.916244) (xy 106.901424 -232.884057)
			(xy 106.945498 -232.858611) (xy 106.993084 -232.840564) (xy 107.042948 -232.830384) (xy 107.0938 -232.828335)
			(xy 107.144321 -232.834469) (xy 107.193205 -232.848629) (xy 107.239184 -232.870446) (xy 107.281068 -232.899356)
			(xy 107.317772 -232.934611) (xy 107.348345 -232.975297) (xy 107.371996 -233.02036) (xy 107.388112 -233.068634)
			(xy 107.396276 -233.118868) (xy 107.396788 -233.144314) (xy 107.396285 -233.169303) (xy 107.703602 -233.169303)
			(xy 107.703602 -233.119325) (xy 107.711421 -233.069962) (xy 107.726865 -233.02243) (xy 107.749555 -232.977898)
			(xy 107.778931 -232.937465) (xy 107.814271 -232.902125) (xy 107.854704 -232.872749) (xy 107.899236 -232.850059)
			(xy 107.946768 -232.834615) (xy 107.996131 -232.826796) (xy 108.046109 -232.826796) (xy 108.095472 -232.834615)
			(xy 108.143004 -232.850059) (xy 108.187536 -232.872749) (xy 108.227969 -232.902125) (xy 108.263309 -232.937465)
			(xy 108.292685 -232.977898) (xy 108.315375 -233.02243) (xy 108.330819 -233.069962) (xy 108.338638 -233.119325)
			(xy 108.339128 -233.144314) (xy 108.338638 -233.169303) (xy 108.643656 -233.169303) (xy 108.643656 -233.119325)
			(xy 108.651475 -233.069962) (xy 108.666919 -233.02243) (xy 108.689609 -232.977898) (xy 108.718985 -232.937465)
			(xy 108.754325 -232.902125) (xy 108.794758 -232.872749) (xy 108.83929 -232.850059) (xy 108.886822 -232.834615)
			(xy 108.936185 -232.826796) (xy 108.986163 -232.826796) (xy 109.035526 -232.834615) (xy 109.083058 -232.850059)
			(xy 109.12759 -232.872749) (xy 109.168023 -232.902125) (xy 109.203363 -232.937465) (xy 109.232739 -232.977898)
			(xy 109.255429 -233.02243) (xy 109.270873 -233.069962) (xy 109.278692 -233.119325) (xy 109.279182 -233.144314)
			(xy 109.278692 -233.169303) (xy 109.583456 -233.169303) (xy 109.583456 -233.119325) (xy 109.591275 -233.069962)
			(xy 109.606719 -233.02243) (xy 109.629409 -232.977898) (xy 109.658785 -232.937465) (xy 109.694125 -232.902125)
			(xy 109.734558 -232.872749) (xy 109.77909 -232.850059) (xy 109.826622 -232.834615) (xy 109.875985 -232.826796)
			(xy 109.925963 -232.826796) (xy 109.975326 -232.834615) (xy 110.022858 -232.850059) (xy 110.06739 -232.872749)
			(xy 110.107823 -232.902125) (xy 110.143163 -232.937465) (xy 110.172539 -232.977898) (xy 110.195229 -233.02243)
			(xy 110.210673 -233.069962) (xy 110.218492 -233.119325) (xy 110.218982 -233.144314) (xy 110.218492 -233.169303)
			(xy 113.337322 -233.169303) (xy 113.337322 -233.119325) (xy 113.345141 -233.069962) (xy 113.360585 -233.02243)
			(xy 113.383275 -232.977898) (xy 113.412651 -232.937465) (xy 113.447991 -232.902125) (xy 113.488424 -232.872749)
			(xy 113.532956 -232.850059) (xy 113.580488 -232.834615) (xy 113.629851 -232.826796) (xy 113.679829 -232.826796)
			(xy 113.729192 -232.834615) (xy 113.776724 -232.850059) (xy 113.821256 -232.872749) (xy 113.861689 -232.902125)
			(xy 113.897029 -232.937465) (xy 113.926405 -232.977898) (xy 113.949095 -233.02243) (xy 113.964539 -233.069962)
			(xy 113.972358 -233.119325) (xy 113.972848 -233.144314) (xy 113.972358 -233.169303) (xy 114.277122 -233.169303)
			(xy 114.277122 -233.119325) (xy 114.284941 -233.069962) (xy 114.300385 -233.02243) (xy 114.323075 -232.977898)
			(xy 114.352451 -232.937465) (xy 114.387791 -232.902125) (xy 114.428224 -232.872749) (xy 114.472756 -232.850059)
			(xy 114.520288 -232.834615) (xy 114.569651 -232.826796) (xy 114.619629 -232.826796) (xy 114.668992 -232.834615)
			(xy 114.716524 -232.850059) (xy 114.761056 -232.872749) (xy 114.801489 -232.902125) (xy 114.836829 -232.937465)
			(xy 114.866205 -232.977898) (xy 114.888895 -233.02243) (xy 114.904339 -233.069962) (xy 114.912158 -233.119325)
			(xy 114.912648 -233.144314) (xy 114.912158 -233.169303) (xy 115.217176 -233.169303) (xy 115.217176 -233.119325)
			(xy 115.224995 -233.069962) (xy 115.240439 -233.02243) (xy 115.263129 -232.977898) (xy 115.292505 -232.937465)
			(xy 115.327845 -232.902125) (xy 115.368278 -232.872749) (xy 115.41281 -232.850059) (xy 115.460342 -232.834615)
			(xy 115.509705 -232.826796) (xy 115.559683 -232.826796) (xy 115.609046 -232.834615) (xy 115.656578 -232.850059)
			(xy 115.70111 -232.872749) (xy 115.741543 -232.902125) (xy 115.776883 -232.937465) (xy 115.806259 -232.977898)
			(xy 115.828949 -233.02243) (xy 115.844393 -233.069962) (xy 115.852212 -233.119325) (xy 115.852702 -233.144314)
			(xy 116.158513 -233.144314) (xy 116.162608 -233.093586) (xy 116.174787 -233.044172) (xy 116.194735 -232.997352)
			(xy 116.221936 -232.954338) (xy 116.255684 -232.916244) (xy 116.295106 -232.884057) (xy 116.33918 -232.858611)
			(xy 116.386766 -232.840564) (xy 116.43663 -232.830384) (xy 116.487482 -232.828335) (xy 116.538003 -232.834469)
			(xy 116.586887 -232.848629) (xy 116.632866 -232.870446) (xy 116.67475 -232.899356) (xy 116.711454 -232.934611)
			(xy 116.742027 -232.975297) (xy 116.765678 -233.02036) (xy 116.781794 -233.068634) (xy 116.789958 -233.118868)
			(xy 116.79047 -233.144314) (xy 117.098567 -233.144314) (xy 117.102662 -233.093586) (xy 117.114841 -233.044172)
			(xy 117.134789 -232.997352) (xy 117.16199 -232.954338) (xy 117.195738 -232.916244) (xy 117.23516 -232.884057)
			(xy 117.279234 -232.858611) (xy 117.32682 -232.840564) (xy 117.376684 -232.830384) (xy 117.427536 -232.828335)
			(xy 117.478057 -232.834469) (xy 117.526941 -232.848629) (xy 117.57292 -232.870446) (xy 117.614804 -232.899356)
			(xy 117.651508 -232.934611) (xy 117.682081 -232.975297) (xy 117.705732 -233.02036) (xy 117.721848 -233.068634)
			(xy 117.730012 -233.118868) (xy 117.730524 -233.144314) (xy 117.730021 -233.169303) (xy 118.037338 -233.169303)
			(xy 118.037338 -233.119325) (xy 118.045157 -233.069962) (xy 118.060601 -233.02243) (xy 118.083291 -232.977898)
			(xy 118.112667 -232.937465) (xy 118.148007 -232.902125) (xy 118.18844 -232.872749) (xy 118.232972 -232.850059)
			(xy 118.280504 -232.834615) (xy 118.329867 -232.826796) (xy 118.379845 -232.826796) (xy 118.429208 -232.834615)
			(xy 118.47674 -232.850059) (xy 118.521272 -232.872749) (xy 118.561705 -232.902125) (xy 118.597045 -232.937465)
			(xy 118.626421 -232.977898) (xy 118.649111 -233.02243) (xy 118.664555 -233.069962) (xy 118.672374 -233.119325)
			(xy 118.672864 -233.144314) (xy 118.978421 -233.144314) (xy 118.982516 -233.093586) (xy 118.994695 -233.044172)
			(xy 119.014643 -232.997352) (xy 119.041844 -232.954338) (xy 119.075592 -232.916244) (xy 119.115014 -232.884057)
			(xy 119.159088 -232.858611) (xy 119.206674 -232.840564) (xy 119.256538 -232.830384) (xy 119.30739 -232.828335)
			(xy 119.357911 -232.834469) (xy 119.406795 -232.848629) (xy 119.452774 -232.870446) (xy 119.494658 -232.899356)
			(xy 119.531362 -232.934611) (xy 119.561935 -232.975297) (xy 119.585586 -233.02036) (xy 119.601702 -233.068634)
			(xy 119.609866 -233.118868) (xy 119.610378 -233.144314) (xy 119.918475 -233.144314) (xy 119.92257 -233.093586)
			(xy 119.934749 -233.044172) (xy 119.954697 -232.997352) (xy 119.981898 -232.954338) (xy 120.015646 -232.916244)
			(xy 120.055068 -232.884057) (xy 120.099142 -232.858611) (xy 120.146728 -232.840564) (xy 120.196592 -232.830384)
			(xy 120.247444 -232.828335) (xy 120.297965 -232.834469) (xy 120.346849 -232.848629) (xy 120.392828 -232.870446)
			(xy 120.434712 -232.899356) (xy 120.471416 -232.934611) (xy 120.501989 -232.975297) (xy 120.52564 -233.02036)
			(xy 120.541756 -233.068634) (xy 120.54992 -233.118868) (xy 120.550432 -233.144314) (xy 120.549929 -233.169303)
			(xy 120.857246 -233.169303) (xy 120.857246 -233.119325) (xy 120.865065 -233.069962) (xy 120.880509 -233.02243)
			(xy 120.903199 -232.977898) (xy 120.932575 -232.937465) (xy 120.967915 -232.902125) (xy 121.008348 -232.872749)
			(xy 121.05288 -232.850059) (xy 121.100412 -232.834615) (xy 121.149775 -232.826796) (xy 121.199753 -232.826796)
			(xy 121.249116 -232.834615) (xy 121.296648 -232.850059) (xy 121.34118 -232.872749) (xy 121.381613 -232.902125)
			(xy 121.416953 -232.937465) (xy 121.446329 -232.977898) (xy 121.469019 -233.02243) (xy 121.484463 -233.069962)
			(xy 121.492282 -233.119325) (xy 121.492772 -233.144314) (xy 121.798583 -233.144314) (xy 121.802678 -233.093586)
			(xy 121.814857 -233.044172) (xy 121.834805 -232.997352) (xy 121.862006 -232.954338) (xy 121.895754 -232.916244)
			(xy 121.935176 -232.884057) (xy 121.97925 -232.858611) (xy 122.026836 -232.840564) (xy 122.0767 -232.830384)
			(xy 122.127552 -232.828335) (xy 122.178073 -232.834469) (xy 122.226957 -232.848629) (xy 122.272936 -232.870446)
			(xy 122.31482 -232.899356) (xy 122.351524 -232.934611) (xy 122.382097 -232.975297) (xy 122.405748 -233.02036)
			(xy 122.421864 -233.068634) (xy 122.430028 -233.118868) (xy 122.43054 -233.144314) (xy 122.738383 -233.144314)
			(xy 122.742478 -233.093586) (xy 122.754657 -233.044172) (xy 122.774605 -232.997352) (xy 122.801806 -232.954338)
			(xy 122.835554 -232.916244) (xy 122.874976 -232.884057) (xy 122.91905 -232.858611) (xy 122.966636 -232.840564)
			(xy 123.0165 -232.830384) (xy 123.067352 -232.828335) (xy 123.117873 -232.834469) (xy 123.166757 -232.848629)
			(xy 123.212736 -232.870446) (xy 123.25462 -232.899356) (xy 123.291324 -232.934611) (xy 123.321897 -232.975297)
			(xy 123.345548 -233.02036) (xy 123.361664 -233.068634) (xy 123.369828 -233.118868) (xy 123.37034 -233.144314)
			(xy 123.369837 -233.169303) (xy 123.677154 -233.169303) (xy 123.677154 -233.119325) (xy 123.684973 -233.069962)
			(xy 123.700417 -233.02243) (xy 123.723107 -232.977898) (xy 123.752483 -232.937465) (xy 123.787823 -232.902125)
			(xy 123.828256 -232.872749) (xy 123.872788 -232.850059) (xy 123.92032 -232.834615) (xy 123.969683 -232.826796)
			(xy 124.019661 -232.826796) (xy 124.069024 -232.834615) (xy 124.116556 -232.850059) (xy 124.161088 -232.872749)
			(xy 124.201521 -232.902125) (xy 124.236861 -232.937465) (xy 124.266237 -232.977898) (xy 124.288927 -233.02243)
			(xy 124.304371 -233.069962) (xy 124.31219 -233.119325) (xy 124.31268 -233.144314) (xy 124.618491 -233.144314)
			(xy 124.622586 -233.093586) (xy 124.634765 -233.044172) (xy 124.654713 -232.997352) (xy 124.681914 -232.954338)
			(xy 124.715662 -232.916244) (xy 124.755084 -232.884057) (xy 124.799158 -232.858611) (xy 124.846744 -232.840564)
			(xy 124.896608 -232.830384) (xy 124.94746 -232.828335) (xy 124.997981 -232.834469) (xy 125.046865 -232.848629)
			(xy 125.092844 -232.870446) (xy 125.134728 -232.899356) (xy 125.171432 -232.934611) (xy 125.202005 -232.975297)
			(xy 125.225656 -233.02036) (xy 125.241772 -233.068634) (xy 125.249936 -233.118868) (xy 125.250448 -233.144314)
			(xy 125.558545 -233.144314) (xy 125.56264 -233.093586) (xy 125.574819 -233.044172) (xy 125.594767 -232.997352)
			(xy 125.621968 -232.954338) (xy 125.655716 -232.916244) (xy 125.695138 -232.884057) (xy 125.739212 -232.858611)
			(xy 125.786798 -232.840564) (xy 125.836662 -232.830384) (xy 125.887514 -232.828335) (xy 125.938035 -232.834469)
			(xy 125.986919 -232.848629) (xy 126.032898 -232.870446) (xy 126.074782 -232.899356) (xy 126.111486 -232.934611)
			(xy 126.142059 -232.975297) (xy 126.16571 -233.02036) (xy 126.181826 -233.068634) (xy 126.18999 -233.118868)
			(xy 126.190502 -233.144314) (xy 126.18999 -233.16976) (xy 126.181826 -233.219994) (xy 126.16571 -233.268268)
			(xy 126.142059 -233.313331) (xy 126.111486 -233.354017) (xy 126.074782 -233.389272) (xy 126.032898 -233.418182)
			(xy 125.986919 -233.439999) (xy 125.938035 -233.454159) (xy 125.887514 -233.460293) (xy 125.836662 -233.458244)
			(xy 125.786798 -233.448064) (xy 125.739212 -233.430017) (xy 125.695138 -233.404571) (xy 125.655716 -233.372384)
			(xy 125.621968 -233.33429) (xy 125.594767 -233.291276) (xy 125.574819 -233.244456) (xy 125.56264 -233.195042)
			(xy 125.558545 -233.144314) (xy 125.250448 -233.144314) (xy 125.249936 -233.16976) (xy 125.241772 -233.219994)
			(xy 125.225656 -233.268268) (xy 125.202005 -233.313331) (xy 125.171432 -233.354017) (xy 125.134728 -233.389272)
			(xy 125.092844 -233.418182) (xy 125.046865 -233.439999) (xy 124.997981 -233.454159) (xy 124.94746 -233.460293)
			(xy 124.896608 -233.458244) (xy 124.846744 -233.448064) (xy 124.799158 -233.430017) (xy 124.755084 -233.404571)
			(xy 124.715662 -233.372384) (xy 124.681914 -233.33429) (xy 124.654713 -233.291276) (xy 124.634765 -233.244456)
			(xy 124.622586 -233.195042) (xy 124.618491 -233.144314) (xy 124.31268 -233.144314) (xy 124.31219 -233.169303)
			(xy 124.304371 -233.218666) (xy 124.288927 -233.266198) (xy 124.266237 -233.31073) (xy 124.236861 -233.351163)
			(xy 124.201521 -233.386503) (xy 124.161088 -233.415879) (xy 124.116556 -233.438569) (xy 124.069024 -233.454013)
			(xy 124.019661 -233.461832) (xy 123.969683 -233.461832) (xy 123.92032 -233.454013) (xy 123.872788 -233.438569)
			(xy 123.828256 -233.415879) (xy 123.787823 -233.386503) (xy 123.752483 -233.351163) (xy 123.723107 -233.31073)
			(xy 123.700417 -233.266198) (xy 123.684973 -233.218666) (xy 123.677154 -233.169303) (xy 123.369837 -233.169303)
			(xy 123.369828 -233.16976) (xy 123.361664 -233.219994) (xy 123.345548 -233.268268) (xy 123.321897 -233.313331)
			(xy 123.291324 -233.354017) (xy 123.25462 -233.389272) (xy 123.212736 -233.418182) (xy 123.166757 -233.439999)
			(xy 123.117873 -233.454159) (xy 123.067352 -233.460293) (xy 123.0165 -233.458244) (xy 122.966636 -233.448064)
			(xy 122.91905 -233.430017) (xy 122.874976 -233.404571) (xy 122.835554 -233.372384) (xy 122.801806 -233.33429)
			(xy 122.774605 -233.291276) (xy 122.754657 -233.244456) (xy 122.742478 -233.195042) (xy 122.738383 -233.144314)
			(xy 122.43054 -233.144314) (xy 122.430028 -233.16976) (xy 122.421864 -233.219994) (xy 122.405748 -233.268268)
			(xy 122.382097 -233.313331) (xy 122.351524 -233.354017) (xy 122.31482 -233.389272) (xy 122.272936 -233.418182)
			(xy 122.226957 -233.439999) (xy 122.178073 -233.454159) (xy 122.127552 -233.460293) (xy 122.0767 -233.458244)
			(xy 122.026836 -233.448064) (xy 121.97925 -233.430017) (xy 121.935176 -233.404571) (xy 121.895754 -233.372384)
			(xy 121.862006 -233.33429) (xy 121.834805 -233.291276) (xy 121.814857 -233.244456) (xy 121.802678 -233.195042)
			(xy 121.798583 -233.144314) (xy 121.492772 -233.144314) (xy 121.492282 -233.169303) (xy 121.484463 -233.218666)
			(xy 121.469019 -233.266198) (xy 121.446329 -233.31073) (xy 121.416953 -233.351163) (xy 121.381613 -233.386503)
			(xy 121.34118 -233.415879) (xy 121.296648 -233.438569) (xy 121.249116 -233.454013) (xy 121.199753 -233.461832)
			(xy 121.149775 -233.461832) (xy 121.100412 -233.454013) (xy 121.05288 -233.438569) (xy 121.008348 -233.415879)
			(xy 120.967915 -233.386503) (xy 120.932575 -233.351163) (xy 120.903199 -233.31073) (xy 120.880509 -233.266198)
			(xy 120.865065 -233.218666) (xy 120.857246 -233.169303) (xy 120.549929 -233.169303) (xy 120.54992 -233.16976)
			(xy 120.541756 -233.219994) (xy 120.52564 -233.268268) (xy 120.501989 -233.313331) (xy 120.471416 -233.354017)
			(xy 120.434712 -233.389272) (xy 120.392828 -233.418182) (xy 120.346849 -233.439999) (xy 120.297965 -233.454159)
			(xy 120.247444 -233.460293) (xy 120.196592 -233.458244) (xy 120.146728 -233.448064) (xy 120.099142 -233.430017)
			(xy 120.055068 -233.404571) (xy 120.015646 -233.372384) (xy 119.981898 -233.33429) (xy 119.954697 -233.291276)
			(xy 119.934749 -233.244456) (xy 119.92257 -233.195042) (xy 119.918475 -233.144314) (xy 119.610378 -233.144314)
			(xy 119.609866 -233.16976) (xy 119.601702 -233.219994) (xy 119.585586 -233.268268) (xy 119.561935 -233.313331)
			(xy 119.531362 -233.354017) (xy 119.494658 -233.389272) (xy 119.452774 -233.418182) (xy 119.406795 -233.439999)
			(xy 119.357911 -233.454159) (xy 119.30739 -233.460293) (xy 119.256538 -233.458244) (xy 119.206674 -233.448064)
			(xy 119.159088 -233.430017) (xy 119.115014 -233.404571) (xy 119.075592 -233.372384) (xy 119.041844 -233.33429)
			(xy 119.014643 -233.291276) (xy 118.994695 -233.244456) (xy 118.982516 -233.195042) (xy 118.978421 -233.144314)
			(xy 118.672864 -233.144314) (xy 118.672374 -233.169303) (xy 118.664555 -233.218666) (xy 118.649111 -233.266198)
			(xy 118.626421 -233.31073) (xy 118.597045 -233.351163) (xy 118.561705 -233.386503) (xy 118.521272 -233.415879)
			(xy 118.47674 -233.438569) (xy 118.429208 -233.454013) (xy 118.379845 -233.461832) (xy 118.329867 -233.461832)
			(xy 118.280504 -233.454013) (xy 118.232972 -233.438569) (xy 118.18844 -233.415879) (xy 118.148007 -233.386503)
			(xy 118.112667 -233.351163) (xy 118.083291 -233.31073) (xy 118.060601 -233.266198) (xy 118.045157 -233.218666)
			(xy 118.037338 -233.169303) (xy 117.730021 -233.169303) (xy 117.730012 -233.16976) (xy 117.721848 -233.219994)
			(xy 117.705732 -233.268268) (xy 117.682081 -233.313331) (xy 117.651508 -233.354017) (xy 117.614804 -233.389272)
			(xy 117.57292 -233.418182) (xy 117.526941 -233.439999) (xy 117.478057 -233.454159) (xy 117.427536 -233.460293)
			(xy 117.376684 -233.458244) (xy 117.32682 -233.448064) (xy 117.279234 -233.430017) (xy 117.23516 -233.404571)
			(xy 117.195738 -233.372384) (xy 117.16199 -233.33429) (xy 117.134789 -233.291276) (xy 117.114841 -233.244456)
			(xy 117.102662 -233.195042) (xy 117.098567 -233.144314) (xy 116.79047 -233.144314) (xy 116.789958 -233.16976)
			(xy 116.781794 -233.219994) (xy 116.765678 -233.268268) (xy 116.742027 -233.313331) (xy 116.711454 -233.354017)
			(xy 116.67475 -233.389272) (xy 116.632866 -233.418182) (xy 116.586887 -233.439999) (xy 116.538003 -233.454159)
			(xy 116.487482 -233.460293) (xy 116.43663 -233.458244) (xy 116.386766 -233.448064) (xy 116.33918 -233.430017)
			(xy 116.295106 -233.404571) (xy 116.255684 -233.372384) (xy 116.221936 -233.33429) (xy 116.194735 -233.291276)
			(xy 116.174787 -233.244456) (xy 116.162608 -233.195042) (xy 116.158513 -233.144314) (xy 115.852702 -233.144314)
			(xy 115.852212 -233.169303) (xy 115.844393 -233.218666) (xy 115.828949 -233.266198) (xy 115.806259 -233.31073)
			(xy 115.776883 -233.351163) (xy 115.741543 -233.386503) (xy 115.70111 -233.415879) (xy 115.656578 -233.438569)
			(xy 115.609046 -233.454013) (xy 115.559683 -233.461832) (xy 115.509705 -233.461832) (xy 115.460342 -233.454013)
			(xy 115.41281 -233.438569) (xy 115.368278 -233.415879) (xy 115.327845 -233.386503) (xy 115.292505 -233.351163)
			(xy 115.263129 -233.31073) (xy 115.240439 -233.266198) (xy 115.224995 -233.218666) (xy 115.217176 -233.169303)
			(xy 114.912158 -233.169303) (xy 114.904339 -233.218666) (xy 114.888895 -233.266198) (xy 114.866205 -233.31073)
			(xy 114.836829 -233.351163) (xy 114.801489 -233.386503) (xy 114.761056 -233.415879) (xy 114.716524 -233.438569)
			(xy 114.668992 -233.454013) (xy 114.619629 -233.461832) (xy 114.569651 -233.461832) (xy 114.520288 -233.454013)
			(xy 114.472756 -233.438569) (xy 114.428224 -233.415879) (xy 114.387791 -233.386503) (xy 114.352451 -233.351163)
			(xy 114.323075 -233.31073) (xy 114.300385 -233.266198) (xy 114.284941 -233.218666) (xy 114.277122 -233.169303)
			(xy 113.972358 -233.169303) (xy 113.964539 -233.218666) (xy 113.949095 -233.266198) (xy 113.926405 -233.31073)
			(xy 113.897029 -233.351163) (xy 113.861689 -233.386503) (xy 113.821256 -233.415879) (xy 113.776724 -233.438569)
			(xy 113.729192 -233.454013) (xy 113.679829 -233.461832) (xy 113.629851 -233.461832) (xy 113.580488 -233.454013)
			(xy 113.532956 -233.438569) (xy 113.488424 -233.415879) (xy 113.447991 -233.386503) (xy 113.412651 -233.351163)
			(xy 113.383275 -233.31073) (xy 113.360585 -233.266198) (xy 113.345141 -233.218666) (xy 113.337322 -233.169303)
			(xy 110.218492 -233.169303) (xy 110.210673 -233.218666) (xy 110.195229 -233.266198) (xy 110.172539 -233.31073)
			(xy 110.143163 -233.351163) (xy 110.107823 -233.386503) (xy 110.06739 -233.415879) (xy 110.022858 -233.438569)
			(xy 109.975326 -233.454013) (xy 109.925963 -233.461832) (xy 109.875985 -233.461832) (xy 109.826622 -233.454013)
			(xy 109.77909 -233.438569) (xy 109.734558 -233.415879) (xy 109.694125 -233.386503) (xy 109.658785 -233.351163)
			(xy 109.629409 -233.31073) (xy 109.606719 -233.266198) (xy 109.591275 -233.218666) (xy 109.583456 -233.169303)
			(xy 109.278692 -233.169303) (xy 109.270873 -233.218666) (xy 109.255429 -233.266198) (xy 109.232739 -233.31073)
			(xy 109.203363 -233.351163) (xy 109.168023 -233.386503) (xy 109.12759 -233.415879) (xy 109.083058 -233.438569)
			(xy 109.035526 -233.454013) (xy 108.986163 -233.461832) (xy 108.936185 -233.461832) (xy 108.886822 -233.454013)
			(xy 108.83929 -233.438569) (xy 108.794758 -233.415879) (xy 108.754325 -233.386503) (xy 108.718985 -233.351163)
			(xy 108.689609 -233.31073) (xy 108.666919 -233.266198) (xy 108.651475 -233.218666) (xy 108.643656 -233.169303)
			(xy 108.338638 -233.169303) (xy 108.330819 -233.218666) (xy 108.315375 -233.266198) (xy 108.292685 -233.31073)
			(xy 108.263309 -233.351163) (xy 108.227969 -233.386503) (xy 108.187536 -233.415879) (xy 108.143004 -233.438569)
			(xy 108.095472 -233.454013) (xy 108.046109 -233.461832) (xy 107.996131 -233.461832) (xy 107.946768 -233.454013)
			(xy 107.899236 -233.438569) (xy 107.854704 -233.415879) (xy 107.814271 -233.386503) (xy 107.778931 -233.351163)
			(xy 107.749555 -233.31073) (xy 107.726865 -233.266198) (xy 107.711421 -233.218666) (xy 107.703602 -233.169303)
			(xy 107.396285 -233.169303) (xy 107.396276 -233.16976) (xy 107.388112 -233.219994) (xy 107.371996 -233.268268)
			(xy 107.348345 -233.313331) (xy 107.317772 -233.354017) (xy 107.281068 -233.389272) (xy 107.239184 -233.418182)
			(xy 107.193205 -233.439999) (xy 107.144321 -233.454159) (xy 107.0938 -233.460293) (xy 107.042948 -233.458244)
			(xy 106.993084 -233.448064) (xy 106.945498 -233.430017) (xy 106.901424 -233.404571) (xy 106.862002 -233.372384)
			(xy 106.828254 -233.33429) (xy 106.801053 -233.291276) (xy 106.781105 -233.244456) (xy 106.768926 -233.195042)
			(xy 106.764831 -233.144314) (xy 106.456734 -233.144314) (xy 106.456222 -233.16976) (xy 106.448058 -233.219994)
			(xy 106.431942 -233.268268) (xy 106.408291 -233.313331) (xy 106.377718 -233.354017) (xy 106.341014 -233.389272)
			(xy 106.29913 -233.418182) (xy 106.253151 -233.439999) (xy 106.204267 -233.454159) (xy 106.153746 -233.460293)
			(xy 106.102894 -233.458244) (xy 106.05303 -233.448064) (xy 106.005444 -233.430017) (xy 105.96137 -233.404571)
			(xy 105.921948 -233.372384) (xy 105.8882 -233.33429) (xy 105.860999 -233.291276) (xy 105.841051 -233.244456)
			(xy 105.828872 -233.195042) (xy 105.824777 -233.144314) (xy 105.518966 -233.144314) (xy 105.518476 -233.169303)
			(xy 105.510657 -233.218666) (xy 105.495213 -233.266198) (xy 105.472523 -233.31073) (xy 105.443147 -233.351163)
			(xy 105.407807 -233.386503) (xy 105.367374 -233.415879) (xy 105.322842 -233.438569) (xy 105.27531 -233.454013)
			(xy 105.225947 -233.461832) (xy 105.175969 -233.461832) (xy 105.126606 -233.454013) (xy 105.079074 -233.438569)
			(xy 105.034542 -233.415879) (xy 104.994109 -233.386503) (xy 104.958769 -233.351163) (xy 104.929393 -233.31073)
			(xy 104.906703 -233.266198) (xy 104.891259 -233.218666) (xy 104.88344 -233.169303) (xy 104.576377 -233.169303)
			(xy 104.576368 -233.16976) (xy 104.568204 -233.219994) (xy 104.552088 -233.268268) (xy 104.528437 -233.313331)
			(xy 104.497864 -233.354017) (xy 104.46116 -233.389272) (xy 104.419276 -233.418182) (xy 104.373297 -233.439999)
			(xy 104.324413 -233.454159) (xy 104.273892 -233.460293) (xy 104.22304 -233.458244) (xy 104.173176 -233.448064)
			(xy 104.12559 -233.430017) (xy 104.081516 -233.404571) (xy 104.042094 -233.372384) (xy 104.008346 -233.33429)
			(xy 103.981145 -233.291276) (xy 103.961197 -233.244456) (xy 103.949018 -233.195042) (xy 103.944923 -233.144314)
			(xy 103.636826 -233.144314) (xy 103.636314 -233.16976) (xy 103.62815 -233.219994) (xy 103.612034 -233.268268)
			(xy 103.588383 -233.313331) (xy 103.55781 -233.354017) (xy 103.521106 -233.389272) (xy 103.479222 -233.418182)
			(xy 103.433243 -233.439999) (xy 103.384359 -233.454159) (xy 103.333838 -233.460293) (xy 103.282986 -233.458244)
			(xy 103.233122 -233.448064) (xy 103.185536 -233.430017) (xy 103.141462 -233.404571) (xy 103.10204 -233.372384)
			(xy 103.068292 -233.33429) (xy 103.041091 -233.291276) (xy 103.021143 -233.244456) (xy 103.008964 -233.195042)
			(xy 103.004869 -233.144314) (xy 102.699058 -233.144314) (xy 102.698568 -233.169303) (xy 102.690749 -233.218666)
			(xy 102.675305 -233.266198) (xy 102.652615 -233.31073) (xy 102.623239 -233.351163) (xy 102.587899 -233.386503)
			(xy 102.547466 -233.415879) (xy 102.502934 -233.438569) (xy 102.455402 -233.454013) (xy 102.406039 -233.461832)
			(xy 102.356061 -233.461832) (xy 102.306698 -233.454013) (xy 102.259166 -233.438569) (xy 102.214634 -233.415879)
			(xy 102.174201 -233.386503) (xy 102.138861 -233.351163) (xy 102.109485 -233.31073) (xy 102.086795 -233.266198)
			(xy 102.071351 -233.218666) (xy 102.063532 -233.169303) (xy 101.756215 -233.169303) (xy 101.756206 -233.16976)
			(xy 101.748042 -233.219994) (xy 101.731926 -233.268268) (xy 101.708275 -233.313331) (xy 101.677702 -233.354017)
			(xy 101.640998 -233.389272) (xy 101.599114 -233.418182) (xy 101.553135 -233.439999) (xy 101.504251 -233.454159)
			(xy 101.45373 -233.460293) (xy 101.402878 -233.458244) (xy 101.353014 -233.448064) (xy 101.305428 -233.430017)
			(xy 101.261354 -233.404571) (xy 101.221932 -233.372384) (xy 101.188184 -233.33429) (xy 101.160983 -233.291276)
			(xy 101.141035 -233.244456) (xy 101.128856 -233.195042) (xy 101.124761 -233.144314) (xy 100.816664 -233.144314)
			(xy 100.816152 -233.16976) (xy 100.807988 -233.219994) (xy 100.791872 -233.268268) (xy 100.768221 -233.313331)
			(xy 100.737648 -233.354017) (xy 100.700944 -233.389272) (xy 100.65906 -233.418182) (xy 100.613081 -233.439999)
			(xy 100.564197 -233.454159) (xy 100.513676 -233.460293) (xy 100.462824 -233.458244) (xy 100.41296 -233.448064)
			(xy 100.365374 -233.430017) (xy 100.3213 -233.404571) (xy 100.281878 -233.372384) (xy 100.24813 -233.33429)
			(xy 100.220929 -233.291276) (xy 100.200981 -233.244456) (xy 100.188802 -233.195042) (xy 100.184707 -233.144314)
			(xy 99.87915 -233.144314) (xy 99.87866 -233.169303) (xy 99.870841 -233.218666) (xy 99.855397 -233.266198)
			(xy 99.832707 -233.31073) (xy 99.803331 -233.351163) (xy 99.767991 -233.386503) (xy 99.727558 -233.415879)
			(xy 99.683026 -233.438569) (xy 99.635494 -233.454013) (xy 99.586131 -233.461832) (xy 99.536153 -233.461832)
			(xy 99.48679 -233.454013) (xy 99.439258 -233.438569) (xy 99.394726 -233.415879) (xy 99.354293 -233.386503)
			(xy 99.318953 -233.351163) (xy 99.289577 -233.31073) (xy 99.266887 -233.266198) (xy 99.251443 -233.218666)
			(xy 99.243624 -233.169303) (xy 98.936307 -233.169303) (xy 98.936298 -233.16976) (xy 98.928134 -233.219994)
			(xy 98.912018 -233.268268) (xy 98.888367 -233.313331) (xy 98.857794 -233.354017) (xy 98.82109 -233.389272)
			(xy 98.779206 -233.418182) (xy 98.733227 -233.439999) (xy 98.684343 -233.454159) (xy 98.633822 -233.460293)
			(xy 98.58297 -233.458244) (xy 98.533106 -233.448064) (xy 98.48552 -233.430017) (xy 98.441446 -233.404571)
			(xy 98.402024 -233.372384) (xy 98.368276 -233.33429) (xy 98.341075 -233.291276) (xy 98.321127 -233.244456)
			(xy 98.308948 -233.195042) (xy 98.304853 -233.144314) (xy 97.996756 -233.144314) (xy 97.996244 -233.16976)
			(xy 97.98808 -233.219994) (xy 97.971964 -233.268268) (xy 97.948313 -233.313331) (xy 97.91774 -233.354017)
			(xy 97.881036 -233.389272) (xy 97.839152 -233.418182) (xy 97.793173 -233.439999) (xy 97.744289 -233.454159)
			(xy 97.693768 -233.460293) (xy 97.642916 -233.458244) (xy 97.593052 -233.448064) (xy 97.545466 -233.430017)
			(xy 97.501392 -233.404571) (xy 97.46197 -233.372384) (xy 97.428222 -233.33429) (xy 97.401021 -233.291276)
			(xy 97.381073 -233.244456) (xy 97.368894 -233.195042) (xy 97.364799 -233.144314) (xy 97.058988 -233.144314)
			(xy 97.058988 -233.14787) (xy 97.057718 -233.177842) (xy 97.057464 -233.179366) (xy 97.057464 -233.979309)
			(xy 98.77347 -233.979309) (xy 98.77347 -233.929331) (xy 98.781289 -233.879968) (xy 98.796733 -233.832436)
			(xy 98.819423 -233.787904) (xy 98.848799 -233.747471) (xy 98.884139 -233.712131) (xy 98.924572 -233.682755)
			(xy 98.969104 -233.660065) (xy 99.016636 -233.644621) (xy 99.065999 -233.636802) (xy 99.115977 -233.636802)
			(xy 99.16534 -233.644621) (xy 99.212872 -233.660065) (xy 99.257404 -233.682755) (xy 99.297837 -233.712131)
			(xy 99.333177 -233.747471) (xy 99.362553 -233.787904) (xy 99.385243 -233.832436) (xy 99.400687 -233.879968)
			(xy 99.408506 -233.929331) (xy 99.408996 -233.95432) (xy 99.408506 -233.979309) (xy 101.593632 -233.979309)
			(xy 101.593632 -233.929331) (xy 101.601451 -233.879968) (xy 101.616895 -233.832436) (xy 101.639585 -233.787904)
			(xy 101.668961 -233.747471) (xy 101.704301 -233.712131) (xy 101.744734 -233.682755) (xy 101.789266 -233.660065)
			(xy 101.836798 -233.644621) (xy 101.886161 -233.636802) (xy 101.936139 -233.636802) (xy 101.985502 -233.644621)
			(xy 102.033034 -233.660065) (xy 102.077566 -233.682755) (xy 102.117999 -233.712131) (xy 102.153339 -233.747471)
			(xy 102.182715 -233.787904) (xy 102.205405 -233.832436) (xy 102.220849 -233.879968) (xy 102.228668 -233.929331)
			(xy 102.229158 -233.95432) (xy 102.228668 -233.979309) (xy 104.41354 -233.979309) (xy 104.41354 -233.929331)
			(xy 104.421359 -233.879968) (xy 104.436803 -233.832436) (xy 104.459493 -233.787904) (xy 104.488869 -233.747471)
			(xy 104.524209 -233.712131) (xy 104.564642 -233.682755) (xy 104.609174 -233.660065) (xy 104.656706 -233.644621)
			(xy 104.706069 -233.636802) (xy 104.756047 -233.636802) (xy 104.80541 -233.644621) (xy 104.852942 -233.660065)
			(xy 104.897474 -233.682755) (xy 104.937907 -233.712131) (xy 104.973247 -233.747471) (xy 105.002623 -233.787904)
			(xy 105.025313 -233.832436) (xy 105.040757 -233.879968) (xy 105.048576 -233.929331) (xy 105.049066 -233.95432)
			(xy 105.048576 -233.979309) (xy 107.233448 -233.979309) (xy 107.233448 -233.929331) (xy 107.241267 -233.879968)
			(xy 107.256711 -233.832436) (xy 107.279401 -233.787904) (xy 107.308777 -233.747471) (xy 107.344117 -233.712131)
			(xy 107.38455 -233.682755) (xy 107.429082 -233.660065) (xy 107.476614 -233.644621) (xy 107.525977 -233.636802)
			(xy 107.575955 -233.636802) (xy 107.625318 -233.644621) (xy 107.67285 -233.660065) (xy 107.717382 -233.682755)
			(xy 107.757815 -233.712131) (xy 107.793155 -233.747471) (xy 107.822531 -233.787904) (xy 107.845221 -233.832436)
			(xy 107.860665 -233.879968) (xy 107.868484 -233.929331) (xy 107.868974 -233.95432) (xy 108.174785 -233.95432)
			(xy 108.17888 -233.903592) (xy 108.191059 -233.854178) (xy 108.211007 -233.807358) (xy 108.238208 -233.764344)
			(xy 108.271956 -233.72625) (xy 108.311378 -233.694063) (xy 108.355452 -233.668617) (xy 108.403038 -233.65057)
			(xy 108.452902 -233.64039) (xy 108.503754 -233.638341) (xy 108.554275 -233.644475) (xy 108.603159 -233.658635)
			(xy 108.649138 -233.680452) (xy 108.691022 -233.709362) (xy 108.727726 -233.744617) (xy 108.758299 -233.785303)
			(xy 108.78195 -233.830366) (xy 108.798066 -233.87864) (xy 108.80623 -233.928874) (xy 108.806742 -233.95432)
			(xy 109.114839 -233.95432) (xy 109.118934 -233.903592) (xy 109.131113 -233.854178) (xy 109.151061 -233.807358)
			(xy 109.178262 -233.764344) (xy 109.21201 -233.72625) (xy 109.251432 -233.694063) (xy 109.295506 -233.668617)
			(xy 109.343092 -233.65057) (xy 109.392956 -233.64039) (xy 109.443808 -233.638341) (xy 109.494329 -233.644475)
			(xy 109.543213 -233.658635) (xy 109.589192 -233.680452) (xy 109.631076 -233.709362) (xy 109.66778 -233.744617)
			(xy 109.698353 -233.785303) (xy 109.722004 -233.830366) (xy 109.73812 -233.87864) (xy 109.746284 -233.928874)
			(xy 109.746796 -233.95432) (xy 109.746293 -233.979309) (xy 110.05361 -233.979309) (xy 110.05361 -233.929331)
			(xy 110.061429 -233.879968) (xy 110.076873 -233.832436) (xy 110.099563 -233.787904) (xy 110.128939 -233.747471)
			(xy 110.164279 -233.712131) (xy 110.204712 -233.682755) (xy 110.249244 -233.660065) (xy 110.296776 -233.644621)
			(xy 110.346139 -233.636802) (xy 110.396117 -233.636802) (xy 110.44548 -233.644621) (xy 110.493012 -233.660065)
			(xy 110.537544 -233.682755) (xy 110.577977 -233.712131) (xy 110.613317 -233.747471) (xy 110.642693 -233.787904)
			(xy 110.665383 -233.832436) (xy 110.680827 -233.879968) (xy 110.688646 -233.929331) (xy 110.689136 -233.95432)
			(xy 110.688646 -233.979309) (xy 112.867168 -233.979309) (xy 112.867168 -233.929331) (xy 112.874987 -233.879968)
			(xy 112.890431 -233.832436) (xy 112.913121 -233.787904) (xy 112.942497 -233.747471) (xy 112.977837 -233.712131)
			(xy 113.01827 -233.682755) (xy 113.062802 -233.660065) (xy 113.110334 -233.644621) (xy 113.159697 -233.636802)
			(xy 113.209675 -233.636802) (xy 113.259038 -233.644621) (xy 113.30657 -233.660065) (xy 113.351102 -233.682755)
			(xy 113.391535 -233.712131) (xy 113.426875 -233.747471) (xy 113.456251 -233.787904) (xy 113.478941 -233.832436)
			(xy 113.494385 -233.879968) (xy 113.502204 -233.929331) (xy 113.502694 -233.95432) (xy 113.808505 -233.95432)
			(xy 113.8126 -233.903592) (xy 113.824779 -233.854178) (xy 113.844727 -233.807358) (xy 113.871928 -233.764344)
			(xy 113.905676 -233.72625) (xy 113.945098 -233.694063) (xy 113.989172 -233.668617) (xy 114.036758 -233.65057)
			(xy 114.086622 -233.64039) (xy 114.137474 -233.638341) (xy 114.187995 -233.644475) (xy 114.236879 -233.658635)
			(xy 114.282858 -233.680452) (xy 114.324742 -233.709362) (xy 114.361446 -233.744617) (xy 114.392019 -233.785303)
			(xy 114.41567 -233.830366) (xy 114.431786 -233.87864) (xy 114.43995 -233.928874) (xy 114.440462 -233.95432)
			(xy 114.748559 -233.95432) (xy 114.752654 -233.903592) (xy 114.764833 -233.854178) (xy 114.784781 -233.807358)
			(xy 114.811982 -233.764344) (xy 114.84573 -233.72625) (xy 114.885152 -233.694063) (xy 114.929226 -233.668617)
			(xy 114.976812 -233.65057) (xy 115.026676 -233.64039) (xy 115.077528 -233.638341) (xy 115.128049 -233.644475)
			(xy 115.176933 -233.658635) (xy 115.222912 -233.680452) (xy 115.264796 -233.709362) (xy 115.3015 -233.744617)
			(xy 115.332073 -233.785303) (xy 115.355724 -233.830366) (xy 115.37184 -233.87864) (xy 115.380004 -233.928874)
			(xy 115.380516 -233.95432) (xy 115.380013 -233.979309) (xy 115.68733 -233.979309) (xy 115.68733 -233.929331)
			(xy 115.695149 -233.879968) (xy 115.710593 -233.832436) (xy 115.733283 -233.787904) (xy 115.762659 -233.747471)
			(xy 115.797999 -233.712131) (xy 115.838432 -233.682755) (xy 115.882964 -233.660065) (xy 115.930496 -233.644621)
			(xy 115.979859 -233.636802) (xy 116.029837 -233.636802) (xy 116.0792 -233.644621) (xy 116.126732 -233.660065)
			(xy 116.171264 -233.682755) (xy 116.211697 -233.712131) (xy 116.247037 -233.747471) (xy 116.276413 -233.787904)
			(xy 116.299103 -233.832436) (xy 116.314547 -233.879968) (xy 116.322366 -233.929331) (xy 116.322856 -233.95432)
			(xy 116.322366 -233.979309) (xy 118.507238 -233.979309) (xy 118.507238 -233.929331) (xy 118.515057 -233.879968)
			(xy 118.530501 -233.832436) (xy 118.553191 -233.787904) (xy 118.582567 -233.747471) (xy 118.617907 -233.712131)
			(xy 118.65834 -233.682755) (xy 118.702872 -233.660065) (xy 118.750404 -233.644621) (xy 118.799767 -233.636802)
			(xy 118.849745 -233.636802) (xy 118.899108 -233.644621) (xy 118.94664 -233.660065) (xy 118.991172 -233.682755)
			(xy 119.031605 -233.712131) (xy 119.066945 -233.747471) (xy 119.096321 -233.787904) (xy 119.119011 -233.832436)
			(xy 119.134455 -233.879968) (xy 119.142274 -233.929331) (xy 119.142764 -233.95432) (xy 119.142274 -233.979309)
			(xy 121.327146 -233.979309) (xy 121.327146 -233.929331) (xy 121.334965 -233.879968) (xy 121.350409 -233.832436)
			(xy 121.373099 -233.787904) (xy 121.402475 -233.747471) (xy 121.437815 -233.712131) (xy 121.478248 -233.682755)
			(xy 121.52278 -233.660065) (xy 121.570312 -233.644621) (xy 121.619675 -233.636802) (xy 121.669653 -233.636802)
			(xy 121.719016 -233.644621) (xy 121.766548 -233.660065) (xy 121.81108 -233.682755) (xy 121.851513 -233.712131)
			(xy 121.886853 -233.747471) (xy 121.916229 -233.787904) (xy 121.938919 -233.832436) (xy 121.954363 -233.879968)
			(xy 121.962182 -233.929331) (xy 121.962672 -233.95432) (xy 121.962182 -233.979309) (xy 124.147308 -233.979309)
			(xy 124.147308 -233.929331) (xy 124.155127 -233.879968) (xy 124.170571 -233.832436) (xy 124.193261 -233.787904)
			(xy 124.222637 -233.747471) (xy 124.257977 -233.712131) (xy 124.29841 -233.682755) (xy 124.342942 -233.660065)
			(xy 124.390474 -233.644621) (xy 124.439837 -233.636802) (xy 124.489815 -233.636802) (xy 124.539178 -233.644621)
			(xy 124.58671 -233.660065) (xy 124.631242 -233.682755) (xy 124.671675 -233.712131) (xy 124.707015 -233.747471)
			(xy 124.736391 -233.787904) (xy 124.759081 -233.832436) (xy 124.774525 -233.879968) (xy 124.782344 -233.929331)
			(xy 124.782834 -233.95432) (xy 124.782344 -233.979309) (xy 124.774525 -234.028672) (xy 124.759081 -234.076204)
			(xy 124.736391 -234.120736) (xy 124.707015 -234.161169) (xy 124.671675 -234.196509) (xy 124.631242 -234.225885)
			(xy 124.58671 -234.248575) (xy 124.539178 -234.264019) (xy 124.489815 -234.271838) (xy 124.439837 -234.271838)
			(xy 124.390474 -234.264019) (xy 124.342942 -234.248575) (xy 124.29841 -234.225885) (xy 124.257977 -234.196509)
			(xy 124.222637 -234.161169) (xy 124.193261 -234.120736) (xy 124.170571 -234.076204) (xy 124.155127 -234.028672)
			(xy 124.147308 -233.979309) (xy 121.962182 -233.979309) (xy 121.954363 -234.028672) (xy 121.938919 -234.076204)
			(xy 121.916229 -234.120736) (xy 121.886853 -234.161169) (xy 121.851513 -234.196509) (xy 121.81108 -234.225885)
			(xy 121.766548 -234.248575) (xy 121.719016 -234.264019) (xy 121.669653 -234.271838) (xy 121.619675 -234.271838)
			(xy 121.570312 -234.264019) (xy 121.52278 -234.248575) (xy 121.478248 -234.225885) (xy 121.437815 -234.196509)
			(xy 121.402475 -234.161169) (xy 121.373099 -234.120736) (xy 121.350409 -234.076204) (xy 121.334965 -234.028672)
			(xy 121.327146 -233.979309) (xy 119.142274 -233.979309) (xy 119.134455 -234.028672) (xy 119.119011 -234.076204)
			(xy 119.096321 -234.120736) (xy 119.066945 -234.161169) (xy 119.031605 -234.196509) (xy 118.991172 -234.225885)
			(xy 118.94664 -234.248575) (xy 118.899108 -234.264019) (xy 118.849745 -234.271838) (xy 118.799767 -234.271838)
			(xy 118.750404 -234.264019) (xy 118.702872 -234.248575) (xy 118.65834 -234.225885) (xy 118.617907 -234.196509)
			(xy 118.582567 -234.161169) (xy 118.553191 -234.120736) (xy 118.530501 -234.076204) (xy 118.515057 -234.028672)
			(xy 118.507238 -233.979309) (xy 116.322366 -233.979309) (xy 116.314547 -234.028672) (xy 116.299103 -234.076204)
			(xy 116.276413 -234.120736) (xy 116.247037 -234.161169) (xy 116.211697 -234.196509) (xy 116.171264 -234.225885)
			(xy 116.126732 -234.248575) (xy 116.0792 -234.264019) (xy 116.029837 -234.271838) (xy 115.979859 -234.271838)
			(xy 115.930496 -234.264019) (xy 115.882964 -234.248575) (xy 115.838432 -234.225885) (xy 115.797999 -234.196509)
			(xy 115.762659 -234.161169) (xy 115.733283 -234.120736) (xy 115.710593 -234.076204) (xy 115.695149 -234.028672)
			(xy 115.68733 -233.979309) (xy 115.380013 -233.979309) (xy 115.380004 -233.979766) (xy 115.37184 -234.03)
			(xy 115.355724 -234.078274) (xy 115.332073 -234.123337) (xy 115.3015 -234.164023) (xy 115.264796 -234.199278)
			(xy 115.222912 -234.228188) (xy 115.176933 -234.250005) (xy 115.128049 -234.264165) (xy 115.077528 -234.270299)
			(xy 115.026676 -234.26825) (xy 114.976812 -234.25807) (xy 114.929226 -234.240023) (xy 114.885152 -234.214577)
			(xy 114.84573 -234.18239) (xy 114.811982 -234.144296) (xy 114.784781 -234.101282) (xy 114.764833 -234.054462)
			(xy 114.752654 -234.005048) (xy 114.748559 -233.95432) (xy 114.440462 -233.95432) (xy 114.43995 -233.979766)
			(xy 114.431786 -234.03) (xy 114.41567 -234.078274) (xy 114.392019 -234.123337) (xy 114.361446 -234.164023)
			(xy 114.324742 -234.199278) (xy 114.282858 -234.228188) (xy 114.236879 -234.250005) (xy 114.187995 -234.264165)
			(xy 114.137474 -234.270299) (xy 114.086622 -234.26825) (xy 114.036758 -234.25807) (xy 113.989172 -234.240023)
			(xy 113.945098 -234.214577) (xy 113.905676 -234.18239) (xy 113.871928 -234.144296) (xy 113.844727 -234.101282)
			(xy 113.824779 -234.054462) (xy 113.8126 -234.005048) (xy 113.808505 -233.95432) (xy 113.502694 -233.95432)
			(xy 113.502204 -233.979309) (xy 113.494385 -234.028672) (xy 113.478941 -234.076204) (xy 113.456251 -234.120736)
			(xy 113.426875 -234.161169) (xy 113.391535 -234.196509) (xy 113.351102 -234.225885) (xy 113.30657 -234.248575)
			(xy 113.259038 -234.264019) (xy 113.209675 -234.271838) (xy 113.159697 -234.271838) (xy 113.110334 -234.264019)
			(xy 113.062802 -234.248575) (xy 113.01827 -234.225885) (xy 112.977837 -234.196509) (xy 112.942497 -234.161169)
			(xy 112.913121 -234.120736) (xy 112.890431 -234.076204) (xy 112.874987 -234.028672) (xy 112.867168 -233.979309)
			(xy 110.688646 -233.979309) (xy 110.680827 -234.028672) (xy 110.665383 -234.076204) (xy 110.642693 -234.120736)
			(xy 110.613317 -234.161169) (xy 110.577977 -234.196509) (xy 110.537544 -234.225885) (xy 110.493012 -234.248575)
			(xy 110.44548 -234.264019) (xy 110.396117 -234.271838) (xy 110.346139 -234.271838) (xy 110.296776 -234.264019)
			(xy 110.249244 -234.248575) (xy 110.204712 -234.225885) (xy 110.164279 -234.196509) (xy 110.128939 -234.161169)
			(xy 110.099563 -234.120736) (xy 110.076873 -234.076204) (xy 110.061429 -234.028672) (xy 110.05361 -233.979309)
			(xy 109.746293 -233.979309) (xy 109.746284 -233.979766) (xy 109.73812 -234.03) (xy 109.722004 -234.078274)
			(xy 109.698353 -234.123337) (xy 109.66778 -234.164023) (xy 109.631076 -234.199278) (xy 109.589192 -234.228188)
			(xy 109.543213 -234.250005) (xy 109.494329 -234.264165) (xy 109.443808 -234.270299) (xy 109.392956 -234.26825)
			(xy 109.343092 -234.25807) (xy 109.295506 -234.240023) (xy 109.251432 -234.214577) (xy 109.21201 -234.18239)
			(xy 109.178262 -234.144296) (xy 109.151061 -234.101282) (xy 109.131113 -234.054462) (xy 109.118934 -234.005048)
			(xy 109.114839 -233.95432) (xy 108.806742 -233.95432) (xy 108.80623 -233.979766) (xy 108.798066 -234.03)
			(xy 108.78195 -234.078274) (xy 108.758299 -234.123337) (xy 108.727726 -234.164023) (xy 108.691022 -234.199278)
			(xy 108.649138 -234.228188) (xy 108.603159 -234.250005) (xy 108.554275 -234.264165) (xy 108.503754 -234.270299)
			(xy 108.452902 -234.26825) (xy 108.403038 -234.25807) (xy 108.355452 -234.240023) (xy 108.311378 -234.214577)
			(xy 108.271956 -234.18239) (xy 108.238208 -234.144296) (xy 108.211007 -234.101282) (xy 108.191059 -234.054462)
			(xy 108.17888 -234.005048) (xy 108.174785 -233.95432) (xy 107.868974 -233.95432) (xy 107.868484 -233.979309)
			(xy 107.860665 -234.028672) (xy 107.845221 -234.076204) (xy 107.822531 -234.120736) (xy 107.793155 -234.161169)
			(xy 107.757815 -234.196509) (xy 107.717382 -234.225885) (xy 107.67285 -234.248575) (xy 107.625318 -234.264019)
			(xy 107.575955 -234.271838) (xy 107.525977 -234.271838) (xy 107.476614 -234.264019) (xy 107.429082 -234.248575)
			(xy 107.38455 -234.225885) (xy 107.344117 -234.196509) (xy 107.308777 -234.161169) (xy 107.279401 -234.120736)
			(xy 107.256711 -234.076204) (xy 107.241267 -234.028672) (xy 107.233448 -233.979309) (xy 105.048576 -233.979309)
			(xy 105.040757 -234.028672) (xy 105.025313 -234.076204) (xy 105.002623 -234.120736) (xy 104.973247 -234.161169)
			(xy 104.937907 -234.196509) (xy 104.897474 -234.225885) (xy 104.852942 -234.248575) (xy 104.80541 -234.264019)
			(xy 104.756047 -234.271838) (xy 104.706069 -234.271838) (xy 104.656706 -234.264019) (xy 104.609174 -234.248575)
			(xy 104.564642 -234.225885) (xy 104.524209 -234.196509) (xy 104.488869 -234.161169) (xy 104.459493 -234.120736)
			(xy 104.436803 -234.076204) (xy 104.421359 -234.028672) (xy 104.41354 -233.979309) (xy 102.228668 -233.979309)
			(xy 102.220849 -234.028672) (xy 102.205405 -234.076204) (xy 102.182715 -234.120736) (xy 102.153339 -234.161169)
			(xy 102.117999 -234.196509) (xy 102.077566 -234.225885) (xy 102.033034 -234.248575) (xy 101.985502 -234.264019)
			(xy 101.936139 -234.271838) (xy 101.886161 -234.271838) (xy 101.836798 -234.264019) (xy 101.789266 -234.248575)
			(xy 101.744734 -234.225885) (xy 101.704301 -234.196509) (xy 101.668961 -234.161169) (xy 101.639585 -234.120736)
			(xy 101.616895 -234.076204) (xy 101.601451 -234.028672) (xy 101.593632 -233.979309) (xy 99.408506 -233.979309)
			(xy 99.400687 -234.028672) (xy 99.385243 -234.076204) (xy 99.362553 -234.120736) (xy 99.333177 -234.161169)
			(xy 99.297837 -234.196509) (xy 99.257404 -234.225885) (xy 99.212872 -234.248575) (xy 99.16534 -234.264019)
			(xy 99.115977 -234.271838) (xy 99.065999 -234.271838) (xy 99.016636 -234.264019) (xy 98.969104 -234.248575)
			(xy 98.924572 -234.225885) (xy 98.884139 -234.196509) (xy 98.848799 -234.161169) (xy 98.819423 -234.120736)
			(xy 98.796733 -234.076204) (xy 98.781289 -234.028672) (xy 98.77347 -233.979309) (xy 97.057464 -233.979309)
			(xy 97.057464 -234.726734) (xy 97.057718 -234.731306) (xy 97.058988 -234.761786) (xy 97.058988 -234.764326)
			(xy 97.364799 -234.764326) (xy 97.368894 -234.713598) (xy 97.381073 -234.664184) (xy 97.401021 -234.617364)
			(xy 97.428222 -234.57435) (xy 97.46197 -234.536256) (xy 97.501392 -234.504069) (xy 97.545466 -234.478623)
			(xy 97.593052 -234.460576) (xy 97.642916 -234.450396) (xy 97.693768 -234.448347) (xy 97.744289 -234.454481)
			(xy 97.793173 -234.468641) (xy 97.839152 -234.490458) (xy 97.881036 -234.519368) (xy 97.91774 -234.554623)
			(xy 97.948313 -234.595309) (xy 97.971964 -234.640372) (xy 97.98808 -234.688646) (xy 97.996244 -234.73888)
			(xy 97.996756 -234.764326) (xy 98.304853 -234.764326) (xy 98.308948 -234.713598) (xy 98.321127 -234.664184)
			(xy 98.341075 -234.617364) (xy 98.368276 -234.57435) (xy 98.402024 -234.536256) (xy 98.441446 -234.504069)
			(xy 98.48552 -234.478623) (xy 98.533106 -234.460576) (xy 98.58297 -234.450396) (xy 98.633822 -234.448347)
			(xy 98.684343 -234.454481) (xy 98.733227 -234.468641) (xy 98.779206 -234.490458) (xy 98.82109 -234.519368)
			(xy 98.857794 -234.554623) (xy 98.888367 -234.595309) (xy 98.912018 -234.640372) (xy 98.928134 -234.688646)
			(xy 98.936298 -234.73888) (xy 98.93681 -234.764326) (xy 98.936307 -234.789315) (xy 99.243624 -234.789315)
			(xy 99.243624 -234.739337) (xy 99.251443 -234.689974) (xy 99.266887 -234.642442) (xy 99.289577 -234.59791)
			(xy 99.318953 -234.557477) (xy 99.354293 -234.522137) (xy 99.394726 -234.492761) (xy 99.439258 -234.470071)
			(xy 99.48679 -234.454627) (xy 99.536153 -234.446808) (xy 99.586131 -234.446808) (xy 99.635494 -234.454627)
			(xy 99.683026 -234.470071) (xy 99.727558 -234.492761) (xy 99.767991 -234.522137) (xy 99.803331 -234.557477)
			(xy 99.832707 -234.59791) (xy 99.855397 -234.642442) (xy 99.870841 -234.689974) (xy 99.87866 -234.739337)
			(xy 99.87915 -234.764326) (xy 100.184707 -234.764326) (xy 100.188802 -234.713598) (xy 100.200981 -234.664184)
			(xy 100.220929 -234.617364) (xy 100.24813 -234.57435) (xy 100.281878 -234.536256) (xy 100.3213 -234.504069)
			(xy 100.365374 -234.478623) (xy 100.41296 -234.460576) (xy 100.462824 -234.450396) (xy 100.513676 -234.448347)
			(xy 100.564197 -234.454481) (xy 100.613081 -234.468641) (xy 100.65906 -234.490458) (xy 100.700944 -234.519368)
			(xy 100.737648 -234.554623) (xy 100.768221 -234.595309) (xy 100.791872 -234.640372) (xy 100.807988 -234.688646)
			(xy 100.816152 -234.73888) (xy 100.816664 -234.764326) (xy 101.124761 -234.764326) (xy 101.128856 -234.713598)
			(xy 101.141035 -234.664184) (xy 101.160983 -234.617364) (xy 101.188184 -234.57435) (xy 101.221932 -234.536256)
			(xy 101.261354 -234.504069) (xy 101.305428 -234.478623) (xy 101.353014 -234.460576) (xy 101.402878 -234.450396)
			(xy 101.45373 -234.448347) (xy 101.504251 -234.454481) (xy 101.553135 -234.468641) (xy 101.599114 -234.490458)
			(xy 101.640998 -234.519368) (xy 101.677702 -234.554623) (xy 101.708275 -234.595309) (xy 101.731926 -234.640372)
			(xy 101.748042 -234.688646) (xy 101.756206 -234.73888) (xy 101.756718 -234.764326) (xy 101.756215 -234.789315)
			(xy 102.063532 -234.789315) (xy 102.063532 -234.739337) (xy 102.071351 -234.689974) (xy 102.086795 -234.642442)
			(xy 102.109485 -234.59791) (xy 102.138861 -234.557477) (xy 102.174201 -234.522137) (xy 102.214634 -234.492761)
			(xy 102.259166 -234.470071) (xy 102.306698 -234.454627) (xy 102.356061 -234.446808) (xy 102.406039 -234.446808)
			(xy 102.455402 -234.454627) (xy 102.502934 -234.470071) (xy 102.547466 -234.492761) (xy 102.587899 -234.522137)
			(xy 102.623239 -234.557477) (xy 102.652615 -234.59791) (xy 102.675305 -234.642442) (xy 102.690749 -234.689974)
			(xy 102.698568 -234.739337) (xy 102.699058 -234.764326) (xy 103.004869 -234.764326) (xy 103.008964 -234.713598)
			(xy 103.021143 -234.664184) (xy 103.041091 -234.617364) (xy 103.068292 -234.57435) (xy 103.10204 -234.536256)
			(xy 103.141462 -234.504069) (xy 103.185536 -234.478623) (xy 103.233122 -234.460576) (xy 103.282986 -234.450396)
			(xy 103.333838 -234.448347) (xy 103.384359 -234.454481) (xy 103.433243 -234.468641) (xy 103.479222 -234.490458)
			(xy 103.521106 -234.519368) (xy 103.55781 -234.554623) (xy 103.588383 -234.595309) (xy 103.612034 -234.640372)
			(xy 103.62815 -234.688646) (xy 103.636314 -234.73888) (xy 103.636826 -234.764326) (xy 103.944923 -234.764326)
			(xy 103.949018 -234.713598) (xy 103.961197 -234.664184) (xy 103.981145 -234.617364) (xy 104.008346 -234.57435)
			(xy 104.042094 -234.536256) (xy 104.081516 -234.504069) (xy 104.12559 -234.478623) (xy 104.173176 -234.460576)
			(xy 104.22304 -234.450396) (xy 104.273892 -234.448347) (xy 104.324413 -234.454481) (xy 104.373297 -234.468641)
			(xy 104.419276 -234.490458) (xy 104.46116 -234.519368) (xy 104.497864 -234.554623) (xy 104.528437 -234.595309)
			(xy 104.552088 -234.640372) (xy 104.568204 -234.688646) (xy 104.576368 -234.73888) (xy 104.57688 -234.764326)
			(xy 104.576377 -234.789315) (xy 104.88344 -234.789315) (xy 104.88344 -234.739337) (xy 104.891259 -234.689974)
			(xy 104.906703 -234.642442) (xy 104.929393 -234.59791) (xy 104.958769 -234.557477) (xy 104.994109 -234.522137)
			(xy 105.034542 -234.492761) (xy 105.079074 -234.470071) (xy 105.126606 -234.454627) (xy 105.175969 -234.446808)
			(xy 105.225947 -234.446808) (xy 105.27531 -234.454627) (xy 105.322842 -234.470071) (xy 105.367374 -234.492761)
			(xy 105.407807 -234.522137) (xy 105.443147 -234.557477) (xy 105.472523 -234.59791) (xy 105.495213 -234.642442)
			(xy 105.510657 -234.689974) (xy 105.518476 -234.739337) (xy 105.518966 -234.764326) (xy 105.824777 -234.764326)
			(xy 105.828872 -234.713598) (xy 105.841051 -234.664184) (xy 105.860999 -234.617364) (xy 105.8882 -234.57435)
			(xy 105.921948 -234.536256) (xy 105.96137 -234.504069) (xy 106.005444 -234.478623) (xy 106.05303 -234.460576)
			(xy 106.102894 -234.450396) (xy 106.153746 -234.448347) (xy 106.204267 -234.454481) (xy 106.253151 -234.468641)
			(xy 106.29913 -234.490458) (xy 106.341014 -234.519368) (xy 106.377718 -234.554623) (xy 106.408291 -234.595309)
			(xy 106.431942 -234.640372) (xy 106.448058 -234.688646) (xy 106.456222 -234.73888) (xy 106.456734 -234.764326)
			(xy 106.764831 -234.764326) (xy 106.768926 -234.713598) (xy 106.781105 -234.664184) (xy 106.801053 -234.617364)
			(xy 106.828254 -234.57435) (xy 106.862002 -234.536256) (xy 106.901424 -234.504069) (xy 106.945498 -234.478623)
			(xy 106.993084 -234.460576) (xy 107.042948 -234.450396) (xy 107.0938 -234.448347) (xy 107.144321 -234.454481)
			(xy 107.193205 -234.468641) (xy 107.239184 -234.490458) (xy 107.281068 -234.519368) (xy 107.317772 -234.554623)
			(xy 107.348345 -234.595309) (xy 107.371996 -234.640372) (xy 107.388112 -234.688646) (xy 107.396276 -234.73888)
			(xy 107.396788 -234.764326) (xy 107.396285 -234.789315) (xy 107.703602 -234.789315) (xy 107.703602 -234.739337)
			(xy 107.711421 -234.689974) (xy 107.726865 -234.642442) (xy 107.749555 -234.59791) (xy 107.778931 -234.557477)
			(xy 107.814271 -234.522137) (xy 107.854704 -234.492761) (xy 107.899236 -234.470071) (xy 107.946768 -234.454627)
			(xy 107.996131 -234.446808) (xy 108.046109 -234.446808) (xy 108.095472 -234.454627) (xy 108.143004 -234.470071)
			(xy 108.187536 -234.492761) (xy 108.227969 -234.522137) (xy 108.263309 -234.557477) (xy 108.292685 -234.59791)
			(xy 108.315375 -234.642442) (xy 108.330819 -234.689974) (xy 108.338638 -234.739337) (xy 108.339128 -234.764326)
			(xy 108.338638 -234.789315) (xy 115.217176 -234.789315) (xy 115.217176 -234.739337) (xy 115.224995 -234.689974)
			(xy 115.240439 -234.642442) (xy 115.263129 -234.59791) (xy 115.292505 -234.557477) (xy 115.327845 -234.522137)
			(xy 115.368278 -234.492761) (xy 115.41281 -234.470071) (xy 115.460342 -234.454627) (xy 115.509705 -234.446808)
			(xy 115.559683 -234.446808) (xy 115.609046 -234.454627) (xy 115.656578 -234.470071) (xy 115.70111 -234.492761)
			(xy 115.741543 -234.522137) (xy 115.776883 -234.557477) (xy 115.806259 -234.59791) (xy 115.828949 -234.642442)
			(xy 115.844393 -234.689974) (xy 115.852212 -234.739337) (xy 115.852702 -234.764326) (xy 116.158513 -234.764326)
			(xy 116.162608 -234.713598) (xy 116.174787 -234.664184) (xy 116.194735 -234.617364) (xy 116.221936 -234.57435)
			(xy 116.255684 -234.536256) (xy 116.295106 -234.504069) (xy 116.33918 -234.478623) (xy 116.386766 -234.460576)
			(xy 116.43663 -234.450396) (xy 116.487482 -234.448347) (xy 116.538003 -234.454481) (xy 116.586887 -234.468641)
			(xy 116.632866 -234.490458) (xy 116.67475 -234.519368) (xy 116.711454 -234.554623) (xy 116.742027 -234.595309)
			(xy 116.765678 -234.640372) (xy 116.781794 -234.688646) (xy 116.789958 -234.73888) (xy 116.79047 -234.764326)
			(xy 117.098567 -234.764326) (xy 117.102662 -234.713598) (xy 117.114841 -234.664184) (xy 117.134789 -234.617364)
			(xy 117.16199 -234.57435) (xy 117.195738 -234.536256) (xy 117.23516 -234.504069) (xy 117.279234 -234.478623)
			(xy 117.32682 -234.460576) (xy 117.376684 -234.450396) (xy 117.427536 -234.448347) (xy 117.478057 -234.454481)
			(xy 117.526941 -234.468641) (xy 117.57292 -234.490458) (xy 117.614804 -234.519368) (xy 117.651508 -234.554623)
			(xy 117.682081 -234.595309) (xy 117.705732 -234.640372) (xy 117.721848 -234.688646) (xy 117.730012 -234.73888)
			(xy 117.730524 -234.764326) (xy 117.730021 -234.789315) (xy 118.037338 -234.789315) (xy 118.037338 -234.739337)
			(xy 118.045157 -234.689974) (xy 118.060601 -234.642442) (xy 118.083291 -234.59791) (xy 118.112667 -234.557477)
			(xy 118.148007 -234.522137) (xy 118.18844 -234.492761) (xy 118.232972 -234.470071) (xy 118.280504 -234.454627)
			(xy 118.329867 -234.446808) (xy 118.379845 -234.446808) (xy 118.429208 -234.454627) (xy 118.47674 -234.470071)
			(xy 118.521272 -234.492761) (xy 118.561705 -234.522137) (xy 118.597045 -234.557477) (xy 118.626421 -234.59791)
			(xy 118.649111 -234.642442) (xy 118.664555 -234.689974) (xy 118.672374 -234.739337) (xy 118.672864 -234.764326)
			(xy 118.978421 -234.764326) (xy 118.982516 -234.713598) (xy 118.994695 -234.664184) (xy 119.014643 -234.617364)
			(xy 119.041844 -234.57435) (xy 119.075592 -234.536256) (xy 119.115014 -234.504069) (xy 119.159088 -234.478623)
			(xy 119.206674 -234.460576) (xy 119.256538 -234.450396) (xy 119.30739 -234.448347) (xy 119.357911 -234.454481)
			(xy 119.406795 -234.468641) (xy 119.452774 -234.490458) (xy 119.494658 -234.519368) (xy 119.531362 -234.554623)
			(xy 119.561935 -234.595309) (xy 119.585586 -234.640372) (xy 119.601702 -234.688646) (xy 119.609866 -234.73888)
			(xy 119.610378 -234.764326) (xy 119.918475 -234.764326) (xy 119.92257 -234.713598) (xy 119.934749 -234.664184)
			(xy 119.954697 -234.617364) (xy 119.981898 -234.57435) (xy 120.015646 -234.536256) (xy 120.055068 -234.504069)
			(xy 120.099142 -234.478623) (xy 120.146728 -234.460576) (xy 120.196592 -234.450396) (xy 120.247444 -234.448347)
			(xy 120.297965 -234.454481) (xy 120.346849 -234.468641) (xy 120.392828 -234.490458) (xy 120.434712 -234.519368)
			(xy 120.471416 -234.554623) (xy 120.501989 -234.595309) (xy 120.52564 -234.640372) (xy 120.541756 -234.688646)
			(xy 120.54992 -234.73888) (xy 120.550432 -234.764326) (xy 120.549929 -234.789315) (xy 120.857246 -234.789315)
			(xy 120.857246 -234.739337) (xy 120.865065 -234.689974) (xy 120.880509 -234.642442) (xy 120.903199 -234.59791)
			(xy 120.932575 -234.557477) (xy 120.967915 -234.522137) (xy 121.008348 -234.492761) (xy 121.05288 -234.470071)
			(xy 121.100412 -234.454627) (xy 121.149775 -234.446808) (xy 121.199753 -234.446808) (xy 121.249116 -234.454627)
			(xy 121.296648 -234.470071) (xy 121.34118 -234.492761) (xy 121.381613 -234.522137) (xy 121.416953 -234.557477)
			(xy 121.446329 -234.59791) (xy 121.469019 -234.642442) (xy 121.484463 -234.689974) (xy 121.492282 -234.739337)
			(xy 121.492772 -234.764326) (xy 121.798583 -234.764326) (xy 121.802678 -234.713598) (xy 121.814857 -234.664184)
			(xy 121.834805 -234.617364) (xy 121.862006 -234.57435) (xy 121.895754 -234.536256) (xy 121.935176 -234.504069)
			(xy 121.97925 -234.478623) (xy 122.026836 -234.460576) (xy 122.0767 -234.450396) (xy 122.127552 -234.448347)
			(xy 122.178073 -234.454481) (xy 122.226957 -234.468641) (xy 122.272936 -234.490458) (xy 122.31482 -234.519368)
			(xy 122.351524 -234.554623) (xy 122.382097 -234.595309) (xy 122.405748 -234.640372) (xy 122.421864 -234.688646)
			(xy 122.430028 -234.73888) (xy 122.43054 -234.764326) (xy 122.738383 -234.764326) (xy 122.742478 -234.713598)
			(xy 122.754657 -234.664184) (xy 122.774605 -234.617364) (xy 122.801806 -234.57435) (xy 122.835554 -234.536256)
			(xy 122.874976 -234.504069) (xy 122.91905 -234.478623) (xy 122.966636 -234.460576) (xy 123.0165 -234.450396)
			(xy 123.067352 -234.448347) (xy 123.117873 -234.454481) (xy 123.166757 -234.468641) (xy 123.212736 -234.490458)
			(xy 123.25462 -234.519368) (xy 123.291324 -234.554623) (xy 123.321897 -234.595309) (xy 123.345548 -234.640372)
			(xy 123.361664 -234.688646) (xy 123.369828 -234.73888) (xy 123.37034 -234.764326) (xy 123.369837 -234.789315)
			(xy 123.677154 -234.789315) (xy 123.677154 -234.739337) (xy 123.684973 -234.689974) (xy 123.700417 -234.642442)
			(xy 123.723107 -234.59791) (xy 123.752483 -234.557477) (xy 123.787823 -234.522137) (xy 123.828256 -234.492761)
			(xy 123.872788 -234.470071) (xy 123.92032 -234.454627) (xy 123.969683 -234.446808) (xy 124.019661 -234.446808)
			(xy 124.069024 -234.454627) (xy 124.116556 -234.470071) (xy 124.161088 -234.492761) (xy 124.201521 -234.522137)
			(xy 124.236861 -234.557477) (xy 124.266237 -234.59791) (xy 124.288927 -234.642442) (xy 124.304371 -234.689974)
			(xy 124.31219 -234.739337) (xy 124.31268 -234.764326) (xy 124.618491 -234.764326) (xy 124.622586 -234.713598)
			(xy 124.634765 -234.664184) (xy 124.654713 -234.617364) (xy 124.681914 -234.57435) (xy 124.715662 -234.536256)
			(xy 124.755084 -234.504069) (xy 124.799158 -234.478623) (xy 124.846744 -234.460576) (xy 124.896608 -234.450396)
			(xy 124.94746 -234.448347) (xy 124.997981 -234.454481) (xy 125.046865 -234.468641) (xy 125.092844 -234.490458)
			(xy 125.134728 -234.519368) (xy 125.171432 -234.554623) (xy 125.202005 -234.595309) (xy 125.225656 -234.640372)
			(xy 125.241772 -234.688646) (xy 125.249936 -234.73888) (xy 125.250448 -234.764326) (xy 125.558545 -234.764326)
			(xy 125.56264 -234.713598) (xy 125.574819 -234.664184) (xy 125.594767 -234.617364) (xy 125.621968 -234.57435)
			(xy 125.655716 -234.536256) (xy 125.695138 -234.504069) (xy 125.739212 -234.478623) (xy 125.786798 -234.460576)
			(xy 125.836662 -234.450396) (xy 125.887514 -234.448347) (xy 125.938035 -234.454481) (xy 125.986919 -234.468641)
			(xy 126.032898 -234.490458) (xy 126.074782 -234.519368) (xy 126.111486 -234.554623) (xy 126.142059 -234.595309)
			(xy 126.16571 -234.640372) (xy 126.181826 -234.688646) (xy 126.18999 -234.73888) (xy 126.190502 -234.764326)
			(xy 126.18999 -234.789772) (xy 126.181826 -234.840006) (xy 126.16571 -234.88828) (xy 126.142059 -234.933343)
			(xy 126.111486 -234.974029) (xy 126.074782 -235.009284) (xy 126.032898 -235.038194) (xy 125.986919 -235.060011)
			(xy 125.938035 -235.074171) (xy 125.887514 -235.080305) (xy 125.836662 -235.078256) (xy 125.786798 -235.068076)
			(xy 125.739212 -235.050029) (xy 125.695138 -235.024583) (xy 125.655716 -234.992396) (xy 125.621968 -234.954302)
			(xy 125.594767 -234.911288) (xy 125.574819 -234.864468) (xy 125.56264 -234.815054) (xy 125.558545 -234.764326)
			(xy 125.250448 -234.764326) (xy 125.249936 -234.789772) (xy 125.241772 -234.840006) (xy 125.225656 -234.88828)
			(xy 125.202005 -234.933343) (xy 125.171432 -234.974029) (xy 125.134728 -235.009284) (xy 125.092844 -235.038194)
			(xy 125.046865 -235.060011) (xy 124.997981 -235.074171) (xy 124.94746 -235.080305) (xy 124.896608 -235.078256)
			(xy 124.846744 -235.068076) (xy 124.799158 -235.050029) (xy 124.755084 -235.024583) (xy 124.715662 -234.992396)
			(xy 124.681914 -234.954302) (xy 124.654713 -234.911288) (xy 124.634765 -234.864468) (xy 124.622586 -234.815054)
			(xy 124.618491 -234.764326) (xy 124.31268 -234.764326) (xy 124.31219 -234.789315) (xy 124.304371 -234.838678)
			(xy 124.288927 -234.88621) (xy 124.266237 -234.930742) (xy 124.236861 -234.971175) (xy 124.201521 -235.006515)
			(xy 124.161088 -235.035891) (xy 124.116556 -235.058581) (xy 124.069024 -235.074025) (xy 124.019661 -235.081844)
			(xy 123.969683 -235.081844) (xy 123.92032 -235.074025) (xy 123.872788 -235.058581) (xy 123.828256 -235.035891)
			(xy 123.787823 -235.006515) (xy 123.752483 -234.971175) (xy 123.723107 -234.930742) (xy 123.700417 -234.88621)
			(xy 123.684973 -234.838678) (xy 123.677154 -234.789315) (xy 123.369837 -234.789315) (xy 123.369828 -234.789772)
			(xy 123.361664 -234.840006) (xy 123.345548 -234.88828) (xy 123.321897 -234.933343) (xy 123.291324 -234.974029)
			(xy 123.25462 -235.009284) (xy 123.212736 -235.038194) (xy 123.166757 -235.060011) (xy 123.117873 -235.074171)
			(xy 123.067352 -235.080305) (xy 123.0165 -235.078256) (xy 122.966636 -235.068076) (xy 122.91905 -235.050029)
			(xy 122.874976 -235.024583) (xy 122.835554 -234.992396) (xy 122.801806 -234.954302) (xy 122.774605 -234.911288)
			(xy 122.754657 -234.864468) (xy 122.742478 -234.815054) (xy 122.738383 -234.764326) (xy 122.43054 -234.764326)
			(xy 122.430028 -234.789772) (xy 122.421864 -234.840006) (xy 122.405748 -234.88828) (xy 122.382097 -234.933343)
			(xy 122.351524 -234.974029) (xy 122.31482 -235.009284) (xy 122.272936 -235.038194) (xy 122.226957 -235.060011)
			(xy 122.178073 -235.074171) (xy 122.127552 -235.080305) (xy 122.0767 -235.078256) (xy 122.026836 -235.068076)
			(xy 121.97925 -235.050029) (xy 121.935176 -235.024583) (xy 121.895754 -234.992396) (xy 121.862006 -234.954302)
			(xy 121.834805 -234.911288) (xy 121.814857 -234.864468) (xy 121.802678 -234.815054) (xy 121.798583 -234.764326)
			(xy 121.492772 -234.764326) (xy 121.492282 -234.789315) (xy 121.484463 -234.838678) (xy 121.469019 -234.88621)
			(xy 121.446329 -234.930742) (xy 121.416953 -234.971175) (xy 121.381613 -235.006515) (xy 121.34118 -235.035891)
			(xy 121.296648 -235.058581) (xy 121.249116 -235.074025) (xy 121.199753 -235.081844) (xy 121.149775 -235.081844)
			(xy 121.100412 -235.074025) (xy 121.05288 -235.058581) (xy 121.008348 -235.035891) (xy 120.967915 -235.006515)
			(xy 120.932575 -234.971175) (xy 120.903199 -234.930742) (xy 120.880509 -234.88621) (xy 120.865065 -234.838678)
			(xy 120.857246 -234.789315) (xy 120.549929 -234.789315) (xy 120.54992 -234.789772) (xy 120.541756 -234.840006)
			(xy 120.52564 -234.88828) (xy 120.501989 -234.933343) (xy 120.471416 -234.974029) (xy 120.434712 -235.009284)
			(xy 120.392828 -235.038194) (xy 120.346849 -235.060011) (xy 120.297965 -235.074171) (xy 120.247444 -235.080305)
			(xy 120.196592 -235.078256) (xy 120.146728 -235.068076) (xy 120.099142 -235.050029) (xy 120.055068 -235.024583)
			(xy 120.015646 -234.992396) (xy 119.981898 -234.954302) (xy 119.954697 -234.911288) (xy 119.934749 -234.864468)
			(xy 119.92257 -234.815054) (xy 119.918475 -234.764326) (xy 119.610378 -234.764326) (xy 119.609866 -234.789772)
			(xy 119.601702 -234.840006) (xy 119.585586 -234.88828) (xy 119.561935 -234.933343) (xy 119.531362 -234.974029)
			(xy 119.494658 -235.009284) (xy 119.452774 -235.038194) (xy 119.406795 -235.060011) (xy 119.357911 -235.074171)
			(xy 119.30739 -235.080305) (xy 119.256538 -235.078256) (xy 119.206674 -235.068076) (xy 119.159088 -235.050029)
			(xy 119.115014 -235.024583) (xy 119.075592 -234.992396) (xy 119.041844 -234.954302) (xy 119.014643 -234.911288)
			(xy 118.994695 -234.864468) (xy 118.982516 -234.815054) (xy 118.978421 -234.764326) (xy 118.672864 -234.764326)
			(xy 118.672374 -234.789315) (xy 118.664555 -234.838678) (xy 118.649111 -234.88621) (xy 118.626421 -234.930742)
			(xy 118.597045 -234.971175) (xy 118.561705 -235.006515) (xy 118.521272 -235.035891) (xy 118.47674 -235.058581)
			(xy 118.429208 -235.074025) (xy 118.379845 -235.081844) (xy 118.329867 -235.081844) (xy 118.280504 -235.074025)
			(xy 118.232972 -235.058581) (xy 118.18844 -235.035891) (xy 118.148007 -235.006515) (xy 118.112667 -234.971175)
			(xy 118.083291 -234.930742) (xy 118.060601 -234.88621) (xy 118.045157 -234.838678) (xy 118.037338 -234.789315)
			(xy 117.730021 -234.789315) (xy 117.730012 -234.789772) (xy 117.721848 -234.840006) (xy 117.705732 -234.88828)
			(xy 117.682081 -234.933343) (xy 117.651508 -234.974029) (xy 117.614804 -235.009284) (xy 117.57292 -235.038194)
			(xy 117.526941 -235.060011) (xy 117.478057 -235.074171) (xy 117.427536 -235.080305) (xy 117.376684 -235.078256)
			(xy 117.32682 -235.068076) (xy 117.279234 -235.050029) (xy 117.23516 -235.024583) (xy 117.195738 -234.992396)
			(xy 117.16199 -234.954302) (xy 117.134789 -234.911288) (xy 117.114841 -234.864468) (xy 117.102662 -234.815054)
			(xy 117.098567 -234.764326) (xy 116.79047 -234.764326) (xy 116.789958 -234.789772) (xy 116.781794 -234.840006)
			(xy 116.765678 -234.88828) (xy 116.742027 -234.933343) (xy 116.711454 -234.974029) (xy 116.67475 -235.009284)
			(xy 116.632866 -235.038194) (xy 116.586887 -235.060011) (xy 116.538003 -235.074171) (xy 116.487482 -235.080305)
			(xy 116.43663 -235.078256) (xy 116.386766 -235.068076) (xy 116.33918 -235.050029) (xy 116.295106 -235.024583)
			(xy 116.255684 -234.992396) (xy 116.221936 -234.954302) (xy 116.194735 -234.911288) (xy 116.174787 -234.864468)
			(xy 116.162608 -234.815054) (xy 116.158513 -234.764326) (xy 115.852702 -234.764326) (xy 115.852212 -234.789315)
			(xy 115.844393 -234.838678) (xy 115.828949 -234.88621) (xy 115.806259 -234.930742) (xy 115.776883 -234.971175)
			(xy 115.741543 -235.006515) (xy 115.70111 -235.035891) (xy 115.656578 -235.058581) (xy 115.609046 -235.074025)
			(xy 115.559683 -235.081844) (xy 115.509705 -235.081844) (xy 115.460342 -235.074025) (xy 115.41281 -235.058581)
			(xy 115.368278 -235.035891) (xy 115.327845 -235.006515) (xy 115.292505 -234.971175) (xy 115.263129 -234.930742)
			(xy 115.240439 -234.88621) (xy 115.224995 -234.838678) (xy 115.217176 -234.789315) (xy 108.338638 -234.789315)
			(xy 108.330819 -234.838678) (xy 108.315375 -234.88621) (xy 108.292685 -234.930742) (xy 108.263309 -234.971175)
			(xy 108.227969 -235.006515) (xy 108.187536 -235.035891) (xy 108.143004 -235.058581) (xy 108.095472 -235.074025)
			(xy 108.046109 -235.081844) (xy 107.996131 -235.081844) (xy 107.946768 -235.074025) (xy 107.899236 -235.058581)
			(xy 107.854704 -235.035891) (xy 107.814271 -235.006515) (xy 107.778931 -234.971175) (xy 107.749555 -234.930742)
			(xy 107.726865 -234.88621) (xy 107.711421 -234.838678) (xy 107.703602 -234.789315) (xy 107.396285 -234.789315)
			(xy 107.396276 -234.789772) (xy 107.388112 -234.840006) (xy 107.371996 -234.88828) (xy 107.348345 -234.933343)
			(xy 107.317772 -234.974029) (xy 107.281068 -235.009284) (xy 107.239184 -235.038194) (xy 107.193205 -235.060011)
			(xy 107.144321 -235.074171) (xy 107.0938 -235.080305) (xy 107.042948 -235.078256) (xy 106.993084 -235.068076)
			(xy 106.945498 -235.050029) (xy 106.901424 -235.024583) (xy 106.862002 -234.992396) (xy 106.828254 -234.954302)
			(xy 106.801053 -234.911288) (xy 106.781105 -234.864468) (xy 106.768926 -234.815054) (xy 106.764831 -234.764326)
			(xy 106.456734 -234.764326) (xy 106.456222 -234.789772) (xy 106.448058 -234.840006) (xy 106.431942 -234.88828)
			(xy 106.408291 -234.933343) (xy 106.377718 -234.974029) (xy 106.341014 -235.009284) (xy 106.29913 -235.038194)
			(xy 106.253151 -235.060011) (xy 106.204267 -235.074171) (xy 106.153746 -235.080305) (xy 106.102894 -235.078256)
			(xy 106.05303 -235.068076) (xy 106.005444 -235.050029) (xy 105.96137 -235.024583) (xy 105.921948 -234.992396)
			(xy 105.8882 -234.954302) (xy 105.860999 -234.911288) (xy 105.841051 -234.864468) (xy 105.828872 -234.815054)
			(xy 105.824777 -234.764326) (xy 105.518966 -234.764326) (xy 105.518476 -234.789315) (xy 105.510657 -234.838678)
			(xy 105.495213 -234.88621) (xy 105.472523 -234.930742) (xy 105.443147 -234.971175) (xy 105.407807 -235.006515)
			(xy 105.367374 -235.035891) (xy 105.322842 -235.058581) (xy 105.27531 -235.074025) (xy 105.225947 -235.081844)
			(xy 105.175969 -235.081844) (xy 105.126606 -235.074025) (xy 105.079074 -235.058581) (xy 105.034542 -235.035891)
			(xy 104.994109 -235.006515) (xy 104.958769 -234.971175) (xy 104.929393 -234.930742) (xy 104.906703 -234.88621)
			(xy 104.891259 -234.838678) (xy 104.88344 -234.789315) (xy 104.576377 -234.789315) (xy 104.576368 -234.789772)
			(xy 104.568204 -234.840006) (xy 104.552088 -234.88828) (xy 104.528437 -234.933343) (xy 104.497864 -234.974029)
			(xy 104.46116 -235.009284) (xy 104.419276 -235.038194) (xy 104.373297 -235.060011) (xy 104.324413 -235.074171)
			(xy 104.273892 -235.080305) (xy 104.22304 -235.078256) (xy 104.173176 -235.068076) (xy 104.12559 -235.050029)
			(xy 104.081516 -235.024583) (xy 104.042094 -234.992396) (xy 104.008346 -234.954302) (xy 103.981145 -234.911288)
			(xy 103.961197 -234.864468) (xy 103.949018 -234.815054) (xy 103.944923 -234.764326) (xy 103.636826 -234.764326)
			(xy 103.636314 -234.789772) (xy 103.62815 -234.840006) (xy 103.612034 -234.88828) (xy 103.588383 -234.933343)
			(xy 103.55781 -234.974029) (xy 103.521106 -235.009284) (xy 103.479222 -235.038194) (xy 103.433243 -235.060011)
			(xy 103.384359 -235.074171) (xy 103.333838 -235.080305) (xy 103.282986 -235.078256) (xy 103.233122 -235.068076)
			(xy 103.185536 -235.050029) (xy 103.141462 -235.024583) (xy 103.10204 -234.992396) (xy 103.068292 -234.954302)
			(xy 103.041091 -234.911288) (xy 103.021143 -234.864468) (xy 103.008964 -234.815054) (xy 103.004869 -234.764326)
			(xy 102.699058 -234.764326) (xy 102.698568 -234.789315) (xy 102.690749 -234.838678) (xy 102.675305 -234.88621)
			(xy 102.652615 -234.930742) (xy 102.623239 -234.971175) (xy 102.587899 -235.006515) (xy 102.547466 -235.035891)
			(xy 102.502934 -235.058581) (xy 102.455402 -235.074025) (xy 102.406039 -235.081844) (xy 102.356061 -235.081844)
			(xy 102.306698 -235.074025) (xy 102.259166 -235.058581) (xy 102.214634 -235.035891) (xy 102.174201 -235.006515)
			(xy 102.138861 -234.971175) (xy 102.109485 -234.930742) (xy 102.086795 -234.88621) (xy 102.071351 -234.838678)
			(xy 102.063532 -234.789315) (xy 101.756215 -234.789315) (xy 101.756206 -234.789772) (xy 101.748042 -234.840006)
			(xy 101.731926 -234.88828) (xy 101.708275 -234.933343) (xy 101.677702 -234.974029) (xy 101.640998 -235.009284)
			(xy 101.599114 -235.038194) (xy 101.553135 -235.060011) (xy 101.504251 -235.074171) (xy 101.45373 -235.080305)
			(xy 101.402878 -235.078256) (xy 101.353014 -235.068076) (xy 101.305428 -235.050029) (xy 101.261354 -235.024583)
			(xy 101.221932 -234.992396) (xy 101.188184 -234.954302) (xy 101.160983 -234.911288) (xy 101.141035 -234.864468)
			(xy 101.128856 -234.815054) (xy 101.124761 -234.764326) (xy 100.816664 -234.764326) (xy 100.816152 -234.789772)
			(xy 100.807988 -234.840006) (xy 100.791872 -234.88828) (xy 100.768221 -234.933343) (xy 100.737648 -234.974029)
			(xy 100.700944 -235.009284) (xy 100.65906 -235.038194) (xy 100.613081 -235.060011) (xy 100.564197 -235.074171)
			(xy 100.513676 -235.080305) (xy 100.462824 -235.078256) (xy 100.41296 -235.068076) (xy 100.365374 -235.050029)
			(xy 100.3213 -235.024583) (xy 100.281878 -234.992396) (xy 100.24813 -234.954302) (xy 100.220929 -234.911288)
			(xy 100.200981 -234.864468) (xy 100.188802 -234.815054) (xy 100.184707 -234.764326) (xy 99.87915 -234.764326)
			(xy 99.87866 -234.789315) (xy 99.870841 -234.838678) (xy 99.855397 -234.88621) (xy 99.832707 -234.930742)
			(xy 99.803331 -234.971175) (xy 99.767991 -235.006515) (xy 99.727558 -235.035891) (xy 99.683026 -235.058581)
			(xy 99.635494 -235.074025) (xy 99.586131 -235.081844) (xy 99.536153 -235.081844) (xy 99.48679 -235.074025)
			(xy 99.439258 -235.058581) (xy 99.394726 -235.035891) (xy 99.354293 -235.006515) (xy 99.318953 -234.971175)
			(xy 99.289577 -234.930742) (xy 99.266887 -234.88621) (xy 99.251443 -234.838678) (xy 99.243624 -234.789315)
			(xy 98.936307 -234.789315) (xy 98.936298 -234.789772) (xy 98.928134 -234.840006) (xy 98.912018 -234.88828)
			(xy 98.888367 -234.933343) (xy 98.857794 -234.974029) (xy 98.82109 -235.009284) (xy 98.779206 -235.038194)
			(xy 98.733227 -235.060011) (xy 98.684343 -235.074171) (xy 98.633822 -235.080305) (xy 98.58297 -235.078256)
			(xy 98.533106 -235.068076) (xy 98.48552 -235.050029) (xy 98.441446 -235.024583) (xy 98.402024 -234.992396)
			(xy 98.368276 -234.954302) (xy 98.341075 -234.911288) (xy 98.321127 -234.864468) (xy 98.308948 -234.815054)
			(xy 98.304853 -234.764326) (xy 97.996756 -234.764326) (xy 97.996244 -234.789772) (xy 97.98808 -234.840006)
			(xy 97.971964 -234.88828) (xy 97.948313 -234.933343) (xy 97.91774 -234.974029) (xy 97.881036 -235.009284)
			(xy 97.839152 -235.038194) (xy 97.793173 -235.060011) (xy 97.744289 -235.074171) (xy 97.693768 -235.080305)
			(xy 97.642916 -235.078256) (xy 97.593052 -235.068076) (xy 97.545466 -235.050029) (xy 97.501392 -235.024583)
			(xy 97.46197 -234.992396) (xy 97.428222 -234.954302) (xy 97.401021 -234.911288) (xy 97.381073 -234.864468)
			(xy 97.368894 -234.815054) (xy 97.364799 -234.764326) (xy 97.058988 -234.764326) (xy 97.058988 -234.767882)
			(xy 97.057718 -234.797854) (xy 97.057464 -234.799378) (xy 97.057464 -235.161074) (xy 97.05825 -235.170849)
			(xy 97.066216 -235.188751) (xy 97.072958 -235.195872) (xy 97.124266 -235.24083) (xy 97.124774 -235.241338)
			(xy 97.138744 -235.253784) (xy 97.149666 -235.256832) (xy 97.160588 -235.260134) (xy 97.17151 -235.258864)
			(xy 97.181374 -235.257686) (xy 97.2012 -235.256414) (xy 97.211134 -235.256324) (xy 97.211388 -235.256324)
			(xy 97.23636 -235.256836) (xy 97.285683 -235.264689) (xy 97.333172 -235.280157) (xy 97.377659 -235.30286)
			(xy 97.418049 -235.332238) (xy 97.453349 -235.367571) (xy 97.482691 -235.407987) (xy 97.505353 -235.452494)
			(xy 97.520778 -235.499997) (xy 97.528587 -235.549328) (xy 97.528587 -235.599272) (xy 97.528579 -235.599321)
			(xy 97.833416 -235.599321) (xy 97.833416 -235.549343) (xy 97.841235 -235.49998) (xy 97.856679 -235.452448)
			(xy 97.879369 -235.407916) (xy 97.908745 -235.367483) (xy 97.944085 -235.332143) (xy 97.984518 -235.302767)
			(xy 98.02905 -235.280077) (xy 98.076582 -235.264633) (xy 98.125945 -235.256814) (xy 98.175923 -235.256814)
			(xy 98.225286 -235.264633) (xy 98.272818 -235.280077) (xy 98.31735 -235.302767) (xy 98.357783 -235.332143)
			(xy 98.393123 -235.367483) (xy 98.422499 -235.407916) (xy 98.445189 -235.452448) (xy 98.460633 -235.49998)
			(xy 98.468452 -235.549343) (xy 98.468942 -235.574332) (xy 98.468452 -235.599321) (xy 98.77347 -235.599321)
			(xy 98.77347 -235.549343) (xy 98.781289 -235.49998) (xy 98.796733 -235.452448) (xy 98.819423 -235.407916)
			(xy 98.848799 -235.367483) (xy 98.884139 -235.332143) (xy 98.924572 -235.302767) (xy 98.969104 -235.280077)
			(xy 99.016636 -235.264633) (xy 99.065999 -235.256814) (xy 99.115977 -235.256814) (xy 99.16534 -235.264633)
			(xy 99.212872 -235.280077) (xy 99.257404 -235.302767) (xy 99.297837 -235.332143) (xy 99.333177 -235.367483)
			(xy 99.362553 -235.407916) (xy 99.385243 -235.452448) (xy 99.400687 -235.49998) (xy 99.408506 -235.549343)
			(xy 99.408996 -235.574332) (xy 99.408506 -235.599321) (xy 99.713524 -235.599321) (xy 99.713524 -235.549343)
			(xy 99.721343 -235.49998) (xy 99.736787 -235.452448) (xy 99.759477 -235.407916) (xy 99.788853 -235.367483)
			(xy 99.824193 -235.332143) (xy 99.864626 -235.302767) (xy 99.909158 -235.280077) (xy 99.95669 -235.264633)
			(xy 100.006053 -235.256814) (xy 100.056031 -235.256814) (xy 100.105394 -235.264633) (xy 100.152926 -235.280077)
			(xy 100.197458 -235.302767) (xy 100.237891 -235.332143) (xy 100.273231 -235.367483) (xy 100.302607 -235.407916)
			(xy 100.325297 -235.452448) (xy 100.340741 -235.49998) (xy 100.34856 -235.549343) (xy 100.34905 -235.574332)
			(xy 100.34856 -235.599321) (xy 100.653578 -235.599321) (xy 100.653578 -235.549343) (xy 100.661397 -235.49998)
			(xy 100.676841 -235.452448) (xy 100.699531 -235.407916) (xy 100.728907 -235.367483) (xy 100.764247 -235.332143)
			(xy 100.80468 -235.302767) (xy 100.849212 -235.280077) (xy 100.896744 -235.264633) (xy 100.946107 -235.256814)
			(xy 100.996085 -235.256814) (xy 101.045448 -235.264633) (xy 101.09298 -235.280077) (xy 101.137512 -235.302767)
			(xy 101.177945 -235.332143) (xy 101.213285 -235.367483) (xy 101.242661 -235.407916) (xy 101.265351 -235.452448)
			(xy 101.280795 -235.49998) (xy 101.288614 -235.549343) (xy 101.289104 -235.574332) (xy 101.288614 -235.599321)
			(xy 101.593632 -235.599321) (xy 101.593632 -235.549343) (xy 101.601451 -235.49998) (xy 101.616895 -235.452448)
			(xy 101.639585 -235.407916) (xy 101.668961 -235.367483) (xy 101.704301 -235.332143) (xy 101.744734 -235.302767)
			(xy 101.789266 -235.280077) (xy 101.836798 -235.264633) (xy 101.886161 -235.256814) (xy 101.936139 -235.256814)
			(xy 101.985502 -235.264633) (xy 102.033034 -235.280077) (xy 102.077566 -235.302767) (xy 102.117999 -235.332143)
			(xy 102.153339 -235.367483) (xy 102.182715 -235.407916) (xy 102.205405 -235.452448) (xy 102.220849 -235.49998)
			(xy 102.228668 -235.549343) (xy 102.229158 -235.574332) (xy 102.228668 -235.599321) (xy 102.533432 -235.599321)
			(xy 102.533432 -235.549343) (xy 102.541251 -235.49998) (xy 102.556695 -235.452448) (xy 102.579385 -235.407916)
			(xy 102.608761 -235.367483) (xy 102.644101 -235.332143) (xy 102.684534 -235.302767) (xy 102.729066 -235.280077)
			(xy 102.776598 -235.264633) (xy 102.825961 -235.256814) (xy 102.875939 -235.256814) (xy 102.925302 -235.264633)
			(xy 102.972834 -235.280077) (xy 103.017366 -235.302767) (xy 103.057799 -235.332143) (xy 103.093139 -235.367483)
			(xy 103.122515 -235.407916) (xy 103.145205 -235.452448) (xy 103.160649 -235.49998) (xy 103.168468 -235.549343)
			(xy 103.168958 -235.574332) (xy 103.168468 -235.599321) (xy 103.473486 -235.599321) (xy 103.473486 -235.549343)
			(xy 103.481305 -235.49998) (xy 103.496749 -235.452448) (xy 103.519439 -235.407916) (xy 103.548815 -235.367483)
			(xy 103.584155 -235.332143) (xy 103.624588 -235.302767) (xy 103.66912 -235.280077) (xy 103.716652 -235.264633)
			(xy 103.766015 -235.256814) (xy 103.815993 -235.256814) (xy 103.865356 -235.264633) (xy 103.912888 -235.280077)
			(xy 103.95742 -235.302767) (xy 103.997853 -235.332143) (xy 104.033193 -235.367483) (xy 104.062569 -235.407916)
			(xy 104.085259 -235.452448) (xy 104.100703 -235.49998) (xy 104.108522 -235.549343) (xy 104.109012 -235.574332)
			(xy 104.108522 -235.599321) (xy 104.41354 -235.599321) (xy 104.41354 -235.549343) (xy 104.421359 -235.49998)
			(xy 104.436803 -235.452448) (xy 104.459493 -235.407916) (xy 104.488869 -235.367483) (xy 104.524209 -235.332143)
			(xy 104.564642 -235.302767) (xy 104.609174 -235.280077) (xy 104.656706 -235.264633) (xy 104.706069 -235.256814)
			(xy 104.756047 -235.256814) (xy 104.80541 -235.264633) (xy 104.852942 -235.280077) (xy 104.897474 -235.302767)
			(xy 104.937907 -235.332143) (xy 104.973247 -235.367483) (xy 105.002623 -235.407916) (xy 105.025313 -235.452448)
			(xy 105.040757 -235.49998) (xy 105.048576 -235.549343) (xy 105.049066 -235.574332) (xy 105.048576 -235.599321)
			(xy 105.353594 -235.599321) (xy 105.353594 -235.549343) (xy 105.361413 -235.49998) (xy 105.376857 -235.452448)
			(xy 105.399547 -235.407916) (xy 105.428923 -235.367483) (xy 105.464263 -235.332143) (xy 105.504696 -235.302767)
			(xy 105.549228 -235.280077) (xy 105.59676 -235.264633) (xy 105.646123 -235.256814) (xy 105.696101 -235.256814)
			(xy 105.745464 -235.264633) (xy 105.792996 -235.280077) (xy 105.837528 -235.302767) (xy 105.877961 -235.332143)
			(xy 105.913301 -235.367483) (xy 105.942677 -235.407916) (xy 105.965367 -235.452448) (xy 105.980811 -235.49998)
			(xy 105.98863 -235.549343) (xy 105.98912 -235.574332) (xy 105.98863 -235.599321) (xy 106.293648 -235.599321)
			(xy 106.293648 -235.549343) (xy 106.301467 -235.49998) (xy 106.316911 -235.452448) (xy 106.339601 -235.407916)
			(xy 106.368977 -235.367483) (xy 106.404317 -235.332143) (xy 106.44475 -235.302767) (xy 106.489282 -235.280077)
			(xy 106.536814 -235.264633) (xy 106.586177 -235.256814) (xy 106.636155 -235.256814) (xy 106.685518 -235.264633)
			(xy 106.73305 -235.280077) (xy 106.777582 -235.302767) (xy 106.818015 -235.332143) (xy 106.853355 -235.367483)
			(xy 106.882731 -235.407916) (xy 106.905421 -235.452448) (xy 106.920865 -235.49998) (xy 106.928684 -235.549343)
			(xy 106.929174 -235.574332) (xy 106.928684 -235.599321) (xy 107.233448 -235.599321) (xy 107.233448 -235.549343)
			(xy 107.241267 -235.49998) (xy 107.256711 -235.452448) (xy 107.279401 -235.407916) (xy 107.308777 -235.367483)
			(xy 107.344117 -235.332143) (xy 107.38455 -235.302767) (xy 107.429082 -235.280077) (xy 107.476614 -235.264633)
			(xy 107.525977 -235.256814) (xy 107.575955 -235.256814) (xy 107.625318 -235.264633) (xy 107.67285 -235.280077)
			(xy 107.717382 -235.302767) (xy 107.757815 -235.332143) (xy 107.793155 -235.367483) (xy 107.822531 -235.407916)
			(xy 107.845221 -235.452448) (xy 107.860665 -235.49998) (xy 107.868484 -235.549343) (xy 107.868974 -235.574332)
			(xy 108.174785 -235.574332) (xy 108.17888 -235.523604) (xy 108.191059 -235.47419) (xy 108.211007 -235.42737)
			(xy 108.238208 -235.384356) (xy 108.271956 -235.346262) (xy 108.311378 -235.314075) (xy 108.355452 -235.288629)
			(xy 108.403038 -235.270582) (xy 108.452902 -235.260402) (xy 108.503754 -235.258353) (xy 108.554275 -235.264487)
			(xy 108.603159 -235.278647) (xy 108.649138 -235.300464) (xy 108.691022 -235.329374) (xy 108.727726 -235.364629)
			(xy 108.758299 -235.405315) (xy 108.78195 -235.450378) (xy 108.798066 -235.498652) (xy 108.80623 -235.548886)
			(xy 108.806742 -235.574332) (xy 109.114839 -235.574332) (xy 109.118934 -235.523604) (xy 109.131113 -235.47419)
			(xy 109.151061 -235.42737) (xy 109.178262 -235.384356) (xy 109.21201 -235.346262) (xy 109.251432 -235.314075)
			(xy 109.295506 -235.288629) (xy 109.343092 -235.270582) (xy 109.392956 -235.260402) (xy 109.443808 -235.258353)
			(xy 109.494329 -235.264487) (xy 109.543213 -235.278647) (xy 109.589192 -235.300464) (xy 109.631076 -235.329374)
			(xy 109.66778 -235.364629) (xy 109.698353 -235.405315) (xy 109.722004 -235.450378) (xy 109.73812 -235.498652)
			(xy 109.746284 -235.548886) (xy 109.746796 -235.574332) (xy 109.746293 -235.599321) (xy 110.05361 -235.599321)
			(xy 110.05361 -235.549343) (xy 110.061429 -235.49998) (xy 110.076873 -235.452448) (xy 110.099563 -235.407916)
			(xy 110.128939 -235.367483) (xy 110.164279 -235.332143) (xy 110.204712 -235.302767) (xy 110.249244 -235.280077)
			(xy 110.296776 -235.264633) (xy 110.346139 -235.256814) (xy 110.396117 -235.256814) (xy 110.44548 -235.264633)
			(xy 110.493012 -235.280077) (xy 110.537544 -235.302767) (xy 110.577977 -235.332143) (xy 110.613317 -235.367483)
			(xy 110.642693 -235.407916) (xy 110.665383 -235.452448) (xy 110.680827 -235.49998) (xy 110.688646 -235.549343)
			(xy 110.689136 -235.574332) (xy 110.688646 -235.599321) (xy 112.867168 -235.599321) (xy 112.867168 -235.549343)
			(xy 112.874987 -235.49998) (xy 112.890431 -235.452448) (xy 112.913121 -235.407916) (xy 112.942497 -235.367483)
			(xy 112.977837 -235.332143) (xy 113.01827 -235.302767) (xy 113.062802 -235.280077) (xy 113.110334 -235.264633)
			(xy 113.159697 -235.256814) (xy 113.209675 -235.256814) (xy 113.259038 -235.264633) (xy 113.30657 -235.280077)
			(xy 113.351102 -235.302767) (xy 113.391535 -235.332143) (xy 113.426875 -235.367483) (xy 113.456251 -235.407916)
			(xy 113.478941 -235.452448) (xy 113.494385 -235.49998) (xy 113.502204 -235.549343) (xy 113.502694 -235.574332)
			(xy 113.808505 -235.574332) (xy 113.8126 -235.523604) (xy 113.824779 -235.47419) (xy 113.844727 -235.42737)
			(xy 113.871928 -235.384356) (xy 113.905676 -235.346262) (xy 113.945098 -235.314075) (xy 113.989172 -235.288629)
			(xy 114.036758 -235.270582) (xy 114.086622 -235.260402) (xy 114.137474 -235.258353) (xy 114.187995 -235.264487)
			(xy 114.236879 -235.278647) (xy 114.282858 -235.300464) (xy 114.324742 -235.329374) (xy 114.361446 -235.364629)
			(xy 114.392019 -235.405315) (xy 114.41567 -235.450378) (xy 114.431786 -235.498652) (xy 114.43995 -235.548886)
			(xy 114.440462 -235.574332) (xy 114.748559 -235.574332) (xy 114.752654 -235.523604) (xy 114.764833 -235.47419)
			(xy 114.784781 -235.42737) (xy 114.811982 -235.384356) (xy 114.84573 -235.346262) (xy 114.885152 -235.314075)
			(xy 114.929226 -235.288629) (xy 114.976812 -235.270582) (xy 115.026676 -235.260402) (xy 115.077528 -235.258353)
			(xy 115.128049 -235.264487) (xy 115.176933 -235.278647) (xy 115.222912 -235.300464) (xy 115.264796 -235.329374)
			(xy 115.3015 -235.364629) (xy 115.332073 -235.405315) (xy 115.355724 -235.450378) (xy 115.37184 -235.498652)
			(xy 115.380004 -235.548886) (xy 115.380516 -235.574332) (xy 115.380013 -235.599321) (xy 115.68733 -235.599321)
			(xy 115.68733 -235.549343) (xy 115.695149 -235.49998) (xy 115.710593 -235.452448) (xy 115.733283 -235.407916)
			(xy 115.762659 -235.367483) (xy 115.797999 -235.332143) (xy 115.838432 -235.302767) (xy 115.882964 -235.280077)
			(xy 115.930496 -235.264633) (xy 115.979859 -235.256814) (xy 116.029837 -235.256814) (xy 116.0792 -235.264633)
			(xy 116.126732 -235.280077) (xy 116.171264 -235.302767) (xy 116.211697 -235.332143) (xy 116.247037 -235.367483)
			(xy 116.276413 -235.407916) (xy 116.299103 -235.452448) (xy 116.314547 -235.49998) (xy 116.322366 -235.549343)
			(xy 116.322856 -235.574332) (xy 116.322366 -235.599321) (xy 116.62713 -235.599321) (xy 116.62713 -235.549343)
			(xy 116.634949 -235.49998) (xy 116.650393 -235.452448) (xy 116.673083 -235.407916) (xy 116.702459 -235.367483)
			(xy 116.737799 -235.332143) (xy 116.778232 -235.302767) (xy 116.822764 -235.280077) (xy 116.870296 -235.264633)
			(xy 116.919659 -235.256814) (xy 116.969637 -235.256814) (xy 117.019 -235.264633) (xy 117.066532 -235.280077)
			(xy 117.111064 -235.302767) (xy 117.151497 -235.332143) (xy 117.186837 -235.367483) (xy 117.216213 -235.407916)
			(xy 117.238903 -235.452448) (xy 117.254347 -235.49998) (xy 117.262166 -235.549343) (xy 117.262656 -235.574332)
			(xy 117.262166 -235.599321) (xy 117.567184 -235.599321) (xy 117.567184 -235.549343) (xy 117.575003 -235.49998)
			(xy 117.590447 -235.452448) (xy 117.613137 -235.407916) (xy 117.642513 -235.367483) (xy 117.677853 -235.332143)
			(xy 117.718286 -235.302767) (xy 117.762818 -235.280077) (xy 117.81035 -235.264633) (xy 117.859713 -235.256814)
			(xy 117.909691 -235.256814) (xy 117.959054 -235.264633) (xy 118.006586 -235.280077) (xy 118.051118 -235.302767)
			(xy 118.091551 -235.332143) (xy 118.126891 -235.367483) (xy 118.156267 -235.407916) (xy 118.178957 -235.452448)
			(xy 118.194401 -235.49998) (xy 118.20222 -235.549343) (xy 118.20271 -235.574332) (xy 118.20222 -235.599321)
			(xy 118.507238 -235.599321) (xy 118.507238 -235.549343) (xy 118.515057 -235.49998) (xy 118.530501 -235.452448)
			(xy 118.553191 -235.407916) (xy 118.582567 -235.367483) (xy 118.617907 -235.332143) (xy 118.65834 -235.302767)
			(xy 118.702872 -235.280077) (xy 118.750404 -235.264633) (xy 118.799767 -235.256814) (xy 118.849745 -235.256814)
			(xy 118.899108 -235.264633) (xy 118.94664 -235.280077) (xy 118.991172 -235.302767) (xy 119.031605 -235.332143)
			(xy 119.066945 -235.367483) (xy 119.096321 -235.407916) (xy 119.119011 -235.452448) (xy 119.134455 -235.49998)
			(xy 119.142274 -235.549343) (xy 119.142764 -235.574332) (xy 119.142274 -235.599321) (xy 119.447292 -235.599321)
			(xy 119.447292 -235.549343) (xy 119.455111 -235.49998) (xy 119.470555 -235.452448) (xy 119.493245 -235.407916)
			(xy 119.522621 -235.367483) (xy 119.557961 -235.332143) (xy 119.598394 -235.302767) (xy 119.642926 -235.280077)
			(xy 119.690458 -235.264633) (xy 119.739821 -235.256814) (xy 119.789799 -235.256814) (xy 119.839162 -235.264633)
			(xy 119.886694 -235.280077) (xy 119.931226 -235.302767) (xy 119.971659 -235.332143) (xy 120.006999 -235.367483)
			(xy 120.036375 -235.407916) (xy 120.059065 -235.452448) (xy 120.074509 -235.49998) (xy 120.082328 -235.549343)
			(xy 120.082818 -235.574332) (xy 120.082328 -235.599321) (xy 120.387092 -235.599321) (xy 120.387092 -235.549343)
			(xy 120.394911 -235.49998) (xy 120.410355 -235.452448) (xy 120.433045 -235.407916) (xy 120.462421 -235.367483)
			(xy 120.497761 -235.332143) (xy 120.538194 -235.302767) (xy 120.582726 -235.280077) (xy 120.630258 -235.264633)
			(xy 120.679621 -235.256814) (xy 120.729599 -235.256814) (xy 120.778962 -235.264633) (xy 120.826494 -235.280077)
			(xy 120.871026 -235.302767) (xy 120.911459 -235.332143) (xy 120.946799 -235.367483) (xy 120.976175 -235.407916)
			(xy 120.998865 -235.452448) (xy 121.014309 -235.49998) (xy 121.022128 -235.549343) (xy 121.022618 -235.574332)
			(xy 121.022128 -235.599321) (xy 121.327146 -235.599321) (xy 121.327146 -235.549343) (xy 121.334965 -235.49998)
			(xy 121.350409 -235.452448) (xy 121.373099 -235.407916) (xy 121.402475 -235.367483) (xy 121.437815 -235.332143)
			(xy 121.478248 -235.302767) (xy 121.52278 -235.280077) (xy 121.570312 -235.264633) (xy 121.619675 -235.256814)
			(xy 121.669653 -235.256814) (xy 121.719016 -235.264633) (xy 121.766548 -235.280077) (xy 121.81108 -235.302767)
			(xy 121.851513 -235.332143) (xy 121.886853 -235.367483) (xy 121.916229 -235.407916) (xy 121.938919 -235.452448)
			(xy 121.954363 -235.49998) (xy 121.962182 -235.549343) (xy 121.962672 -235.574332) (xy 121.962182 -235.599321)
			(xy 122.2672 -235.599321) (xy 122.2672 -235.549343) (xy 122.275019 -235.49998) (xy 122.290463 -235.452448)
			(xy 122.313153 -235.407916) (xy 122.342529 -235.367483) (xy 122.377869 -235.332143) (xy 122.418302 -235.302767)
			(xy 122.462834 -235.280077) (xy 122.510366 -235.264633) (xy 122.559729 -235.256814) (xy 122.609707 -235.256814)
			(xy 122.65907 -235.264633) (xy 122.706602 -235.280077) (xy 122.751134 -235.302767) (xy 122.791567 -235.332143)
			(xy 122.826907 -235.367483) (xy 122.856283 -235.407916) (xy 122.878973 -235.452448) (xy 122.894417 -235.49998)
			(xy 122.902236 -235.549343) (xy 122.902726 -235.574332) (xy 122.902236 -235.599321) (xy 123.207254 -235.599321)
			(xy 123.207254 -235.549343) (xy 123.215073 -235.49998) (xy 123.230517 -235.452448) (xy 123.253207 -235.407916)
			(xy 123.282583 -235.367483) (xy 123.317923 -235.332143) (xy 123.358356 -235.302767) (xy 123.402888 -235.280077)
			(xy 123.45042 -235.264633) (xy 123.499783 -235.256814) (xy 123.549761 -235.256814) (xy 123.599124 -235.264633)
			(xy 123.646656 -235.280077) (xy 123.691188 -235.302767) (xy 123.731621 -235.332143) (xy 123.766961 -235.367483)
			(xy 123.796337 -235.407916) (xy 123.819027 -235.452448) (xy 123.834471 -235.49998) (xy 123.84229 -235.549343)
			(xy 123.84278 -235.574332) (xy 123.84229 -235.599321) (xy 124.147308 -235.599321) (xy 124.147308 -235.549343)
			(xy 124.155127 -235.49998) (xy 124.170571 -235.452448) (xy 124.193261 -235.407916) (xy 124.222637 -235.367483)
			(xy 124.257977 -235.332143) (xy 124.29841 -235.302767) (xy 124.342942 -235.280077) (xy 124.390474 -235.264633)
			(xy 124.439837 -235.256814) (xy 124.489815 -235.256814) (xy 124.539178 -235.264633) (xy 124.58671 -235.280077)
			(xy 124.631242 -235.302767) (xy 124.671675 -235.332143) (xy 124.707015 -235.367483) (xy 124.736391 -235.407916)
			(xy 124.759081 -235.452448) (xy 124.774525 -235.49998) (xy 124.782344 -235.549343) (xy 124.782834 -235.574332)
			(xy 124.782344 -235.599321) (xy 125.087108 -235.599321) (xy 125.087108 -235.549343) (xy 125.094927 -235.49998)
			(xy 125.110371 -235.452448) (xy 125.133061 -235.407916) (xy 125.162437 -235.367483) (xy 125.197777 -235.332143)
			(xy 125.23821 -235.302767) (xy 125.282742 -235.280077) (xy 125.330274 -235.264633) (xy 125.379637 -235.256814)
			(xy 125.429615 -235.256814) (xy 125.478978 -235.264633) (xy 125.52651 -235.280077) (xy 125.571042 -235.302767)
			(xy 125.611475 -235.332143) (xy 125.646815 -235.367483) (xy 125.676191 -235.407916) (xy 125.698881 -235.452448)
			(xy 125.714325 -235.49998) (xy 125.722144 -235.549343) (xy 125.722634 -235.574332) (xy 125.722144 -235.599321)
			(xy 125.714325 -235.648684) (xy 125.698881 -235.696216) (xy 125.676191 -235.740748) (xy 125.646815 -235.781181)
			(xy 125.611475 -235.816521) (xy 125.571042 -235.845897) (xy 125.52651 -235.868587) (xy 125.478978 -235.884031)
			(xy 125.429615 -235.89185) (xy 125.379637 -235.89185) (xy 125.330274 -235.884031) (xy 125.282742 -235.868587)
			(xy 125.23821 -235.845897) (xy 125.197777 -235.816521) (xy 125.162437 -235.781181) (xy 125.133061 -235.740748)
			(xy 125.110371 -235.696216) (xy 125.094927 -235.648684) (xy 125.087108 -235.599321) (xy 124.782344 -235.599321)
			(xy 124.774525 -235.648684) (xy 124.759081 -235.696216) (xy 124.736391 -235.740748) (xy 124.707015 -235.781181)
			(xy 124.671675 -235.816521) (xy 124.631242 -235.845897) (xy 124.58671 -235.868587) (xy 124.539178 -235.884031)
			(xy 124.489815 -235.89185) (xy 124.439837 -235.89185) (xy 124.390474 -235.884031) (xy 124.342942 -235.868587)
			(xy 124.29841 -235.845897) (xy 124.257977 -235.816521) (xy 124.222637 -235.781181) (xy 124.193261 -235.740748)
			(xy 124.170571 -235.696216) (xy 124.155127 -235.648684) (xy 124.147308 -235.599321) (xy 123.84229 -235.599321)
			(xy 123.834471 -235.648684) (xy 123.819027 -235.696216) (xy 123.796337 -235.740748) (xy 123.766961 -235.781181)
			(xy 123.731621 -235.816521) (xy 123.691188 -235.845897) (xy 123.646656 -235.868587) (xy 123.599124 -235.884031)
			(xy 123.549761 -235.89185) (xy 123.499783 -235.89185) (xy 123.45042 -235.884031) (xy 123.402888 -235.868587)
			(xy 123.358356 -235.845897) (xy 123.317923 -235.816521) (xy 123.282583 -235.781181) (xy 123.253207 -235.740748)
			(xy 123.230517 -235.696216) (xy 123.215073 -235.648684) (xy 123.207254 -235.599321) (xy 122.902236 -235.599321)
			(xy 122.894417 -235.648684) (xy 122.878973 -235.696216) (xy 122.856283 -235.740748) (xy 122.826907 -235.781181)
			(xy 122.791567 -235.816521) (xy 122.751134 -235.845897) (xy 122.706602 -235.868587) (xy 122.65907 -235.884031)
			(xy 122.609707 -235.89185) (xy 122.559729 -235.89185) (xy 122.510366 -235.884031) (xy 122.462834 -235.868587)
			(xy 122.418302 -235.845897) (xy 122.377869 -235.816521) (xy 122.342529 -235.781181) (xy 122.313153 -235.740748)
			(xy 122.290463 -235.696216) (xy 122.275019 -235.648684) (xy 122.2672 -235.599321) (xy 121.962182 -235.599321)
			(xy 121.954363 -235.648684) (xy 121.938919 -235.696216) (xy 121.916229 -235.740748) (xy 121.886853 -235.781181)
			(xy 121.851513 -235.816521) (xy 121.81108 -235.845897) (xy 121.766548 -235.868587) (xy 121.719016 -235.884031)
			(xy 121.669653 -235.89185) (xy 121.619675 -235.89185) (xy 121.570312 -235.884031) (xy 121.52278 -235.868587)
			(xy 121.478248 -235.845897) (xy 121.437815 -235.816521) (xy 121.402475 -235.781181) (xy 121.373099 -235.740748)
			(xy 121.350409 -235.696216) (xy 121.334965 -235.648684) (xy 121.327146 -235.599321) (xy 121.022128 -235.599321)
			(xy 121.014309 -235.648684) (xy 120.998865 -235.696216) (xy 120.976175 -235.740748) (xy 120.946799 -235.781181)
			(xy 120.911459 -235.816521) (xy 120.871026 -235.845897) (xy 120.826494 -235.868587) (xy 120.778962 -235.884031)
			(xy 120.729599 -235.89185) (xy 120.679621 -235.89185) (xy 120.630258 -235.884031) (xy 120.582726 -235.868587)
			(xy 120.538194 -235.845897) (xy 120.497761 -235.816521) (xy 120.462421 -235.781181) (xy 120.433045 -235.740748)
			(xy 120.410355 -235.696216) (xy 120.394911 -235.648684) (xy 120.387092 -235.599321) (xy 120.082328 -235.599321)
			(xy 120.074509 -235.648684) (xy 120.059065 -235.696216) (xy 120.036375 -235.740748) (xy 120.006999 -235.781181)
			(xy 119.971659 -235.816521) (xy 119.931226 -235.845897) (xy 119.886694 -235.868587) (xy 119.839162 -235.884031)
			(xy 119.789799 -235.89185) (xy 119.739821 -235.89185) (xy 119.690458 -235.884031) (xy 119.642926 -235.868587)
			(xy 119.598394 -235.845897) (xy 119.557961 -235.816521) (xy 119.522621 -235.781181) (xy 119.493245 -235.740748)
			(xy 119.470555 -235.696216) (xy 119.455111 -235.648684) (xy 119.447292 -235.599321) (xy 119.142274 -235.599321)
			(xy 119.134455 -235.648684) (xy 119.119011 -235.696216) (xy 119.096321 -235.740748) (xy 119.066945 -235.781181)
			(xy 119.031605 -235.816521) (xy 118.991172 -235.845897) (xy 118.94664 -235.868587) (xy 118.899108 -235.884031)
			(xy 118.849745 -235.89185) (xy 118.799767 -235.89185) (xy 118.750404 -235.884031) (xy 118.702872 -235.868587)
			(xy 118.65834 -235.845897) (xy 118.617907 -235.816521) (xy 118.582567 -235.781181) (xy 118.553191 -235.740748)
			(xy 118.530501 -235.696216) (xy 118.515057 -235.648684) (xy 118.507238 -235.599321) (xy 118.20222 -235.599321)
			(xy 118.194401 -235.648684) (xy 118.178957 -235.696216) (xy 118.156267 -235.740748) (xy 118.126891 -235.781181)
			(xy 118.091551 -235.816521) (xy 118.051118 -235.845897) (xy 118.006586 -235.868587) (xy 117.959054 -235.884031)
			(xy 117.909691 -235.89185) (xy 117.859713 -235.89185) (xy 117.81035 -235.884031) (xy 117.762818 -235.868587)
			(xy 117.718286 -235.845897) (xy 117.677853 -235.816521) (xy 117.642513 -235.781181) (xy 117.613137 -235.740748)
			(xy 117.590447 -235.696216) (xy 117.575003 -235.648684) (xy 117.567184 -235.599321) (xy 117.262166 -235.599321)
			(xy 117.254347 -235.648684) (xy 117.238903 -235.696216) (xy 117.216213 -235.740748) (xy 117.186837 -235.781181)
			(xy 117.151497 -235.816521) (xy 117.111064 -235.845897) (xy 117.066532 -235.868587) (xy 117.019 -235.884031)
			(xy 116.969637 -235.89185) (xy 116.919659 -235.89185) (xy 116.870296 -235.884031) (xy 116.822764 -235.868587)
			(xy 116.778232 -235.845897) (xy 116.737799 -235.816521) (xy 116.702459 -235.781181) (xy 116.673083 -235.740748)
			(xy 116.650393 -235.696216) (xy 116.634949 -235.648684) (xy 116.62713 -235.599321) (xy 116.322366 -235.599321)
			(xy 116.314547 -235.648684) (xy 116.299103 -235.696216) (xy 116.276413 -235.740748) (xy 116.247037 -235.781181)
			(xy 116.211697 -235.816521) (xy 116.171264 -235.845897) (xy 116.126732 -235.868587) (xy 116.0792 -235.884031)
			(xy 116.029837 -235.89185) (xy 115.979859 -235.89185) (xy 115.930496 -235.884031) (xy 115.882964 -235.868587)
			(xy 115.838432 -235.845897) (xy 115.797999 -235.816521) (xy 115.762659 -235.781181) (xy 115.733283 -235.740748)
			(xy 115.710593 -235.696216) (xy 115.695149 -235.648684) (xy 115.68733 -235.599321) (xy 115.380013 -235.599321)
			(xy 115.380004 -235.599778) (xy 115.37184 -235.650012) (xy 115.355724 -235.698286) (xy 115.332073 -235.743349)
			(xy 115.3015 -235.784035) (xy 115.264796 -235.81929) (xy 115.222912 -235.8482) (xy 115.176933 -235.870017)
			(xy 115.128049 -235.884177) (xy 115.077528 -235.890311) (xy 115.026676 -235.888262) (xy 114.976812 -235.878082)
			(xy 114.929226 -235.860035) (xy 114.885152 -235.834589) (xy 114.84573 -235.802402) (xy 114.811982 -235.764308)
			(xy 114.784781 -235.721294) (xy 114.764833 -235.674474) (xy 114.752654 -235.62506) (xy 114.748559 -235.574332)
			(xy 114.440462 -235.574332) (xy 114.43995 -235.599778) (xy 114.431786 -235.650012) (xy 114.41567 -235.698286)
			(xy 114.392019 -235.743349) (xy 114.361446 -235.784035) (xy 114.324742 -235.81929) (xy 114.282858 -235.8482)
			(xy 114.236879 -235.870017) (xy 114.187995 -235.884177) (xy 114.137474 -235.890311) (xy 114.086622 -235.888262)
			(xy 114.036758 -235.878082) (xy 113.989172 -235.860035) (xy 113.945098 -235.834589) (xy 113.905676 -235.802402)
			(xy 113.871928 -235.764308) (xy 113.844727 -235.721294) (xy 113.824779 -235.674474) (xy 113.8126 -235.62506)
			(xy 113.808505 -235.574332) (xy 113.502694 -235.574332) (xy 113.502204 -235.599321) (xy 113.494385 -235.648684)
			(xy 113.478941 -235.696216) (xy 113.456251 -235.740748) (xy 113.426875 -235.781181) (xy 113.391535 -235.816521)
			(xy 113.351102 -235.845897) (xy 113.30657 -235.868587) (xy 113.259038 -235.884031) (xy 113.209675 -235.89185)
			(xy 113.159697 -235.89185) (xy 113.110334 -235.884031) (xy 113.062802 -235.868587) (xy 113.01827 -235.845897)
			(xy 112.977837 -235.816521) (xy 112.942497 -235.781181) (xy 112.913121 -235.740748) (xy 112.890431 -235.696216)
			(xy 112.874987 -235.648684) (xy 112.867168 -235.599321) (xy 110.688646 -235.599321) (xy 110.680827 -235.648684)
			(xy 110.665383 -235.696216) (xy 110.642693 -235.740748) (xy 110.613317 -235.781181) (xy 110.577977 -235.816521)
			(xy 110.537544 -235.845897) (xy 110.493012 -235.868587) (xy 110.44548 -235.884031) (xy 110.396117 -235.89185)
			(xy 110.346139 -235.89185) (xy 110.296776 -235.884031) (xy 110.249244 -235.868587) (xy 110.204712 -235.845897)
			(xy 110.164279 -235.816521) (xy 110.128939 -235.781181) (xy 110.099563 -235.740748) (xy 110.076873 -235.696216)
			(xy 110.061429 -235.648684) (xy 110.05361 -235.599321) (xy 109.746293 -235.599321) (xy 109.746284 -235.599778)
			(xy 109.73812 -235.650012) (xy 109.722004 -235.698286) (xy 109.698353 -235.743349) (xy 109.66778 -235.784035)
			(xy 109.631076 -235.81929) (xy 109.589192 -235.8482) (xy 109.543213 -235.870017) (xy 109.494329 -235.884177)
			(xy 109.443808 -235.890311) (xy 109.392956 -235.888262) (xy 109.343092 -235.878082) (xy 109.295506 -235.860035)
			(xy 109.251432 -235.834589) (xy 109.21201 -235.802402) (xy 109.178262 -235.764308) (xy 109.151061 -235.721294)
			(xy 109.131113 -235.674474) (xy 109.118934 -235.62506) (xy 109.114839 -235.574332) (xy 108.806742 -235.574332)
			(xy 108.80623 -235.599778) (xy 108.798066 -235.650012) (xy 108.78195 -235.698286) (xy 108.758299 -235.743349)
			(xy 108.727726 -235.784035) (xy 108.691022 -235.81929) (xy 108.649138 -235.8482) (xy 108.603159 -235.870017)
			(xy 108.554275 -235.884177) (xy 108.503754 -235.890311) (xy 108.452902 -235.888262) (xy 108.403038 -235.878082)
			(xy 108.355452 -235.860035) (xy 108.311378 -235.834589) (xy 108.271956 -235.802402) (xy 108.238208 -235.764308)
			(xy 108.211007 -235.721294) (xy 108.191059 -235.674474) (xy 108.17888 -235.62506) (xy 108.174785 -235.574332)
			(xy 107.868974 -235.574332) (xy 107.868484 -235.599321) (xy 107.860665 -235.648684) (xy 107.845221 -235.696216)
			(xy 107.822531 -235.740748) (xy 107.793155 -235.781181) (xy 107.757815 -235.816521) (xy 107.717382 -235.845897)
			(xy 107.67285 -235.868587) (xy 107.625318 -235.884031) (xy 107.575955 -235.89185) (xy 107.525977 -235.89185)
			(xy 107.476614 -235.884031) (xy 107.429082 -235.868587) (xy 107.38455 -235.845897) (xy 107.344117 -235.816521)
			(xy 107.308777 -235.781181) (xy 107.279401 -235.740748) (xy 107.256711 -235.696216) (xy 107.241267 -235.648684)
			(xy 107.233448 -235.599321) (xy 106.928684 -235.599321) (xy 106.920865 -235.648684) (xy 106.905421 -235.696216)
			(xy 106.882731 -235.740748) (xy 106.853355 -235.781181) (xy 106.818015 -235.816521) (xy 106.777582 -235.845897)
			(xy 106.73305 -235.868587) (xy 106.685518 -235.884031) (xy 106.636155 -235.89185) (xy 106.586177 -235.89185)
			(xy 106.536814 -235.884031) (xy 106.489282 -235.868587) (xy 106.44475 -235.845897) (xy 106.404317 -235.816521)
			(xy 106.368977 -235.781181) (xy 106.339601 -235.740748) (xy 106.316911 -235.696216) (xy 106.301467 -235.648684)
			(xy 106.293648 -235.599321) (xy 105.98863 -235.599321) (xy 105.980811 -235.648684) (xy 105.965367 -235.696216)
			(xy 105.942677 -235.740748) (xy 105.913301 -235.781181) (xy 105.877961 -235.816521) (xy 105.837528 -235.845897)
			(xy 105.792996 -235.868587) (xy 105.745464 -235.884031) (xy 105.696101 -235.89185) (xy 105.646123 -235.89185)
			(xy 105.59676 -235.884031) (xy 105.549228 -235.868587) (xy 105.504696 -235.845897) (xy 105.464263 -235.816521)
			(xy 105.428923 -235.781181) (xy 105.399547 -235.740748) (xy 105.376857 -235.696216) (xy 105.361413 -235.648684)
			(xy 105.353594 -235.599321) (xy 105.048576 -235.599321) (xy 105.040757 -235.648684) (xy 105.025313 -235.696216)
			(xy 105.002623 -235.740748) (xy 104.973247 -235.781181) (xy 104.937907 -235.816521) (xy 104.897474 -235.845897)
			(xy 104.852942 -235.868587) (xy 104.80541 -235.884031) (xy 104.756047 -235.89185) (xy 104.706069 -235.89185)
			(xy 104.656706 -235.884031) (xy 104.609174 -235.868587) (xy 104.564642 -235.845897) (xy 104.524209 -235.816521)
			(xy 104.488869 -235.781181) (xy 104.459493 -235.740748) (xy 104.436803 -235.696216) (xy 104.421359 -235.648684)
			(xy 104.41354 -235.599321) (xy 104.108522 -235.599321) (xy 104.100703 -235.648684) (xy 104.085259 -235.696216)
			(xy 104.062569 -235.740748) (xy 104.033193 -235.781181) (xy 103.997853 -235.816521) (xy 103.95742 -235.845897)
			(xy 103.912888 -235.868587) (xy 103.865356 -235.884031) (xy 103.815993 -235.89185) (xy 103.766015 -235.89185)
			(xy 103.716652 -235.884031) (xy 103.66912 -235.868587) (xy 103.624588 -235.845897) (xy 103.584155 -235.816521)
			(xy 103.548815 -235.781181) (xy 103.519439 -235.740748) (xy 103.496749 -235.696216) (xy 103.481305 -235.648684)
			(xy 103.473486 -235.599321) (xy 103.168468 -235.599321) (xy 103.160649 -235.648684) (xy 103.145205 -235.696216)
			(xy 103.122515 -235.740748) (xy 103.093139 -235.781181) (xy 103.057799 -235.816521) (xy 103.017366 -235.845897)
			(xy 102.972834 -235.868587) (xy 102.925302 -235.884031) (xy 102.875939 -235.89185) (xy 102.825961 -235.89185)
			(xy 102.776598 -235.884031) (xy 102.729066 -235.868587) (xy 102.684534 -235.845897) (xy 102.644101 -235.816521)
			(xy 102.608761 -235.781181) (xy 102.579385 -235.740748) (xy 102.556695 -235.696216) (xy 102.541251 -235.648684)
			(xy 102.533432 -235.599321) (xy 102.228668 -235.599321) (xy 102.220849 -235.648684) (xy 102.205405 -235.696216)
			(xy 102.182715 -235.740748) (xy 102.153339 -235.781181) (xy 102.117999 -235.816521) (xy 102.077566 -235.845897)
			(xy 102.033034 -235.868587) (xy 101.985502 -235.884031) (xy 101.936139 -235.89185) (xy 101.886161 -235.89185)
			(xy 101.836798 -235.884031) (xy 101.789266 -235.868587) (xy 101.744734 -235.845897) (xy 101.704301 -235.816521)
			(xy 101.668961 -235.781181) (xy 101.639585 -235.740748) (xy 101.616895 -235.696216) (xy 101.601451 -235.648684)
			(xy 101.593632 -235.599321) (xy 101.288614 -235.599321) (xy 101.280795 -235.648684) (xy 101.265351 -235.696216)
			(xy 101.242661 -235.740748) (xy 101.213285 -235.781181) (xy 101.177945 -235.816521) (xy 101.137512 -235.845897)
			(xy 101.09298 -235.868587) (xy 101.045448 -235.884031) (xy 100.996085 -235.89185) (xy 100.946107 -235.89185)
			(xy 100.896744 -235.884031) (xy 100.849212 -235.868587) (xy 100.80468 -235.845897) (xy 100.764247 -235.816521)
			(xy 100.728907 -235.781181) (xy 100.699531 -235.740748) (xy 100.676841 -235.696216) (xy 100.661397 -235.648684)
			(xy 100.653578 -235.599321) (xy 100.34856 -235.599321) (xy 100.340741 -235.648684) (xy 100.325297 -235.696216)
			(xy 100.302607 -235.740748) (xy 100.273231 -235.781181) (xy 100.237891 -235.816521) (xy 100.197458 -235.845897)
			(xy 100.152926 -235.868587) (xy 100.105394 -235.884031) (xy 100.056031 -235.89185) (xy 100.006053 -235.89185)
			(xy 99.95669 -235.884031) (xy 99.909158 -235.868587) (xy 99.864626 -235.845897) (xy 99.824193 -235.816521)
			(xy 99.788853 -235.781181) (xy 99.759477 -235.740748) (xy 99.736787 -235.696216) (xy 99.721343 -235.648684)
			(xy 99.713524 -235.599321) (xy 99.408506 -235.599321) (xy 99.400687 -235.648684) (xy 99.385243 -235.696216)
			(xy 99.362553 -235.740748) (xy 99.333177 -235.781181) (xy 99.297837 -235.816521) (xy 99.257404 -235.845897)
			(xy 99.212872 -235.868587) (xy 99.16534 -235.884031) (xy 99.115977 -235.89185) (xy 99.065999 -235.89185)
			(xy 99.016636 -235.884031) (xy 98.969104 -235.868587) (xy 98.924572 -235.845897) (xy 98.884139 -235.816521)
			(xy 98.848799 -235.781181) (xy 98.819423 -235.740748) (xy 98.796733 -235.696216) (xy 98.781289 -235.648684)
			(xy 98.77347 -235.599321) (xy 98.468452 -235.599321) (xy 98.460633 -235.648684) (xy 98.445189 -235.696216)
			(xy 98.422499 -235.740748) (xy 98.393123 -235.781181) (xy 98.357783 -235.816521) (xy 98.31735 -235.845897)
			(xy 98.272818 -235.868587) (xy 98.225286 -235.884031) (xy 98.175923 -235.89185) (xy 98.125945 -235.89185)
			(xy 98.076582 -235.884031) (xy 98.02905 -235.868587) (xy 97.984518 -235.845897) (xy 97.944085 -235.816521)
			(xy 97.908745 -235.781181) (xy 97.879369 -235.740748) (xy 97.856679 -235.696216) (xy 97.841235 -235.648684)
			(xy 97.833416 -235.599321) (xy 97.528579 -235.599321) (xy 97.520778 -235.648603) (xy 97.505353 -235.696106)
			(xy 97.482691 -235.740613) (xy 97.453349 -235.781029) (xy 97.418049 -235.816362) (xy 97.377659 -235.84574)
			(xy 97.333172 -235.868443) (xy 97.285683 -235.883911) (xy 97.23636 -235.891764) (xy 97.211388 -235.89234)
			(xy 97.211134 -235.89234) (xy 97.201776 -235.892249) (xy 97.183095 -235.891107) (xy 97.173796 -235.890054)
			(xy 97.171002 -235.8898) (xy 97.170494 -235.8898) (xy 97.160588 -235.88853) (xy 97.148396 -235.892086)
			(xy 97.137474 -235.89615) (xy 97.073212 -235.952538) (xy 97.066394 -235.959632) (xy 97.05827 -235.977532)
			(xy 97.057464 -235.987336) (xy 97.057464 -236.346746) (xy 97.057718 -236.351318) (xy 97.058988 -236.381798)
			(xy 97.058988 -236.384338) (xy 97.364799 -236.384338) (xy 97.368894 -236.33361) (xy 97.381073 -236.284196)
			(xy 97.401021 -236.237376) (xy 97.428222 -236.194362) (xy 97.46197 -236.156268) (xy 97.501392 -236.124081)
			(xy 97.545466 -236.098635) (xy 97.593052 -236.080588) (xy 97.642916 -236.070408) (xy 97.693768 -236.068359)
			(xy 97.744289 -236.074493) (xy 97.793173 -236.088653) (xy 97.839152 -236.11047) (xy 97.881036 -236.13938)
			(xy 97.91774 -236.174635) (xy 97.948313 -236.215321) (xy 97.971964 -236.260384) (xy 97.98808 -236.308658)
			(xy 97.996244 -236.358892) (xy 97.996756 -236.384338) (xy 98.304853 -236.384338) (xy 98.308948 -236.33361)
			(xy 98.321127 -236.284196) (xy 98.341075 -236.237376) (xy 98.368276 -236.194362) (xy 98.402024 -236.156268)
			(xy 98.441446 -236.124081) (xy 98.48552 -236.098635) (xy 98.533106 -236.080588) (xy 98.58297 -236.070408)
			(xy 98.633822 -236.068359) (xy 98.684343 -236.074493) (xy 98.733227 -236.088653) (xy 98.779206 -236.11047)
			(xy 98.82109 -236.13938) (xy 98.857794 -236.174635) (xy 98.888367 -236.215321) (xy 98.912018 -236.260384)
			(xy 98.928134 -236.308658) (xy 98.936298 -236.358892) (xy 98.93681 -236.384338) (xy 98.936307 -236.409327)
			(xy 99.243624 -236.409327) (xy 99.243624 -236.359349) (xy 99.251443 -236.309986) (xy 99.266887 -236.262454)
			(xy 99.289577 -236.217922) (xy 99.318953 -236.177489) (xy 99.354293 -236.142149) (xy 99.394726 -236.112773)
			(xy 99.439258 -236.090083) (xy 99.48679 -236.074639) (xy 99.536153 -236.06682) (xy 99.586131 -236.06682)
			(xy 99.635494 -236.074639) (xy 99.683026 -236.090083) (xy 99.727558 -236.112773) (xy 99.767991 -236.142149)
			(xy 99.803331 -236.177489) (xy 99.832707 -236.217922) (xy 99.855397 -236.262454) (xy 99.870841 -236.309986)
			(xy 99.87866 -236.359349) (xy 99.87915 -236.384338) (xy 100.184707 -236.384338) (xy 100.188802 -236.33361)
			(xy 100.200981 -236.284196) (xy 100.220929 -236.237376) (xy 100.24813 -236.194362) (xy 100.281878 -236.156268)
			(xy 100.3213 -236.124081) (xy 100.365374 -236.098635) (xy 100.41296 -236.080588) (xy 100.462824 -236.070408)
			(xy 100.513676 -236.068359) (xy 100.564197 -236.074493) (xy 100.613081 -236.088653) (xy 100.65906 -236.11047)
			(xy 100.700944 -236.13938) (xy 100.737648 -236.174635) (xy 100.768221 -236.215321) (xy 100.791872 -236.260384)
			(xy 100.807988 -236.308658) (xy 100.816152 -236.358892) (xy 100.816664 -236.384338) (xy 101.124761 -236.384338)
			(xy 101.128856 -236.33361) (xy 101.141035 -236.284196) (xy 101.160983 -236.237376) (xy 101.188184 -236.194362)
			(xy 101.221932 -236.156268) (xy 101.261354 -236.124081) (xy 101.305428 -236.098635) (xy 101.353014 -236.080588)
			(xy 101.402878 -236.070408) (xy 101.45373 -236.068359) (xy 101.504251 -236.074493) (xy 101.553135 -236.088653)
			(xy 101.599114 -236.11047) (xy 101.640998 -236.13938) (xy 101.677702 -236.174635) (xy 101.708275 -236.215321)
			(xy 101.731926 -236.260384) (xy 101.748042 -236.308658) (xy 101.756206 -236.358892) (xy 101.756718 -236.384338)
			(xy 101.756215 -236.409327) (xy 102.063532 -236.409327) (xy 102.063532 -236.359349) (xy 102.071351 -236.309986)
			(xy 102.086795 -236.262454) (xy 102.109485 -236.217922) (xy 102.138861 -236.177489) (xy 102.174201 -236.142149)
			(xy 102.214634 -236.112773) (xy 102.259166 -236.090083) (xy 102.306698 -236.074639) (xy 102.356061 -236.06682)
			(xy 102.406039 -236.06682) (xy 102.455402 -236.074639) (xy 102.502934 -236.090083) (xy 102.547466 -236.112773)
			(xy 102.587899 -236.142149) (xy 102.623239 -236.177489) (xy 102.652615 -236.217922) (xy 102.675305 -236.262454)
			(xy 102.690749 -236.309986) (xy 102.698568 -236.359349) (xy 102.699058 -236.384338) (xy 102.698568 -236.409327)
			(xy 104.88344 -236.409327) (xy 104.88344 -236.359349) (xy 104.891259 -236.309986) (xy 104.906703 -236.262454)
			(xy 104.929393 -236.217922) (xy 104.958769 -236.177489) (xy 104.994109 -236.142149) (xy 105.034542 -236.112773)
			(xy 105.079074 -236.090083) (xy 105.126606 -236.074639) (xy 105.175969 -236.06682) (xy 105.225947 -236.06682)
			(xy 105.27531 -236.074639) (xy 105.322842 -236.090083) (xy 105.367374 -236.112773) (xy 105.407807 -236.142149)
			(xy 105.443147 -236.177489) (xy 105.472523 -236.217922) (xy 105.495213 -236.262454) (xy 105.510657 -236.309986)
			(xy 105.518476 -236.359349) (xy 105.518966 -236.384338) (xy 105.518476 -236.409327) (xy 107.703602 -236.409327)
			(xy 107.703602 -236.359349) (xy 107.711421 -236.309986) (xy 107.726865 -236.262454) (xy 107.749555 -236.217922)
			(xy 107.778931 -236.177489) (xy 107.814271 -236.142149) (xy 107.854704 -236.112773) (xy 107.899236 -236.090083)
			(xy 107.946768 -236.074639) (xy 107.996131 -236.06682) (xy 108.046109 -236.06682) (xy 108.095472 -236.074639)
			(xy 108.143004 -236.090083) (xy 108.187536 -236.112773) (xy 108.227969 -236.142149) (xy 108.263309 -236.177489)
			(xy 108.292685 -236.217922) (xy 108.315375 -236.262454) (xy 108.330819 -236.309986) (xy 108.338638 -236.359349)
			(xy 108.339128 -236.384338) (xy 108.338638 -236.409327) (xy 108.643656 -236.409327) (xy 108.643656 -236.359349)
			(xy 108.651475 -236.309986) (xy 108.666919 -236.262454) (xy 108.689609 -236.217922) (xy 108.718985 -236.177489)
			(xy 108.754325 -236.142149) (xy 108.794758 -236.112773) (xy 108.83929 -236.090083) (xy 108.886822 -236.074639)
			(xy 108.936185 -236.06682) (xy 108.986163 -236.06682) (xy 109.035526 -236.074639) (xy 109.083058 -236.090083)
			(xy 109.12759 -236.112773) (xy 109.168023 -236.142149) (xy 109.203363 -236.177489) (xy 109.232739 -236.217922)
			(xy 109.255429 -236.262454) (xy 109.270873 -236.309986) (xy 109.278692 -236.359349) (xy 109.279182 -236.384338)
			(xy 109.278692 -236.409327) (xy 109.583456 -236.409327) (xy 109.583456 -236.359349) (xy 109.591275 -236.309986)
			(xy 109.606719 -236.262454) (xy 109.629409 -236.217922) (xy 109.658785 -236.177489) (xy 109.694125 -236.142149)
			(xy 109.734558 -236.112773) (xy 109.77909 -236.090083) (xy 109.826622 -236.074639) (xy 109.875985 -236.06682)
			(xy 109.925963 -236.06682) (xy 109.975326 -236.074639) (xy 110.022858 -236.090083) (xy 110.06739 -236.112773)
			(xy 110.107823 -236.142149) (xy 110.143163 -236.177489) (xy 110.172539 -236.217922) (xy 110.195229 -236.262454)
			(xy 110.210673 -236.309986) (xy 110.218492 -236.359349) (xy 110.218982 -236.384338) (xy 110.218492 -236.409327)
			(xy 113.337322 -236.409327) (xy 113.337322 -236.359349) (xy 113.345141 -236.309986) (xy 113.360585 -236.262454)
			(xy 113.383275 -236.217922) (xy 113.412651 -236.177489) (xy 113.447991 -236.142149) (xy 113.488424 -236.112773)
			(xy 113.532956 -236.090083) (xy 113.580488 -236.074639) (xy 113.629851 -236.06682) (xy 113.679829 -236.06682)
			(xy 113.729192 -236.074639) (xy 113.776724 -236.090083) (xy 113.821256 -236.112773) (xy 113.861689 -236.142149)
			(xy 113.897029 -236.177489) (xy 113.926405 -236.217922) (xy 113.949095 -236.262454) (xy 113.964539 -236.309986)
			(xy 113.972358 -236.359349) (xy 113.972848 -236.384338) (xy 113.972358 -236.409327) (xy 114.277122 -236.409327)
			(xy 114.277122 -236.359349) (xy 114.284941 -236.309986) (xy 114.300385 -236.262454) (xy 114.323075 -236.217922)
			(xy 114.352451 -236.177489) (xy 114.387791 -236.142149) (xy 114.428224 -236.112773) (xy 114.472756 -236.090083)
			(xy 114.520288 -236.074639) (xy 114.569651 -236.06682) (xy 114.619629 -236.06682) (xy 114.668992 -236.074639)
			(xy 114.716524 -236.090083) (xy 114.761056 -236.112773) (xy 114.801489 -236.142149) (xy 114.836829 -236.177489)
			(xy 114.866205 -236.217922) (xy 114.888895 -236.262454) (xy 114.904339 -236.309986) (xy 114.912158 -236.359349)
			(xy 114.912648 -236.384338) (xy 114.912158 -236.409327) (xy 115.217176 -236.409327) (xy 115.217176 -236.359349)
			(xy 115.224995 -236.309986) (xy 115.240439 -236.262454) (xy 115.263129 -236.217922) (xy 115.292505 -236.177489)
			(xy 115.327845 -236.142149) (xy 115.368278 -236.112773) (xy 115.41281 -236.090083) (xy 115.460342 -236.074639)
			(xy 115.509705 -236.06682) (xy 115.559683 -236.06682) (xy 115.609046 -236.074639) (xy 115.656578 -236.090083)
			(xy 115.70111 -236.112773) (xy 115.741543 -236.142149) (xy 115.776883 -236.177489) (xy 115.806259 -236.217922)
			(xy 115.828949 -236.262454) (xy 115.844393 -236.309986) (xy 115.852212 -236.359349) (xy 115.852702 -236.384338)
			(xy 115.852212 -236.409327) (xy 118.037338 -236.409327) (xy 118.037338 -236.359349) (xy 118.045157 -236.309986)
			(xy 118.060601 -236.262454) (xy 118.083291 -236.217922) (xy 118.112667 -236.177489) (xy 118.148007 -236.142149)
			(xy 118.18844 -236.112773) (xy 118.232972 -236.090083) (xy 118.280504 -236.074639) (xy 118.329867 -236.06682)
			(xy 118.379845 -236.06682) (xy 118.429208 -236.074639) (xy 118.47674 -236.090083) (xy 118.521272 -236.112773)
			(xy 118.561705 -236.142149) (xy 118.597045 -236.177489) (xy 118.626421 -236.217922) (xy 118.649111 -236.262454)
			(xy 118.664555 -236.309986) (xy 118.672374 -236.359349) (xy 118.672864 -236.384338) (xy 118.672374 -236.409327)
			(xy 120.857246 -236.409327) (xy 120.857246 -236.359349) (xy 120.865065 -236.309986) (xy 120.880509 -236.262454)
			(xy 120.903199 -236.217922) (xy 120.932575 -236.177489) (xy 120.967915 -236.142149) (xy 121.008348 -236.112773)
			(xy 121.05288 -236.090083) (xy 121.100412 -236.074639) (xy 121.149775 -236.06682) (xy 121.199753 -236.06682)
			(xy 121.249116 -236.074639) (xy 121.296648 -236.090083) (xy 121.34118 -236.112773) (xy 121.381613 -236.142149)
			(xy 121.416953 -236.177489) (xy 121.446329 -236.217922) (xy 121.469019 -236.262454) (xy 121.484463 -236.309986)
			(xy 121.492282 -236.359349) (xy 121.492772 -236.384338) (xy 121.798583 -236.384338) (xy 121.802678 -236.33361)
			(xy 121.814857 -236.284196) (xy 121.834805 -236.237376) (xy 121.862006 -236.194362) (xy 121.895754 -236.156268)
			(xy 121.935176 -236.124081) (xy 121.97925 -236.098635) (xy 122.026836 -236.080588) (xy 122.0767 -236.070408)
			(xy 122.127552 -236.068359) (xy 122.178073 -236.074493) (xy 122.226957 -236.088653) (xy 122.272936 -236.11047)
			(xy 122.31482 -236.13938) (xy 122.351524 -236.174635) (xy 122.382097 -236.215321) (xy 122.405748 -236.260384)
			(xy 122.421864 -236.308658) (xy 122.430028 -236.358892) (xy 122.43054 -236.384338) (xy 122.738383 -236.384338)
			(xy 122.742478 -236.33361) (xy 122.754657 -236.284196) (xy 122.774605 -236.237376) (xy 122.801806 -236.194362)
			(xy 122.835554 -236.156268) (xy 122.874976 -236.124081) (xy 122.91905 -236.098635) (xy 122.966636 -236.080588)
			(xy 123.0165 -236.070408) (xy 123.067352 -236.068359) (xy 123.117873 -236.074493) (xy 123.166757 -236.088653)
			(xy 123.212736 -236.11047) (xy 123.25462 -236.13938) (xy 123.291324 -236.174635) (xy 123.321897 -236.215321)
			(xy 123.345548 -236.260384) (xy 123.361664 -236.308658) (xy 123.369828 -236.358892) (xy 123.37034 -236.384338)
			(xy 123.369837 -236.409327) (xy 123.677154 -236.409327) (xy 123.677154 -236.359349) (xy 123.684973 -236.309986)
			(xy 123.700417 -236.262454) (xy 123.723107 -236.217922) (xy 123.752483 -236.177489) (xy 123.787823 -236.142149)
			(xy 123.828256 -236.112773) (xy 123.872788 -236.090083) (xy 123.92032 -236.074639) (xy 123.969683 -236.06682)
			(xy 124.019661 -236.06682) (xy 124.069024 -236.074639) (xy 124.116556 -236.090083) (xy 124.161088 -236.112773)
			(xy 124.201521 -236.142149) (xy 124.236861 -236.177489) (xy 124.266237 -236.217922) (xy 124.288927 -236.262454)
			(xy 124.304371 -236.309986) (xy 124.31219 -236.359349) (xy 124.31268 -236.384338) (xy 124.618491 -236.384338)
			(xy 124.622586 -236.33361) (xy 124.634765 -236.284196) (xy 124.654713 -236.237376) (xy 124.681914 -236.194362)
			(xy 124.715662 -236.156268) (xy 124.755084 -236.124081) (xy 124.799158 -236.098635) (xy 124.846744 -236.080588)
			(xy 124.896608 -236.070408) (xy 124.94746 -236.068359) (xy 124.997981 -236.074493) (xy 125.046865 -236.088653)
			(xy 125.092844 -236.11047) (xy 125.134728 -236.13938) (xy 125.171432 -236.174635) (xy 125.202005 -236.215321)
			(xy 125.225656 -236.260384) (xy 125.241772 -236.308658) (xy 125.249936 -236.358892) (xy 125.250448 -236.384338)
			(xy 125.558545 -236.384338) (xy 125.56264 -236.33361) (xy 125.574819 -236.284196) (xy 125.594767 -236.237376)
			(xy 125.621968 -236.194362) (xy 125.655716 -236.156268) (xy 125.695138 -236.124081) (xy 125.739212 -236.098635)
			(xy 125.786798 -236.080588) (xy 125.836662 -236.070408) (xy 125.887514 -236.068359) (xy 125.938035 -236.074493)
			(xy 125.986919 -236.088653) (xy 126.032898 -236.11047) (xy 126.074782 -236.13938) (xy 126.111486 -236.174635)
			(xy 126.142059 -236.215321) (xy 126.16571 -236.260384) (xy 126.181826 -236.308658) (xy 126.18999 -236.358892)
			(xy 126.190502 -236.384338) (xy 126.18999 -236.409784) (xy 126.181826 -236.460018) (xy 126.16571 -236.508292)
			(xy 126.142059 -236.553355) (xy 126.111486 -236.594041) (xy 126.074782 -236.629296) (xy 126.032898 -236.658206)
			(xy 125.986919 -236.680023) (xy 125.938035 -236.694183) (xy 125.887514 -236.700317) (xy 125.836662 -236.698268)
			(xy 125.786798 -236.688088) (xy 125.739212 -236.670041) (xy 125.695138 -236.644595) (xy 125.655716 -236.612408)
			(xy 125.621968 -236.574314) (xy 125.594767 -236.5313) (xy 125.574819 -236.48448) (xy 125.56264 -236.435066)
			(xy 125.558545 -236.384338) (xy 125.250448 -236.384338) (xy 125.249936 -236.409784) (xy 125.241772 -236.460018)
			(xy 125.225656 -236.508292) (xy 125.202005 -236.553355) (xy 125.171432 -236.594041) (xy 125.134728 -236.629296)
			(xy 125.092844 -236.658206) (xy 125.046865 -236.680023) (xy 124.997981 -236.694183) (xy 124.94746 -236.700317)
			(xy 124.896608 -236.698268) (xy 124.846744 -236.688088) (xy 124.799158 -236.670041) (xy 124.755084 -236.644595)
			(xy 124.715662 -236.612408) (xy 124.681914 -236.574314) (xy 124.654713 -236.5313) (xy 124.634765 -236.48448)
			(xy 124.622586 -236.435066) (xy 124.618491 -236.384338) (xy 124.31268 -236.384338) (xy 124.31219 -236.409327)
			(xy 124.304371 -236.45869) (xy 124.288927 -236.506222) (xy 124.266237 -236.550754) (xy 124.236861 -236.591187)
			(xy 124.201521 -236.626527) (xy 124.161088 -236.655903) (xy 124.116556 -236.678593) (xy 124.069024 -236.694037)
			(xy 124.019661 -236.701856) (xy 123.969683 -236.701856) (xy 123.92032 -236.694037) (xy 123.872788 -236.678593)
			(xy 123.828256 -236.655903) (xy 123.787823 -236.626527) (xy 123.752483 -236.591187) (xy 123.723107 -236.550754)
			(xy 123.700417 -236.506222) (xy 123.684973 -236.45869) (xy 123.677154 -236.409327) (xy 123.369837 -236.409327)
			(xy 123.369828 -236.409784) (xy 123.361664 -236.460018) (xy 123.345548 -236.508292) (xy 123.321897 -236.553355)
			(xy 123.291324 -236.594041) (xy 123.25462 -236.629296) (xy 123.212736 -236.658206) (xy 123.166757 -236.680023)
			(xy 123.117873 -236.694183) (xy 123.067352 -236.700317) (xy 123.0165 -236.698268) (xy 122.966636 -236.688088)
			(xy 122.91905 -236.670041) (xy 122.874976 -236.644595) (xy 122.835554 -236.612408) (xy 122.801806 -236.574314)
			(xy 122.774605 -236.5313) (xy 122.754657 -236.48448) (xy 122.742478 -236.435066) (xy 122.738383 -236.384338)
			(xy 122.43054 -236.384338) (xy 122.430028 -236.409784) (xy 122.421864 -236.460018) (xy 122.405748 -236.508292)
			(xy 122.382097 -236.553355) (xy 122.351524 -236.594041) (xy 122.31482 -236.629296) (xy 122.272936 -236.658206)
			(xy 122.226957 -236.680023) (xy 122.178073 -236.694183) (xy 122.127552 -236.700317) (xy 122.0767 -236.698268)
			(xy 122.026836 -236.688088) (xy 121.97925 -236.670041) (xy 121.935176 -236.644595) (xy 121.895754 -236.612408)
			(xy 121.862006 -236.574314) (xy 121.834805 -236.5313) (xy 121.814857 -236.48448) (xy 121.802678 -236.435066)
			(xy 121.798583 -236.384338) (xy 121.492772 -236.384338) (xy 121.492282 -236.409327) (xy 121.484463 -236.45869)
			(xy 121.469019 -236.506222) (xy 121.446329 -236.550754) (xy 121.416953 -236.591187) (xy 121.381613 -236.626527)
			(xy 121.34118 -236.655903) (xy 121.296648 -236.678593) (xy 121.249116 -236.694037) (xy 121.199753 -236.701856)
			(xy 121.149775 -236.701856) (xy 121.100412 -236.694037) (xy 121.05288 -236.678593) (xy 121.008348 -236.655903)
			(xy 120.967915 -236.626527) (xy 120.932575 -236.591187) (xy 120.903199 -236.550754) (xy 120.880509 -236.506222)
			(xy 120.865065 -236.45869) (xy 120.857246 -236.409327) (xy 118.672374 -236.409327) (xy 118.664555 -236.45869)
			(xy 118.649111 -236.506222) (xy 118.626421 -236.550754) (xy 118.597045 -236.591187) (xy 118.561705 -236.626527)
			(xy 118.521272 -236.655903) (xy 118.47674 -236.678593) (xy 118.429208 -236.694037) (xy 118.379845 -236.701856)
			(xy 118.329867 -236.701856) (xy 118.280504 -236.694037) (xy 118.232972 -236.678593) (xy 118.18844 -236.655903)
			(xy 118.148007 -236.626527) (xy 118.112667 -236.591187) (xy 118.083291 -236.550754) (xy 118.060601 -236.506222)
			(xy 118.045157 -236.45869) (xy 118.037338 -236.409327) (xy 115.852212 -236.409327) (xy 115.844393 -236.45869)
			(xy 115.828949 -236.506222) (xy 115.806259 -236.550754) (xy 115.776883 -236.591187) (xy 115.741543 -236.626527)
			(xy 115.70111 -236.655903) (xy 115.656578 -236.678593) (xy 115.609046 -236.694037) (xy 115.559683 -236.701856)
			(xy 115.509705 -236.701856) (xy 115.460342 -236.694037) (xy 115.41281 -236.678593) (xy 115.368278 -236.655903)
			(xy 115.327845 -236.626527) (xy 115.292505 -236.591187) (xy 115.263129 -236.550754) (xy 115.240439 -236.506222)
			(xy 115.224995 -236.45869) (xy 115.217176 -236.409327) (xy 114.912158 -236.409327) (xy 114.904339 -236.45869)
			(xy 114.888895 -236.506222) (xy 114.866205 -236.550754) (xy 114.836829 -236.591187) (xy 114.801489 -236.626527)
			(xy 114.761056 -236.655903) (xy 114.716524 -236.678593) (xy 114.668992 -236.694037) (xy 114.619629 -236.701856)
			(xy 114.569651 -236.701856) (xy 114.520288 -236.694037) (xy 114.472756 -236.678593) (xy 114.428224 -236.655903)
			(xy 114.387791 -236.626527) (xy 114.352451 -236.591187) (xy 114.323075 -236.550754) (xy 114.300385 -236.506222)
			(xy 114.284941 -236.45869) (xy 114.277122 -236.409327) (xy 113.972358 -236.409327) (xy 113.964539 -236.45869)
			(xy 113.949095 -236.506222) (xy 113.926405 -236.550754) (xy 113.897029 -236.591187) (xy 113.861689 -236.626527)
			(xy 113.821256 -236.655903) (xy 113.776724 -236.678593) (xy 113.729192 -236.694037) (xy 113.679829 -236.701856)
			(xy 113.629851 -236.701856) (xy 113.580488 -236.694037) (xy 113.532956 -236.678593) (xy 113.488424 -236.655903)
			(xy 113.447991 -236.626527) (xy 113.412651 -236.591187) (xy 113.383275 -236.550754) (xy 113.360585 -236.506222)
			(xy 113.345141 -236.45869) (xy 113.337322 -236.409327) (xy 110.218492 -236.409327) (xy 110.210673 -236.45869)
			(xy 110.195229 -236.506222) (xy 110.172539 -236.550754) (xy 110.143163 -236.591187) (xy 110.107823 -236.626527)
			(xy 110.06739 -236.655903) (xy 110.022858 -236.678593) (xy 109.975326 -236.694037) (xy 109.925963 -236.701856)
			(xy 109.875985 -236.701856) (xy 109.826622 -236.694037) (xy 109.77909 -236.678593) (xy 109.734558 -236.655903)
			(xy 109.694125 -236.626527) (xy 109.658785 -236.591187) (xy 109.629409 -236.550754) (xy 109.606719 -236.506222)
			(xy 109.591275 -236.45869) (xy 109.583456 -236.409327) (xy 109.278692 -236.409327) (xy 109.270873 -236.45869)
			(xy 109.255429 -236.506222) (xy 109.232739 -236.550754) (xy 109.203363 -236.591187) (xy 109.168023 -236.626527)
			(xy 109.12759 -236.655903) (xy 109.083058 -236.678593) (xy 109.035526 -236.694037) (xy 108.986163 -236.701856)
			(xy 108.936185 -236.701856) (xy 108.886822 -236.694037) (xy 108.83929 -236.678593) (xy 108.794758 -236.655903)
			(xy 108.754325 -236.626527) (xy 108.718985 -236.591187) (xy 108.689609 -236.550754) (xy 108.666919 -236.506222)
			(xy 108.651475 -236.45869) (xy 108.643656 -236.409327) (xy 108.338638 -236.409327) (xy 108.330819 -236.45869)
			(xy 108.315375 -236.506222) (xy 108.292685 -236.550754) (xy 108.263309 -236.591187) (xy 108.227969 -236.626527)
			(xy 108.187536 -236.655903) (xy 108.143004 -236.678593) (xy 108.095472 -236.694037) (xy 108.046109 -236.701856)
			(xy 107.996131 -236.701856) (xy 107.946768 -236.694037) (xy 107.899236 -236.678593) (xy 107.854704 -236.655903)
			(xy 107.814271 -236.626527) (xy 107.778931 -236.591187) (xy 107.749555 -236.550754) (xy 107.726865 -236.506222)
			(xy 107.711421 -236.45869) (xy 107.703602 -236.409327) (xy 105.518476 -236.409327) (xy 105.510657 -236.45869)
			(xy 105.495213 -236.506222) (xy 105.472523 -236.550754) (xy 105.443147 -236.591187) (xy 105.407807 -236.626527)
			(xy 105.367374 -236.655903) (xy 105.322842 -236.678593) (xy 105.27531 -236.694037) (xy 105.225947 -236.701856)
			(xy 105.175969 -236.701856) (xy 105.126606 -236.694037) (xy 105.079074 -236.678593) (xy 105.034542 -236.655903)
			(xy 104.994109 -236.626527) (xy 104.958769 -236.591187) (xy 104.929393 -236.550754) (xy 104.906703 -236.506222)
			(xy 104.891259 -236.45869) (xy 104.88344 -236.409327) (xy 102.698568 -236.409327) (xy 102.690749 -236.45869)
			(xy 102.675305 -236.506222) (xy 102.652615 -236.550754) (xy 102.623239 -236.591187) (xy 102.587899 -236.626527)
			(xy 102.547466 -236.655903) (xy 102.502934 -236.678593) (xy 102.455402 -236.694037) (xy 102.406039 -236.701856)
			(xy 102.356061 -236.701856) (xy 102.306698 -236.694037) (xy 102.259166 -236.678593) (xy 102.214634 -236.655903)
			(xy 102.174201 -236.626527) (xy 102.138861 -236.591187) (xy 102.109485 -236.550754) (xy 102.086795 -236.506222)
			(xy 102.071351 -236.45869) (xy 102.063532 -236.409327) (xy 101.756215 -236.409327) (xy 101.756206 -236.409784)
			(xy 101.748042 -236.460018) (xy 101.731926 -236.508292) (xy 101.708275 -236.553355) (xy 101.677702 -236.594041)
			(xy 101.640998 -236.629296) (xy 101.599114 -236.658206) (xy 101.553135 -236.680023) (xy 101.504251 -236.694183)
			(xy 101.45373 -236.700317) (xy 101.402878 -236.698268) (xy 101.353014 -236.688088) (xy 101.305428 -236.670041)
			(xy 101.261354 -236.644595) (xy 101.221932 -236.612408) (xy 101.188184 -236.574314) (xy 101.160983 -236.5313)
			(xy 101.141035 -236.48448) (xy 101.128856 -236.435066) (xy 101.124761 -236.384338) (xy 100.816664 -236.384338)
			(xy 100.816152 -236.409784) (xy 100.807988 -236.460018) (xy 100.791872 -236.508292) (xy 100.768221 -236.553355)
			(xy 100.737648 -236.594041) (xy 100.700944 -236.629296) (xy 100.65906 -236.658206) (xy 100.613081 -236.680023)
			(xy 100.564197 -236.694183) (xy 100.513676 -236.700317) (xy 100.462824 -236.698268) (xy 100.41296 -236.688088)
			(xy 100.365374 -236.670041) (xy 100.3213 -236.644595) (xy 100.281878 -236.612408) (xy 100.24813 -236.574314)
			(xy 100.220929 -236.5313) (xy 100.200981 -236.48448) (xy 100.188802 -236.435066) (xy 100.184707 -236.384338)
			(xy 99.87915 -236.384338) (xy 99.87866 -236.409327) (xy 99.870841 -236.45869) (xy 99.855397 -236.506222)
			(xy 99.832707 -236.550754) (xy 99.803331 -236.591187) (xy 99.767991 -236.626527) (xy 99.727558 -236.655903)
			(xy 99.683026 -236.678593) (xy 99.635494 -236.694037) (xy 99.586131 -236.701856) (xy 99.536153 -236.701856)
			(xy 99.48679 -236.694037) (xy 99.439258 -236.678593) (xy 99.394726 -236.655903) (xy 99.354293 -236.626527)
			(xy 99.318953 -236.591187) (xy 99.289577 -236.550754) (xy 99.266887 -236.506222) (xy 99.251443 -236.45869)
			(xy 99.243624 -236.409327) (xy 98.936307 -236.409327) (xy 98.936298 -236.409784) (xy 98.928134 -236.460018)
			(xy 98.912018 -236.508292) (xy 98.888367 -236.553355) (xy 98.857794 -236.594041) (xy 98.82109 -236.629296)
			(xy 98.779206 -236.658206) (xy 98.733227 -236.680023) (xy 98.684343 -236.694183) (xy 98.633822 -236.700317)
			(xy 98.58297 -236.698268) (xy 98.533106 -236.688088) (xy 98.48552 -236.670041) (xy 98.441446 -236.644595)
			(xy 98.402024 -236.612408) (xy 98.368276 -236.574314) (xy 98.341075 -236.5313) (xy 98.321127 -236.48448)
			(xy 98.308948 -236.435066) (xy 98.304853 -236.384338) (xy 97.996756 -236.384338) (xy 97.996244 -236.409784)
			(xy 97.98808 -236.460018) (xy 97.971964 -236.508292) (xy 97.948313 -236.553355) (xy 97.91774 -236.594041)
			(xy 97.881036 -236.629296) (xy 97.839152 -236.658206) (xy 97.793173 -236.680023) (xy 97.744289 -236.694183)
			(xy 97.693768 -236.700317) (xy 97.642916 -236.698268) (xy 97.593052 -236.688088) (xy 97.545466 -236.670041)
			(xy 97.501392 -236.644595) (xy 97.46197 -236.612408) (xy 97.428222 -236.574314) (xy 97.401021 -236.5313)
			(xy 97.381073 -236.48448) (xy 97.368894 -236.435066) (xy 97.364799 -236.384338) (xy 97.058988 -236.384338)
			(xy 97.058988 -236.387894) (xy 97.057718 -236.417866) (xy 97.057464 -236.41939) (xy 97.057464 -236.779054)
			(xy 97.057949 -236.7898) (xy 97.066771 -236.809398) (xy 97.074482 -236.8169) (xy 97.092516 -236.832902)
			(xy 97.130362 -236.86643) (xy 97.13087 -236.86643) (xy 97.131886 -236.867446) (xy 97.155508 -236.863382)
			(xy 97.169313 -236.861228) (xy 97.197162 -236.858937) (xy 97.211134 -236.85881) (xy 97.237495 -236.85933)
			(xy 97.289568 -236.867582) (xy 97.339708 -236.883878) (xy 97.386683 -236.907817) (xy 97.429334 -236.938809)
			(xy 97.466613 -236.976092) (xy 97.497601 -237.018746) (xy 97.521535 -237.065723) (xy 97.537826 -237.115865)
			(xy 97.546073 -237.167939) (xy 97.546073 -237.219333) (xy 97.833416 -237.219333) (xy 97.833416 -237.169355)
			(xy 97.841235 -237.119992) (xy 97.856679 -237.07246) (xy 97.879369 -237.027928) (xy 97.908745 -236.987495)
			(xy 97.944085 -236.952155) (xy 97.984518 -236.922779) (xy 98.02905 -236.900089) (xy 98.076582 -236.884645)
			(xy 98.125945 -236.876826) (xy 98.175923 -236.876826) (xy 98.225286 -236.884645) (xy 98.272818 -236.900089)
			(xy 98.31735 -236.922779) (xy 98.357783 -236.952155) (xy 98.393123 -236.987495) (xy 98.422499 -237.027928)
			(xy 98.445189 -237.07246) (xy 98.460633 -237.119992) (xy 98.468452 -237.169355) (xy 98.468942 -237.194344)
			(xy 98.468452 -237.219333) (xy 98.77347 -237.219333) (xy 98.77347 -237.169355) (xy 98.781289 -237.119992)
			(xy 98.796733 -237.07246) (xy 98.819423 -237.027928) (xy 98.848799 -236.987495) (xy 98.884139 -236.952155)
			(xy 98.924572 -236.922779) (xy 98.969104 -236.900089) (xy 99.016636 -236.884645) (xy 99.065999 -236.876826)
			(xy 99.115977 -236.876826) (xy 99.16534 -236.884645) (xy 99.212872 -236.900089) (xy 99.257404 -236.922779)
			(xy 99.297837 -236.952155) (xy 99.333177 -236.987495) (xy 99.362553 -237.027928) (xy 99.385243 -237.07246)
			(xy 99.400687 -237.119992) (xy 99.408506 -237.169355) (xy 99.408996 -237.194344) (xy 99.408506 -237.219333)
			(xy 99.713524 -237.219333) (xy 99.713524 -237.169355) (xy 99.721343 -237.119992) (xy 99.736787 -237.07246)
			(xy 99.759477 -237.027928) (xy 99.788853 -236.987495) (xy 99.824193 -236.952155) (xy 99.864626 -236.922779)
			(xy 99.909158 -236.900089) (xy 99.95669 -236.884645) (xy 100.006053 -236.876826) (xy 100.056031 -236.876826)
			(xy 100.105394 -236.884645) (xy 100.152926 -236.900089) (xy 100.197458 -236.922779) (xy 100.237891 -236.952155)
			(xy 100.273231 -236.987495) (xy 100.302607 -237.027928) (xy 100.325297 -237.07246) (xy 100.340741 -237.119992)
			(xy 100.34856 -237.169355) (xy 100.34905 -237.194344) (xy 100.34856 -237.219333) (xy 100.653578 -237.219333)
			(xy 100.653578 -237.169355) (xy 100.661397 -237.119992) (xy 100.676841 -237.07246) (xy 100.699531 -237.027928)
			(xy 100.728907 -236.987495) (xy 100.764247 -236.952155) (xy 100.80468 -236.922779) (xy 100.849212 -236.900089)
			(xy 100.896744 -236.884645) (xy 100.946107 -236.876826) (xy 100.996085 -236.876826) (xy 101.045448 -236.884645)
			(xy 101.09298 -236.900089) (xy 101.137512 -236.922779) (xy 101.177945 -236.952155) (xy 101.213285 -236.987495)
			(xy 101.242661 -237.027928) (xy 101.265351 -237.07246) (xy 101.280795 -237.119992) (xy 101.288614 -237.169355)
			(xy 101.289104 -237.194344) (xy 101.288614 -237.219333) (xy 101.593632 -237.219333) (xy 101.593632 -237.169355)
			(xy 101.601451 -237.119992) (xy 101.616895 -237.07246) (xy 101.639585 -237.027928) (xy 101.668961 -236.987495)
			(xy 101.704301 -236.952155) (xy 101.744734 -236.922779) (xy 101.789266 -236.900089) (xy 101.836798 -236.884645)
			(xy 101.886161 -236.876826) (xy 101.936139 -236.876826) (xy 101.985502 -236.884645) (xy 102.033034 -236.900089)
			(xy 102.077566 -236.922779) (xy 102.117999 -236.952155) (xy 102.153339 -236.987495) (xy 102.182715 -237.027928)
			(xy 102.205405 -237.07246) (xy 102.220849 -237.119992) (xy 102.228668 -237.169355) (xy 102.229158 -237.194344)
			(xy 102.228668 -237.219333) (xy 102.533432 -237.219333) (xy 102.533432 -237.169355) (xy 102.541251 -237.119992)
			(xy 102.556695 -237.07246) (xy 102.579385 -237.027928) (xy 102.608761 -236.987495) (xy 102.644101 -236.952155)
			(xy 102.684534 -236.922779) (xy 102.729066 -236.900089) (xy 102.776598 -236.884645) (xy 102.825961 -236.876826)
			(xy 102.875939 -236.876826) (xy 102.925302 -236.884645) (xy 102.972834 -236.900089) (xy 103.017366 -236.922779)
			(xy 103.057799 -236.952155) (xy 103.093139 -236.987495) (xy 103.122515 -237.027928) (xy 103.145205 -237.07246)
			(xy 103.160649 -237.119992) (xy 103.168468 -237.169355) (xy 103.168958 -237.194344) (xy 103.168468 -237.219333)
			(xy 103.473486 -237.219333) (xy 103.473486 -237.169355) (xy 103.481305 -237.119992) (xy 103.496749 -237.07246)
			(xy 103.519439 -237.027928) (xy 103.548815 -236.987495) (xy 103.584155 -236.952155) (xy 103.624588 -236.922779)
			(xy 103.66912 -236.900089) (xy 103.716652 -236.884645) (xy 103.766015 -236.876826) (xy 103.815993 -236.876826)
			(xy 103.865356 -236.884645) (xy 103.912888 -236.900089) (xy 103.95742 -236.922779) (xy 103.997853 -236.952155)
			(xy 104.033193 -236.987495) (xy 104.062569 -237.027928) (xy 104.085259 -237.07246) (xy 104.100703 -237.119992)
			(xy 104.108522 -237.169355) (xy 104.109012 -237.194344) (xy 104.108522 -237.219333) (xy 104.41354 -237.219333)
			(xy 104.41354 -237.169355) (xy 104.421359 -237.119992) (xy 104.436803 -237.07246) (xy 104.459493 -237.027928)
			(xy 104.488869 -236.987495) (xy 104.524209 -236.952155) (xy 104.564642 -236.922779) (xy 104.609174 -236.900089)
			(xy 104.656706 -236.884645) (xy 104.706069 -236.876826) (xy 104.756047 -236.876826) (xy 104.80541 -236.884645)
			(xy 104.852942 -236.900089) (xy 104.897474 -236.922779) (xy 104.937907 -236.952155) (xy 104.973247 -236.987495)
			(xy 105.002623 -237.027928) (xy 105.025313 -237.07246) (xy 105.040757 -237.119992) (xy 105.048576 -237.169355)
			(xy 105.049066 -237.194344) (xy 105.048576 -237.219333) (xy 105.353594 -237.219333) (xy 105.353594 -237.169355)
			(xy 105.361413 -237.119992) (xy 105.376857 -237.07246) (xy 105.399547 -237.027928) (xy 105.428923 -236.987495)
			(xy 105.464263 -236.952155) (xy 105.504696 -236.922779) (xy 105.549228 -236.900089) (xy 105.59676 -236.884645)
			(xy 105.646123 -236.876826) (xy 105.696101 -236.876826) (xy 105.745464 -236.884645) (xy 105.792996 -236.900089)
			(xy 105.837528 -236.922779) (xy 105.877961 -236.952155) (xy 105.913301 -236.987495) (xy 105.942677 -237.027928)
			(xy 105.965367 -237.07246) (xy 105.980811 -237.119992) (xy 105.98863 -237.169355) (xy 105.98912 -237.194344)
			(xy 105.98863 -237.219333) (xy 106.293648 -237.219333) (xy 106.293648 -237.169355) (xy 106.301467 -237.119992)
			(xy 106.316911 -237.07246) (xy 106.339601 -237.027928) (xy 106.368977 -236.987495) (xy 106.404317 -236.952155)
			(xy 106.44475 -236.922779) (xy 106.489282 -236.900089) (xy 106.536814 -236.884645) (xy 106.586177 -236.876826)
			(xy 106.636155 -236.876826) (xy 106.685518 -236.884645) (xy 106.73305 -236.900089) (xy 106.777582 -236.922779)
			(xy 106.818015 -236.952155) (xy 106.853355 -236.987495) (xy 106.882731 -237.027928) (xy 106.905421 -237.07246)
			(xy 106.920865 -237.119992) (xy 106.928684 -237.169355) (xy 106.929174 -237.194344) (xy 106.928684 -237.219333)
			(xy 107.233448 -237.219333) (xy 107.233448 -237.169355) (xy 107.241267 -237.119992) (xy 107.256711 -237.07246)
			(xy 107.279401 -237.027928) (xy 107.308777 -236.987495) (xy 107.344117 -236.952155) (xy 107.38455 -236.922779)
			(xy 107.429082 -236.900089) (xy 107.476614 -236.884645) (xy 107.525977 -236.876826) (xy 107.575955 -236.876826)
			(xy 107.625318 -236.884645) (xy 107.67285 -236.900089) (xy 107.717382 -236.922779) (xy 107.757815 -236.952155)
			(xy 107.793155 -236.987495) (xy 107.822531 -237.027928) (xy 107.845221 -237.07246) (xy 107.860665 -237.119992)
			(xy 107.868484 -237.169355) (xy 107.868974 -237.194344) (xy 107.868484 -237.219333) (xy 110.05361 -237.219333)
			(xy 110.05361 -237.169355) (xy 110.061429 -237.119992) (xy 110.076873 -237.07246) (xy 110.099563 -237.027928)
			(xy 110.128939 -236.987495) (xy 110.164279 -236.952155) (xy 110.204712 -236.922779) (xy 110.249244 -236.900089)
			(xy 110.296776 -236.884645) (xy 110.346139 -236.876826) (xy 110.396117 -236.876826) (xy 110.44548 -236.884645)
			(xy 110.493012 -236.900089) (xy 110.537544 -236.922779) (xy 110.577977 -236.952155) (xy 110.613317 -236.987495)
			(xy 110.642693 -237.027928) (xy 110.665383 -237.07246) (xy 110.680827 -237.119992) (xy 110.688646 -237.169355)
			(xy 110.689136 -237.194344) (xy 110.688646 -237.219333) (xy 112.867168 -237.219333) (xy 112.867168 -237.169355)
			(xy 112.874987 -237.119992) (xy 112.890431 -237.07246) (xy 112.913121 -237.027928) (xy 112.942497 -236.987495)
			(xy 112.977837 -236.952155) (xy 113.01827 -236.922779) (xy 113.062802 -236.900089) (xy 113.110334 -236.884645)
			(xy 113.159697 -236.876826) (xy 113.209675 -236.876826) (xy 113.259038 -236.884645) (xy 113.30657 -236.900089)
			(xy 113.351102 -236.922779) (xy 113.391535 -236.952155) (xy 113.426875 -236.987495) (xy 113.456251 -237.027928)
			(xy 113.478941 -237.07246) (xy 113.494385 -237.119992) (xy 113.502204 -237.169355) (xy 113.502694 -237.194344)
			(xy 113.502204 -237.219333) (xy 115.68733 -237.219333) (xy 115.68733 -237.169355) (xy 115.695149 -237.119992)
			(xy 115.710593 -237.07246) (xy 115.733283 -237.027928) (xy 115.762659 -236.987495) (xy 115.797999 -236.952155)
			(xy 115.838432 -236.922779) (xy 115.882964 -236.900089) (xy 115.930496 -236.884645) (xy 115.979859 -236.876826)
			(xy 116.029837 -236.876826) (xy 116.0792 -236.884645) (xy 116.126732 -236.900089) (xy 116.171264 -236.922779)
			(xy 116.211697 -236.952155) (xy 116.247037 -236.987495) (xy 116.276413 -237.027928) (xy 116.299103 -237.07246)
			(xy 116.314547 -237.119992) (xy 116.322366 -237.169355) (xy 116.322856 -237.194344) (xy 116.322366 -237.219333)
			(xy 116.62713 -237.219333) (xy 116.62713 -237.169355) (xy 116.634949 -237.119992) (xy 116.650393 -237.07246)
			(xy 116.673083 -237.027928) (xy 116.702459 -236.987495) (xy 116.737799 -236.952155) (xy 116.778232 -236.922779)
			(xy 116.822764 -236.900089) (xy 116.870296 -236.884645) (xy 116.919659 -236.876826) (xy 116.969637 -236.876826)
			(xy 117.019 -236.884645) (xy 117.066532 -236.900089) (xy 117.111064 -236.922779) (xy 117.151497 -236.952155)
			(xy 117.186837 -236.987495) (xy 117.216213 -237.027928) (xy 117.238903 -237.07246) (xy 117.254347 -237.119992)
			(xy 117.262166 -237.169355) (xy 117.262656 -237.194344) (xy 117.262166 -237.219333) (xy 117.567184 -237.219333)
			(xy 117.567184 -237.169355) (xy 117.575003 -237.119992) (xy 117.590447 -237.07246) (xy 117.613137 -237.027928)
			(xy 117.642513 -236.987495) (xy 117.677853 -236.952155) (xy 117.718286 -236.922779) (xy 117.762818 -236.900089)
			(xy 117.81035 -236.884645) (xy 117.859713 -236.876826) (xy 117.909691 -236.876826) (xy 117.959054 -236.884645)
			(xy 118.006586 -236.900089) (xy 118.051118 -236.922779) (xy 118.091551 -236.952155) (xy 118.126891 -236.987495)
			(xy 118.156267 -237.027928) (xy 118.178957 -237.07246) (xy 118.194401 -237.119992) (xy 118.20222 -237.169355)
			(xy 118.20271 -237.194344) (xy 118.20222 -237.219333) (xy 118.507238 -237.219333) (xy 118.507238 -237.169355)
			(xy 118.515057 -237.119992) (xy 118.530501 -237.07246) (xy 118.553191 -237.027928) (xy 118.582567 -236.987495)
			(xy 118.617907 -236.952155) (xy 118.65834 -236.922779) (xy 118.702872 -236.900089) (xy 118.750404 -236.884645)
			(xy 118.799767 -236.876826) (xy 118.849745 -236.876826) (xy 118.899108 -236.884645) (xy 118.94664 -236.900089)
			(xy 118.991172 -236.922779) (xy 119.031605 -236.952155) (xy 119.066945 -236.987495) (xy 119.096321 -237.027928)
			(xy 119.119011 -237.07246) (xy 119.134455 -237.119992) (xy 119.142274 -237.169355) (xy 119.142764 -237.194344)
			(xy 119.142274 -237.219333) (xy 119.447292 -237.219333) (xy 119.447292 -237.169355) (xy 119.455111 -237.119992)
			(xy 119.470555 -237.07246) (xy 119.493245 -237.027928) (xy 119.522621 -236.987495) (xy 119.557961 -236.952155)
			(xy 119.598394 -236.922779) (xy 119.642926 -236.900089) (xy 119.690458 -236.884645) (xy 119.739821 -236.876826)
			(xy 119.789799 -236.876826) (xy 119.839162 -236.884645) (xy 119.886694 -236.900089) (xy 119.931226 -236.922779)
			(xy 119.971659 -236.952155) (xy 120.006999 -236.987495) (xy 120.036375 -237.027928) (xy 120.059065 -237.07246)
			(xy 120.074509 -237.119992) (xy 120.082328 -237.169355) (xy 120.082818 -237.194344) (xy 120.082328 -237.219333)
			(xy 120.387092 -237.219333) (xy 120.387092 -237.169355) (xy 120.394911 -237.119992) (xy 120.410355 -237.07246)
			(xy 120.433045 -237.027928) (xy 120.462421 -236.987495) (xy 120.497761 -236.952155) (xy 120.538194 -236.922779)
			(xy 120.582726 -236.900089) (xy 120.630258 -236.884645) (xy 120.679621 -236.876826) (xy 120.729599 -236.876826)
			(xy 120.778962 -236.884645) (xy 120.826494 -236.900089) (xy 120.871026 -236.922779) (xy 120.911459 -236.952155)
			(xy 120.946799 -236.987495) (xy 120.976175 -237.027928) (xy 120.998865 -237.07246) (xy 121.014309 -237.119992)
			(xy 121.022128 -237.169355) (xy 121.022618 -237.194344) (xy 121.022128 -237.219333) (xy 121.327146 -237.219333)
			(xy 121.327146 -237.169355) (xy 121.334965 -237.119992) (xy 121.350409 -237.07246) (xy 121.373099 -237.027928)
			(xy 121.402475 -236.987495) (xy 121.437815 -236.952155) (xy 121.478248 -236.922779) (xy 121.52278 -236.900089)
			(xy 121.570312 -236.884645) (xy 121.619675 -236.876826) (xy 121.669653 -236.876826) (xy 121.719016 -236.884645)
			(xy 121.766548 -236.900089) (xy 121.81108 -236.922779) (xy 121.851513 -236.952155) (xy 121.886853 -236.987495)
			(xy 121.916229 -237.027928) (xy 121.938919 -237.07246) (xy 121.954363 -237.119992) (xy 121.962182 -237.169355)
			(xy 121.962672 -237.194344) (xy 121.962182 -237.219333) (xy 122.2672 -237.219333) (xy 122.2672 -237.169355)
			(xy 122.275019 -237.119992) (xy 122.290463 -237.07246) (xy 122.313153 -237.027928) (xy 122.342529 -236.987495)
			(xy 122.377869 -236.952155) (xy 122.418302 -236.922779) (xy 122.462834 -236.900089) (xy 122.510366 -236.884645)
			(xy 122.559729 -236.876826) (xy 122.609707 -236.876826) (xy 122.65907 -236.884645) (xy 122.706602 -236.900089)
			(xy 122.751134 -236.922779) (xy 122.791567 -236.952155) (xy 122.826907 -236.987495) (xy 122.856283 -237.027928)
			(xy 122.878973 -237.07246) (xy 122.894417 -237.119992) (xy 122.902236 -237.169355) (xy 122.902726 -237.194344)
			(xy 122.902236 -237.219333) (xy 123.207254 -237.219333) (xy 123.207254 -237.169355) (xy 123.215073 -237.119992)
			(xy 123.230517 -237.07246) (xy 123.253207 -237.027928) (xy 123.282583 -236.987495) (xy 123.317923 -236.952155)
			(xy 123.358356 -236.922779) (xy 123.402888 -236.900089) (xy 123.45042 -236.884645) (xy 123.499783 -236.876826)
			(xy 123.549761 -236.876826) (xy 123.599124 -236.884645) (xy 123.646656 -236.900089) (xy 123.691188 -236.922779)
			(xy 123.731621 -236.952155) (xy 123.766961 -236.987495) (xy 123.796337 -237.027928) (xy 123.819027 -237.07246)
			(xy 123.834471 -237.119992) (xy 123.84229 -237.169355) (xy 123.84278 -237.194344) (xy 123.84229 -237.219333)
			(xy 124.147308 -237.219333) (xy 124.147308 -237.169355) (xy 124.155127 -237.119992) (xy 124.170571 -237.07246)
			(xy 124.193261 -237.027928) (xy 124.222637 -236.987495) (xy 124.257977 -236.952155) (xy 124.29841 -236.922779)
			(xy 124.342942 -236.900089) (xy 124.390474 -236.884645) (xy 124.439837 -236.876826) (xy 124.489815 -236.876826)
			(xy 124.539178 -236.884645) (xy 124.58671 -236.900089) (xy 124.631242 -236.922779) (xy 124.671675 -236.952155)
			(xy 124.707015 -236.987495) (xy 124.736391 -237.027928) (xy 124.759081 -237.07246) (xy 124.774525 -237.119992)
			(xy 124.782344 -237.169355) (xy 124.782834 -237.194344) (xy 124.782344 -237.219333) (xy 125.087108 -237.219333)
			(xy 125.087108 -237.169355) (xy 125.094927 -237.119992) (xy 125.110371 -237.07246) (xy 125.133061 -237.027928)
			(xy 125.162437 -236.987495) (xy 125.197777 -236.952155) (xy 125.23821 -236.922779) (xy 125.282742 -236.900089)
			(xy 125.330274 -236.884645) (xy 125.379637 -236.876826) (xy 125.429615 -236.876826) (xy 125.478978 -236.884645)
			(xy 125.52651 -236.900089) (xy 125.571042 -236.922779) (xy 125.611475 -236.952155) (xy 125.646815 -236.987495)
			(xy 125.676191 -237.027928) (xy 125.698881 -237.07246) (xy 125.714325 -237.119992) (xy 125.722144 -237.169355)
			(xy 125.722634 -237.194344) (xy 125.722144 -237.219333) (xy 125.714325 -237.268696) (xy 125.698881 -237.316228)
			(xy 125.676191 -237.36076) (xy 125.646815 -237.401193) (xy 125.611475 -237.436533) (xy 125.571042 -237.465909)
			(xy 125.52651 -237.488599) (xy 125.478978 -237.504043) (xy 125.429615 -237.511862) (xy 125.379637 -237.511862)
			(xy 125.330274 -237.504043) (xy 125.282742 -237.488599) (xy 125.23821 -237.465909) (xy 125.197777 -237.436533)
			(xy 125.162437 -237.401193) (xy 125.133061 -237.36076) (xy 125.110371 -237.316228) (xy 125.094927 -237.268696)
			(xy 125.087108 -237.219333) (xy 124.782344 -237.219333) (xy 124.774525 -237.268696) (xy 124.759081 -237.316228)
			(xy 124.736391 -237.36076) (xy 124.707015 -237.401193) (xy 124.671675 -237.436533) (xy 124.631242 -237.465909)
			(xy 124.58671 -237.488599) (xy 124.539178 -237.504043) (xy 124.489815 -237.511862) (xy 124.439837 -237.511862)
			(xy 124.390474 -237.504043) (xy 124.342942 -237.488599) (xy 124.29841 -237.465909) (xy 124.257977 -237.436533)
			(xy 124.222637 -237.401193) (xy 124.193261 -237.36076) (xy 124.170571 -237.316228) (xy 124.155127 -237.268696)
			(xy 124.147308 -237.219333) (xy 123.84229 -237.219333) (xy 123.834471 -237.268696) (xy 123.819027 -237.316228)
			(xy 123.796337 -237.36076) (xy 123.766961 -237.401193) (xy 123.731621 -237.436533) (xy 123.691188 -237.465909)
			(xy 123.646656 -237.488599) (xy 123.599124 -237.504043) (xy 123.549761 -237.511862) (xy 123.499783 -237.511862)
			(xy 123.45042 -237.504043) (xy 123.402888 -237.488599) (xy 123.358356 -237.465909) (xy 123.317923 -237.436533)
			(xy 123.282583 -237.401193) (xy 123.253207 -237.36076) (xy 123.230517 -237.316228) (xy 123.215073 -237.268696)
			(xy 123.207254 -237.219333) (xy 122.902236 -237.219333) (xy 122.894417 -237.268696) (xy 122.878973 -237.316228)
			(xy 122.856283 -237.36076) (xy 122.826907 -237.401193) (xy 122.791567 -237.436533) (xy 122.751134 -237.465909)
			(xy 122.706602 -237.488599) (xy 122.65907 -237.504043) (xy 122.609707 -237.511862) (xy 122.559729 -237.511862)
			(xy 122.510366 -237.504043) (xy 122.462834 -237.488599) (xy 122.418302 -237.465909) (xy 122.377869 -237.436533)
			(xy 122.342529 -237.401193) (xy 122.313153 -237.36076) (xy 122.290463 -237.316228) (xy 122.275019 -237.268696)
			(xy 122.2672 -237.219333) (xy 121.962182 -237.219333) (xy 121.954363 -237.268696) (xy 121.938919 -237.316228)
			(xy 121.916229 -237.36076) (xy 121.886853 -237.401193) (xy 121.851513 -237.436533) (xy 121.81108 -237.465909)
			(xy 121.766548 -237.488599) (xy 121.719016 -237.504043) (xy 121.669653 -237.511862) (xy 121.619675 -237.511862)
			(xy 121.570312 -237.504043) (xy 121.52278 -237.488599) (xy 121.478248 -237.465909) (xy 121.437815 -237.436533)
			(xy 121.402475 -237.401193) (xy 121.373099 -237.36076) (xy 121.350409 -237.316228) (xy 121.334965 -237.268696)
			(xy 121.327146 -237.219333) (xy 121.022128 -237.219333) (xy 121.014309 -237.268696) (xy 120.998865 -237.316228)
			(xy 120.976175 -237.36076) (xy 120.946799 -237.401193) (xy 120.911459 -237.436533) (xy 120.871026 -237.465909)
			(xy 120.826494 -237.488599) (xy 120.778962 -237.504043) (xy 120.729599 -237.511862) (xy 120.679621 -237.511862)
			(xy 120.630258 -237.504043) (xy 120.582726 -237.488599) (xy 120.538194 -237.465909) (xy 120.497761 -237.436533)
			(xy 120.462421 -237.401193) (xy 120.433045 -237.36076) (xy 120.410355 -237.316228) (xy 120.394911 -237.268696)
			(xy 120.387092 -237.219333) (xy 120.082328 -237.219333) (xy 120.074509 -237.268696) (xy 120.059065 -237.316228)
			(xy 120.036375 -237.36076) (xy 120.006999 -237.401193) (xy 119.971659 -237.436533) (xy 119.931226 -237.465909)
			(xy 119.886694 -237.488599) (xy 119.839162 -237.504043) (xy 119.789799 -237.511862) (xy 119.739821 -237.511862)
			(xy 119.690458 -237.504043) (xy 119.642926 -237.488599) (xy 119.598394 -237.465909) (xy 119.557961 -237.436533)
			(xy 119.522621 -237.401193) (xy 119.493245 -237.36076) (xy 119.470555 -237.316228) (xy 119.455111 -237.268696)
			(xy 119.447292 -237.219333) (xy 119.142274 -237.219333) (xy 119.134455 -237.268696) (xy 119.119011 -237.316228)
			(xy 119.096321 -237.36076) (xy 119.066945 -237.401193) (xy 119.031605 -237.436533) (xy 118.991172 -237.465909)
			(xy 118.94664 -237.488599) (xy 118.899108 -237.504043) (xy 118.849745 -237.511862) (xy 118.799767 -237.511862)
			(xy 118.750404 -237.504043) (xy 118.702872 -237.488599) (xy 118.65834 -237.465909) (xy 118.617907 -237.436533)
			(xy 118.582567 -237.401193) (xy 118.553191 -237.36076) (xy 118.530501 -237.316228) (xy 118.515057 -237.268696)
			(xy 118.507238 -237.219333) (xy 118.20222 -237.219333) (xy 118.194401 -237.268696) (xy 118.178957 -237.316228)
			(xy 118.156267 -237.36076) (xy 118.126891 -237.401193) (xy 118.091551 -237.436533) (xy 118.051118 -237.465909)
			(xy 118.006586 -237.488599) (xy 117.959054 -237.504043) (xy 117.909691 -237.511862) (xy 117.859713 -237.511862)
			(xy 117.81035 -237.504043) (xy 117.762818 -237.488599) (xy 117.718286 -237.465909) (xy 117.677853 -237.436533)
			(xy 117.642513 -237.401193) (xy 117.613137 -237.36076) (xy 117.590447 -237.316228) (xy 117.575003 -237.268696)
			(xy 117.567184 -237.219333) (xy 117.262166 -237.219333) (xy 117.254347 -237.268696) (xy 117.238903 -237.316228)
			(xy 117.216213 -237.36076) (xy 117.186837 -237.401193) (xy 117.151497 -237.436533) (xy 117.111064 -237.465909)
			(xy 117.066532 -237.488599) (xy 117.019 -237.504043) (xy 116.969637 -237.511862) (xy 116.919659 -237.511862)
			(xy 116.870296 -237.504043) (xy 116.822764 -237.488599) (xy 116.778232 -237.465909) (xy 116.737799 -237.436533)
			(xy 116.702459 -237.401193) (xy 116.673083 -237.36076) (xy 116.650393 -237.316228) (xy 116.634949 -237.268696)
			(xy 116.62713 -237.219333) (xy 116.322366 -237.219333) (xy 116.314547 -237.268696) (xy 116.299103 -237.316228)
			(xy 116.276413 -237.36076) (xy 116.247037 -237.401193) (xy 116.211697 -237.436533) (xy 116.171264 -237.465909)
			(xy 116.126732 -237.488599) (xy 116.0792 -237.504043) (xy 116.029837 -237.511862) (xy 115.979859 -237.511862)
			(xy 115.930496 -237.504043) (xy 115.882964 -237.488599) (xy 115.838432 -237.465909) (xy 115.797999 -237.436533)
			(xy 115.762659 -237.401193) (xy 115.733283 -237.36076) (xy 115.710593 -237.316228) (xy 115.695149 -237.268696)
			(xy 115.68733 -237.219333) (xy 113.502204 -237.219333) (xy 113.494385 -237.268696) (xy 113.478941 -237.316228)
			(xy 113.456251 -237.36076) (xy 113.426875 -237.401193) (xy 113.391535 -237.436533) (xy 113.351102 -237.465909)
			(xy 113.30657 -237.488599) (xy 113.259038 -237.504043) (xy 113.209675 -237.511862) (xy 113.159697 -237.511862)
			(xy 113.110334 -237.504043) (xy 113.062802 -237.488599) (xy 113.01827 -237.465909) (xy 112.977837 -237.436533)
			(xy 112.942497 -237.401193) (xy 112.913121 -237.36076) (xy 112.890431 -237.316228) (xy 112.874987 -237.268696)
			(xy 112.867168 -237.219333) (xy 110.688646 -237.219333) (xy 110.680827 -237.268696) (xy 110.665383 -237.316228)
			(xy 110.642693 -237.36076) (xy 110.613317 -237.401193) (xy 110.577977 -237.436533) (xy 110.537544 -237.465909)
			(xy 110.493012 -237.488599) (xy 110.44548 -237.504043) (xy 110.396117 -237.511862) (xy 110.346139 -237.511862)
			(xy 110.296776 -237.504043) (xy 110.249244 -237.488599) (xy 110.204712 -237.465909) (xy 110.164279 -237.436533)
			(xy 110.128939 -237.401193) (xy 110.099563 -237.36076) (xy 110.076873 -237.316228) (xy 110.061429 -237.268696)
			(xy 110.05361 -237.219333) (xy 107.868484 -237.219333) (xy 107.860665 -237.268696) (xy 107.845221 -237.316228)
			(xy 107.822531 -237.36076) (xy 107.793155 -237.401193) (xy 107.757815 -237.436533) (xy 107.717382 -237.465909)
			(xy 107.67285 -237.488599) (xy 107.625318 -237.504043) (xy 107.575955 -237.511862) (xy 107.525977 -237.511862)
			(xy 107.476614 -237.504043) (xy 107.429082 -237.488599) (xy 107.38455 -237.465909) (xy 107.344117 -237.436533)
			(xy 107.308777 -237.401193) (xy 107.279401 -237.36076) (xy 107.256711 -237.316228) (xy 107.241267 -237.268696)
			(xy 107.233448 -237.219333) (xy 106.928684 -237.219333) (xy 106.920865 -237.268696) (xy 106.905421 -237.316228)
			(xy 106.882731 -237.36076) (xy 106.853355 -237.401193) (xy 106.818015 -237.436533) (xy 106.777582 -237.465909)
			(xy 106.73305 -237.488599) (xy 106.685518 -237.504043) (xy 106.636155 -237.511862) (xy 106.586177 -237.511862)
			(xy 106.536814 -237.504043) (xy 106.489282 -237.488599) (xy 106.44475 -237.465909) (xy 106.404317 -237.436533)
			(xy 106.368977 -237.401193) (xy 106.339601 -237.36076) (xy 106.316911 -237.316228) (xy 106.301467 -237.268696)
			(xy 106.293648 -237.219333) (xy 105.98863 -237.219333) (xy 105.980811 -237.268696) (xy 105.965367 -237.316228)
			(xy 105.942677 -237.36076) (xy 105.913301 -237.401193) (xy 105.877961 -237.436533) (xy 105.837528 -237.465909)
			(xy 105.792996 -237.488599) (xy 105.745464 -237.504043) (xy 105.696101 -237.511862) (xy 105.646123 -237.511862)
			(xy 105.59676 -237.504043) (xy 105.549228 -237.488599) (xy 105.504696 -237.465909) (xy 105.464263 -237.436533)
			(xy 105.428923 -237.401193) (xy 105.399547 -237.36076) (xy 105.376857 -237.316228) (xy 105.361413 -237.268696)
			(xy 105.353594 -237.219333) (xy 105.048576 -237.219333) (xy 105.040757 -237.268696) (xy 105.025313 -237.316228)
			(xy 105.002623 -237.36076) (xy 104.973247 -237.401193) (xy 104.937907 -237.436533) (xy 104.897474 -237.465909)
			(xy 104.852942 -237.488599) (xy 104.80541 -237.504043) (xy 104.756047 -237.511862) (xy 104.706069 -237.511862)
			(xy 104.656706 -237.504043) (xy 104.609174 -237.488599) (xy 104.564642 -237.465909) (xy 104.524209 -237.436533)
			(xy 104.488869 -237.401193) (xy 104.459493 -237.36076) (xy 104.436803 -237.316228) (xy 104.421359 -237.268696)
			(xy 104.41354 -237.219333) (xy 104.108522 -237.219333) (xy 104.100703 -237.268696) (xy 104.085259 -237.316228)
			(xy 104.062569 -237.36076) (xy 104.033193 -237.401193) (xy 103.997853 -237.436533) (xy 103.95742 -237.465909)
			(xy 103.912888 -237.488599) (xy 103.865356 -237.504043) (xy 103.815993 -237.511862) (xy 103.766015 -237.511862)
			(xy 103.716652 -237.504043) (xy 103.66912 -237.488599) (xy 103.624588 -237.465909) (xy 103.584155 -237.436533)
			(xy 103.548815 -237.401193) (xy 103.519439 -237.36076) (xy 103.496749 -237.316228) (xy 103.481305 -237.268696)
			(xy 103.473486 -237.219333) (xy 103.168468 -237.219333) (xy 103.160649 -237.268696) (xy 103.145205 -237.316228)
			(xy 103.122515 -237.36076) (xy 103.093139 -237.401193) (xy 103.057799 -237.436533) (xy 103.017366 -237.465909)
			(xy 102.972834 -237.488599) (xy 102.925302 -237.504043) (xy 102.875939 -237.511862) (xy 102.825961 -237.511862)
			(xy 102.776598 -237.504043) (xy 102.729066 -237.488599) (xy 102.684534 -237.465909) (xy 102.644101 -237.436533)
			(xy 102.608761 -237.401193) (xy 102.579385 -237.36076) (xy 102.556695 -237.316228) (xy 102.541251 -237.268696)
			(xy 102.533432 -237.219333) (xy 102.228668 -237.219333) (xy 102.220849 -237.268696) (xy 102.205405 -237.316228)
			(xy 102.182715 -237.36076) (xy 102.153339 -237.401193) (xy 102.117999 -237.436533) (xy 102.077566 -237.465909)
			(xy 102.033034 -237.488599) (xy 101.985502 -237.504043) (xy 101.936139 -237.511862) (xy 101.886161 -237.511862)
			(xy 101.836798 -237.504043) (xy 101.789266 -237.488599) (xy 101.744734 -237.465909) (xy 101.704301 -237.436533)
			(xy 101.668961 -237.401193) (xy 101.639585 -237.36076) (xy 101.616895 -237.316228) (xy 101.601451 -237.268696)
			(xy 101.593632 -237.219333) (xy 101.288614 -237.219333) (xy 101.280795 -237.268696) (xy 101.265351 -237.316228)
			(xy 101.242661 -237.36076) (xy 101.213285 -237.401193) (xy 101.177945 -237.436533) (xy 101.137512 -237.465909)
			(xy 101.09298 -237.488599) (xy 101.045448 -237.504043) (xy 100.996085 -237.511862) (xy 100.946107 -237.511862)
			(xy 100.896744 -237.504043) (xy 100.849212 -237.488599) (xy 100.80468 -237.465909) (xy 100.764247 -237.436533)
			(xy 100.728907 -237.401193) (xy 100.699531 -237.36076) (xy 100.676841 -237.316228) (xy 100.661397 -237.268696)
			(xy 100.653578 -237.219333) (xy 100.34856 -237.219333) (xy 100.340741 -237.268696) (xy 100.325297 -237.316228)
			(xy 100.302607 -237.36076) (xy 100.273231 -237.401193) (xy 100.237891 -237.436533) (xy 100.197458 -237.465909)
			(xy 100.152926 -237.488599) (xy 100.105394 -237.504043) (xy 100.056031 -237.511862) (xy 100.006053 -237.511862)
			(xy 99.95669 -237.504043) (xy 99.909158 -237.488599) (xy 99.864626 -237.465909) (xy 99.824193 -237.436533)
			(xy 99.788853 -237.401193) (xy 99.759477 -237.36076) (xy 99.736787 -237.316228) (xy 99.721343 -237.268696)
			(xy 99.713524 -237.219333) (xy 99.408506 -237.219333) (xy 99.400687 -237.268696) (xy 99.385243 -237.316228)
			(xy 99.362553 -237.36076) (xy 99.333177 -237.401193) (xy 99.297837 -237.436533) (xy 99.257404 -237.465909)
			(xy 99.212872 -237.488599) (xy 99.16534 -237.504043) (xy 99.115977 -237.511862) (xy 99.065999 -237.511862)
			(xy 99.016636 -237.504043) (xy 98.969104 -237.488599) (xy 98.924572 -237.465909) (xy 98.884139 -237.436533)
			(xy 98.848799 -237.401193) (xy 98.819423 -237.36076) (xy 98.796733 -237.316228) (xy 98.781289 -237.268696)
			(xy 98.77347 -237.219333) (xy 98.468452 -237.219333) (xy 98.460633 -237.268696) (xy 98.445189 -237.316228)
			(xy 98.422499 -237.36076) (xy 98.393123 -237.401193) (xy 98.357783 -237.436533) (xy 98.31735 -237.465909)
			(xy 98.272818 -237.488599) (xy 98.225286 -237.504043) (xy 98.175923 -237.511862) (xy 98.125945 -237.511862)
			(xy 98.076582 -237.504043) (xy 98.02905 -237.488599) (xy 97.984518 -237.465909) (xy 97.944085 -237.436533)
			(xy 97.908745 -237.401193) (xy 97.879369 -237.36076) (xy 97.856679 -237.316228) (xy 97.841235 -237.268696)
			(xy 97.833416 -237.219333) (xy 97.546073 -237.219333) (xy 97.546073 -237.220661) (xy 97.537826 -237.272735)
			(xy 97.521535 -237.322877) (xy 97.497601 -237.369854) (xy 97.466613 -237.412508) (xy 97.429334 -237.449791)
			(xy 97.386683 -237.480783) (xy 97.339708 -237.504722) (xy 97.289568 -237.521018) (xy 97.237495 -237.52927)
			(xy 97.211134 -237.529878) (xy 97.196124 -237.529654) (xy 97.166235 -237.526855) (xy 97.151444 -237.52429)
			(xy 97.14992 -237.524036) (xy 97.14865 -237.524036) (xy 97.131886 -237.521242) (xy 97.13087 -237.522004)
			(xy 97.10293 -237.546642) (xy 97.072958 -237.572804) (xy 97.066209 -237.579924) (xy 97.05822 -237.597822)
			(xy 97.057464 -237.607602) (xy 97.057464 -237.966758) (xy 97.057718 -237.97133) (xy 97.058988 -238.00181)
			(xy 97.058988 -238.007906) (xy 97.05808 -238.029339) (xy 97.363516 -238.029339) (xy 97.363516 -237.979361)
			(xy 97.371335 -237.929998) (xy 97.386779 -237.882466) (xy 97.409469 -237.837934) (xy 97.438845 -237.797501)
			(xy 97.474185 -237.762161) (xy 97.514618 -237.732785) (xy 97.55915 -237.710095) (xy 97.606682 -237.694651)
			(xy 97.656045 -237.686832) (xy 97.706023 -237.686832) (xy 97.755386 -237.694651) (xy 97.802918 -237.710095)
			(xy 97.84745 -237.732785) (xy 97.887883 -237.762161) (xy 97.923223 -237.797501) (xy 97.952599 -237.837934)
			(xy 97.975289 -237.882466) (xy 97.990733 -237.929998) (xy 97.998552 -237.979361) (xy 97.999042 -238.00435)
			(xy 97.998552 -238.029339) (xy 98.30357 -238.029339) (xy 98.30357 -237.979361) (xy 98.311389 -237.929998)
			(xy 98.326833 -237.882466) (xy 98.349523 -237.837934) (xy 98.378899 -237.797501) (xy 98.414239 -237.762161)
			(xy 98.454672 -237.732785) (xy 98.499204 -237.710095) (xy 98.546736 -237.694651) (xy 98.596099 -237.686832)
			(xy 98.646077 -237.686832) (xy 98.69544 -237.694651) (xy 98.742972 -237.710095) (xy 98.787504 -237.732785)
			(xy 98.827937 -237.762161) (xy 98.863277 -237.797501) (xy 98.892653 -237.837934) (xy 98.915343 -237.882466)
			(xy 98.930787 -237.929998) (xy 98.938606 -237.979361) (xy 98.939096 -238.00435) (xy 98.938606 -238.029339)
			(xy 99.243624 -238.029339) (xy 99.243624 -237.979361) (xy 99.251443 -237.929998) (xy 99.266887 -237.882466)
			(xy 99.289577 -237.837934) (xy 99.318953 -237.797501) (xy 99.354293 -237.762161) (xy 99.394726 -237.732785)
			(xy 99.439258 -237.710095) (xy 99.48679 -237.694651) (xy 99.536153 -237.686832) (xy 99.586131 -237.686832)
			(xy 99.635494 -237.694651) (xy 99.683026 -237.710095) (xy 99.727558 -237.732785) (xy 99.767991 -237.762161)
			(xy 99.803331 -237.797501) (xy 99.832707 -237.837934) (xy 99.855397 -237.882466) (xy 99.870841 -237.929998)
			(xy 99.87866 -237.979361) (xy 99.87915 -238.00435) (xy 99.87866 -238.029339) (xy 100.183424 -238.029339)
			(xy 100.183424 -237.979361) (xy 100.191243 -237.929998) (xy 100.206687 -237.882466) (xy 100.229377 -237.837934)
			(xy 100.258753 -237.797501) (xy 100.294093 -237.762161) (xy 100.334526 -237.732785) (xy 100.379058 -237.710095)
			(xy 100.42659 -237.694651) (xy 100.475953 -237.686832) (xy 100.525931 -237.686832) (xy 100.575294 -237.694651)
			(xy 100.622826 -237.710095) (xy 100.667358 -237.732785) (xy 100.707791 -237.762161) (xy 100.743131 -237.797501)
			(xy 100.772507 -237.837934) (xy 100.795197 -237.882466) (xy 100.810641 -237.929998) (xy 100.81846 -237.979361)
			(xy 100.81895 -238.00435) (xy 100.81846 -238.029339) (xy 101.123478 -238.029339) (xy 101.123478 -237.979361)
			(xy 101.131297 -237.929998) (xy 101.146741 -237.882466) (xy 101.169431 -237.837934) (xy 101.198807 -237.797501)
			(xy 101.234147 -237.762161) (xy 101.27458 -237.732785) (xy 101.319112 -237.710095) (xy 101.366644 -237.694651)
			(xy 101.416007 -237.686832) (xy 101.465985 -237.686832) (xy 101.515348 -237.694651) (xy 101.56288 -237.710095)
			(xy 101.607412 -237.732785) (xy 101.647845 -237.762161) (xy 101.683185 -237.797501) (xy 101.712561 -237.837934)
			(xy 101.735251 -237.882466) (xy 101.750695 -237.929998) (xy 101.758514 -237.979361) (xy 101.759004 -238.00435)
			(xy 101.758514 -238.029339) (xy 102.063532 -238.029339) (xy 102.063532 -237.979361) (xy 102.071351 -237.929998)
			(xy 102.086795 -237.882466) (xy 102.109485 -237.837934) (xy 102.138861 -237.797501) (xy 102.174201 -237.762161)
			(xy 102.214634 -237.732785) (xy 102.259166 -237.710095) (xy 102.306698 -237.694651) (xy 102.356061 -237.686832)
			(xy 102.406039 -237.686832) (xy 102.455402 -237.694651) (xy 102.502934 -237.710095) (xy 102.547466 -237.732785)
			(xy 102.587899 -237.762161) (xy 102.623239 -237.797501) (xy 102.652615 -237.837934) (xy 102.675305 -237.882466)
			(xy 102.690749 -237.929998) (xy 102.698568 -237.979361) (xy 102.699058 -238.00435) (xy 102.698568 -238.029339)
			(xy 103.003586 -238.029339) (xy 103.003586 -237.979361) (xy 103.011405 -237.929998) (xy 103.026849 -237.882466)
			(xy 103.049539 -237.837934) (xy 103.078915 -237.797501) (xy 103.114255 -237.762161) (xy 103.154688 -237.732785)
			(xy 103.19922 -237.710095) (xy 103.246752 -237.694651) (xy 103.296115 -237.686832) (xy 103.346093 -237.686832)
			(xy 103.395456 -237.694651) (xy 103.442988 -237.710095) (xy 103.48752 -237.732785) (xy 103.527953 -237.762161)
			(xy 103.563293 -237.797501) (xy 103.592669 -237.837934) (xy 103.615359 -237.882466) (xy 103.630803 -237.929998)
			(xy 103.638622 -237.979361) (xy 103.639112 -238.00435) (xy 103.638622 -238.029339) (xy 103.94364 -238.029339)
			(xy 103.94364 -237.979361) (xy 103.951459 -237.929998) (xy 103.966903 -237.882466) (xy 103.989593 -237.837934)
			(xy 104.018969 -237.797501) (xy 104.054309 -237.762161) (xy 104.094742 -237.732785) (xy 104.139274 -237.710095)
			(xy 104.186806 -237.694651) (xy 104.236169 -237.686832) (xy 104.286147 -237.686832) (xy 104.33551 -237.694651)
			(xy 104.383042 -237.710095) (xy 104.427574 -237.732785) (xy 104.468007 -237.762161) (xy 104.503347 -237.797501)
			(xy 104.532723 -237.837934) (xy 104.555413 -237.882466) (xy 104.570857 -237.929998) (xy 104.578676 -237.979361)
			(xy 104.579166 -238.00435) (xy 104.578676 -238.029339) (xy 104.88344 -238.029339) (xy 104.88344 -237.979361)
			(xy 104.891259 -237.929998) (xy 104.906703 -237.882466) (xy 104.929393 -237.837934) (xy 104.958769 -237.797501)
			(xy 104.994109 -237.762161) (xy 105.034542 -237.732785) (xy 105.079074 -237.710095) (xy 105.126606 -237.694651)
			(xy 105.175969 -237.686832) (xy 105.225947 -237.686832) (xy 105.27531 -237.694651) (xy 105.322842 -237.710095)
			(xy 105.367374 -237.732785) (xy 105.407807 -237.762161) (xy 105.443147 -237.797501) (xy 105.472523 -237.837934)
			(xy 105.495213 -237.882466) (xy 105.510657 -237.929998) (xy 105.518476 -237.979361) (xy 105.518966 -238.00435)
			(xy 105.824777 -238.00435) (xy 105.828872 -237.953622) (xy 105.841051 -237.904208) (xy 105.860999 -237.857388)
			(xy 105.8882 -237.814374) (xy 105.921948 -237.77628) (xy 105.96137 -237.744093) (xy 106.005444 -237.718647)
			(xy 106.05303 -237.7006) (xy 106.102894 -237.69042) (xy 106.153746 -237.688371) (xy 106.204267 -237.694505)
			(xy 106.253151 -237.708665) (xy 106.29913 -237.730482) (xy 106.341014 -237.759392) (xy 106.377718 -237.794647)
			(xy 106.408291 -237.835333) (xy 106.431942 -237.880396) (xy 106.448058 -237.92867) (xy 106.456222 -237.978904)
			(xy 106.456734 -238.00435) (xy 106.764831 -238.00435) (xy 106.768926 -237.953622) (xy 106.781105 -237.904208)
			(xy 106.801053 -237.857388) (xy 106.828254 -237.814374) (xy 106.862002 -237.77628) (xy 106.901424 -237.744093)
			(xy 106.945498 -237.718647) (xy 106.993084 -237.7006) (xy 107.042948 -237.69042) (xy 107.0938 -237.688371)
			(xy 107.144321 -237.694505) (xy 107.193205 -237.708665) (xy 107.239184 -237.730482) (xy 107.281068 -237.759392)
			(xy 107.317772 -237.794647) (xy 107.348345 -237.835333) (xy 107.371996 -237.880396) (xy 107.388112 -237.92867)
			(xy 107.396276 -237.978904) (xy 107.396788 -238.00435) (xy 107.396285 -238.029339) (xy 107.703602 -238.029339)
			(xy 107.703602 -237.979361) (xy 107.711421 -237.929998) (xy 107.726865 -237.882466) (xy 107.749555 -237.837934)
			(xy 107.778931 -237.797501) (xy 107.814271 -237.762161) (xy 107.854704 -237.732785) (xy 107.899236 -237.710095)
			(xy 107.946768 -237.694651) (xy 107.996131 -237.686832) (xy 108.046109 -237.686832) (xy 108.095472 -237.694651)
			(xy 108.143004 -237.710095) (xy 108.187536 -237.732785) (xy 108.227969 -237.762161) (xy 108.263309 -237.797501)
			(xy 108.292685 -237.837934) (xy 108.315375 -237.882466) (xy 108.330819 -237.929998) (xy 108.338638 -237.979361)
			(xy 108.339128 -238.00435) (xy 108.338638 -238.029339) (xy 108.643656 -238.029339) (xy 108.643656 -237.979361)
			(xy 108.651475 -237.929998) (xy 108.666919 -237.882466) (xy 108.689609 -237.837934) (xy 108.718985 -237.797501)
			(xy 108.754325 -237.762161) (xy 108.794758 -237.732785) (xy 108.83929 -237.710095) (xy 108.886822 -237.694651)
			(xy 108.936185 -237.686832) (xy 108.986163 -237.686832) (xy 109.035526 -237.694651) (xy 109.083058 -237.710095)
			(xy 109.12759 -237.732785) (xy 109.168023 -237.762161) (xy 109.203363 -237.797501) (xy 109.232739 -237.837934)
			(xy 109.255429 -237.882466) (xy 109.270873 -237.929998) (xy 109.278692 -237.979361) (xy 109.279182 -238.00435)
			(xy 109.278692 -238.029339) (xy 109.583456 -238.029339) (xy 109.583456 -237.979361) (xy 109.591275 -237.929998)
			(xy 109.606719 -237.882466) (xy 109.629409 -237.837934) (xy 109.658785 -237.797501) (xy 109.694125 -237.762161)
			(xy 109.734558 -237.732785) (xy 109.77909 -237.710095) (xy 109.826622 -237.694651) (xy 109.875985 -237.686832)
			(xy 109.925963 -237.686832) (xy 109.975326 -237.694651) (xy 110.022858 -237.710095) (xy 110.06739 -237.732785)
			(xy 110.107823 -237.762161) (xy 110.143163 -237.797501) (xy 110.172539 -237.837934) (xy 110.195229 -237.882466)
			(xy 110.210673 -237.929998) (xy 110.218492 -237.979361) (xy 110.218982 -238.00435) (xy 110.218492 -238.029339)
			(xy 113.337322 -238.029339) (xy 113.337322 -237.979361) (xy 113.345141 -237.929998) (xy 113.360585 -237.882466)
			(xy 113.383275 -237.837934) (xy 113.412651 -237.797501) (xy 113.447991 -237.762161) (xy 113.488424 -237.732785)
			(xy 113.532956 -237.710095) (xy 113.580488 -237.694651) (xy 113.629851 -237.686832) (xy 113.679829 -237.686832)
			(xy 113.729192 -237.694651) (xy 113.776724 -237.710095) (xy 113.821256 -237.732785) (xy 113.861689 -237.762161)
			(xy 113.897029 -237.797501) (xy 113.926405 -237.837934) (xy 113.949095 -237.882466) (xy 113.964539 -237.929998)
			(xy 113.972358 -237.979361) (xy 113.972848 -238.00435) (xy 113.972358 -238.029339) (xy 114.277122 -238.029339)
			(xy 114.277122 -237.979361) (xy 114.284941 -237.929998) (xy 114.300385 -237.882466) (xy 114.323075 -237.837934)
			(xy 114.352451 -237.797501) (xy 114.387791 -237.762161) (xy 114.428224 -237.732785) (xy 114.472756 -237.710095)
			(xy 114.520288 -237.694651) (xy 114.569651 -237.686832) (xy 114.619629 -237.686832) (xy 114.668992 -237.694651)
			(xy 114.716524 -237.710095) (xy 114.761056 -237.732785) (xy 114.801489 -237.762161) (xy 114.836829 -237.797501)
			(xy 114.866205 -237.837934) (xy 114.888895 -237.882466) (xy 114.904339 -237.929998) (xy 114.912158 -237.979361)
			(xy 114.912648 -238.00435) (xy 114.912158 -238.029339) (xy 115.217176 -238.029339) (xy 115.217176 -237.979361)
			(xy 115.224995 -237.929998) (xy 115.240439 -237.882466) (xy 115.263129 -237.837934) (xy 115.292505 -237.797501)
			(xy 115.327845 -237.762161) (xy 115.368278 -237.732785) (xy 115.41281 -237.710095) (xy 115.460342 -237.694651)
			(xy 115.509705 -237.686832) (xy 115.559683 -237.686832) (xy 115.609046 -237.694651) (xy 115.656578 -237.710095)
			(xy 115.70111 -237.732785) (xy 115.741543 -237.762161) (xy 115.776883 -237.797501) (xy 115.806259 -237.837934)
			(xy 115.828949 -237.882466) (xy 115.844393 -237.929998) (xy 115.852212 -237.979361) (xy 115.852702 -238.00435)
			(xy 116.158513 -238.00435) (xy 116.162608 -237.953622) (xy 116.174787 -237.904208) (xy 116.194735 -237.857388)
			(xy 116.221936 -237.814374) (xy 116.255684 -237.77628) (xy 116.295106 -237.744093) (xy 116.33918 -237.718647)
			(xy 116.386766 -237.7006) (xy 116.43663 -237.69042) (xy 116.487482 -237.688371) (xy 116.538003 -237.694505)
			(xy 116.586887 -237.708665) (xy 116.632866 -237.730482) (xy 116.67475 -237.759392) (xy 116.711454 -237.794647)
			(xy 116.742027 -237.835333) (xy 116.765678 -237.880396) (xy 116.781794 -237.92867) (xy 116.789958 -237.978904)
			(xy 116.79047 -238.00435) (xy 117.098567 -238.00435) (xy 117.102662 -237.953622) (xy 117.114841 -237.904208)
			(xy 117.134789 -237.857388) (xy 117.16199 -237.814374) (xy 117.195738 -237.77628) (xy 117.23516 -237.744093)
			(xy 117.279234 -237.718647) (xy 117.32682 -237.7006) (xy 117.376684 -237.69042) (xy 117.427536 -237.688371)
			(xy 117.478057 -237.694505) (xy 117.526941 -237.708665) (xy 117.57292 -237.730482) (xy 117.614804 -237.759392)
			(xy 117.651508 -237.794647) (xy 117.682081 -237.835333) (xy 117.705732 -237.880396) (xy 117.721848 -237.92867)
			(xy 117.730012 -237.978904) (xy 117.730524 -238.00435) (xy 117.730021 -238.029339) (xy 118.037338 -238.029339)
			(xy 118.037338 -237.979361) (xy 118.045157 -237.929998) (xy 118.060601 -237.882466) (xy 118.083291 -237.837934)
			(xy 118.112667 -237.797501) (xy 118.148007 -237.762161) (xy 118.18844 -237.732785) (xy 118.232972 -237.710095)
			(xy 118.280504 -237.694651) (xy 118.329867 -237.686832) (xy 118.379845 -237.686832) (xy 118.429208 -237.694651)
			(xy 118.47674 -237.710095) (xy 118.521272 -237.732785) (xy 118.561705 -237.762161) (xy 118.597045 -237.797501)
			(xy 118.626421 -237.837934) (xy 118.649111 -237.882466) (xy 118.664555 -237.929998) (xy 118.672374 -237.979361)
			(xy 118.672864 -238.00435) (xy 118.672374 -238.029339) (xy 118.977138 -238.029339) (xy 118.977138 -237.979361)
			(xy 118.984957 -237.929998) (xy 119.000401 -237.882466) (xy 119.023091 -237.837934) (xy 119.052467 -237.797501)
			(xy 119.087807 -237.762161) (xy 119.12824 -237.732785) (xy 119.172772 -237.710095) (xy 119.220304 -237.694651)
			(xy 119.269667 -237.686832) (xy 119.319645 -237.686832) (xy 119.369008 -237.694651) (xy 119.41654 -237.710095)
			(xy 119.461072 -237.732785) (xy 119.501505 -237.762161) (xy 119.536845 -237.797501) (xy 119.566221 -237.837934)
			(xy 119.588911 -237.882466) (xy 119.604355 -237.929998) (xy 119.612174 -237.979361) (xy 119.612664 -238.00435)
			(xy 119.612174 -238.029339) (xy 119.917192 -238.029339) (xy 119.917192 -237.979361) (xy 119.925011 -237.929998)
			(xy 119.940455 -237.882466) (xy 119.963145 -237.837934) (xy 119.992521 -237.797501) (xy 120.027861 -237.762161)
			(xy 120.068294 -237.732785) (xy 120.112826 -237.710095) (xy 120.160358 -237.694651) (xy 120.209721 -237.686832)
			(xy 120.259699 -237.686832) (xy 120.309062 -237.694651) (xy 120.356594 -237.710095) (xy 120.401126 -237.732785)
			(xy 120.441559 -237.762161) (xy 120.476899 -237.797501) (xy 120.506275 -237.837934) (xy 120.528965 -237.882466)
			(xy 120.544409 -237.929998) (xy 120.552228 -237.979361) (xy 120.552718 -238.00435) (xy 120.552228 -238.029339)
			(xy 120.857246 -238.029339) (xy 120.857246 -237.979361) (xy 120.865065 -237.929998) (xy 120.880509 -237.882466)
			(xy 120.903199 -237.837934) (xy 120.932575 -237.797501) (xy 120.967915 -237.762161) (xy 121.008348 -237.732785)
			(xy 121.05288 -237.710095) (xy 121.100412 -237.694651) (xy 121.149775 -237.686832) (xy 121.199753 -237.686832)
			(xy 121.249116 -237.694651) (xy 121.296648 -237.710095) (xy 121.34118 -237.732785) (xy 121.381613 -237.762161)
			(xy 121.416953 -237.797501) (xy 121.446329 -237.837934) (xy 121.469019 -237.882466) (xy 121.484463 -237.929998)
			(xy 121.492282 -237.979361) (xy 121.492772 -238.00435) (xy 121.492282 -238.029339) (xy 121.7973 -238.029339)
			(xy 121.7973 -237.979361) (xy 121.805119 -237.929998) (xy 121.820563 -237.882466) (xy 121.843253 -237.837934)
			(xy 121.872629 -237.797501) (xy 121.907969 -237.762161) (xy 121.948402 -237.732785) (xy 121.992934 -237.710095)
			(xy 122.040466 -237.694651) (xy 122.089829 -237.686832) (xy 122.139807 -237.686832) (xy 122.18917 -237.694651)
			(xy 122.236702 -237.710095) (xy 122.281234 -237.732785) (xy 122.321667 -237.762161) (xy 122.357007 -237.797501)
			(xy 122.386383 -237.837934) (xy 122.409073 -237.882466) (xy 122.424517 -237.929998) (xy 122.432336 -237.979361)
			(xy 122.432826 -238.00435) (xy 122.432336 -238.029339) (xy 122.7371 -238.029339) (xy 122.7371 -237.979361)
			(xy 122.744919 -237.929998) (xy 122.760363 -237.882466) (xy 122.783053 -237.837934) (xy 122.812429 -237.797501)
			(xy 122.847769 -237.762161) (xy 122.888202 -237.732785) (xy 122.932734 -237.710095) (xy 122.980266 -237.694651)
			(xy 123.029629 -237.686832) (xy 123.079607 -237.686832) (xy 123.12897 -237.694651) (xy 123.176502 -237.710095)
			(xy 123.221034 -237.732785) (xy 123.261467 -237.762161) (xy 123.296807 -237.797501) (xy 123.326183 -237.837934)
			(xy 123.348873 -237.882466) (xy 123.364317 -237.929998) (xy 123.372136 -237.979361) (xy 123.372626 -238.00435)
			(xy 123.372136 -238.029339) (xy 123.677154 -238.029339) (xy 123.677154 -237.979361) (xy 123.684973 -237.929998)
			(xy 123.700417 -237.882466) (xy 123.723107 -237.837934) (xy 123.752483 -237.797501) (xy 123.787823 -237.762161)
			(xy 123.828256 -237.732785) (xy 123.872788 -237.710095) (xy 123.92032 -237.694651) (xy 123.969683 -237.686832)
			(xy 124.019661 -237.686832) (xy 124.069024 -237.694651) (xy 124.116556 -237.710095) (xy 124.161088 -237.732785)
			(xy 124.201521 -237.762161) (xy 124.236861 -237.797501) (xy 124.266237 -237.837934) (xy 124.288927 -237.882466)
			(xy 124.304371 -237.929998) (xy 124.31219 -237.979361) (xy 124.31268 -238.00435) (xy 124.31219 -238.029339)
			(xy 124.617208 -238.029339) (xy 124.617208 -237.979361) (xy 124.625027 -237.929998) (xy 124.640471 -237.882466)
			(xy 124.663161 -237.837934) (xy 124.692537 -237.797501) (xy 124.727877 -237.762161) (xy 124.76831 -237.732785)
			(xy 124.812842 -237.710095) (xy 124.860374 -237.694651) (xy 124.909737 -237.686832) (xy 124.959715 -237.686832)
			(xy 125.009078 -237.694651) (xy 125.05661 -237.710095) (xy 125.101142 -237.732785) (xy 125.141575 -237.762161)
			(xy 125.176915 -237.797501) (xy 125.206291 -237.837934) (xy 125.228981 -237.882466) (xy 125.244425 -237.929998)
			(xy 125.252244 -237.979361) (xy 125.252734 -238.00435) (xy 125.252244 -238.029339) (xy 125.557262 -238.029339)
			(xy 125.557262 -237.979361) (xy 125.565081 -237.929998) (xy 125.580525 -237.882466) (xy 125.603215 -237.837934)
			(xy 125.632591 -237.797501) (xy 125.667931 -237.762161) (xy 125.708364 -237.732785) (xy 125.752896 -237.710095)
			(xy 125.800428 -237.694651) (xy 125.849791 -237.686832) (xy 125.899769 -237.686832) (xy 125.949132 -237.694651)
			(xy 125.996664 -237.710095) (xy 126.041196 -237.732785) (xy 126.081629 -237.762161) (xy 126.116969 -237.797501)
			(xy 126.146345 -237.837934) (xy 126.169035 -237.882466) (xy 126.184479 -237.929998) (xy 126.192298 -237.979361)
			(xy 126.192788 -238.00435) (xy 126.192298 -238.029339) (xy 126.184479 -238.078702) (xy 126.169035 -238.126234)
			(xy 126.146345 -238.170766) (xy 126.116969 -238.211199) (xy 126.081629 -238.246539) (xy 126.041196 -238.275915)
			(xy 125.996664 -238.298605) (xy 125.949132 -238.314049) (xy 125.899769 -238.321868) (xy 125.849791 -238.321868)
			(xy 125.800428 -238.314049) (xy 125.752896 -238.298605) (xy 125.708364 -238.275915) (xy 125.667931 -238.246539)
			(xy 125.632591 -238.211199) (xy 125.603215 -238.170766) (xy 125.580525 -238.126234) (xy 125.565081 -238.078702)
			(xy 125.557262 -238.029339) (xy 125.252244 -238.029339) (xy 125.244425 -238.078702) (xy 125.228981 -238.126234)
			(xy 125.206291 -238.170766) (xy 125.176915 -238.211199) (xy 125.141575 -238.246539) (xy 125.101142 -238.275915)
			(xy 125.05661 -238.298605) (xy 125.009078 -238.314049) (xy 124.959715 -238.321868) (xy 124.909737 -238.321868)
			(xy 124.860374 -238.314049) (xy 124.812842 -238.298605) (xy 124.76831 -238.275915) (xy 124.727877 -238.246539)
			(xy 124.692537 -238.211199) (xy 124.663161 -238.170766) (xy 124.640471 -238.126234) (xy 124.625027 -238.078702)
			(xy 124.617208 -238.029339) (xy 124.31219 -238.029339) (xy 124.304371 -238.078702) (xy 124.288927 -238.126234)
			(xy 124.266237 -238.170766) (xy 124.236861 -238.211199) (xy 124.201521 -238.246539) (xy 124.161088 -238.275915)
			(xy 124.116556 -238.298605) (xy 124.069024 -238.314049) (xy 124.019661 -238.321868) (xy 123.969683 -238.321868)
			(xy 123.92032 -238.314049) (xy 123.872788 -238.298605) (xy 123.828256 -238.275915) (xy 123.787823 -238.246539)
			(xy 123.752483 -238.211199) (xy 123.723107 -238.170766) (xy 123.700417 -238.126234) (xy 123.684973 -238.078702)
			(xy 123.677154 -238.029339) (xy 123.372136 -238.029339) (xy 123.364317 -238.078702) (xy 123.348873 -238.126234)
			(xy 123.326183 -238.170766) (xy 123.296807 -238.211199) (xy 123.261467 -238.246539) (xy 123.221034 -238.275915)
			(xy 123.176502 -238.298605) (xy 123.12897 -238.314049) (xy 123.079607 -238.321868) (xy 123.029629 -238.321868)
			(xy 122.980266 -238.314049) (xy 122.932734 -238.298605) (xy 122.888202 -238.275915) (xy 122.847769 -238.246539)
			(xy 122.812429 -238.211199) (xy 122.783053 -238.170766) (xy 122.760363 -238.126234) (xy 122.744919 -238.078702)
			(xy 122.7371 -238.029339) (xy 122.432336 -238.029339) (xy 122.424517 -238.078702) (xy 122.409073 -238.126234)
			(xy 122.386383 -238.170766) (xy 122.357007 -238.211199) (xy 122.321667 -238.246539) (xy 122.281234 -238.275915)
			(xy 122.236702 -238.298605) (xy 122.18917 -238.314049) (xy 122.139807 -238.321868) (xy 122.089829 -238.321868)
			(xy 122.040466 -238.314049) (xy 121.992934 -238.298605) (xy 121.948402 -238.275915) (xy 121.907969 -238.246539)
			(xy 121.872629 -238.211199) (xy 121.843253 -238.170766) (xy 121.820563 -238.126234) (xy 121.805119 -238.078702)
			(xy 121.7973 -238.029339) (xy 121.492282 -238.029339) (xy 121.484463 -238.078702) (xy 121.469019 -238.126234)
			(xy 121.446329 -238.170766) (xy 121.416953 -238.211199) (xy 121.381613 -238.246539) (xy 121.34118 -238.275915)
			(xy 121.296648 -238.298605) (xy 121.249116 -238.314049) (xy 121.199753 -238.321868) (xy 121.149775 -238.321868)
			(xy 121.100412 -238.314049) (xy 121.05288 -238.298605) (xy 121.008348 -238.275915) (xy 120.967915 -238.246539)
			(xy 120.932575 -238.211199) (xy 120.903199 -238.170766) (xy 120.880509 -238.126234) (xy 120.865065 -238.078702)
			(xy 120.857246 -238.029339) (xy 120.552228 -238.029339) (xy 120.544409 -238.078702) (xy 120.528965 -238.126234)
			(xy 120.506275 -238.170766) (xy 120.476899 -238.211199) (xy 120.441559 -238.246539) (xy 120.401126 -238.275915)
			(xy 120.356594 -238.298605) (xy 120.309062 -238.314049) (xy 120.259699 -238.321868) (xy 120.209721 -238.321868)
			(xy 120.160358 -238.314049) (xy 120.112826 -238.298605) (xy 120.068294 -238.275915) (xy 120.027861 -238.246539)
			(xy 119.992521 -238.211199) (xy 119.963145 -238.170766) (xy 119.940455 -238.126234) (xy 119.925011 -238.078702)
			(xy 119.917192 -238.029339) (xy 119.612174 -238.029339) (xy 119.604355 -238.078702) (xy 119.588911 -238.126234)
			(xy 119.566221 -238.170766) (xy 119.536845 -238.211199) (xy 119.501505 -238.246539) (xy 119.461072 -238.275915)
			(xy 119.41654 -238.298605) (xy 119.369008 -238.314049) (xy 119.319645 -238.321868) (xy 119.269667 -238.321868)
			(xy 119.220304 -238.314049) (xy 119.172772 -238.298605) (xy 119.12824 -238.275915) (xy 119.087807 -238.246539)
			(xy 119.052467 -238.211199) (xy 119.023091 -238.170766) (xy 119.000401 -238.126234) (xy 118.984957 -238.078702)
			(xy 118.977138 -238.029339) (xy 118.672374 -238.029339) (xy 118.664555 -238.078702) (xy 118.649111 -238.126234)
			(xy 118.626421 -238.170766) (xy 118.597045 -238.211199) (xy 118.561705 -238.246539) (xy 118.521272 -238.275915)
			(xy 118.47674 -238.298605) (xy 118.429208 -238.314049) (xy 118.379845 -238.321868) (xy 118.329867 -238.321868)
			(xy 118.280504 -238.314049) (xy 118.232972 -238.298605) (xy 118.18844 -238.275915) (xy 118.148007 -238.246539)
			(xy 118.112667 -238.211199) (xy 118.083291 -238.170766) (xy 118.060601 -238.126234) (xy 118.045157 -238.078702)
			(xy 118.037338 -238.029339) (xy 117.730021 -238.029339) (xy 117.730012 -238.029796) (xy 117.721848 -238.08003)
			(xy 117.705732 -238.128304) (xy 117.682081 -238.173367) (xy 117.651508 -238.214053) (xy 117.614804 -238.249308)
			(xy 117.57292 -238.278218) (xy 117.526941 -238.300035) (xy 117.478057 -238.314195) (xy 117.427536 -238.320329)
			(xy 117.376684 -238.31828) (xy 117.32682 -238.3081) (xy 117.279234 -238.290053) (xy 117.23516 -238.264607)
			(xy 117.195738 -238.23242) (xy 117.16199 -238.194326) (xy 117.134789 -238.151312) (xy 117.114841 -238.104492)
			(xy 117.102662 -238.055078) (xy 117.098567 -238.00435) (xy 116.79047 -238.00435) (xy 116.789958 -238.029796)
			(xy 116.781794 -238.08003) (xy 116.765678 -238.128304) (xy 116.742027 -238.173367) (xy 116.711454 -238.214053)
			(xy 116.67475 -238.249308) (xy 116.632866 -238.278218) (xy 116.586887 -238.300035) (xy 116.538003 -238.314195)
			(xy 116.487482 -238.320329) (xy 116.43663 -238.31828) (xy 116.386766 -238.3081) (xy 116.33918 -238.290053)
			(xy 116.295106 -238.264607) (xy 116.255684 -238.23242) (xy 116.221936 -238.194326) (xy 116.194735 -238.151312)
			(xy 116.174787 -238.104492) (xy 116.162608 -238.055078) (xy 116.158513 -238.00435) (xy 115.852702 -238.00435)
			(xy 115.852212 -238.029339) (xy 115.844393 -238.078702) (xy 115.828949 -238.126234) (xy 115.806259 -238.170766)
			(xy 115.776883 -238.211199) (xy 115.741543 -238.246539) (xy 115.70111 -238.275915) (xy 115.656578 -238.298605)
			(xy 115.609046 -238.314049) (xy 115.559683 -238.321868) (xy 115.509705 -238.321868) (xy 115.460342 -238.314049)
			(xy 115.41281 -238.298605) (xy 115.368278 -238.275915) (xy 115.327845 -238.246539) (xy 115.292505 -238.211199)
			(xy 115.263129 -238.170766) (xy 115.240439 -238.126234) (xy 115.224995 -238.078702) (xy 115.217176 -238.029339)
			(xy 114.912158 -238.029339) (xy 114.904339 -238.078702) (xy 114.888895 -238.126234) (xy 114.866205 -238.170766)
			(xy 114.836829 -238.211199) (xy 114.801489 -238.246539) (xy 114.761056 -238.275915) (xy 114.716524 -238.298605)
			(xy 114.668992 -238.314049) (xy 114.619629 -238.321868) (xy 114.569651 -238.321868) (xy 114.520288 -238.314049)
			(xy 114.472756 -238.298605) (xy 114.428224 -238.275915) (xy 114.387791 -238.246539) (xy 114.352451 -238.211199)
			(xy 114.323075 -238.170766) (xy 114.300385 -238.126234) (xy 114.284941 -238.078702) (xy 114.277122 -238.029339)
			(xy 113.972358 -238.029339) (xy 113.964539 -238.078702) (xy 113.949095 -238.126234) (xy 113.926405 -238.170766)
			(xy 113.897029 -238.211199) (xy 113.861689 -238.246539) (xy 113.821256 -238.275915) (xy 113.776724 -238.298605)
			(xy 113.729192 -238.314049) (xy 113.679829 -238.321868) (xy 113.629851 -238.321868) (xy 113.580488 -238.314049)
			(xy 113.532956 -238.298605) (xy 113.488424 -238.275915) (xy 113.447991 -238.246539) (xy 113.412651 -238.211199)
			(xy 113.383275 -238.170766) (xy 113.360585 -238.126234) (xy 113.345141 -238.078702) (xy 113.337322 -238.029339)
			(xy 110.218492 -238.029339) (xy 110.210673 -238.078702) (xy 110.195229 -238.126234) (xy 110.172539 -238.170766)
			(xy 110.143163 -238.211199) (xy 110.107823 -238.246539) (xy 110.06739 -238.275915) (xy 110.022858 -238.298605)
			(xy 109.975326 -238.314049) (xy 109.925963 -238.321868) (xy 109.875985 -238.321868) (xy 109.826622 -238.314049)
			(xy 109.77909 -238.298605) (xy 109.734558 -238.275915) (xy 109.694125 -238.246539) (xy 109.658785 -238.211199)
			(xy 109.629409 -238.170766) (xy 109.606719 -238.126234) (xy 109.591275 -238.078702) (xy 109.583456 -238.029339)
			(xy 109.278692 -238.029339) (xy 109.270873 -238.078702) (xy 109.255429 -238.126234) (xy 109.232739 -238.170766)
			(xy 109.203363 -238.211199) (xy 109.168023 -238.246539) (xy 109.12759 -238.275915) (xy 109.083058 -238.298605)
			(xy 109.035526 -238.314049) (xy 108.986163 -238.321868) (xy 108.936185 -238.321868) (xy 108.886822 -238.314049)
			(xy 108.83929 -238.298605) (xy 108.794758 -238.275915) (xy 108.754325 -238.246539) (xy 108.718985 -238.211199)
			(xy 108.689609 -238.170766) (xy 108.666919 -238.126234) (xy 108.651475 -238.078702) (xy 108.643656 -238.029339)
			(xy 108.338638 -238.029339) (xy 108.330819 -238.078702) (xy 108.315375 -238.126234) (xy 108.292685 -238.170766)
			(xy 108.263309 -238.211199) (xy 108.227969 -238.246539) (xy 108.187536 -238.275915) (xy 108.143004 -238.298605)
			(xy 108.095472 -238.314049) (xy 108.046109 -238.321868) (xy 107.996131 -238.321868) (xy 107.946768 -238.314049)
			(xy 107.899236 -238.298605) (xy 107.854704 -238.275915) (xy 107.814271 -238.246539) (xy 107.778931 -238.211199)
			(xy 107.749555 -238.170766) (xy 107.726865 -238.126234) (xy 107.711421 -238.078702) (xy 107.703602 -238.029339)
			(xy 107.396285 -238.029339) (xy 107.396276 -238.029796) (xy 107.388112 -238.08003) (xy 107.371996 -238.128304)
			(xy 107.348345 -238.173367) (xy 107.317772 -238.214053) (xy 107.281068 -238.249308) (xy 107.239184 -238.278218)
			(xy 107.193205 -238.300035) (xy 107.144321 -238.314195) (xy 107.0938 -238.320329) (xy 107.042948 -238.31828)
			(xy 106.993084 -238.3081) (xy 106.945498 -238.290053) (xy 106.901424 -238.264607) (xy 106.862002 -238.23242)
			(xy 106.828254 -238.194326) (xy 106.801053 -238.151312) (xy 106.781105 -238.104492) (xy 106.768926 -238.055078)
			(xy 106.764831 -238.00435) (xy 106.456734 -238.00435) (xy 106.456222 -238.029796) (xy 106.448058 -238.08003)
			(xy 106.431942 -238.128304) (xy 106.408291 -238.173367) (xy 106.377718 -238.214053) (xy 106.341014 -238.249308)
			(xy 106.29913 -238.278218) (xy 106.253151 -238.300035) (xy 106.204267 -238.314195) (xy 106.153746 -238.320329)
			(xy 106.102894 -238.31828) (xy 106.05303 -238.3081) (xy 106.005444 -238.290053) (xy 105.96137 -238.264607)
			(xy 105.921948 -238.23242) (xy 105.8882 -238.194326) (xy 105.860999 -238.151312) (xy 105.841051 -238.104492)
			(xy 105.828872 -238.055078) (xy 105.824777 -238.00435) (xy 105.518966 -238.00435) (xy 105.518476 -238.029339)
			(xy 105.510657 -238.078702) (xy 105.495213 -238.126234) (xy 105.472523 -238.170766) (xy 105.443147 -238.211199)
			(xy 105.407807 -238.246539) (xy 105.367374 -238.275915) (xy 105.322842 -238.298605) (xy 105.27531 -238.314049)
			(xy 105.225947 -238.321868) (xy 105.175969 -238.321868) (xy 105.126606 -238.314049) (xy 105.079074 -238.298605)
			(xy 105.034542 -238.275915) (xy 104.994109 -238.246539) (xy 104.958769 -238.211199) (xy 104.929393 -238.170766)
			(xy 104.906703 -238.126234) (xy 104.891259 -238.078702) (xy 104.88344 -238.029339) (xy 104.578676 -238.029339)
			(xy 104.570857 -238.078702) (xy 104.555413 -238.126234) (xy 104.532723 -238.170766) (xy 104.503347 -238.211199)
			(xy 104.468007 -238.246539) (xy 104.427574 -238.275915) (xy 104.383042 -238.298605) (xy 104.33551 -238.314049)
			(xy 104.286147 -238.321868) (xy 104.236169 -238.321868) (xy 104.186806 -238.314049) (xy 104.139274 -238.298605)
			(xy 104.094742 -238.275915) (xy 104.054309 -238.246539) (xy 104.018969 -238.211199) (xy 103.989593 -238.170766)
			(xy 103.966903 -238.126234) (xy 103.951459 -238.078702) (xy 103.94364 -238.029339) (xy 103.638622 -238.029339)
			(xy 103.630803 -238.078702) (xy 103.615359 -238.126234) (xy 103.592669 -238.170766) (xy 103.563293 -238.211199)
			(xy 103.527953 -238.246539) (xy 103.48752 -238.275915) (xy 103.442988 -238.298605) (xy 103.395456 -238.314049)
			(xy 103.346093 -238.321868) (xy 103.296115 -238.321868) (xy 103.246752 -238.314049) (xy 103.19922 -238.298605)
			(xy 103.154688 -238.275915) (xy 103.114255 -238.246539) (xy 103.078915 -238.211199) (xy 103.049539 -238.170766)
			(xy 103.026849 -238.126234) (xy 103.011405 -238.078702) (xy 103.003586 -238.029339) (xy 102.698568 -238.029339)
			(xy 102.690749 -238.078702) (xy 102.675305 -238.126234) (xy 102.652615 -238.170766) (xy 102.623239 -238.211199)
			(xy 102.587899 -238.246539) (xy 102.547466 -238.275915) (xy 102.502934 -238.298605) (xy 102.455402 -238.314049)
			(xy 102.406039 -238.321868) (xy 102.356061 -238.321868) (xy 102.306698 -238.314049) (xy 102.259166 -238.298605)
			(xy 102.214634 -238.275915) (xy 102.174201 -238.246539) (xy 102.138861 -238.211199) (xy 102.109485 -238.170766)
			(xy 102.086795 -238.126234) (xy 102.071351 -238.078702) (xy 102.063532 -238.029339) (xy 101.758514 -238.029339)
			(xy 101.750695 -238.078702) (xy 101.735251 -238.126234) (xy 101.712561 -238.170766) (xy 101.683185 -238.211199)
			(xy 101.647845 -238.246539) (xy 101.607412 -238.275915) (xy 101.56288 -238.298605) (xy 101.515348 -238.314049)
			(xy 101.465985 -238.321868) (xy 101.416007 -238.321868) (xy 101.366644 -238.314049) (xy 101.319112 -238.298605)
			(xy 101.27458 -238.275915) (xy 101.234147 -238.246539) (xy 101.198807 -238.211199) (xy 101.169431 -238.170766)
			(xy 101.146741 -238.126234) (xy 101.131297 -238.078702) (xy 101.123478 -238.029339) (xy 100.81846 -238.029339)
			(xy 100.810641 -238.078702) (xy 100.795197 -238.126234) (xy 100.772507 -238.170766) (xy 100.743131 -238.211199)
			(xy 100.707791 -238.246539) (xy 100.667358 -238.275915) (xy 100.622826 -238.298605) (xy 100.575294 -238.314049)
			(xy 100.525931 -238.321868) (xy 100.475953 -238.321868) (xy 100.42659 -238.314049) (xy 100.379058 -238.298605)
			(xy 100.334526 -238.275915) (xy 100.294093 -238.246539) (xy 100.258753 -238.211199) (xy 100.229377 -238.170766)
			(xy 100.206687 -238.126234) (xy 100.191243 -238.078702) (xy 100.183424 -238.029339) (xy 99.87866 -238.029339)
			(xy 99.870841 -238.078702) (xy 99.855397 -238.126234) (xy 99.832707 -238.170766) (xy 99.803331 -238.211199)
			(xy 99.767991 -238.246539) (xy 99.727558 -238.275915) (xy 99.683026 -238.298605) (xy 99.635494 -238.314049)
			(xy 99.586131 -238.321868) (xy 99.536153 -238.321868) (xy 99.48679 -238.314049) (xy 99.439258 -238.298605)
			(xy 99.394726 -238.275915) (xy 99.354293 -238.246539) (xy 99.318953 -238.211199) (xy 99.289577 -238.170766)
			(xy 99.266887 -238.126234) (xy 99.251443 -238.078702) (xy 99.243624 -238.029339) (xy 98.938606 -238.029339)
			(xy 98.930787 -238.078702) (xy 98.915343 -238.126234) (xy 98.892653 -238.170766) (xy 98.863277 -238.211199)
			(xy 98.827937 -238.246539) (xy 98.787504 -238.275915) (xy 98.742972 -238.298605) (xy 98.69544 -238.314049)
			(xy 98.646077 -238.321868) (xy 98.596099 -238.321868) (xy 98.546736 -238.314049) (xy 98.499204 -238.298605)
			(xy 98.454672 -238.275915) (xy 98.414239 -238.246539) (xy 98.378899 -238.211199) (xy 98.349523 -238.170766)
			(xy 98.326833 -238.126234) (xy 98.311389 -238.078702) (xy 98.30357 -238.029339) (xy 97.998552 -238.029339)
			(xy 97.990733 -238.078702) (xy 97.975289 -238.126234) (xy 97.952599 -238.170766) (xy 97.923223 -238.211199)
			(xy 97.887883 -238.246539) (xy 97.84745 -238.275915) (xy 97.802918 -238.298605) (xy 97.755386 -238.314049)
			(xy 97.706023 -238.321868) (xy 97.656045 -238.321868) (xy 97.606682 -238.314049) (xy 97.55915 -238.298605)
			(xy 97.514618 -238.275915) (xy 97.474185 -238.246539) (xy 97.438845 -238.211199) (xy 97.409469 -238.170766)
			(xy 97.386779 -238.126234) (xy 97.371335 -238.078702) (xy 97.363516 -238.029339) (xy 97.05808 -238.029339)
			(xy 97.057718 -238.037878) (xy 97.057464 -238.039402) (xy 97.057464 -238.839345) (xy 98.77347 -238.839345)
			(xy 98.77347 -238.789367) (xy 98.781289 -238.740004) (xy 98.796733 -238.692472) (xy 98.819423 -238.64794)
			(xy 98.848799 -238.607507) (xy 98.884139 -238.572167) (xy 98.924572 -238.542791) (xy 98.969104 -238.520101)
			(xy 99.016636 -238.504657) (xy 99.065999 -238.496838) (xy 99.115977 -238.496838) (xy 99.16534 -238.504657)
			(xy 99.212872 -238.520101) (xy 99.257404 -238.542791) (xy 99.297837 -238.572167) (xy 99.333177 -238.607507)
			(xy 99.362553 -238.64794) (xy 99.385243 -238.692472) (xy 99.400687 -238.740004) (xy 99.408506 -238.789367)
			(xy 99.408996 -238.814356) (xy 99.408506 -238.839345) (xy 101.593632 -238.839345) (xy 101.593632 -238.789367)
			(xy 101.601451 -238.740004) (xy 101.616895 -238.692472) (xy 101.639585 -238.64794) (xy 101.668961 -238.607507)
			(xy 101.704301 -238.572167) (xy 101.744734 -238.542791) (xy 101.789266 -238.520101) (xy 101.836798 -238.504657)
			(xy 101.886161 -238.496838) (xy 101.936139 -238.496838) (xy 101.985502 -238.504657) (xy 102.033034 -238.520101)
			(xy 102.077566 -238.542791) (xy 102.117999 -238.572167) (xy 102.153339 -238.607507) (xy 102.182715 -238.64794)
			(xy 102.205405 -238.692472) (xy 102.220849 -238.740004) (xy 102.228668 -238.789367) (xy 102.229158 -238.814356)
			(xy 102.228668 -238.839345) (xy 104.41354 -238.839345) (xy 104.41354 -238.789367) (xy 104.421359 -238.740004)
			(xy 104.436803 -238.692472) (xy 104.459493 -238.64794) (xy 104.488869 -238.607507) (xy 104.524209 -238.572167)
			(xy 104.564642 -238.542791) (xy 104.609174 -238.520101) (xy 104.656706 -238.504657) (xy 104.706069 -238.496838)
			(xy 104.756047 -238.496838) (xy 104.80541 -238.504657) (xy 104.852942 -238.520101) (xy 104.897474 -238.542791)
			(xy 104.937907 -238.572167) (xy 104.973247 -238.607507) (xy 105.002623 -238.64794) (xy 105.025313 -238.692472)
			(xy 105.040757 -238.740004) (xy 105.048576 -238.789367) (xy 105.049066 -238.814356) (xy 105.048576 -238.839345)
			(xy 107.233448 -238.839345) (xy 107.233448 -238.789367) (xy 107.241267 -238.740004) (xy 107.256711 -238.692472)
			(xy 107.279401 -238.64794) (xy 107.308777 -238.607507) (xy 107.344117 -238.572167) (xy 107.38455 -238.542791)
			(xy 107.429082 -238.520101) (xy 107.476614 -238.504657) (xy 107.525977 -238.496838) (xy 107.575955 -238.496838)
			(xy 107.625318 -238.504657) (xy 107.67285 -238.520101) (xy 107.717382 -238.542791) (xy 107.757815 -238.572167)
			(xy 107.793155 -238.607507) (xy 107.822531 -238.64794) (xy 107.845221 -238.692472) (xy 107.860665 -238.740004)
			(xy 107.868484 -238.789367) (xy 107.868974 -238.814356) (xy 108.174785 -238.814356) (xy 108.17888 -238.763628)
			(xy 108.191059 -238.714214) (xy 108.211007 -238.667394) (xy 108.238208 -238.62438) (xy 108.271956 -238.586286)
			(xy 108.311378 -238.554099) (xy 108.355452 -238.528653) (xy 108.403038 -238.510606) (xy 108.452902 -238.500426)
			(xy 108.503754 -238.498377) (xy 108.554275 -238.504511) (xy 108.603159 -238.518671) (xy 108.649138 -238.540488)
			(xy 108.691022 -238.569398) (xy 108.727726 -238.604653) (xy 108.758299 -238.645339) (xy 108.78195 -238.690402)
			(xy 108.798066 -238.738676) (xy 108.80623 -238.78891) (xy 108.806742 -238.814356) (xy 109.114839 -238.814356)
			(xy 109.118934 -238.763628) (xy 109.131113 -238.714214) (xy 109.151061 -238.667394) (xy 109.178262 -238.62438)
			(xy 109.21201 -238.586286) (xy 109.251432 -238.554099) (xy 109.295506 -238.528653) (xy 109.343092 -238.510606)
			(xy 109.392956 -238.500426) (xy 109.443808 -238.498377) (xy 109.494329 -238.504511) (xy 109.543213 -238.518671)
			(xy 109.589192 -238.540488) (xy 109.631076 -238.569398) (xy 109.66778 -238.604653) (xy 109.698353 -238.645339)
			(xy 109.722004 -238.690402) (xy 109.73812 -238.738676) (xy 109.746284 -238.78891) (xy 109.746796 -238.814356)
			(xy 109.746293 -238.839345) (xy 110.05361 -238.839345) (xy 110.05361 -238.789367) (xy 110.061429 -238.740004)
			(xy 110.076873 -238.692472) (xy 110.099563 -238.64794) (xy 110.128939 -238.607507) (xy 110.164279 -238.572167)
			(xy 110.204712 -238.542791) (xy 110.249244 -238.520101) (xy 110.296776 -238.504657) (xy 110.346139 -238.496838)
			(xy 110.396117 -238.496838) (xy 110.44548 -238.504657) (xy 110.493012 -238.520101) (xy 110.537544 -238.542791)
			(xy 110.577977 -238.572167) (xy 110.613317 -238.607507) (xy 110.642693 -238.64794) (xy 110.665383 -238.692472)
			(xy 110.680827 -238.740004) (xy 110.688646 -238.789367) (xy 110.689136 -238.814356) (xy 110.688646 -238.839345)
			(xy 112.867168 -238.839345) (xy 112.867168 -238.789367) (xy 112.874987 -238.740004) (xy 112.890431 -238.692472)
			(xy 112.913121 -238.64794) (xy 112.942497 -238.607507) (xy 112.977837 -238.572167) (xy 113.01827 -238.542791)
			(xy 113.062802 -238.520101) (xy 113.110334 -238.504657) (xy 113.159697 -238.496838) (xy 113.209675 -238.496838)
			(xy 113.259038 -238.504657) (xy 113.30657 -238.520101) (xy 113.351102 -238.542791) (xy 113.391535 -238.572167)
			(xy 113.426875 -238.607507) (xy 113.456251 -238.64794) (xy 113.478941 -238.692472) (xy 113.494385 -238.740004)
			(xy 113.502204 -238.789367) (xy 113.502694 -238.814356) (xy 113.808505 -238.814356) (xy 113.8126 -238.763628)
			(xy 113.824779 -238.714214) (xy 113.844727 -238.667394) (xy 113.871928 -238.62438) (xy 113.905676 -238.586286)
			(xy 113.945098 -238.554099) (xy 113.989172 -238.528653) (xy 114.036758 -238.510606) (xy 114.086622 -238.500426)
			(xy 114.137474 -238.498377) (xy 114.187995 -238.504511) (xy 114.236879 -238.518671) (xy 114.282858 -238.540488)
			(xy 114.324742 -238.569398) (xy 114.361446 -238.604653) (xy 114.392019 -238.645339) (xy 114.41567 -238.690402)
			(xy 114.431786 -238.738676) (xy 114.43995 -238.78891) (xy 114.440462 -238.814356) (xy 114.748559 -238.814356)
			(xy 114.752654 -238.763628) (xy 114.764833 -238.714214) (xy 114.784781 -238.667394) (xy 114.811982 -238.62438)
			(xy 114.84573 -238.586286) (xy 114.885152 -238.554099) (xy 114.929226 -238.528653) (xy 114.976812 -238.510606)
			(xy 115.026676 -238.500426) (xy 115.077528 -238.498377) (xy 115.128049 -238.504511) (xy 115.176933 -238.518671)
			(xy 115.222912 -238.540488) (xy 115.264796 -238.569398) (xy 115.3015 -238.604653) (xy 115.332073 -238.645339)
			(xy 115.355724 -238.690402) (xy 115.37184 -238.738676) (xy 115.380004 -238.78891) (xy 115.380516 -238.814356)
			(xy 115.380013 -238.839345) (xy 115.68733 -238.839345) (xy 115.68733 -238.789367) (xy 115.695149 -238.740004)
			(xy 115.710593 -238.692472) (xy 115.733283 -238.64794) (xy 115.762659 -238.607507) (xy 115.797999 -238.572167)
			(xy 115.838432 -238.542791) (xy 115.882964 -238.520101) (xy 115.930496 -238.504657) (xy 115.979859 -238.496838)
			(xy 116.029837 -238.496838) (xy 116.0792 -238.504657) (xy 116.126732 -238.520101) (xy 116.171264 -238.542791)
			(xy 116.211697 -238.572167) (xy 116.247037 -238.607507) (xy 116.276413 -238.64794) (xy 116.299103 -238.692472)
			(xy 116.314547 -238.740004) (xy 116.322366 -238.789367) (xy 116.322856 -238.814356) (xy 116.322366 -238.839345)
			(xy 118.507238 -238.839345) (xy 118.507238 -238.789367) (xy 118.515057 -238.740004) (xy 118.530501 -238.692472)
			(xy 118.553191 -238.64794) (xy 118.582567 -238.607507) (xy 118.617907 -238.572167) (xy 118.65834 -238.542791)
			(xy 118.702872 -238.520101) (xy 118.750404 -238.504657) (xy 118.799767 -238.496838) (xy 118.849745 -238.496838)
			(xy 118.899108 -238.504657) (xy 118.94664 -238.520101) (xy 118.991172 -238.542791) (xy 119.031605 -238.572167)
			(xy 119.066945 -238.607507) (xy 119.096321 -238.64794) (xy 119.119011 -238.692472) (xy 119.134455 -238.740004)
			(xy 119.142274 -238.789367) (xy 119.142764 -238.814356) (xy 119.142274 -238.839345) (xy 121.327146 -238.839345)
			(xy 121.327146 -238.789367) (xy 121.334965 -238.740004) (xy 121.350409 -238.692472) (xy 121.373099 -238.64794)
			(xy 121.402475 -238.607507) (xy 121.437815 -238.572167) (xy 121.478248 -238.542791) (xy 121.52278 -238.520101)
			(xy 121.570312 -238.504657) (xy 121.619675 -238.496838) (xy 121.669653 -238.496838) (xy 121.719016 -238.504657)
			(xy 121.766548 -238.520101) (xy 121.81108 -238.542791) (xy 121.851513 -238.572167) (xy 121.886853 -238.607507)
			(xy 121.916229 -238.64794) (xy 121.938919 -238.692472) (xy 121.954363 -238.740004) (xy 121.962182 -238.789367)
			(xy 121.962672 -238.814356) (xy 121.962182 -238.839345) (xy 124.147308 -238.839345) (xy 124.147308 -238.789367)
			(xy 124.155127 -238.740004) (xy 124.170571 -238.692472) (xy 124.193261 -238.64794) (xy 124.222637 -238.607507)
			(xy 124.257977 -238.572167) (xy 124.29841 -238.542791) (xy 124.342942 -238.520101) (xy 124.390474 -238.504657)
			(xy 124.439837 -238.496838) (xy 124.489815 -238.496838) (xy 124.539178 -238.504657) (xy 124.58671 -238.520101)
			(xy 124.631242 -238.542791) (xy 124.671675 -238.572167) (xy 124.707015 -238.607507) (xy 124.736391 -238.64794)
			(xy 124.759081 -238.692472) (xy 124.774525 -238.740004) (xy 124.782344 -238.789367) (xy 124.782834 -238.814356)
			(xy 124.782344 -238.839345) (xy 124.774525 -238.888708) (xy 124.759081 -238.93624) (xy 124.736391 -238.980772)
			(xy 124.707015 -239.021205) (xy 124.671675 -239.056545) (xy 124.631242 -239.085921) (xy 124.58671 -239.108611)
			(xy 124.539178 -239.124055) (xy 124.489815 -239.131874) (xy 124.439837 -239.131874) (xy 124.390474 -239.124055)
			(xy 124.342942 -239.108611) (xy 124.29841 -239.085921) (xy 124.257977 -239.056545) (xy 124.222637 -239.021205)
			(xy 124.193261 -238.980772) (xy 124.170571 -238.93624) (xy 124.155127 -238.888708) (xy 124.147308 -238.839345)
			(xy 121.962182 -238.839345) (xy 121.954363 -238.888708) (xy 121.938919 -238.93624) (xy 121.916229 -238.980772)
			(xy 121.886853 -239.021205) (xy 121.851513 -239.056545) (xy 121.81108 -239.085921) (xy 121.766548 -239.108611)
			(xy 121.719016 -239.124055) (xy 121.669653 -239.131874) (xy 121.619675 -239.131874) (xy 121.570312 -239.124055)
			(xy 121.52278 -239.108611) (xy 121.478248 -239.085921) (xy 121.437815 -239.056545) (xy 121.402475 -239.021205)
			(xy 121.373099 -238.980772) (xy 121.350409 -238.93624) (xy 121.334965 -238.888708) (xy 121.327146 -238.839345)
			(xy 119.142274 -238.839345) (xy 119.134455 -238.888708) (xy 119.119011 -238.93624) (xy 119.096321 -238.980772)
			(xy 119.066945 -239.021205) (xy 119.031605 -239.056545) (xy 118.991172 -239.085921) (xy 118.94664 -239.108611)
			(xy 118.899108 -239.124055) (xy 118.849745 -239.131874) (xy 118.799767 -239.131874) (xy 118.750404 -239.124055)
			(xy 118.702872 -239.108611) (xy 118.65834 -239.085921) (xy 118.617907 -239.056545) (xy 118.582567 -239.021205)
			(xy 118.553191 -238.980772) (xy 118.530501 -238.93624) (xy 118.515057 -238.888708) (xy 118.507238 -238.839345)
			(xy 116.322366 -238.839345) (xy 116.314547 -238.888708) (xy 116.299103 -238.93624) (xy 116.276413 -238.980772)
			(xy 116.247037 -239.021205) (xy 116.211697 -239.056545) (xy 116.171264 -239.085921) (xy 116.126732 -239.108611)
			(xy 116.0792 -239.124055) (xy 116.029837 -239.131874) (xy 115.979859 -239.131874) (xy 115.930496 -239.124055)
			(xy 115.882964 -239.108611) (xy 115.838432 -239.085921) (xy 115.797999 -239.056545) (xy 115.762659 -239.021205)
			(xy 115.733283 -238.980772) (xy 115.710593 -238.93624) (xy 115.695149 -238.888708) (xy 115.68733 -238.839345)
			(xy 115.380013 -238.839345) (xy 115.380004 -238.839802) (xy 115.37184 -238.890036) (xy 115.355724 -238.93831)
			(xy 115.332073 -238.983373) (xy 115.3015 -239.024059) (xy 115.264796 -239.059314) (xy 115.222912 -239.088224)
			(xy 115.176933 -239.110041) (xy 115.128049 -239.124201) (xy 115.077528 -239.130335) (xy 115.026676 -239.128286)
			(xy 114.976812 -239.118106) (xy 114.929226 -239.100059) (xy 114.885152 -239.074613) (xy 114.84573 -239.042426)
			(xy 114.811982 -239.004332) (xy 114.784781 -238.961318) (xy 114.764833 -238.914498) (xy 114.752654 -238.865084)
			(xy 114.748559 -238.814356) (xy 114.440462 -238.814356) (xy 114.43995 -238.839802) (xy 114.431786 -238.890036)
			(xy 114.41567 -238.93831) (xy 114.392019 -238.983373) (xy 114.361446 -239.024059) (xy 114.324742 -239.059314)
			(xy 114.282858 -239.088224) (xy 114.236879 -239.110041) (xy 114.187995 -239.124201) (xy 114.137474 -239.130335)
			(xy 114.086622 -239.128286) (xy 114.036758 -239.118106) (xy 113.989172 -239.100059) (xy 113.945098 -239.074613)
			(xy 113.905676 -239.042426) (xy 113.871928 -239.004332) (xy 113.844727 -238.961318) (xy 113.824779 -238.914498)
			(xy 113.8126 -238.865084) (xy 113.808505 -238.814356) (xy 113.502694 -238.814356) (xy 113.502204 -238.839345)
			(xy 113.494385 -238.888708) (xy 113.478941 -238.93624) (xy 113.456251 -238.980772) (xy 113.426875 -239.021205)
			(xy 113.391535 -239.056545) (xy 113.351102 -239.085921) (xy 113.30657 -239.108611) (xy 113.259038 -239.124055)
			(xy 113.209675 -239.131874) (xy 113.159697 -239.131874) (xy 113.110334 -239.124055) (xy 113.062802 -239.108611)
			(xy 113.01827 -239.085921) (xy 112.977837 -239.056545) (xy 112.942497 -239.021205) (xy 112.913121 -238.980772)
			(xy 112.890431 -238.93624) (xy 112.874987 -238.888708) (xy 112.867168 -238.839345) (xy 110.688646 -238.839345)
			(xy 110.680827 -238.888708) (xy 110.665383 -238.93624) (xy 110.642693 -238.980772) (xy 110.613317 -239.021205)
			(xy 110.577977 -239.056545) (xy 110.537544 -239.085921) (xy 110.493012 -239.108611) (xy 110.44548 -239.124055)
			(xy 110.396117 -239.131874) (xy 110.346139 -239.131874) (xy 110.296776 -239.124055) (xy 110.249244 -239.108611)
			(xy 110.204712 -239.085921) (xy 110.164279 -239.056545) (xy 110.128939 -239.021205) (xy 110.099563 -238.980772)
			(xy 110.076873 -238.93624) (xy 110.061429 -238.888708) (xy 110.05361 -238.839345) (xy 109.746293 -238.839345)
			(xy 109.746284 -238.839802) (xy 109.73812 -238.890036) (xy 109.722004 -238.93831) (xy 109.698353 -238.983373)
			(xy 109.66778 -239.024059) (xy 109.631076 -239.059314) (xy 109.589192 -239.088224) (xy 109.543213 -239.110041)
			(xy 109.494329 -239.124201) (xy 109.443808 -239.130335) (xy 109.392956 -239.128286) (xy 109.343092 -239.118106)
			(xy 109.295506 -239.100059) (xy 109.251432 -239.074613) (xy 109.21201 -239.042426) (xy 109.178262 -239.004332)
			(xy 109.151061 -238.961318) (xy 109.131113 -238.914498) (xy 109.118934 -238.865084) (xy 109.114839 -238.814356)
			(xy 108.806742 -238.814356) (xy 108.80623 -238.839802) (xy 108.798066 -238.890036) (xy 108.78195 -238.93831)
			(xy 108.758299 -238.983373) (xy 108.727726 -239.024059) (xy 108.691022 -239.059314) (xy 108.649138 -239.088224)
			(xy 108.603159 -239.110041) (xy 108.554275 -239.124201) (xy 108.503754 -239.130335) (xy 108.452902 -239.128286)
			(xy 108.403038 -239.118106) (xy 108.355452 -239.100059) (xy 108.311378 -239.074613) (xy 108.271956 -239.042426)
			(xy 108.238208 -239.004332) (xy 108.211007 -238.961318) (xy 108.191059 -238.914498) (xy 108.17888 -238.865084)
			(xy 108.174785 -238.814356) (xy 107.868974 -238.814356) (xy 107.868484 -238.839345) (xy 107.860665 -238.888708)
			(xy 107.845221 -238.93624) (xy 107.822531 -238.980772) (xy 107.793155 -239.021205) (xy 107.757815 -239.056545)
			(xy 107.717382 -239.085921) (xy 107.67285 -239.108611) (xy 107.625318 -239.124055) (xy 107.575955 -239.131874)
			(xy 107.525977 -239.131874) (xy 107.476614 -239.124055) (xy 107.429082 -239.108611) (xy 107.38455 -239.085921)
			(xy 107.344117 -239.056545) (xy 107.308777 -239.021205) (xy 107.279401 -238.980772) (xy 107.256711 -238.93624)
			(xy 107.241267 -238.888708) (xy 107.233448 -238.839345) (xy 105.048576 -238.839345) (xy 105.040757 -238.888708)
			(xy 105.025313 -238.93624) (xy 105.002623 -238.980772) (xy 104.973247 -239.021205) (xy 104.937907 -239.056545)
			(xy 104.897474 -239.085921) (xy 104.852942 -239.108611) (xy 104.80541 -239.124055) (xy 104.756047 -239.131874)
			(xy 104.706069 -239.131874) (xy 104.656706 -239.124055) (xy 104.609174 -239.108611) (xy 104.564642 -239.085921)
			(xy 104.524209 -239.056545) (xy 104.488869 -239.021205) (xy 104.459493 -238.980772) (xy 104.436803 -238.93624)
			(xy 104.421359 -238.888708) (xy 104.41354 -238.839345) (xy 102.228668 -238.839345) (xy 102.220849 -238.888708)
			(xy 102.205405 -238.93624) (xy 102.182715 -238.980772) (xy 102.153339 -239.021205) (xy 102.117999 -239.056545)
			(xy 102.077566 -239.085921) (xy 102.033034 -239.108611) (xy 101.985502 -239.124055) (xy 101.936139 -239.131874)
			(xy 101.886161 -239.131874) (xy 101.836798 -239.124055) (xy 101.789266 -239.108611) (xy 101.744734 -239.085921)
			(xy 101.704301 -239.056545) (xy 101.668961 -239.021205) (xy 101.639585 -238.980772) (xy 101.616895 -238.93624)
			(xy 101.601451 -238.888708) (xy 101.593632 -238.839345) (xy 99.408506 -238.839345) (xy 99.400687 -238.888708)
			(xy 99.385243 -238.93624) (xy 99.362553 -238.980772) (xy 99.333177 -239.021205) (xy 99.297837 -239.056545)
			(xy 99.257404 -239.085921) (xy 99.212872 -239.108611) (xy 99.16534 -239.124055) (xy 99.115977 -239.131874)
			(xy 99.065999 -239.131874) (xy 99.016636 -239.124055) (xy 98.969104 -239.108611) (xy 98.924572 -239.085921)
			(xy 98.884139 -239.056545) (xy 98.848799 -239.021205) (xy 98.819423 -238.980772) (xy 98.796733 -238.93624)
			(xy 98.781289 -238.888708) (xy 98.77347 -238.839345) (xy 97.057464 -238.839345) (xy 97.057464 -239.58677)
			(xy 97.057718 -239.591342) (xy 97.058988 -239.621822) (xy 97.058988 -239.624362) (xy 97.364799 -239.624362)
			(xy 97.368894 -239.573634) (xy 97.381073 -239.52422) (xy 97.401021 -239.4774) (xy 97.428222 -239.434386)
			(xy 97.46197 -239.396292) (xy 97.501392 -239.364105) (xy 97.545466 -239.338659) (xy 97.593052 -239.320612)
			(xy 97.642916 -239.310432) (xy 97.693768 -239.308383) (xy 97.744289 -239.314517) (xy 97.793173 -239.328677)
			(xy 97.839152 -239.350494) (xy 97.881036 -239.379404) (xy 97.91774 -239.414659) (xy 97.948313 -239.455345)
			(xy 97.971964 -239.500408) (xy 97.98808 -239.548682) (xy 97.996244 -239.598916) (xy 97.996756 -239.624362)
			(xy 98.304853 -239.624362) (xy 98.308948 -239.573634) (xy 98.321127 -239.52422) (xy 98.341075 -239.4774)
			(xy 98.368276 -239.434386) (xy 98.402024 -239.396292) (xy 98.441446 -239.364105) (xy 98.48552 -239.338659)
			(xy 98.533106 -239.320612) (xy 98.58297 -239.310432) (xy 98.633822 -239.308383) (xy 98.684343 -239.314517)
			(xy 98.733227 -239.328677) (xy 98.779206 -239.350494) (xy 98.82109 -239.379404) (xy 98.857794 -239.414659)
			(xy 98.888367 -239.455345) (xy 98.912018 -239.500408) (xy 98.928134 -239.548682) (xy 98.936298 -239.598916)
			(xy 98.93681 -239.624362) (xy 98.936307 -239.649351) (xy 99.243624 -239.649351) (xy 99.243624 -239.599373)
			(xy 99.251443 -239.55001) (xy 99.266887 -239.502478) (xy 99.289577 -239.457946) (xy 99.318953 -239.417513)
			(xy 99.354293 -239.382173) (xy 99.394726 -239.352797) (xy 99.439258 -239.330107) (xy 99.48679 -239.314663)
			(xy 99.536153 -239.306844) (xy 99.586131 -239.306844) (xy 99.635494 -239.314663) (xy 99.683026 -239.330107)
			(xy 99.727558 -239.352797) (xy 99.767991 -239.382173) (xy 99.803331 -239.417513) (xy 99.832707 -239.457946)
			(xy 99.855397 -239.502478) (xy 99.870841 -239.55001) (xy 99.87866 -239.599373) (xy 99.87915 -239.624362)
			(xy 100.184707 -239.624362) (xy 100.188802 -239.573634) (xy 100.200981 -239.52422) (xy 100.220929 -239.4774)
			(xy 100.24813 -239.434386) (xy 100.281878 -239.396292) (xy 100.3213 -239.364105) (xy 100.365374 -239.338659)
			(xy 100.41296 -239.320612) (xy 100.462824 -239.310432) (xy 100.513676 -239.308383) (xy 100.564197 -239.314517)
			(xy 100.613081 -239.328677) (xy 100.65906 -239.350494) (xy 100.700944 -239.379404) (xy 100.737648 -239.414659)
			(xy 100.768221 -239.455345) (xy 100.791872 -239.500408) (xy 100.807988 -239.548682) (xy 100.816152 -239.598916)
			(xy 100.816664 -239.624362) (xy 101.124761 -239.624362) (xy 101.128856 -239.573634) (xy 101.141035 -239.52422)
			(xy 101.160983 -239.4774) (xy 101.188184 -239.434386) (xy 101.221932 -239.396292) (xy 101.261354 -239.364105)
			(xy 101.305428 -239.338659) (xy 101.353014 -239.320612) (xy 101.402878 -239.310432) (xy 101.45373 -239.308383)
			(xy 101.504251 -239.314517) (xy 101.553135 -239.328677) (xy 101.599114 -239.350494) (xy 101.640998 -239.379404)
			(xy 101.677702 -239.414659) (xy 101.708275 -239.455345) (xy 101.731926 -239.500408) (xy 101.748042 -239.548682)
			(xy 101.756206 -239.598916) (xy 101.756718 -239.624362) (xy 101.756215 -239.649351) (xy 102.063532 -239.649351)
			(xy 102.063532 -239.599373) (xy 102.071351 -239.55001) (xy 102.086795 -239.502478) (xy 102.109485 -239.457946)
			(xy 102.138861 -239.417513) (xy 102.174201 -239.382173) (xy 102.214634 -239.352797) (xy 102.259166 -239.330107)
			(xy 102.306698 -239.314663) (xy 102.356061 -239.306844) (xy 102.406039 -239.306844) (xy 102.455402 -239.314663)
			(xy 102.502934 -239.330107) (xy 102.547466 -239.352797) (xy 102.587899 -239.382173) (xy 102.623239 -239.417513)
			(xy 102.652615 -239.457946) (xy 102.675305 -239.502478) (xy 102.690749 -239.55001) (xy 102.698568 -239.599373)
			(xy 102.699058 -239.624362) (xy 103.004869 -239.624362) (xy 103.008964 -239.573634) (xy 103.021143 -239.52422)
			(xy 103.041091 -239.4774) (xy 103.068292 -239.434386) (xy 103.10204 -239.396292) (xy 103.141462 -239.364105)
			(xy 103.185536 -239.338659) (xy 103.233122 -239.320612) (xy 103.282986 -239.310432) (xy 103.333838 -239.308383)
			(xy 103.384359 -239.314517) (xy 103.433243 -239.328677) (xy 103.479222 -239.350494) (xy 103.521106 -239.379404)
			(xy 103.55781 -239.414659) (xy 103.588383 -239.455345) (xy 103.612034 -239.500408) (xy 103.62815 -239.548682)
			(xy 103.636314 -239.598916) (xy 103.636826 -239.624362) (xy 103.944923 -239.624362) (xy 103.949018 -239.573634)
			(xy 103.961197 -239.52422) (xy 103.981145 -239.4774) (xy 104.008346 -239.434386) (xy 104.042094 -239.396292)
			(xy 104.081516 -239.364105) (xy 104.12559 -239.338659) (xy 104.173176 -239.320612) (xy 104.22304 -239.310432)
			(xy 104.273892 -239.308383) (xy 104.324413 -239.314517) (xy 104.373297 -239.328677) (xy 104.419276 -239.350494)
			(xy 104.46116 -239.379404) (xy 104.497864 -239.414659) (xy 104.528437 -239.455345) (xy 104.552088 -239.500408)
			(xy 104.568204 -239.548682) (xy 104.576368 -239.598916) (xy 104.57688 -239.624362) (xy 104.576377 -239.649351)
			(xy 104.88344 -239.649351) (xy 104.88344 -239.599373) (xy 104.891259 -239.55001) (xy 104.906703 -239.502478)
			(xy 104.929393 -239.457946) (xy 104.958769 -239.417513) (xy 104.994109 -239.382173) (xy 105.034542 -239.352797)
			(xy 105.079074 -239.330107) (xy 105.126606 -239.314663) (xy 105.175969 -239.306844) (xy 105.225947 -239.306844)
			(xy 105.27531 -239.314663) (xy 105.322842 -239.330107) (xy 105.367374 -239.352797) (xy 105.407807 -239.382173)
			(xy 105.443147 -239.417513) (xy 105.472523 -239.457946) (xy 105.495213 -239.502478) (xy 105.510657 -239.55001)
			(xy 105.518476 -239.599373) (xy 105.518966 -239.624362) (xy 105.824777 -239.624362) (xy 105.828872 -239.573634)
			(xy 105.841051 -239.52422) (xy 105.860999 -239.4774) (xy 105.8882 -239.434386) (xy 105.921948 -239.396292)
			(xy 105.96137 -239.364105) (xy 106.005444 -239.338659) (xy 106.05303 -239.320612) (xy 106.102894 -239.310432)
			(xy 106.153746 -239.308383) (xy 106.204267 -239.314517) (xy 106.253151 -239.328677) (xy 106.29913 -239.350494)
			(xy 106.341014 -239.379404) (xy 106.377718 -239.414659) (xy 106.408291 -239.455345) (xy 106.431942 -239.500408)
			(xy 106.448058 -239.548682) (xy 106.456222 -239.598916) (xy 106.456734 -239.624362) (xy 106.764831 -239.624362)
			(xy 106.768926 -239.573634) (xy 106.781105 -239.52422) (xy 106.801053 -239.4774) (xy 106.828254 -239.434386)
			(xy 106.862002 -239.396292) (xy 106.901424 -239.364105) (xy 106.945498 -239.338659) (xy 106.993084 -239.320612)
			(xy 107.042948 -239.310432) (xy 107.0938 -239.308383) (xy 107.144321 -239.314517) (xy 107.193205 -239.328677)
			(xy 107.239184 -239.350494) (xy 107.281068 -239.379404) (xy 107.317772 -239.414659) (xy 107.348345 -239.455345)
			(xy 107.371996 -239.500408) (xy 107.388112 -239.548682) (xy 107.396276 -239.598916) (xy 107.396788 -239.624362)
			(xy 107.396285 -239.649351) (xy 107.703602 -239.649351) (xy 107.703602 -239.599373) (xy 107.711421 -239.55001)
			(xy 107.726865 -239.502478) (xy 107.749555 -239.457946) (xy 107.778931 -239.417513) (xy 107.814271 -239.382173)
			(xy 107.854704 -239.352797) (xy 107.899236 -239.330107) (xy 107.946768 -239.314663) (xy 107.996131 -239.306844)
			(xy 108.046109 -239.306844) (xy 108.095472 -239.314663) (xy 108.143004 -239.330107) (xy 108.187536 -239.352797)
			(xy 108.227969 -239.382173) (xy 108.263309 -239.417513) (xy 108.292685 -239.457946) (xy 108.315375 -239.502478)
			(xy 108.330819 -239.55001) (xy 108.338638 -239.599373) (xy 108.339128 -239.624362) (xy 108.338638 -239.649351)
			(xy 115.217176 -239.649351) (xy 115.217176 -239.599373) (xy 115.224995 -239.55001) (xy 115.240439 -239.502478)
			(xy 115.263129 -239.457946) (xy 115.292505 -239.417513) (xy 115.327845 -239.382173) (xy 115.368278 -239.352797)
			(xy 115.41281 -239.330107) (xy 115.460342 -239.314663) (xy 115.509705 -239.306844) (xy 115.559683 -239.306844)
			(xy 115.609046 -239.314663) (xy 115.656578 -239.330107) (xy 115.70111 -239.352797) (xy 115.741543 -239.382173)
			(xy 115.776883 -239.417513) (xy 115.806259 -239.457946) (xy 115.828949 -239.502478) (xy 115.844393 -239.55001)
			(xy 115.852212 -239.599373) (xy 115.852702 -239.624362) (xy 116.158513 -239.624362) (xy 116.162608 -239.573634)
			(xy 116.174787 -239.52422) (xy 116.194735 -239.4774) (xy 116.221936 -239.434386) (xy 116.255684 -239.396292)
			(xy 116.295106 -239.364105) (xy 116.33918 -239.338659) (xy 116.386766 -239.320612) (xy 116.43663 -239.310432)
			(xy 116.487482 -239.308383) (xy 116.538003 -239.314517) (xy 116.586887 -239.328677) (xy 116.632866 -239.350494)
			(xy 116.67475 -239.379404) (xy 116.711454 -239.414659) (xy 116.742027 -239.455345) (xy 116.765678 -239.500408)
			(xy 116.781794 -239.548682) (xy 116.789958 -239.598916) (xy 116.79047 -239.624362) (xy 117.098567 -239.624362)
			(xy 117.102662 -239.573634) (xy 117.114841 -239.52422) (xy 117.134789 -239.4774) (xy 117.16199 -239.434386)
			(xy 117.195738 -239.396292) (xy 117.23516 -239.364105) (xy 117.279234 -239.338659) (xy 117.32682 -239.320612)
			(xy 117.376684 -239.310432) (xy 117.427536 -239.308383) (xy 117.478057 -239.314517) (xy 117.526941 -239.328677)
			(xy 117.57292 -239.350494) (xy 117.614804 -239.379404) (xy 117.651508 -239.414659) (xy 117.682081 -239.455345)
			(xy 117.705732 -239.500408) (xy 117.721848 -239.548682) (xy 117.730012 -239.598916) (xy 117.730524 -239.624362)
			(xy 117.730021 -239.649351) (xy 118.037338 -239.649351) (xy 118.037338 -239.599373) (xy 118.045157 -239.55001)
			(xy 118.060601 -239.502478) (xy 118.083291 -239.457946) (xy 118.112667 -239.417513) (xy 118.148007 -239.382173)
			(xy 118.18844 -239.352797) (xy 118.232972 -239.330107) (xy 118.280504 -239.314663) (xy 118.329867 -239.306844)
			(xy 118.379845 -239.306844) (xy 118.429208 -239.314663) (xy 118.47674 -239.330107) (xy 118.521272 -239.352797)
			(xy 118.561705 -239.382173) (xy 118.597045 -239.417513) (xy 118.626421 -239.457946) (xy 118.649111 -239.502478)
			(xy 118.664555 -239.55001) (xy 118.672374 -239.599373) (xy 118.672864 -239.624362) (xy 118.978421 -239.624362)
			(xy 118.982516 -239.573634) (xy 118.994695 -239.52422) (xy 119.014643 -239.4774) (xy 119.041844 -239.434386)
			(xy 119.075592 -239.396292) (xy 119.115014 -239.364105) (xy 119.159088 -239.338659) (xy 119.206674 -239.320612)
			(xy 119.256538 -239.310432) (xy 119.30739 -239.308383) (xy 119.357911 -239.314517) (xy 119.406795 -239.328677)
			(xy 119.452774 -239.350494) (xy 119.494658 -239.379404) (xy 119.531362 -239.414659) (xy 119.561935 -239.455345)
			(xy 119.585586 -239.500408) (xy 119.601702 -239.548682) (xy 119.609866 -239.598916) (xy 119.610378 -239.624362)
			(xy 119.918475 -239.624362) (xy 119.92257 -239.573634) (xy 119.934749 -239.52422) (xy 119.954697 -239.4774)
			(xy 119.981898 -239.434386) (xy 120.015646 -239.396292) (xy 120.055068 -239.364105) (xy 120.099142 -239.338659)
			(xy 120.146728 -239.320612) (xy 120.196592 -239.310432) (xy 120.247444 -239.308383) (xy 120.297965 -239.314517)
			(xy 120.346849 -239.328677) (xy 120.392828 -239.350494) (xy 120.434712 -239.379404) (xy 120.471416 -239.414659)
			(xy 120.501989 -239.455345) (xy 120.52564 -239.500408) (xy 120.541756 -239.548682) (xy 120.54992 -239.598916)
			(xy 120.550432 -239.624362) (xy 120.549929 -239.649351) (xy 120.857246 -239.649351) (xy 120.857246 -239.599373)
			(xy 120.865065 -239.55001) (xy 120.880509 -239.502478) (xy 120.903199 -239.457946) (xy 120.932575 -239.417513)
			(xy 120.967915 -239.382173) (xy 121.008348 -239.352797) (xy 121.05288 -239.330107) (xy 121.100412 -239.314663)
			(xy 121.149775 -239.306844) (xy 121.199753 -239.306844) (xy 121.249116 -239.314663) (xy 121.296648 -239.330107)
			(xy 121.34118 -239.352797) (xy 121.381613 -239.382173) (xy 121.416953 -239.417513) (xy 121.446329 -239.457946)
			(xy 121.469019 -239.502478) (xy 121.484463 -239.55001) (xy 121.492282 -239.599373) (xy 121.492772 -239.624362)
			(xy 121.798583 -239.624362) (xy 121.802678 -239.573634) (xy 121.814857 -239.52422) (xy 121.834805 -239.4774)
			(xy 121.862006 -239.434386) (xy 121.895754 -239.396292) (xy 121.935176 -239.364105) (xy 121.97925 -239.338659)
			(xy 122.026836 -239.320612) (xy 122.0767 -239.310432) (xy 122.127552 -239.308383) (xy 122.178073 -239.314517)
			(xy 122.226957 -239.328677) (xy 122.272936 -239.350494) (xy 122.31482 -239.379404) (xy 122.351524 -239.414659)
			(xy 122.382097 -239.455345) (xy 122.405748 -239.500408) (xy 122.421864 -239.548682) (xy 122.430028 -239.598916)
			(xy 122.43054 -239.624362) (xy 122.738383 -239.624362) (xy 122.742478 -239.573634) (xy 122.754657 -239.52422)
			(xy 122.774605 -239.4774) (xy 122.801806 -239.434386) (xy 122.835554 -239.396292) (xy 122.874976 -239.364105)
			(xy 122.91905 -239.338659) (xy 122.966636 -239.320612) (xy 123.0165 -239.310432) (xy 123.067352 -239.308383)
			(xy 123.117873 -239.314517) (xy 123.166757 -239.328677) (xy 123.212736 -239.350494) (xy 123.25462 -239.379404)
			(xy 123.291324 -239.414659) (xy 123.321897 -239.455345) (xy 123.345548 -239.500408) (xy 123.361664 -239.548682)
			(xy 123.369828 -239.598916) (xy 123.37034 -239.624362) (xy 123.369837 -239.649351) (xy 123.677154 -239.649351)
			(xy 123.677154 -239.599373) (xy 123.684973 -239.55001) (xy 123.700417 -239.502478) (xy 123.723107 -239.457946)
			(xy 123.752483 -239.417513) (xy 123.787823 -239.382173) (xy 123.828256 -239.352797) (xy 123.872788 -239.330107)
			(xy 123.92032 -239.314663) (xy 123.969683 -239.306844) (xy 124.019661 -239.306844) (xy 124.069024 -239.314663)
			(xy 124.116556 -239.330107) (xy 124.161088 -239.352797) (xy 124.201521 -239.382173) (xy 124.236861 -239.417513)
			(xy 124.266237 -239.457946) (xy 124.288927 -239.502478) (xy 124.304371 -239.55001) (xy 124.31219 -239.599373)
			(xy 124.31268 -239.624362) (xy 124.618491 -239.624362) (xy 124.622586 -239.573634) (xy 124.634765 -239.52422)
			(xy 124.654713 -239.4774) (xy 124.681914 -239.434386) (xy 124.715662 -239.396292) (xy 124.755084 -239.364105)
			(xy 124.799158 -239.338659) (xy 124.846744 -239.320612) (xy 124.896608 -239.310432) (xy 124.94746 -239.308383)
			(xy 124.997981 -239.314517) (xy 125.046865 -239.328677) (xy 125.092844 -239.350494) (xy 125.134728 -239.379404)
			(xy 125.171432 -239.414659) (xy 125.202005 -239.455345) (xy 125.225656 -239.500408) (xy 125.241772 -239.548682)
			(xy 125.249936 -239.598916) (xy 125.250448 -239.624362) (xy 125.558545 -239.624362) (xy 125.56264 -239.573634)
			(xy 125.574819 -239.52422) (xy 125.594767 -239.4774) (xy 125.621968 -239.434386) (xy 125.655716 -239.396292)
			(xy 125.695138 -239.364105) (xy 125.739212 -239.338659) (xy 125.786798 -239.320612) (xy 125.836662 -239.310432)
			(xy 125.887514 -239.308383) (xy 125.938035 -239.314517) (xy 125.986919 -239.328677) (xy 126.032898 -239.350494)
			(xy 126.074782 -239.379404) (xy 126.111486 -239.414659) (xy 126.142059 -239.455345) (xy 126.16571 -239.500408)
			(xy 126.181826 -239.548682) (xy 126.18999 -239.598916) (xy 126.190502 -239.624362) (xy 126.18999 -239.649808)
			(xy 126.181826 -239.700042) (xy 126.16571 -239.748316) (xy 126.142059 -239.793379) (xy 126.111486 -239.834065)
			(xy 126.074782 -239.86932) (xy 126.032898 -239.89823) (xy 125.986919 -239.920047) (xy 125.938035 -239.934207)
			(xy 125.887514 -239.940341) (xy 125.836662 -239.938292) (xy 125.786798 -239.928112) (xy 125.739212 -239.910065)
			(xy 125.695138 -239.884619) (xy 125.655716 -239.852432) (xy 125.621968 -239.814338) (xy 125.594767 -239.771324)
			(xy 125.574819 -239.724504) (xy 125.56264 -239.67509) (xy 125.558545 -239.624362) (xy 125.250448 -239.624362)
			(xy 125.249936 -239.649808) (xy 125.241772 -239.700042) (xy 125.225656 -239.748316) (xy 125.202005 -239.793379)
			(xy 125.171432 -239.834065) (xy 125.134728 -239.86932) (xy 125.092844 -239.89823) (xy 125.046865 -239.920047)
			(xy 124.997981 -239.934207) (xy 124.94746 -239.940341) (xy 124.896608 -239.938292) (xy 124.846744 -239.928112)
			(xy 124.799158 -239.910065) (xy 124.755084 -239.884619) (xy 124.715662 -239.852432) (xy 124.681914 -239.814338)
			(xy 124.654713 -239.771324) (xy 124.634765 -239.724504) (xy 124.622586 -239.67509) (xy 124.618491 -239.624362)
			(xy 124.31268 -239.624362) (xy 124.31219 -239.649351) (xy 124.304371 -239.698714) (xy 124.288927 -239.746246)
			(xy 124.266237 -239.790778) (xy 124.236861 -239.831211) (xy 124.201521 -239.866551) (xy 124.161088 -239.895927)
			(xy 124.116556 -239.918617) (xy 124.069024 -239.934061) (xy 124.019661 -239.94188) (xy 123.969683 -239.94188)
			(xy 123.92032 -239.934061) (xy 123.872788 -239.918617) (xy 123.828256 -239.895927) (xy 123.787823 -239.866551)
			(xy 123.752483 -239.831211) (xy 123.723107 -239.790778) (xy 123.700417 -239.746246) (xy 123.684973 -239.698714)
			(xy 123.677154 -239.649351) (xy 123.369837 -239.649351) (xy 123.369828 -239.649808) (xy 123.361664 -239.700042)
			(xy 123.345548 -239.748316) (xy 123.321897 -239.793379) (xy 123.291324 -239.834065) (xy 123.25462 -239.86932)
			(xy 123.212736 -239.89823) (xy 123.166757 -239.920047) (xy 123.117873 -239.934207) (xy 123.067352 -239.940341)
			(xy 123.0165 -239.938292) (xy 122.966636 -239.928112) (xy 122.91905 -239.910065) (xy 122.874976 -239.884619)
			(xy 122.835554 -239.852432) (xy 122.801806 -239.814338) (xy 122.774605 -239.771324) (xy 122.754657 -239.724504)
			(xy 122.742478 -239.67509) (xy 122.738383 -239.624362) (xy 122.43054 -239.624362) (xy 122.430028 -239.649808)
			(xy 122.421864 -239.700042) (xy 122.405748 -239.748316) (xy 122.382097 -239.793379) (xy 122.351524 -239.834065)
			(xy 122.31482 -239.86932) (xy 122.272936 -239.89823) (xy 122.226957 -239.920047) (xy 122.178073 -239.934207)
			(xy 122.127552 -239.940341) (xy 122.0767 -239.938292) (xy 122.026836 -239.928112) (xy 121.97925 -239.910065)
			(xy 121.935176 -239.884619) (xy 121.895754 -239.852432) (xy 121.862006 -239.814338) (xy 121.834805 -239.771324)
			(xy 121.814857 -239.724504) (xy 121.802678 -239.67509) (xy 121.798583 -239.624362) (xy 121.492772 -239.624362)
			(xy 121.492282 -239.649351) (xy 121.484463 -239.698714) (xy 121.469019 -239.746246) (xy 121.446329 -239.790778)
			(xy 121.416953 -239.831211) (xy 121.381613 -239.866551) (xy 121.34118 -239.895927) (xy 121.296648 -239.918617)
			(xy 121.249116 -239.934061) (xy 121.199753 -239.94188) (xy 121.149775 -239.94188) (xy 121.100412 -239.934061)
			(xy 121.05288 -239.918617) (xy 121.008348 -239.895927) (xy 120.967915 -239.866551) (xy 120.932575 -239.831211)
			(xy 120.903199 -239.790778) (xy 120.880509 -239.746246) (xy 120.865065 -239.698714) (xy 120.857246 -239.649351)
			(xy 120.549929 -239.649351) (xy 120.54992 -239.649808) (xy 120.541756 -239.700042) (xy 120.52564 -239.748316)
			(xy 120.501989 -239.793379) (xy 120.471416 -239.834065) (xy 120.434712 -239.86932) (xy 120.392828 -239.89823)
			(xy 120.346849 -239.920047) (xy 120.297965 -239.934207) (xy 120.247444 -239.940341) (xy 120.196592 -239.938292)
			(xy 120.146728 -239.928112) (xy 120.099142 -239.910065) (xy 120.055068 -239.884619) (xy 120.015646 -239.852432)
			(xy 119.981898 -239.814338) (xy 119.954697 -239.771324) (xy 119.934749 -239.724504) (xy 119.92257 -239.67509)
			(xy 119.918475 -239.624362) (xy 119.610378 -239.624362) (xy 119.609866 -239.649808) (xy 119.601702 -239.700042)
			(xy 119.585586 -239.748316) (xy 119.561935 -239.793379) (xy 119.531362 -239.834065) (xy 119.494658 -239.86932)
			(xy 119.452774 -239.89823) (xy 119.406795 -239.920047) (xy 119.357911 -239.934207) (xy 119.30739 -239.940341)
			(xy 119.256538 -239.938292) (xy 119.206674 -239.928112) (xy 119.159088 -239.910065) (xy 119.115014 -239.884619)
			(xy 119.075592 -239.852432) (xy 119.041844 -239.814338) (xy 119.014643 -239.771324) (xy 118.994695 -239.724504)
			(xy 118.982516 -239.67509) (xy 118.978421 -239.624362) (xy 118.672864 -239.624362) (xy 118.672374 -239.649351)
			(xy 118.664555 -239.698714) (xy 118.649111 -239.746246) (xy 118.626421 -239.790778) (xy 118.597045 -239.831211)
			(xy 118.561705 -239.866551) (xy 118.521272 -239.895927) (xy 118.47674 -239.918617) (xy 118.429208 -239.934061)
			(xy 118.379845 -239.94188) (xy 118.329867 -239.94188) (xy 118.280504 -239.934061) (xy 118.232972 -239.918617)
			(xy 118.18844 -239.895927) (xy 118.148007 -239.866551) (xy 118.112667 -239.831211) (xy 118.083291 -239.790778)
			(xy 118.060601 -239.746246) (xy 118.045157 -239.698714) (xy 118.037338 -239.649351) (xy 117.730021 -239.649351)
			(xy 117.730012 -239.649808) (xy 117.721848 -239.700042) (xy 117.705732 -239.748316) (xy 117.682081 -239.793379)
			(xy 117.651508 -239.834065) (xy 117.614804 -239.86932) (xy 117.57292 -239.89823) (xy 117.526941 -239.920047)
			(xy 117.478057 -239.934207) (xy 117.427536 -239.940341) (xy 117.376684 -239.938292) (xy 117.32682 -239.928112)
			(xy 117.279234 -239.910065) (xy 117.23516 -239.884619) (xy 117.195738 -239.852432) (xy 117.16199 -239.814338)
			(xy 117.134789 -239.771324) (xy 117.114841 -239.724504) (xy 117.102662 -239.67509) (xy 117.098567 -239.624362)
			(xy 116.79047 -239.624362) (xy 116.789958 -239.649808) (xy 116.781794 -239.700042) (xy 116.765678 -239.748316)
			(xy 116.742027 -239.793379) (xy 116.711454 -239.834065) (xy 116.67475 -239.86932) (xy 116.632866 -239.89823)
			(xy 116.586887 -239.920047) (xy 116.538003 -239.934207) (xy 116.487482 -239.940341) (xy 116.43663 -239.938292)
			(xy 116.386766 -239.928112) (xy 116.33918 -239.910065) (xy 116.295106 -239.884619) (xy 116.255684 -239.852432)
			(xy 116.221936 -239.814338) (xy 116.194735 -239.771324) (xy 116.174787 -239.724504) (xy 116.162608 -239.67509)
			(xy 116.158513 -239.624362) (xy 115.852702 -239.624362) (xy 115.852212 -239.649351) (xy 115.844393 -239.698714)
			(xy 115.828949 -239.746246) (xy 115.806259 -239.790778) (xy 115.776883 -239.831211) (xy 115.741543 -239.866551)
			(xy 115.70111 -239.895927) (xy 115.656578 -239.918617) (xy 115.609046 -239.934061) (xy 115.559683 -239.94188)
			(xy 115.509705 -239.94188) (xy 115.460342 -239.934061) (xy 115.41281 -239.918617) (xy 115.368278 -239.895927)
			(xy 115.327845 -239.866551) (xy 115.292505 -239.831211) (xy 115.263129 -239.790778) (xy 115.240439 -239.746246)
			(xy 115.224995 -239.698714) (xy 115.217176 -239.649351) (xy 108.338638 -239.649351) (xy 108.330819 -239.698714)
			(xy 108.315375 -239.746246) (xy 108.292685 -239.790778) (xy 108.263309 -239.831211) (xy 108.227969 -239.866551)
			(xy 108.187536 -239.895927) (xy 108.143004 -239.918617) (xy 108.095472 -239.934061) (xy 108.046109 -239.94188)
			(xy 107.996131 -239.94188) (xy 107.946768 -239.934061) (xy 107.899236 -239.918617) (xy 107.854704 -239.895927)
			(xy 107.814271 -239.866551) (xy 107.778931 -239.831211) (xy 107.749555 -239.790778) (xy 107.726865 -239.746246)
			(xy 107.711421 -239.698714) (xy 107.703602 -239.649351) (xy 107.396285 -239.649351) (xy 107.396276 -239.649808)
			(xy 107.388112 -239.700042) (xy 107.371996 -239.748316) (xy 107.348345 -239.793379) (xy 107.317772 -239.834065)
			(xy 107.281068 -239.86932) (xy 107.239184 -239.89823) (xy 107.193205 -239.920047) (xy 107.144321 -239.934207)
			(xy 107.0938 -239.940341) (xy 107.042948 -239.938292) (xy 106.993084 -239.928112) (xy 106.945498 -239.910065)
			(xy 106.901424 -239.884619) (xy 106.862002 -239.852432) (xy 106.828254 -239.814338) (xy 106.801053 -239.771324)
			(xy 106.781105 -239.724504) (xy 106.768926 -239.67509) (xy 106.764831 -239.624362) (xy 106.456734 -239.624362)
			(xy 106.456222 -239.649808) (xy 106.448058 -239.700042) (xy 106.431942 -239.748316) (xy 106.408291 -239.793379)
			(xy 106.377718 -239.834065) (xy 106.341014 -239.86932) (xy 106.29913 -239.89823) (xy 106.253151 -239.920047)
			(xy 106.204267 -239.934207) (xy 106.153746 -239.940341) (xy 106.102894 -239.938292) (xy 106.05303 -239.928112)
			(xy 106.005444 -239.910065) (xy 105.96137 -239.884619) (xy 105.921948 -239.852432) (xy 105.8882 -239.814338)
			(xy 105.860999 -239.771324) (xy 105.841051 -239.724504) (xy 105.828872 -239.67509) (xy 105.824777 -239.624362)
			(xy 105.518966 -239.624362) (xy 105.518476 -239.649351) (xy 105.510657 -239.698714) (xy 105.495213 -239.746246)
			(xy 105.472523 -239.790778) (xy 105.443147 -239.831211) (xy 105.407807 -239.866551) (xy 105.367374 -239.895927)
			(xy 105.322842 -239.918617) (xy 105.27531 -239.934061) (xy 105.225947 -239.94188) (xy 105.175969 -239.94188)
			(xy 105.126606 -239.934061) (xy 105.079074 -239.918617) (xy 105.034542 -239.895927) (xy 104.994109 -239.866551)
			(xy 104.958769 -239.831211) (xy 104.929393 -239.790778) (xy 104.906703 -239.746246) (xy 104.891259 -239.698714)
			(xy 104.88344 -239.649351) (xy 104.576377 -239.649351) (xy 104.576368 -239.649808) (xy 104.568204 -239.700042)
			(xy 104.552088 -239.748316) (xy 104.528437 -239.793379) (xy 104.497864 -239.834065) (xy 104.46116 -239.86932)
			(xy 104.419276 -239.89823) (xy 104.373297 -239.920047) (xy 104.324413 -239.934207) (xy 104.273892 -239.940341)
			(xy 104.22304 -239.938292) (xy 104.173176 -239.928112) (xy 104.12559 -239.910065) (xy 104.081516 -239.884619)
			(xy 104.042094 -239.852432) (xy 104.008346 -239.814338) (xy 103.981145 -239.771324) (xy 103.961197 -239.724504)
			(xy 103.949018 -239.67509) (xy 103.944923 -239.624362) (xy 103.636826 -239.624362) (xy 103.636314 -239.649808)
			(xy 103.62815 -239.700042) (xy 103.612034 -239.748316) (xy 103.588383 -239.793379) (xy 103.55781 -239.834065)
			(xy 103.521106 -239.86932) (xy 103.479222 -239.89823) (xy 103.433243 -239.920047) (xy 103.384359 -239.934207)
			(xy 103.333838 -239.940341) (xy 103.282986 -239.938292) (xy 103.233122 -239.928112) (xy 103.185536 -239.910065)
			(xy 103.141462 -239.884619) (xy 103.10204 -239.852432) (xy 103.068292 -239.814338) (xy 103.041091 -239.771324)
			(xy 103.021143 -239.724504) (xy 103.008964 -239.67509) (xy 103.004869 -239.624362) (xy 102.699058 -239.624362)
			(xy 102.698568 -239.649351) (xy 102.690749 -239.698714) (xy 102.675305 -239.746246) (xy 102.652615 -239.790778)
			(xy 102.623239 -239.831211) (xy 102.587899 -239.866551) (xy 102.547466 -239.895927) (xy 102.502934 -239.918617)
			(xy 102.455402 -239.934061) (xy 102.406039 -239.94188) (xy 102.356061 -239.94188) (xy 102.306698 -239.934061)
			(xy 102.259166 -239.918617) (xy 102.214634 -239.895927) (xy 102.174201 -239.866551) (xy 102.138861 -239.831211)
			(xy 102.109485 -239.790778) (xy 102.086795 -239.746246) (xy 102.071351 -239.698714) (xy 102.063532 -239.649351)
			(xy 101.756215 -239.649351) (xy 101.756206 -239.649808) (xy 101.748042 -239.700042) (xy 101.731926 -239.748316)
			(xy 101.708275 -239.793379) (xy 101.677702 -239.834065) (xy 101.640998 -239.86932) (xy 101.599114 -239.89823)
			(xy 101.553135 -239.920047) (xy 101.504251 -239.934207) (xy 101.45373 -239.940341) (xy 101.402878 -239.938292)
			(xy 101.353014 -239.928112) (xy 101.305428 -239.910065) (xy 101.261354 -239.884619) (xy 101.221932 -239.852432)
			(xy 101.188184 -239.814338) (xy 101.160983 -239.771324) (xy 101.141035 -239.724504) (xy 101.128856 -239.67509)
			(xy 101.124761 -239.624362) (xy 100.816664 -239.624362) (xy 100.816152 -239.649808) (xy 100.807988 -239.700042)
			(xy 100.791872 -239.748316) (xy 100.768221 -239.793379) (xy 100.737648 -239.834065) (xy 100.700944 -239.86932)
			(xy 100.65906 -239.89823) (xy 100.613081 -239.920047) (xy 100.564197 -239.934207) (xy 100.513676 -239.940341)
			(xy 100.462824 -239.938292) (xy 100.41296 -239.928112) (xy 100.365374 -239.910065) (xy 100.3213 -239.884619)
			(xy 100.281878 -239.852432) (xy 100.24813 -239.814338) (xy 100.220929 -239.771324) (xy 100.200981 -239.724504)
			(xy 100.188802 -239.67509) (xy 100.184707 -239.624362) (xy 99.87915 -239.624362) (xy 99.87866 -239.649351)
			(xy 99.870841 -239.698714) (xy 99.855397 -239.746246) (xy 99.832707 -239.790778) (xy 99.803331 -239.831211)
			(xy 99.767991 -239.866551) (xy 99.727558 -239.895927) (xy 99.683026 -239.918617) (xy 99.635494 -239.934061)
			(xy 99.586131 -239.94188) (xy 99.536153 -239.94188) (xy 99.48679 -239.934061) (xy 99.439258 -239.918617)
			(xy 99.394726 -239.895927) (xy 99.354293 -239.866551) (xy 99.318953 -239.831211) (xy 99.289577 -239.790778)
			(xy 99.266887 -239.746246) (xy 99.251443 -239.698714) (xy 99.243624 -239.649351) (xy 98.936307 -239.649351)
			(xy 98.936298 -239.649808) (xy 98.928134 -239.700042) (xy 98.912018 -239.748316) (xy 98.888367 -239.793379)
			(xy 98.857794 -239.834065) (xy 98.82109 -239.86932) (xy 98.779206 -239.89823) (xy 98.733227 -239.920047)
			(xy 98.684343 -239.934207) (xy 98.633822 -239.940341) (xy 98.58297 -239.938292) (xy 98.533106 -239.928112)
			(xy 98.48552 -239.910065) (xy 98.441446 -239.884619) (xy 98.402024 -239.852432) (xy 98.368276 -239.814338)
			(xy 98.341075 -239.771324) (xy 98.321127 -239.724504) (xy 98.308948 -239.67509) (xy 98.304853 -239.624362)
			(xy 97.996756 -239.624362) (xy 97.996244 -239.649808) (xy 97.98808 -239.700042) (xy 97.971964 -239.748316)
			(xy 97.948313 -239.793379) (xy 97.91774 -239.834065) (xy 97.881036 -239.86932) (xy 97.839152 -239.89823)
			(xy 97.793173 -239.920047) (xy 97.744289 -239.934207) (xy 97.693768 -239.940341) (xy 97.642916 -239.938292)
			(xy 97.593052 -239.928112) (xy 97.545466 -239.910065) (xy 97.501392 -239.884619) (xy 97.46197 -239.852432)
			(xy 97.428222 -239.814338) (xy 97.401021 -239.771324) (xy 97.381073 -239.724504) (xy 97.368894 -239.67509)
			(xy 97.364799 -239.624362) (xy 97.058988 -239.624362) (xy 97.058988 -239.627918) (xy 97.057718 -239.65789)
			(xy 97.057464 -239.659414) (xy 97.057464 -240.019078) (xy 97.057934 -240.029832) (xy 97.066736 -240.049452)
			(xy 97.074482 -240.056924) (xy 97.130362 -240.106454) (xy 97.13087 -240.106454) (xy 97.138236 -240.113312)
			(xy 97.159318 -240.12017) (xy 97.171002 -240.1189) (xy 97.17151 -240.1189) (xy 97.18049 -240.117814)
			(xy 97.198535 -240.116544) (xy 97.207578 -240.11636) (xy 97.211134 -240.11636) (xy 97.236122 -240.116853)
			(xy 97.285483 -240.124675) (xy 97.333013 -240.140122) (xy 97.377542 -240.162813) (xy 97.417973 -240.19219)
			(xy 97.453312 -240.227529) (xy 97.482688 -240.26796) (xy 97.505379 -240.312489) (xy 97.520825 -240.360019)
			(xy 97.528647 -240.40938) (xy 97.529142 -240.434368) (xy 97.528655 -240.459347) (xy 97.528653 -240.459357)
			(xy 97.833416 -240.459357) (xy 97.833416 -240.409379) (xy 97.841235 -240.360016) (xy 97.856679 -240.312484)
			(xy 97.879369 -240.267952) (xy 97.908745 -240.227519) (xy 97.944085 -240.192179) (xy 97.984518 -240.162803)
			(xy 98.02905 -240.140113) (xy 98.076582 -240.124669) (xy 98.125945 -240.11685) (xy 98.175923 -240.11685)
			(xy 98.225286 -240.124669) (xy 98.272818 -240.140113) (xy 98.31735 -240.162803) (xy 98.357783 -240.192179)
			(xy 98.393123 -240.227519) (xy 98.422499 -240.267952) (xy 98.445189 -240.312484) (xy 98.460633 -240.360016)
			(xy 98.468452 -240.409379) (xy 98.468942 -240.434368) (xy 98.468452 -240.459357) (xy 98.77347 -240.459357)
			(xy 98.77347 -240.409379) (xy 98.781289 -240.360016) (xy 98.796733 -240.312484) (xy 98.819423 -240.267952)
			(xy 98.848799 -240.227519) (xy 98.884139 -240.192179) (xy 98.924572 -240.162803) (xy 98.969104 -240.140113)
			(xy 99.016636 -240.124669) (xy 99.065999 -240.11685) (xy 99.115977 -240.11685) (xy 99.16534 -240.124669)
			(xy 99.212872 -240.140113) (xy 99.257404 -240.162803) (xy 99.297837 -240.192179) (xy 99.333177 -240.227519)
			(xy 99.362553 -240.267952) (xy 99.385243 -240.312484) (xy 99.400687 -240.360016) (xy 99.408506 -240.409379)
			(xy 99.408996 -240.434368) (xy 99.408506 -240.459357) (xy 99.713524 -240.459357) (xy 99.713524 -240.409379)
			(xy 99.721343 -240.360016) (xy 99.736787 -240.312484) (xy 99.759477 -240.267952) (xy 99.788853 -240.227519)
			(xy 99.824193 -240.192179) (xy 99.864626 -240.162803) (xy 99.909158 -240.140113) (xy 99.95669 -240.124669)
			(xy 100.006053 -240.11685) (xy 100.056031 -240.11685) (xy 100.105394 -240.124669) (xy 100.152926 -240.140113)
			(xy 100.197458 -240.162803) (xy 100.237891 -240.192179) (xy 100.273231 -240.227519) (xy 100.302607 -240.267952)
			(xy 100.325297 -240.312484) (xy 100.340741 -240.360016) (xy 100.34856 -240.409379) (xy 100.34905 -240.434368)
			(xy 100.34856 -240.459357) (xy 100.653578 -240.459357) (xy 100.653578 -240.409379) (xy 100.661397 -240.360016)
			(xy 100.676841 -240.312484) (xy 100.699531 -240.267952) (xy 100.728907 -240.227519) (xy 100.764247 -240.192179)
			(xy 100.80468 -240.162803) (xy 100.849212 -240.140113) (xy 100.896744 -240.124669) (xy 100.946107 -240.11685)
			(xy 100.996085 -240.11685) (xy 101.045448 -240.124669) (xy 101.09298 -240.140113) (xy 101.137512 -240.162803)
			(xy 101.177945 -240.192179) (xy 101.213285 -240.227519) (xy 101.242661 -240.267952) (xy 101.265351 -240.312484)
			(xy 101.280795 -240.360016) (xy 101.288614 -240.409379) (xy 101.289104 -240.434368) (xy 101.288614 -240.459357)
			(xy 101.593632 -240.459357) (xy 101.593632 -240.409379) (xy 101.601451 -240.360016) (xy 101.616895 -240.312484)
			(xy 101.639585 -240.267952) (xy 101.668961 -240.227519) (xy 101.704301 -240.192179) (xy 101.744734 -240.162803)
			(xy 101.789266 -240.140113) (xy 101.836798 -240.124669) (xy 101.886161 -240.11685) (xy 101.936139 -240.11685)
			(xy 101.985502 -240.124669) (xy 102.033034 -240.140113) (xy 102.077566 -240.162803) (xy 102.117999 -240.192179)
			(xy 102.153339 -240.227519) (xy 102.182715 -240.267952) (xy 102.205405 -240.312484) (xy 102.220849 -240.360016)
			(xy 102.228668 -240.409379) (xy 102.229158 -240.434368) (xy 102.228668 -240.459357) (xy 102.533432 -240.459357)
			(xy 102.533432 -240.409379) (xy 102.541251 -240.360016) (xy 102.556695 -240.312484) (xy 102.579385 -240.267952)
			(xy 102.608761 -240.227519) (xy 102.644101 -240.192179) (xy 102.684534 -240.162803) (xy 102.729066 -240.140113)
			(xy 102.776598 -240.124669) (xy 102.825961 -240.11685) (xy 102.875939 -240.11685) (xy 102.925302 -240.124669)
			(xy 102.972834 -240.140113) (xy 103.017366 -240.162803) (xy 103.057799 -240.192179) (xy 103.093139 -240.227519)
			(xy 103.122515 -240.267952) (xy 103.145205 -240.312484) (xy 103.160649 -240.360016) (xy 103.168468 -240.409379)
			(xy 103.168958 -240.434368) (xy 103.168468 -240.459357) (xy 103.473486 -240.459357) (xy 103.473486 -240.409379)
			(xy 103.481305 -240.360016) (xy 103.496749 -240.312484) (xy 103.519439 -240.267952) (xy 103.548815 -240.227519)
			(xy 103.584155 -240.192179) (xy 103.624588 -240.162803) (xy 103.66912 -240.140113) (xy 103.716652 -240.124669)
			(xy 103.766015 -240.11685) (xy 103.815993 -240.11685) (xy 103.865356 -240.124669) (xy 103.912888 -240.140113)
			(xy 103.95742 -240.162803) (xy 103.997853 -240.192179) (xy 104.033193 -240.227519) (xy 104.062569 -240.267952)
			(xy 104.085259 -240.312484) (xy 104.100703 -240.360016) (xy 104.108522 -240.409379) (xy 104.109012 -240.434368)
			(xy 104.108522 -240.459357) (xy 104.41354 -240.459357) (xy 104.41354 -240.409379) (xy 104.421359 -240.360016)
			(xy 104.436803 -240.312484) (xy 104.459493 -240.267952) (xy 104.488869 -240.227519) (xy 104.524209 -240.192179)
			(xy 104.564642 -240.162803) (xy 104.609174 -240.140113) (xy 104.656706 -240.124669) (xy 104.706069 -240.11685)
			(xy 104.756047 -240.11685) (xy 104.80541 -240.124669) (xy 104.852942 -240.140113) (xy 104.897474 -240.162803)
			(xy 104.937907 -240.192179) (xy 104.973247 -240.227519) (xy 105.002623 -240.267952) (xy 105.025313 -240.312484)
			(xy 105.040757 -240.360016) (xy 105.048576 -240.409379) (xy 105.049066 -240.434368) (xy 105.048576 -240.459357)
			(xy 105.353594 -240.459357) (xy 105.353594 -240.409379) (xy 105.361413 -240.360016) (xy 105.376857 -240.312484)
			(xy 105.399547 -240.267952) (xy 105.428923 -240.227519) (xy 105.464263 -240.192179) (xy 105.504696 -240.162803)
			(xy 105.549228 -240.140113) (xy 105.59676 -240.124669) (xy 105.646123 -240.11685) (xy 105.696101 -240.11685)
			(xy 105.745464 -240.124669) (xy 105.792996 -240.140113) (xy 105.837528 -240.162803) (xy 105.877961 -240.192179)
			(xy 105.913301 -240.227519) (xy 105.942677 -240.267952) (xy 105.965367 -240.312484) (xy 105.980811 -240.360016)
			(xy 105.98863 -240.409379) (xy 105.98912 -240.434368) (xy 105.98863 -240.459357) (xy 106.293648 -240.459357)
			(xy 106.293648 -240.409379) (xy 106.301467 -240.360016) (xy 106.316911 -240.312484) (xy 106.339601 -240.267952)
			(xy 106.368977 -240.227519) (xy 106.404317 -240.192179) (xy 106.44475 -240.162803) (xy 106.489282 -240.140113)
			(xy 106.536814 -240.124669) (xy 106.586177 -240.11685) (xy 106.636155 -240.11685) (xy 106.685518 -240.124669)
			(xy 106.73305 -240.140113) (xy 106.777582 -240.162803) (xy 106.818015 -240.192179) (xy 106.853355 -240.227519)
			(xy 106.882731 -240.267952) (xy 106.905421 -240.312484) (xy 106.920865 -240.360016) (xy 106.928684 -240.409379)
			(xy 106.929174 -240.434368) (xy 106.928684 -240.459357) (xy 107.233448 -240.459357) (xy 107.233448 -240.409379)
			(xy 107.241267 -240.360016) (xy 107.256711 -240.312484) (xy 107.279401 -240.267952) (xy 107.308777 -240.227519)
			(xy 107.344117 -240.192179) (xy 107.38455 -240.162803) (xy 107.429082 -240.140113) (xy 107.476614 -240.124669)
			(xy 107.525977 -240.11685) (xy 107.575955 -240.11685) (xy 107.625318 -240.124669) (xy 107.67285 -240.140113)
			(xy 107.717382 -240.162803) (xy 107.757815 -240.192179) (xy 107.793155 -240.227519) (xy 107.822531 -240.267952)
			(xy 107.845221 -240.312484) (xy 107.860665 -240.360016) (xy 107.868484 -240.409379) (xy 107.868974 -240.434368)
			(xy 108.174785 -240.434368) (xy 108.17888 -240.38364) (xy 108.191059 -240.334226) (xy 108.211007 -240.287406)
			(xy 108.238208 -240.244392) (xy 108.271956 -240.206298) (xy 108.311378 -240.174111) (xy 108.355452 -240.148665)
			(xy 108.403038 -240.130618) (xy 108.452902 -240.120438) (xy 108.503754 -240.118389) (xy 108.554275 -240.124523)
			(xy 108.603159 -240.138683) (xy 108.649138 -240.1605) (xy 108.691022 -240.18941) (xy 108.727726 -240.224665)
			(xy 108.758299 -240.265351) (xy 108.78195 -240.310414) (xy 108.798066 -240.358688) (xy 108.80623 -240.408922)
			(xy 108.806742 -240.434368) (xy 109.114839 -240.434368) (xy 109.118934 -240.38364) (xy 109.131113 -240.334226)
			(xy 109.151061 -240.287406) (xy 109.178262 -240.244392) (xy 109.21201 -240.206298) (xy 109.251432 -240.174111)
			(xy 109.295506 -240.148665) (xy 109.343092 -240.130618) (xy 109.392956 -240.120438) (xy 109.443808 -240.118389)
			(xy 109.494329 -240.124523) (xy 109.543213 -240.138683) (xy 109.589192 -240.1605) (xy 109.631076 -240.18941)
			(xy 109.66778 -240.224665) (xy 109.698353 -240.265351) (xy 109.722004 -240.310414) (xy 109.73812 -240.358688)
			(xy 109.746284 -240.408922) (xy 109.746796 -240.434368) (xy 109.746293 -240.459357) (xy 110.05361 -240.459357)
			(xy 110.05361 -240.409379) (xy 110.061429 -240.360016) (xy 110.076873 -240.312484) (xy 110.099563 -240.267952)
			(xy 110.128939 -240.227519) (xy 110.164279 -240.192179) (xy 110.204712 -240.162803) (xy 110.249244 -240.140113)
			(xy 110.296776 -240.124669) (xy 110.346139 -240.11685) (xy 110.396117 -240.11685) (xy 110.44548 -240.124669)
			(xy 110.493012 -240.140113) (xy 110.537544 -240.162803) (xy 110.577977 -240.192179) (xy 110.613317 -240.227519)
			(xy 110.642693 -240.267952) (xy 110.665383 -240.312484) (xy 110.680827 -240.360016) (xy 110.688646 -240.409379)
			(xy 110.689136 -240.434368) (xy 110.688646 -240.459357) (xy 112.867168 -240.459357) (xy 112.867168 -240.409379)
			(xy 112.874987 -240.360016) (xy 112.890431 -240.312484) (xy 112.913121 -240.267952) (xy 112.942497 -240.227519)
			(xy 112.977837 -240.192179) (xy 113.01827 -240.162803) (xy 113.062802 -240.140113) (xy 113.110334 -240.124669)
			(xy 113.159697 -240.11685) (xy 113.209675 -240.11685) (xy 113.259038 -240.124669) (xy 113.30657 -240.140113)
			(xy 113.351102 -240.162803) (xy 113.391535 -240.192179) (xy 113.426875 -240.227519) (xy 113.456251 -240.267952)
			(xy 113.478941 -240.312484) (xy 113.494385 -240.360016) (xy 113.502204 -240.409379) (xy 113.502694 -240.434368)
			(xy 113.808505 -240.434368) (xy 113.8126 -240.38364) (xy 113.824779 -240.334226) (xy 113.844727 -240.287406)
			(xy 113.871928 -240.244392) (xy 113.905676 -240.206298) (xy 113.945098 -240.174111) (xy 113.989172 -240.148665)
			(xy 114.036758 -240.130618) (xy 114.086622 -240.120438) (xy 114.137474 -240.118389) (xy 114.187995 -240.124523)
			(xy 114.236879 -240.138683) (xy 114.282858 -240.1605) (xy 114.324742 -240.18941) (xy 114.361446 -240.224665)
			(xy 114.392019 -240.265351) (xy 114.41567 -240.310414) (xy 114.431786 -240.358688) (xy 114.43995 -240.408922)
			(xy 114.440462 -240.434368) (xy 114.748559 -240.434368) (xy 114.752654 -240.38364) (xy 114.764833 -240.334226)
			(xy 114.784781 -240.287406) (xy 114.811982 -240.244392) (xy 114.84573 -240.206298) (xy 114.885152 -240.174111)
			(xy 114.929226 -240.148665) (xy 114.976812 -240.130618) (xy 115.026676 -240.120438) (xy 115.077528 -240.118389)
			(xy 115.128049 -240.124523) (xy 115.176933 -240.138683) (xy 115.222912 -240.1605) (xy 115.264796 -240.18941)
			(xy 115.3015 -240.224665) (xy 115.332073 -240.265351) (xy 115.355724 -240.310414) (xy 115.37184 -240.358688)
			(xy 115.380004 -240.408922) (xy 115.380516 -240.434368) (xy 115.380013 -240.459357) (xy 115.68733 -240.459357)
			(xy 115.68733 -240.409379) (xy 115.695149 -240.360016) (xy 115.710593 -240.312484) (xy 115.733283 -240.267952)
			(xy 115.762659 -240.227519) (xy 115.797999 -240.192179) (xy 115.838432 -240.162803) (xy 115.882964 -240.140113)
			(xy 115.930496 -240.124669) (xy 115.979859 -240.11685) (xy 116.029837 -240.11685) (xy 116.0792 -240.124669)
			(xy 116.126732 -240.140113) (xy 116.171264 -240.162803) (xy 116.211697 -240.192179) (xy 116.247037 -240.227519)
			(xy 116.276413 -240.267952) (xy 116.299103 -240.312484) (xy 116.314547 -240.360016) (xy 116.322366 -240.409379)
			(xy 116.322856 -240.434368) (xy 116.322366 -240.459357) (xy 116.62713 -240.459357) (xy 116.62713 -240.409379)
			(xy 116.634949 -240.360016) (xy 116.650393 -240.312484) (xy 116.673083 -240.267952) (xy 116.702459 -240.227519)
			(xy 116.737799 -240.192179) (xy 116.778232 -240.162803) (xy 116.822764 -240.140113) (xy 116.870296 -240.124669)
			(xy 116.919659 -240.11685) (xy 116.969637 -240.11685) (xy 117.019 -240.124669) (xy 117.066532 -240.140113)
			(xy 117.111064 -240.162803) (xy 117.151497 -240.192179) (xy 117.186837 -240.227519) (xy 117.216213 -240.267952)
			(xy 117.238903 -240.312484) (xy 117.254347 -240.360016) (xy 117.262166 -240.409379) (xy 117.262656 -240.434368)
			(xy 117.262166 -240.459357) (xy 117.567184 -240.459357) (xy 117.567184 -240.409379) (xy 117.575003 -240.360016)
			(xy 117.590447 -240.312484) (xy 117.613137 -240.267952) (xy 117.642513 -240.227519) (xy 117.677853 -240.192179)
			(xy 117.718286 -240.162803) (xy 117.762818 -240.140113) (xy 117.81035 -240.124669) (xy 117.859713 -240.11685)
			(xy 117.909691 -240.11685) (xy 117.959054 -240.124669) (xy 118.006586 -240.140113) (xy 118.051118 -240.162803)
			(xy 118.091551 -240.192179) (xy 118.126891 -240.227519) (xy 118.156267 -240.267952) (xy 118.178957 -240.312484)
			(xy 118.194401 -240.360016) (xy 118.20222 -240.409379) (xy 118.20271 -240.434368) (xy 118.20222 -240.459357)
			(xy 118.507238 -240.459357) (xy 118.507238 -240.409379) (xy 118.515057 -240.360016) (xy 118.530501 -240.312484)
			(xy 118.553191 -240.267952) (xy 118.582567 -240.227519) (xy 118.617907 -240.192179) (xy 118.65834 -240.162803)
			(xy 118.702872 -240.140113) (xy 118.750404 -240.124669) (xy 118.799767 -240.11685) (xy 118.849745 -240.11685)
			(xy 118.899108 -240.124669) (xy 118.94664 -240.140113) (xy 118.991172 -240.162803) (xy 119.031605 -240.192179)
			(xy 119.066945 -240.227519) (xy 119.096321 -240.267952) (xy 119.119011 -240.312484) (xy 119.134455 -240.360016)
			(xy 119.142274 -240.409379) (xy 119.142764 -240.434368) (xy 119.142274 -240.459357) (xy 119.447292 -240.459357)
			(xy 119.447292 -240.409379) (xy 119.455111 -240.360016) (xy 119.470555 -240.312484) (xy 119.493245 -240.267952)
			(xy 119.522621 -240.227519) (xy 119.557961 -240.192179) (xy 119.598394 -240.162803) (xy 119.642926 -240.140113)
			(xy 119.690458 -240.124669) (xy 119.739821 -240.11685) (xy 119.789799 -240.11685) (xy 119.839162 -240.124669)
			(xy 119.886694 -240.140113) (xy 119.931226 -240.162803) (xy 119.971659 -240.192179) (xy 120.006999 -240.227519)
			(xy 120.036375 -240.267952) (xy 120.059065 -240.312484) (xy 120.074509 -240.360016) (xy 120.082328 -240.409379)
			(xy 120.082818 -240.434368) (xy 120.082328 -240.459357) (xy 120.387092 -240.459357) (xy 120.387092 -240.409379)
			(xy 120.394911 -240.360016) (xy 120.410355 -240.312484) (xy 120.433045 -240.267952) (xy 120.462421 -240.227519)
			(xy 120.497761 -240.192179) (xy 120.538194 -240.162803) (xy 120.582726 -240.140113) (xy 120.630258 -240.124669)
			(xy 120.679621 -240.11685) (xy 120.729599 -240.11685) (xy 120.778962 -240.124669) (xy 120.826494 -240.140113)
			(xy 120.871026 -240.162803) (xy 120.911459 -240.192179) (xy 120.946799 -240.227519) (xy 120.976175 -240.267952)
			(xy 120.998865 -240.312484) (xy 121.014309 -240.360016) (xy 121.022128 -240.409379) (xy 121.022618 -240.434368)
			(xy 121.022128 -240.459357) (xy 121.327146 -240.459357) (xy 121.327146 -240.409379) (xy 121.334965 -240.360016)
			(xy 121.350409 -240.312484) (xy 121.373099 -240.267952) (xy 121.402475 -240.227519) (xy 121.437815 -240.192179)
			(xy 121.478248 -240.162803) (xy 121.52278 -240.140113) (xy 121.570312 -240.124669) (xy 121.619675 -240.11685)
			(xy 121.669653 -240.11685) (xy 121.719016 -240.124669) (xy 121.766548 -240.140113) (xy 121.81108 -240.162803)
			(xy 121.851513 -240.192179) (xy 121.886853 -240.227519) (xy 121.916229 -240.267952) (xy 121.938919 -240.312484)
			(xy 121.954363 -240.360016) (xy 121.962182 -240.409379) (xy 121.962672 -240.434368) (xy 121.962182 -240.459357)
			(xy 122.2672 -240.459357) (xy 122.2672 -240.409379) (xy 122.275019 -240.360016) (xy 122.290463 -240.312484)
			(xy 122.313153 -240.267952) (xy 122.342529 -240.227519) (xy 122.377869 -240.192179) (xy 122.418302 -240.162803)
			(xy 122.462834 -240.140113) (xy 122.510366 -240.124669) (xy 122.559729 -240.11685) (xy 122.609707 -240.11685)
			(xy 122.65907 -240.124669) (xy 122.706602 -240.140113) (xy 122.751134 -240.162803) (xy 122.791567 -240.192179)
			(xy 122.826907 -240.227519) (xy 122.856283 -240.267952) (xy 122.878973 -240.312484) (xy 122.894417 -240.360016)
			(xy 122.902236 -240.409379) (xy 122.902726 -240.434368) (xy 122.902236 -240.459357) (xy 123.207254 -240.459357)
			(xy 123.207254 -240.409379) (xy 123.215073 -240.360016) (xy 123.230517 -240.312484) (xy 123.253207 -240.267952)
			(xy 123.282583 -240.227519) (xy 123.317923 -240.192179) (xy 123.358356 -240.162803) (xy 123.402888 -240.140113)
			(xy 123.45042 -240.124669) (xy 123.499783 -240.11685) (xy 123.549761 -240.11685) (xy 123.599124 -240.124669)
			(xy 123.646656 -240.140113) (xy 123.691188 -240.162803) (xy 123.731621 -240.192179) (xy 123.766961 -240.227519)
			(xy 123.796337 -240.267952) (xy 123.819027 -240.312484) (xy 123.834471 -240.360016) (xy 123.84229 -240.409379)
			(xy 123.84278 -240.434368) (xy 123.84229 -240.459357) (xy 124.147308 -240.459357) (xy 124.147308 -240.409379)
			(xy 124.155127 -240.360016) (xy 124.170571 -240.312484) (xy 124.193261 -240.267952) (xy 124.222637 -240.227519)
			(xy 124.257977 -240.192179) (xy 124.29841 -240.162803) (xy 124.342942 -240.140113) (xy 124.390474 -240.124669)
			(xy 124.439837 -240.11685) (xy 124.489815 -240.11685) (xy 124.539178 -240.124669) (xy 124.58671 -240.140113)
			(xy 124.631242 -240.162803) (xy 124.671675 -240.192179) (xy 124.707015 -240.227519) (xy 124.736391 -240.267952)
			(xy 124.759081 -240.312484) (xy 124.774525 -240.360016) (xy 124.782344 -240.409379) (xy 124.782834 -240.434368)
			(xy 124.782344 -240.459357) (xy 125.087108 -240.459357) (xy 125.087108 -240.409379) (xy 125.094927 -240.360016)
			(xy 125.110371 -240.312484) (xy 125.133061 -240.267952) (xy 125.162437 -240.227519) (xy 125.197777 -240.192179)
			(xy 125.23821 -240.162803) (xy 125.282742 -240.140113) (xy 125.330274 -240.124669) (xy 125.379637 -240.11685)
			(xy 125.429615 -240.11685) (xy 125.478978 -240.124669) (xy 125.52651 -240.140113) (xy 125.571042 -240.162803)
			(xy 125.611475 -240.192179) (xy 125.646815 -240.227519) (xy 125.676191 -240.267952) (xy 125.698881 -240.312484)
			(xy 125.714325 -240.360016) (xy 125.722144 -240.409379) (xy 125.722634 -240.434368) (xy 125.722144 -240.459357)
			(xy 125.714325 -240.50872) (xy 125.698881 -240.556252) (xy 125.676191 -240.600784) (xy 125.646815 -240.641217)
			(xy 125.611475 -240.676557) (xy 125.571042 -240.705933) (xy 125.52651 -240.728623) (xy 125.478978 -240.744067)
			(xy 125.429615 -240.751886) (xy 125.379637 -240.751886) (xy 125.330274 -240.744067) (xy 125.282742 -240.728623)
			(xy 125.23821 -240.705933) (xy 125.197777 -240.676557) (xy 125.162437 -240.641217) (xy 125.133061 -240.600784)
			(xy 125.110371 -240.556252) (xy 125.094927 -240.50872) (xy 125.087108 -240.459357) (xy 124.782344 -240.459357)
			(xy 124.774525 -240.50872) (xy 124.759081 -240.556252) (xy 124.736391 -240.600784) (xy 124.707015 -240.641217)
			(xy 124.671675 -240.676557) (xy 124.631242 -240.705933) (xy 124.58671 -240.728623) (xy 124.539178 -240.744067)
			(xy 124.489815 -240.751886) (xy 124.439837 -240.751886) (xy 124.390474 -240.744067) (xy 124.342942 -240.728623)
			(xy 124.29841 -240.705933) (xy 124.257977 -240.676557) (xy 124.222637 -240.641217) (xy 124.193261 -240.600784)
			(xy 124.170571 -240.556252) (xy 124.155127 -240.50872) (xy 124.147308 -240.459357) (xy 123.84229 -240.459357)
			(xy 123.834471 -240.50872) (xy 123.819027 -240.556252) (xy 123.796337 -240.600784) (xy 123.766961 -240.641217)
			(xy 123.731621 -240.676557) (xy 123.691188 -240.705933) (xy 123.646656 -240.728623) (xy 123.599124 -240.744067)
			(xy 123.549761 -240.751886) (xy 123.499783 -240.751886) (xy 123.45042 -240.744067) (xy 123.402888 -240.728623)
			(xy 123.358356 -240.705933) (xy 123.317923 -240.676557) (xy 123.282583 -240.641217) (xy 123.253207 -240.600784)
			(xy 123.230517 -240.556252) (xy 123.215073 -240.50872) (xy 123.207254 -240.459357) (xy 122.902236 -240.459357)
			(xy 122.894417 -240.50872) (xy 122.878973 -240.556252) (xy 122.856283 -240.600784) (xy 122.826907 -240.641217)
			(xy 122.791567 -240.676557) (xy 122.751134 -240.705933) (xy 122.706602 -240.728623) (xy 122.65907 -240.744067)
			(xy 122.609707 -240.751886) (xy 122.559729 -240.751886) (xy 122.510366 -240.744067) (xy 122.462834 -240.728623)
			(xy 122.418302 -240.705933) (xy 122.377869 -240.676557) (xy 122.342529 -240.641217) (xy 122.313153 -240.600784)
			(xy 122.290463 -240.556252) (xy 122.275019 -240.50872) (xy 122.2672 -240.459357) (xy 121.962182 -240.459357)
			(xy 121.954363 -240.50872) (xy 121.938919 -240.556252) (xy 121.916229 -240.600784) (xy 121.886853 -240.641217)
			(xy 121.851513 -240.676557) (xy 121.81108 -240.705933) (xy 121.766548 -240.728623) (xy 121.719016 -240.744067)
			(xy 121.669653 -240.751886) (xy 121.619675 -240.751886) (xy 121.570312 -240.744067) (xy 121.52278 -240.728623)
			(xy 121.478248 -240.705933) (xy 121.437815 -240.676557) (xy 121.402475 -240.641217) (xy 121.373099 -240.600784)
			(xy 121.350409 -240.556252) (xy 121.334965 -240.50872) (xy 121.327146 -240.459357) (xy 121.022128 -240.459357)
			(xy 121.014309 -240.50872) (xy 120.998865 -240.556252) (xy 120.976175 -240.600784) (xy 120.946799 -240.641217)
			(xy 120.911459 -240.676557) (xy 120.871026 -240.705933) (xy 120.826494 -240.728623) (xy 120.778962 -240.744067)
			(xy 120.729599 -240.751886) (xy 120.679621 -240.751886) (xy 120.630258 -240.744067) (xy 120.582726 -240.728623)
			(xy 120.538194 -240.705933) (xy 120.497761 -240.676557) (xy 120.462421 -240.641217) (xy 120.433045 -240.600784)
			(xy 120.410355 -240.556252) (xy 120.394911 -240.50872) (xy 120.387092 -240.459357) (xy 120.082328 -240.459357)
			(xy 120.074509 -240.50872) (xy 120.059065 -240.556252) (xy 120.036375 -240.600784) (xy 120.006999 -240.641217)
			(xy 119.971659 -240.676557) (xy 119.931226 -240.705933) (xy 119.886694 -240.728623) (xy 119.839162 -240.744067)
			(xy 119.789799 -240.751886) (xy 119.739821 -240.751886) (xy 119.690458 -240.744067) (xy 119.642926 -240.728623)
			(xy 119.598394 -240.705933) (xy 119.557961 -240.676557) (xy 119.522621 -240.641217) (xy 119.493245 -240.600784)
			(xy 119.470555 -240.556252) (xy 119.455111 -240.50872) (xy 119.447292 -240.459357) (xy 119.142274 -240.459357)
			(xy 119.134455 -240.50872) (xy 119.119011 -240.556252) (xy 119.096321 -240.600784) (xy 119.066945 -240.641217)
			(xy 119.031605 -240.676557) (xy 118.991172 -240.705933) (xy 118.94664 -240.728623) (xy 118.899108 -240.744067)
			(xy 118.849745 -240.751886) (xy 118.799767 -240.751886) (xy 118.750404 -240.744067) (xy 118.702872 -240.728623)
			(xy 118.65834 -240.705933) (xy 118.617907 -240.676557) (xy 118.582567 -240.641217) (xy 118.553191 -240.600784)
			(xy 118.530501 -240.556252) (xy 118.515057 -240.50872) (xy 118.507238 -240.459357) (xy 118.20222 -240.459357)
			(xy 118.194401 -240.50872) (xy 118.178957 -240.556252) (xy 118.156267 -240.600784) (xy 118.126891 -240.641217)
			(xy 118.091551 -240.676557) (xy 118.051118 -240.705933) (xy 118.006586 -240.728623) (xy 117.959054 -240.744067)
			(xy 117.909691 -240.751886) (xy 117.859713 -240.751886) (xy 117.81035 -240.744067) (xy 117.762818 -240.728623)
			(xy 117.718286 -240.705933) (xy 117.677853 -240.676557) (xy 117.642513 -240.641217) (xy 117.613137 -240.600784)
			(xy 117.590447 -240.556252) (xy 117.575003 -240.50872) (xy 117.567184 -240.459357) (xy 117.262166 -240.459357)
			(xy 117.254347 -240.50872) (xy 117.238903 -240.556252) (xy 117.216213 -240.600784) (xy 117.186837 -240.641217)
			(xy 117.151497 -240.676557) (xy 117.111064 -240.705933) (xy 117.066532 -240.728623) (xy 117.019 -240.744067)
			(xy 116.969637 -240.751886) (xy 116.919659 -240.751886) (xy 116.870296 -240.744067) (xy 116.822764 -240.728623)
			(xy 116.778232 -240.705933) (xy 116.737799 -240.676557) (xy 116.702459 -240.641217) (xy 116.673083 -240.600784)
			(xy 116.650393 -240.556252) (xy 116.634949 -240.50872) (xy 116.62713 -240.459357) (xy 116.322366 -240.459357)
			(xy 116.314547 -240.50872) (xy 116.299103 -240.556252) (xy 116.276413 -240.600784) (xy 116.247037 -240.641217)
			(xy 116.211697 -240.676557) (xy 116.171264 -240.705933) (xy 116.126732 -240.728623) (xy 116.0792 -240.744067)
			(xy 116.029837 -240.751886) (xy 115.979859 -240.751886) (xy 115.930496 -240.744067) (xy 115.882964 -240.728623)
			(xy 115.838432 -240.705933) (xy 115.797999 -240.676557) (xy 115.762659 -240.641217) (xy 115.733283 -240.600784)
			(xy 115.710593 -240.556252) (xy 115.695149 -240.50872) (xy 115.68733 -240.459357) (xy 115.380013 -240.459357)
			(xy 115.380004 -240.459814) (xy 115.37184 -240.510048) (xy 115.355724 -240.558322) (xy 115.332073 -240.603385)
			(xy 115.3015 -240.644071) (xy 115.264796 -240.679326) (xy 115.222912 -240.708236) (xy 115.176933 -240.730053)
			(xy 115.128049 -240.744213) (xy 115.077528 -240.750347) (xy 115.026676 -240.748298) (xy 114.976812 -240.738118)
			(xy 114.929226 -240.720071) (xy 114.885152 -240.694625) (xy 114.84573 -240.662438) (xy 114.811982 -240.624344)
			(xy 114.784781 -240.58133) (xy 114.764833 -240.53451) (xy 114.752654 -240.485096) (xy 114.748559 -240.434368)
			(xy 114.440462 -240.434368) (xy 114.43995 -240.459814) (xy 114.431786 -240.510048) (xy 114.41567 -240.558322)
			(xy 114.392019 -240.603385) (xy 114.361446 -240.644071) (xy 114.324742 -240.679326) (xy 114.282858 -240.708236)
			(xy 114.236879 -240.730053) (xy 114.187995 -240.744213) (xy 114.137474 -240.750347) (xy 114.086622 -240.748298)
			(xy 114.036758 -240.738118) (xy 113.989172 -240.720071) (xy 113.945098 -240.694625) (xy 113.905676 -240.662438)
			(xy 113.871928 -240.624344) (xy 113.844727 -240.58133) (xy 113.824779 -240.53451) (xy 113.8126 -240.485096)
			(xy 113.808505 -240.434368) (xy 113.502694 -240.434368) (xy 113.502204 -240.459357) (xy 113.494385 -240.50872)
			(xy 113.478941 -240.556252) (xy 113.456251 -240.600784) (xy 113.426875 -240.641217) (xy 113.391535 -240.676557)
			(xy 113.351102 -240.705933) (xy 113.30657 -240.728623) (xy 113.259038 -240.744067) (xy 113.209675 -240.751886)
			(xy 113.159697 -240.751886) (xy 113.110334 -240.744067) (xy 113.062802 -240.728623) (xy 113.01827 -240.705933)
			(xy 112.977837 -240.676557) (xy 112.942497 -240.641217) (xy 112.913121 -240.600784) (xy 112.890431 -240.556252)
			(xy 112.874987 -240.50872) (xy 112.867168 -240.459357) (xy 110.688646 -240.459357) (xy 110.680827 -240.50872)
			(xy 110.665383 -240.556252) (xy 110.642693 -240.600784) (xy 110.613317 -240.641217) (xy 110.577977 -240.676557)
			(xy 110.537544 -240.705933) (xy 110.493012 -240.728623) (xy 110.44548 -240.744067) (xy 110.396117 -240.751886)
			(xy 110.346139 -240.751886) (xy 110.296776 -240.744067) (xy 110.249244 -240.728623) (xy 110.204712 -240.705933)
			(xy 110.164279 -240.676557) (xy 110.128939 -240.641217) (xy 110.099563 -240.600784) (xy 110.076873 -240.556252)
			(xy 110.061429 -240.50872) (xy 110.05361 -240.459357) (xy 109.746293 -240.459357) (xy 109.746284 -240.459814)
			(xy 109.73812 -240.510048) (xy 109.722004 -240.558322) (xy 109.698353 -240.603385) (xy 109.66778 -240.644071)
			(xy 109.631076 -240.679326) (xy 109.589192 -240.708236) (xy 109.543213 -240.730053) (xy 109.494329 -240.744213)
			(xy 109.443808 -240.750347) (xy 109.392956 -240.748298) (xy 109.343092 -240.738118) (xy 109.295506 -240.720071)
			(xy 109.251432 -240.694625) (xy 109.21201 -240.662438) (xy 109.178262 -240.624344) (xy 109.151061 -240.58133)
			(xy 109.131113 -240.53451) (xy 109.118934 -240.485096) (xy 109.114839 -240.434368) (xy 108.806742 -240.434368)
			(xy 108.80623 -240.459814) (xy 108.798066 -240.510048) (xy 108.78195 -240.558322) (xy 108.758299 -240.603385)
			(xy 108.727726 -240.644071) (xy 108.691022 -240.679326) (xy 108.649138 -240.708236) (xy 108.603159 -240.730053)
			(xy 108.554275 -240.744213) (xy 108.503754 -240.750347) (xy 108.452902 -240.748298) (xy 108.403038 -240.738118)
			(xy 108.355452 -240.720071) (xy 108.311378 -240.694625) (xy 108.271956 -240.662438) (xy 108.238208 -240.624344)
			(xy 108.211007 -240.58133) (xy 108.191059 -240.53451) (xy 108.17888 -240.485096) (xy 108.174785 -240.434368)
			(xy 107.868974 -240.434368) (xy 107.868484 -240.459357) (xy 107.860665 -240.50872) (xy 107.845221 -240.556252)
			(xy 107.822531 -240.600784) (xy 107.793155 -240.641217) (xy 107.757815 -240.676557) (xy 107.717382 -240.705933)
			(xy 107.67285 -240.728623) (xy 107.625318 -240.744067) (xy 107.575955 -240.751886) (xy 107.525977 -240.751886)
			(xy 107.476614 -240.744067) (xy 107.429082 -240.728623) (xy 107.38455 -240.705933) (xy 107.344117 -240.676557)
			(xy 107.308777 -240.641217) (xy 107.279401 -240.600784) (xy 107.256711 -240.556252) (xy 107.241267 -240.50872)
			(xy 107.233448 -240.459357) (xy 106.928684 -240.459357) (xy 106.920865 -240.50872) (xy 106.905421 -240.556252)
			(xy 106.882731 -240.600784) (xy 106.853355 -240.641217) (xy 106.818015 -240.676557) (xy 106.777582 -240.705933)
			(xy 106.73305 -240.728623) (xy 106.685518 -240.744067) (xy 106.636155 -240.751886) (xy 106.586177 -240.751886)
			(xy 106.536814 -240.744067) (xy 106.489282 -240.728623) (xy 106.44475 -240.705933) (xy 106.404317 -240.676557)
			(xy 106.368977 -240.641217) (xy 106.339601 -240.600784) (xy 106.316911 -240.556252) (xy 106.301467 -240.50872)
			(xy 106.293648 -240.459357) (xy 105.98863 -240.459357) (xy 105.980811 -240.50872) (xy 105.965367 -240.556252)
			(xy 105.942677 -240.600784) (xy 105.913301 -240.641217) (xy 105.877961 -240.676557) (xy 105.837528 -240.705933)
			(xy 105.792996 -240.728623) (xy 105.745464 -240.744067) (xy 105.696101 -240.751886) (xy 105.646123 -240.751886)
			(xy 105.59676 -240.744067) (xy 105.549228 -240.728623) (xy 105.504696 -240.705933) (xy 105.464263 -240.676557)
			(xy 105.428923 -240.641217) (xy 105.399547 -240.600784) (xy 105.376857 -240.556252) (xy 105.361413 -240.50872)
			(xy 105.353594 -240.459357) (xy 105.048576 -240.459357) (xy 105.040757 -240.50872) (xy 105.025313 -240.556252)
			(xy 105.002623 -240.600784) (xy 104.973247 -240.641217) (xy 104.937907 -240.676557) (xy 104.897474 -240.705933)
			(xy 104.852942 -240.728623) (xy 104.80541 -240.744067) (xy 104.756047 -240.751886) (xy 104.706069 -240.751886)
			(xy 104.656706 -240.744067) (xy 104.609174 -240.728623) (xy 104.564642 -240.705933) (xy 104.524209 -240.676557)
			(xy 104.488869 -240.641217) (xy 104.459493 -240.600784) (xy 104.436803 -240.556252) (xy 104.421359 -240.50872)
			(xy 104.41354 -240.459357) (xy 104.108522 -240.459357) (xy 104.100703 -240.50872) (xy 104.085259 -240.556252)
			(xy 104.062569 -240.600784) (xy 104.033193 -240.641217) (xy 103.997853 -240.676557) (xy 103.95742 -240.705933)
			(xy 103.912888 -240.728623) (xy 103.865356 -240.744067) (xy 103.815993 -240.751886) (xy 103.766015 -240.751886)
			(xy 103.716652 -240.744067) (xy 103.66912 -240.728623) (xy 103.624588 -240.705933) (xy 103.584155 -240.676557)
			(xy 103.548815 -240.641217) (xy 103.519439 -240.600784) (xy 103.496749 -240.556252) (xy 103.481305 -240.50872)
			(xy 103.473486 -240.459357) (xy 103.168468 -240.459357) (xy 103.160649 -240.50872) (xy 103.145205 -240.556252)
			(xy 103.122515 -240.600784) (xy 103.093139 -240.641217) (xy 103.057799 -240.676557) (xy 103.017366 -240.705933)
			(xy 102.972834 -240.728623) (xy 102.925302 -240.744067) (xy 102.875939 -240.751886) (xy 102.825961 -240.751886)
			(xy 102.776598 -240.744067) (xy 102.729066 -240.728623) (xy 102.684534 -240.705933) (xy 102.644101 -240.676557)
			(xy 102.608761 -240.641217) (xy 102.579385 -240.600784) (xy 102.556695 -240.556252) (xy 102.541251 -240.50872)
			(xy 102.533432 -240.459357) (xy 102.228668 -240.459357) (xy 102.220849 -240.50872) (xy 102.205405 -240.556252)
			(xy 102.182715 -240.600784) (xy 102.153339 -240.641217) (xy 102.117999 -240.676557) (xy 102.077566 -240.705933)
			(xy 102.033034 -240.728623) (xy 101.985502 -240.744067) (xy 101.936139 -240.751886) (xy 101.886161 -240.751886)
			(xy 101.836798 -240.744067) (xy 101.789266 -240.728623) (xy 101.744734 -240.705933) (xy 101.704301 -240.676557)
			(xy 101.668961 -240.641217) (xy 101.639585 -240.600784) (xy 101.616895 -240.556252) (xy 101.601451 -240.50872)
			(xy 101.593632 -240.459357) (xy 101.288614 -240.459357) (xy 101.280795 -240.50872) (xy 101.265351 -240.556252)
			(xy 101.242661 -240.600784) (xy 101.213285 -240.641217) (xy 101.177945 -240.676557) (xy 101.137512 -240.705933)
			(xy 101.09298 -240.728623) (xy 101.045448 -240.744067) (xy 100.996085 -240.751886) (xy 100.946107 -240.751886)
			(xy 100.896744 -240.744067) (xy 100.849212 -240.728623) (xy 100.80468 -240.705933) (xy 100.764247 -240.676557)
			(xy 100.728907 -240.641217) (xy 100.699531 -240.600784) (xy 100.676841 -240.556252) (xy 100.661397 -240.50872)
			(xy 100.653578 -240.459357) (xy 100.34856 -240.459357) (xy 100.340741 -240.50872) (xy 100.325297 -240.556252)
			(xy 100.302607 -240.600784) (xy 100.273231 -240.641217) (xy 100.237891 -240.676557) (xy 100.197458 -240.705933)
			(xy 100.152926 -240.728623) (xy 100.105394 -240.744067) (xy 100.056031 -240.751886) (xy 100.006053 -240.751886)
			(xy 99.95669 -240.744067) (xy 99.909158 -240.728623) (xy 99.864626 -240.705933) (xy 99.824193 -240.676557)
			(xy 99.788853 -240.641217) (xy 99.759477 -240.600784) (xy 99.736787 -240.556252) (xy 99.721343 -240.50872)
			(xy 99.713524 -240.459357) (xy 99.408506 -240.459357) (xy 99.400687 -240.50872) (xy 99.385243 -240.556252)
			(xy 99.362553 -240.600784) (xy 99.333177 -240.641217) (xy 99.297837 -240.676557) (xy 99.257404 -240.705933)
			(xy 99.212872 -240.728623) (xy 99.16534 -240.744067) (xy 99.115977 -240.751886) (xy 99.065999 -240.751886)
			(xy 99.016636 -240.744067) (xy 98.969104 -240.728623) (xy 98.924572 -240.705933) (xy 98.884139 -240.676557)
			(xy 98.848799 -240.641217) (xy 98.819423 -240.600784) (xy 98.796733 -240.556252) (xy 98.781289 -240.50872)
			(xy 98.77347 -240.459357) (xy 98.468452 -240.459357) (xy 98.460633 -240.50872) (xy 98.445189 -240.556252)
			(xy 98.422499 -240.600784) (xy 98.393123 -240.641217) (xy 98.357783 -240.676557) (xy 98.31735 -240.705933)
			(xy 98.272818 -240.728623) (xy 98.225286 -240.744067) (xy 98.175923 -240.751886) (xy 98.125945 -240.751886)
			(xy 98.076582 -240.744067) (xy 98.02905 -240.728623) (xy 97.984518 -240.705933) (xy 97.944085 -240.676557)
			(xy 97.908745 -240.641217) (xy 97.879369 -240.600784) (xy 97.856679 -240.556252) (xy 97.841235 -240.50872)
			(xy 97.833416 -240.459357) (xy 97.528653 -240.459357) (xy 97.520849 -240.508692) (xy 97.505423 -240.556209)
			(xy 97.482758 -240.600729) (xy 97.453411 -240.641159) (xy 97.418103 -240.676502) (xy 97.377703 -240.705891)
			(xy 97.333205 -240.728601) (xy 97.285703 -240.744074) (xy 97.236367 -240.75193) (xy 97.211388 -240.752376)
			(xy 97.211134 -240.752376) (xy 97.201776 -240.752285) (xy 97.183095 -240.751142) (xy 97.173796 -240.75009)
			(xy 97.171002 -240.749836) (xy 97.170494 -240.749836) (xy 97.160588 -240.748566) (xy 97.148396 -240.752122)
			(xy 97.137474 -240.756186) (xy 97.073212 -240.812574) (xy 97.0664 -240.81967) (xy 97.058288 -240.837571)
			(xy 97.057464 -240.847372) (xy 97.057464 -241.206782) (xy 97.057718 -241.211354) (xy 97.058988 -241.241834)
			(xy 97.058988 -241.244374) (xy 97.364799 -241.244374) (xy 97.368894 -241.193646) (xy 97.381073 -241.144232)
			(xy 97.401021 -241.097412) (xy 97.428222 -241.054398) (xy 97.46197 -241.016304) (xy 97.501392 -240.984117)
			(xy 97.545466 -240.958671) (xy 97.593052 -240.940624) (xy 97.642916 -240.930444) (xy 97.693768 -240.928395)
			(xy 97.744289 -240.934529) (xy 97.793173 -240.948689) (xy 97.839152 -240.970506) (xy 97.881036 -240.999416)
			(xy 97.91774 -241.034671) (xy 97.948313 -241.075357) (xy 97.971964 -241.12042) (xy 97.98808 -241.168694)
			(xy 97.996244 -241.218928) (xy 97.996756 -241.244374) (xy 98.304853 -241.244374) (xy 98.308948 -241.193646)
			(xy 98.321127 -241.144232) (xy 98.341075 -241.097412) (xy 98.368276 -241.054398) (xy 98.402024 -241.016304)
			(xy 98.441446 -240.984117) (xy 98.48552 -240.958671) (xy 98.533106 -240.940624) (xy 98.58297 -240.930444)
			(xy 98.633822 -240.928395) (xy 98.684343 -240.934529) (xy 98.733227 -240.948689) (xy 98.779206 -240.970506)
			(xy 98.82109 -240.999416) (xy 98.857794 -241.034671) (xy 98.888367 -241.075357) (xy 98.912018 -241.12042)
			(xy 98.928134 -241.168694) (xy 98.936298 -241.218928) (xy 98.93681 -241.244374) (xy 98.936307 -241.269363)
			(xy 99.243624 -241.269363) (xy 99.243624 -241.219385) (xy 99.251443 -241.170022) (xy 99.266887 -241.12249)
			(xy 99.289577 -241.077958) (xy 99.318953 -241.037525) (xy 99.354293 -241.002185) (xy 99.394726 -240.972809)
			(xy 99.439258 -240.950119) (xy 99.48679 -240.934675) (xy 99.536153 -240.926856) (xy 99.586131 -240.926856)
			(xy 99.635494 -240.934675) (xy 99.683026 -240.950119) (xy 99.727558 -240.972809) (xy 99.767991 -241.002185)
			(xy 99.803331 -241.037525) (xy 99.832707 -241.077958) (xy 99.855397 -241.12249) (xy 99.870841 -241.170022)
			(xy 99.87866 -241.219385) (xy 99.87915 -241.244374) (xy 100.184707 -241.244374) (xy 100.188802 -241.193646)
			(xy 100.200981 -241.144232) (xy 100.220929 -241.097412) (xy 100.24813 -241.054398) (xy 100.281878 -241.016304)
			(xy 100.3213 -240.984117) (xy 100.365374 -240.958671) (xy 100.41296 -240.940624) (xy 100.462824 -240.930444)
			(xy 100.513676 -240.928395) (xy 100.564197 -240.934529) (xy 100.613081 -240.948689) (xy 100.65906 -240.970506)
			(xy 100.700944 -240.999416) (xy 100.737648 -241.034671) (xy 100.768221 -241.075357) (xy 100.791872 -241.12042)
			(xy 100.807988 -241.168694) (xy 100.816152 -241.218928) (xy 100.816664 -241.244374) (xy 101.124761 -241.244374)
			(xy 101.128856 -241.193646) (xy 101.141035 -241.144232) (xy 101.160983 -241.097412) (xy 101.188184 -241.054398)
			(xy 101.221932 -241.016304) (xy 101.261354 -240.984117) (xy 101.305428 -240.958671) (xy 101.353014 -240.940624)
			(xy 101.402878 -240.930444) (xy 101.45373 -240.928395) (xy 101.504251 -240.934529) (xy 101.553135 -240.948689)
			(xy 101.599114 -240.970506) (xy 101.640998 -240.999416) (xy 101.677702 -241.034671) (xy 101.708275 -241.075357)
			(xy 101.731926 -241.12042) (xy 101.748042 -241.168694) (xy 101.756206 -241.218928) (xy 101.756718 -241.244374)
			(xy 101.756215 -241.269363) (xy 102.063532 -241.269363) (xy 102.063532 -241.219385) (xy 102.071351 -241.170022)
			(xy 102.086795 -241.12249) (xy 102.109485 -241.077958) (xy 102.138861 -241.037525) (xy 102.174201 -241.002185)
			(xy 102.214634 -240.972809) (xy 102.259166 -240.950119) (xy 102.306698 -240.934675) (xy 102.356061 -240.926856)
			(xy 102.406039 -240.926856) (xy 102.455402 -240.934675) (xy 102.502934 -240.950119) (xy 102.547466 -240.972809)
			(xy 102.587899 -241.002185) (xy 102.623239 -241.037525) (xy 102.652615 -241.077958) (xy 102.675305 -241.12249)
			(xy 102.690749 -241.170022) (xy 102.698568 -241.219385) (xy 102.699058 -241.244374) (xy 103.004869 -241.244374)
			(xy 103.008964 -241.193646) (xy 103.021143 -241.144232) (xy 103.041091 -241.097412) (xy 103.068292 -241.054398)
			(xy 103.10204 -241.016304) (xy 103.141462 -240.984117) (xy 103.185536 -240.958671) (xy 103.233122 -240.940624)
			(xy 103.282986 -240.930444) (xy 103.333838 -240.928395) (xy 103.384359 -240.934529) (xy 103.433243 -240.948689)
			(xy 103.479222 -240.970506) (xy 103.521106 -240.999416) (xy 103.55781 -241.034671) (xy 103.588383 -241.075357)
			(xy 103.612034 -241.12042) (xy 103.62815 -241.168694) (xy 103.636314 -241.218928) (xy 103.636826 -241.244374)
			(xy 103.944923 -241.244374) (xy 103.949018 -241.193646) (xy 103.961197 -241.144232) (xy 103.981145 -241.097412)
			(xy 104.008346 -241.054398) (xy 104.042094 -241.016304) (xy 104.081516 -240.984117) (xy 104.12559 -240.958671)
			(xy 104.173176 -240.940624) (xy 104.22304 -240.930444) (xy 104.273892 -240.928395) (xy 104.324413 -240.934529)
			(xy 104.373297 -240.948689) (xy 104.419276 -240.970506) (xy 104.46116 -240.999416) (xy 104.497864 -241.034671)
			(xy 104.528437 -241.075357) (xy 104.552088 -241.12042) (xy 104.568204 -241.168694) (xy 104.576368 -241.218928)
			(xy 104.57688 -241.244374) (xy 104.576377 -241.269363) (xy 104.88344 -241.269363) (xy 104.88344 -241.219385)
			(xy 104.891259 -241.170022) (xy 104.906703 -241.12249) (xy 104.929393 -241.077958) (xy 104.958769 -241.037525)
			(xy 104.994109 -241.002185) (xy 105.034542 -240.972809) (xy 105.079074 -240.950119) (xy 105.126606 -240.934675)
			(xy 105.175969 -240.926856) (xy 105.225947 -240.926856) (xy 105.27531 -240.934675) (xy 105.322842 -240.950119)
			(xy 105.367374 -240.972809) (xy 105.407807 -241.002185) (xy 105.443147 -241.037525) (xy 105.472523 -241.077958)
			(xy 105.495213 -241.12249) (xy 105.510657 -241.170022) (xy 105.518476 -241.219385) (xy 105.518966 -241.244374)
			(xy 105.824777 -241.244374) (xy 105.828872 -241.193646) (xy 105.841051 -241.144232) (xy 105.860999 -241.097412)
			(xy 105.8882 -241.054398) (xy 105.921948 -241.016304) (xy 105.96137 -240.984117) (xy 106.005444 -240.958671)
			(xy 106.05303 -240.940624) (xy 106.102894 -240.930444) (xy 106.153746 -240.928395) (xy 106.204267 -240.934529)
			(xy 106.253151 -240.948689) (xy 106.29913 -240.970506) (xy 106.341014 -240.999416) (xy 106.377718 -241.034671)
			(xy 106.408291 -241.075357) (xy 106.431942 -241.12042) (xy 106.448058 -241.168694) (xy 106.456222 -241.218928)
			(xy 106.456734 -241.244374) (xy 106.764831 -241.244374) (xy 106.768926 -241.193646) (xy 106.781105 -241.144232)
			(xy 106.801053 -241.097412) (xy 106.828254 -241.054398) (xy 106.862002 -241.016304) (xy 106.901424 -240.984117)
			(xy 106.945498 -240.958671) (xy 106.993084 -240.940624) (xy 107.042948 -240.930444) (xy 107.0938 -240.928395)
			(xy 107.144321 -240.934529) (xy 107.193205 -240.948689) (xy 107.239184 -240.970506) (xy 107.281068 -240.999416)
			(xy 107.317772 -241.034671) (xy 107.348345 -241.075357) (xy 107.371996 -241.12042) (xy 107.388112 -241.168694)
			(xy 107.396276 -241.218928) (xy 107.396788 -241.244374) (xy 107.396285 -241.269363) (xy 107.703602 -241.269363)
			(xy 107.703602 -241.219385) (xy 107.711421 -241.170022) (xy 107.726865 -241.12249) (xy 107.749555 -241.077958)
			(xy 107.778931 -241.037525) (xy 107.814271 -241.002185) (xy 107.854704 -240.972809) (xy 107.899236 -240.950119)
			(xy 107.946768 -240.934675) (xy 107.996131 -240.926856) (xy 108.046109 -240.926856) (xy 108.095472 -240.934675)
			(xy 108.143004 -240.950119) (xy 108.187536 -240.972809) (xy 108.227969 -241.002185) (xy 108.263309 -241.037525)
			(xy 108.292685 -241.077958) (xy 108.315375 -241.12249) (xy 108.330819 -241.170022) (xy 108.338638 -241.219385)
			(xy 108.339128 -241.244374) (xy 108.338638 -241.269363) (xy 108.643656 -241.269363) (xy 108.643656 -241.219385)
			(xy 108.651475 -241.170022) (xy 108.666919 -241.12249) (xy 108.689609 -241.077958) (xy 108.718985 -241.037525)
			(xy 108.754325 -241.002185) (xy 108.794758 -240.972809) (xy 108.83929 -240.950119) (xy 108.886822 -240.934675)
			(xy 108.936185 -240.926856) (xy 108.986163 -240.926856) (xy 109.035526 -240.934675) (xy 109.083058 -240.950119)
			(xy 109.12759 -240.972809) (xy 109.168023 -241.002185) (xy 109.203363 -241.037525) (xy 109.232739 -241.077958)
			(xy 109.255429 -241.12249) (xy 109.270873 -241.170022) (xy 109.278692 -241.219385) (xy 109.279182 -241.244374)
			(xy 109.278692 -241.269363) (xy 109.583456 -241.269363) (xy 109.583456 -241.219385) (xy 109.591275 -241.170022)
			(xy 109.606719 -241.12249) (xy 109.629409 -241.077958) (xy 109.658785 -241.037525) (xy 109.694125 -241.002185)
			(xy 109.734558 -240.972809) (xy 109.77909 -240.950119) (xy 109.826622 -240.934675) (xy 109.875985 -240.926856)
			(xy 109.925963 -240.926856) (xy 109.975326 -240.934675) (xy 110.022858 -240.950119) (xy 110.06739 -240.972809)
			(xy 110.107823 -241.002185) (xy 110.143163 -241.037525) (xy 110.172539 -241.077958) (xy 110.195229 -241.12249)
			(xy 110.210673 -241.170022) (xy 110.218492 -241.219385) (xy 110.218982 -241.244374) (xy 110.218492 -241.269363)
			(xy 113.337322 -241.269363) (xy 113.337322 -241.219385) (xy 113.345141 -241.170022) (xy 113.360585 -241.12249)
			(xy 113.383275 -241.077958) (xy 113.412651 -241.037525) (xy 113.447991 -241.002185) (xy 113.488424 -240.972809)
			(xy 113.532956 -240.950119) (xy 113.580488 -240.934675) (xy 113.629851 -240.926856) (xy 113.679829 -240.926856)
			(xy 113.729192 -240.934675) (xy 113.776724 -240.950119) (xy 113.821256 -240.972809) (xy 113.861689 -241.002185)
			(xy 113.897029 -241.037525) (xy 113.926405 -241.077958) (xy 113.949095 -241.12249) (xy 113.964539 -241.170022)
			(xy 113.972358 -241.219385) (xy 113.972848 -241.244374) (xy 113.972358 -241.269363) (xy 114.277122 -241.269363)
			(xy 114.277122 -241.219385) (xy 114.284941 -241.170022) (xy 114.300385 -241.12249) (xy 114.323075 -241.077958)
			(xy 114.352451 -241.037525) (xy 114.387791 -241.002185) (xy 114.428224 -240.972809) (xy 114.472756 -240.950119)
			(xy 114.520288 -240.934675) (xy 114.569651 -240.926856) (xy 114.619629 -240.926856) (xy 114.668992 -240.934675)
			(xy 114.716524 -240.950119) (xy 114.761056 -240.972809) (xy 114.801489 -241.002185) (xy 114.836829 -241.037525)
			(xy 114.866205 -241.077958) (xy 114.888895 -241.12249) (xy 114.904339 -241.170022) (xy 114.912158 -241.219385)
			(xy 114.912648 -241.244374) (xy 114.912158 -241.269363) (xy 115.217176 -241.269363) (xy 115.217176 -241.219385)
			(xy 115.224995 -241.170022) (xy 115.240439 -241.12249) (xy 115.263129 -241.077958) (xy 115.292505 -241.037525)
			(xy 115.327845 -241.002185) (xy 115.368278 -240.972809) (xy 115.41281 -240.950119) (xy 115.460342 -240.934675)
			(xy 115.509705 -240.926856) (xy 115.559683 -240.926856) (xy 115.609046 -240.934675) (xy 115.656578 -240.950119)
			(xy 115.70111 -240.972809) (xy 115.741543 -241.002185) (xy 115.776883 -241.037525) (xy 115.806259 -241.077958)
			(xy 115.828949 -241.12249) (xy 115.844393 -241.170022) (xy 115.852212 -241.219385) (xy 115.852702 -241.244374)
			(xy 116.158513 -241.244374) (xy 116.162608 -241.193646) (xy 116.174787 -241.144232) (xy 116.194735 -241.097412)
			(xy 116.221936 -241.054398) (xy 116.255684 -241.016304) (xy 116.295106 -240.984117) (xy 116.33918 -240.958671)
			(xy 116.386766 -240.940624) (xy 116.43663 -240.930444) (xy 116.487482 -240.928395) (xy 116.538003 -240.934529)
			(xy 116.586887 -240.948689) (xy 116.632866 -240.970506) (xy 116.67475 -240.999416) (xy 116.711454 -241.034671)
			(xy 116.742027 -241.075357) (xy 116.765678 -241.12042) (xy 116.781794 -241.168694) (xy 116.789958 -241.218928)
			(xy 116.79047 -241.244374) (xy 117.098567 -241.244374) (xy 117.102662 -241.193646) (xy 117.114841 -241.144232)
			(xy 117.134789 -241.097412) (xy 117.16199 -241.054398) (xy 117.195738 -241.016304) (xy 117.23516 -240.984117)
			(xy 117.279234 -240.958671) (xy 117.32682 -240.940624) (xy 117.376684 -240.930444) (xy 117.427536 -240.928395)
			(xy 117.478057 -240.934529) (xy 117.526941 -240.948689) (xy 117.57292 -240.970506) (xy 117.614804 -240.999416)
			(xy 117.651508 -241.034671) (xy 117.682081 -241.075357) (xy 117.705732 -241.12042) (xy 117.721848 -241.168694)
			(xy 117.730012 -241.218928) (xy 117.730524 -241.244374) (xy 117.730021 -241.269363) (xy 118.037338 -241.269363)
			(xy 118.037338 -241.219385) (xy 118.045157 -241.170022) (xy 118.060601 -241.12249) (xy 118.083291 -241.077958)
			(xy 118.112667 -241.037525) (xy 118.148007 -241.002185) (xy 118.18844 -240.972809) (xy 118.232972 -240.950119)
			(xy 118.280504 -240.934675) (xy 118.329867 -240.926856) (xy 118.379845 -240.926856) (xy 118.429208 -240.934675)
			(xy 118.47674 -240.950119) (xy 118.521272 -240.972809) (xy 118.561705 -241.002185) (xy 118.597045 -241.037525)
			(xy 118.626421 -241.077958) (xy 118.649111 -241.12249) (xy 118.664555 -241.170022) (xy 118.672374 -241.219385)
			(xy 118.672864 -241.244374) (xy 118.978421 -241.244374) (xy 118.982516 -241.193646) (xy 118.994695 -241.144232)
			(xy 119.014643 -241.097412) (xy 119.041844 -241.054398) (xy 119.075592 -241.016304) (xy 119.115014 -240.984117)
			(xy 119.159088 -240.958671) (xy 119.206674 -240.940624) (xy 119.256538 -240.930444) (xy 119.30739 -240.928395)
			(xy 119.357911 -240.934529) (xy 119.406795 -240.948689) (xy 119.452774 -240.970506) (xy 119.494658 -240.999416)
			(xy 119.531362 -241.034671) (xy 119.561935 -241.075357) (xy 119.585586 -241.12042) (xy 119.601702 -241.168694)
			(xy 119.609866 -241.218928) (xy 119.610378 -241.244374) (xy 119.918475 -241.244374) (xy 119.92257 -241.193646)
			(xy 119.934749 -241.144232) (xy 119.954697 -241.097412) (xy 119.981898 -241.054398) (xy 120.015646 -241.016304)
			(xy 120.055068 -240.984117) (xy 120.099142 -240.958671) (xy 120.146728 -240.940624) (xy 120.196592 -240.930444)
			(xy 120.247444 -240.928395) (xy 120.297965 -240.934529) (xy 120.346849 -240.948689) (xy 120.392828 -240.970506)
			(xy 120.434712 -240.999416) (xy 120.471416 -241.034671) (xy 120.501989 -241.075357) (xy 120.52564 -241.12042)
			(xy 120.541756 -241.168694) (xy 120.54992 -241.218928) (xy 120.550432 -241.244374) (xy 120.549929 -241.269363)
			(xy 120.857246 -241.269363) (xy 120.857246 -241.219385) (xy 120.865065 -241.170022) (xy 120.880509 -241.12249)
			(xy 120.903199 -241.077958) (xy 120.932575 -241.037525) (xy 120.967915 -241.002185) (xy 121.008348 -240.972809)
			(xy 121.05288 -240.950119) (xy 121.100412 -240.934675) (xy 121.149775 -240.926856) (xy 121.199753 -240.926856)
			(xy 121.249116 -240.934675) (xy 121.296648 -240.950119) (xy 121.34118 -240.972809) (xy 121.381613 -241.002185)
			(xy 121.416953 -241.037525) (xy 121.446329 -241.077958) (xy 121.469019 -241.12249) (xy 121.484463 -241.170022)
			(xy 121.492282 -241.219385) (xy 121.492772 -241.244374) (xy 121.798583 -241.244374) (xy 121.802678 -241.193646)
			(xy 121.814857 -241.144232) (xy 121.834805 -241.097412) (xy 121.862006 -241.054398) (xy 121.895754 -241.016304)
			(xy 121.935176 -240.984117) (xy 121.97925 -240.958671) (xy 122.026836 -240.940624) (xy 122.0767 -240.930444)
			(xy 122.127552 -240.928395) (xy 122.178073 -240.934529) (xy 122.226957 -240.948689) (xy 122.272936 -240.970506)
			(xy 122.31482 -240.999416) (xy 122.351524 -241.034671) (xy 122.382097 -241.075357) (xy 122.405748 -241.12042)
			(xy 122.421864 -241.168694) (xy 122.430028 -241.218928) (xy 122.43054 -241.244374) (xy 122.738383 -241.244374)
			(xy 122.742478 -241.193646) (xy 122.754657 -241.144232) (xy 122.774605 -241.097412) (xy 122.801806 -241.054398)
			(xy 122.835554 -241.016304) (xy 122.874976 -240.984117) (xy 122.91905 -240.958671) (xy 122.966636 -240.940624)
			(xy 123.0165 -240.930444) (xy 123.067352 -240.928395) (xy 123.117873 -240.934529) (xy 123.166757 -240.948689)
			(xy 123.212736 -240.970506) (xy 123.25462 -240.999416) (xy 123.291324 -241.034671) (xy 123.321897 -241.075357)
			(xy 123.345548 -241.12042) (xy 123.361664 -241.168694) (xy 123.369828 -241.218928) (xy 123.37034 -241.244374)
			(xy 123.369837 -241.269363) (xy 123.677154 -241.269363) (xy 123.677154 -241.219385) (xy 123.684973 -241.170022)
			(xy 123.700417 -241.12249) (xy 123.723107 -241.077958) (xy 123.752483 -241.037525) (xy 123.787823 -241.002185)
			(xy 123.828256 -240.972809) (xy 123.872788 -240.950119) (xy 123.92032 -240.934675) (xy 123.969683 -240.926856)
			(xy 124.019661 -240.926856) (xy 124.069024 -240.934675) (xy 124.116556 -240.950119) (xy 124.161088 -240.972809)
			(xy 124.201521 -241.002185) (xy 124.236861 -241.037525) (xy 124.266237 -241.077958) (xy 124.288927 -241.12249)
			(xy 124.304371 -241.170022) (xy 124.31219 -241.219385) (xy 124.31268 -241.244374) (xy 124.618491 -241.244374)
			(xy 124.622586 -241.193646) (xy 124.634765 -241.144232) (xy 124.654713 -241.097412) (xy 124.681914 -241.054398)
			(xy 124.715662 -241.016304) (xy 124.755084 -240.984117) (xy 124.799158 -240.958671) (xy 124.846744 -240.940624)
			(xy 124.896608 -240.930444) (xy 124.94746 -240.928395) (xy 124.997981 -240.934529) (xy 125.046865 -240.948689)
			(xy 125.092844 -240.970506) (xy 125.134728 -240.999416) (xy 125.171432 -241.034671) (xy 125.202005 -241.075357)
			(xy 125.225656 -241.12042) (xy 125.241772 -241.168694) (xy 125.249936 -241.218928) (xy 125.250448 -241.244374)
			(xy 125.558545 -241.244374) (xy 125.56264 -241.193646) (xy 125.574819 -241.144232) (xy 125.594767 -241.097412)
			(xy 125.621968 -241.054398) (xy 125.655716 -241.016304) (xy 125.695138 -240.984117) (xy 125.739212 -240.958671)
			(xy 125.786798 -240.940624) (xy 125.836662 -240.930444) (xy 125.887514 -240.928395) (xy 125.938035 -240.934529)
			(xy 125.986919 -240.948689) (xy 126.032898 -240.970506) (xy 126.074782 -240.999416) (xy 126.111486 -241.034671)
			(xy 126.142059 -241.075357) (xy 126.16571 -241.12042) (xy 126.181826 -241.168694) (xy 126.18999 -241.218928)
			(xy 126.190502 -241.244374) (xy 126.18999 -241.26982) (xy 126.181826 -241.320054) (xy 126.16571 -241.368328)
			(xy 126.142059 -241.413391) (xy 126.111486 -241.454077) (xy 126.074782 -241.489332) (xy 126.032898 -241.518242)
			(xy 125.986919 -241.540059) (xy 125.938035 -241.554219) (xy 125.887514 -241.560353) (xy 125.836662 -241.558304)
			(xy 125.786798 -241.548124) (xy 125.739212 -241.530077) (xy 125.695138 -241.504631) (xy 125.655716 -241.472444)
			(xy 125.621968 -241.43435) (xy 125.594767 -241.391336) (xy 125.574819 -241.344516) (xy 125.56264 -241.295102)
			(xy 125.558545 -241.244374) (xy 125.250448 -241.244374) (xy 125.249936 -241.26982) (xy 125.241772 -241.320054)
			(xy 125.225656 -241.368328) (xy 125.202005 -241.413391) (xy 125.171432 -241.454077) (xy 125.134728 -241.489332)
			(xy 125.092844 -241.518242) (xy 125.046865 -241.540059) (xy 124.997981 -241.554219) (xy 124.94746 -241.560353)
			(xy 124.896608 -241.558304) (xy 124.846744 -241.548124) (xy 124.799158 -241.530077) (xy 124.755084 -241.504631)
			(xy 124.715662 -241.472444) (xy 124.681914 -241.43435) (xy 124.654713 -241.391336) (xy 124.634765 -241.344516)
			(xy 124.622586 -241.295102) (xy 124.618491 -241.244374) (xy 124.31268 -241.244374) (xy 124.31219 -241.269363)
			(xy 124.304371 -241.318726) (xy 124.288927 -241.366258) (xy 124.266237 -241.41079) (xy 124.236861 -241.451223)
			(xy 124.201521 -241.486563) (xy 124.161088 -241.515939) (xy 124.116556 -241.538629) (xy 124.069024 -241.554073)
			(xy 124.019661 -241.561892) (xy 123.969683 -241.561892) (xy 123.92032 -241.554073) (xy 123.872788 -241.538629)
			(xy 123.828256 -241.515939) (xy 123.787823 -241.486563) (xy 123.752483 -241.451223) (xy 123.723107 -241.41079)
			(xy 123.700417 -241.366258) (xy 123.684973 -241.318726) (xy 123.677154 -241.269363) (xy 123.369837 -241.269363)
			(xy 123.369828 -241.26982) (xy 123.361664 -241.320054) (xy 123.345548 -241.368328) (xy 123.321897 -241.413391)
			(xy 123.291324 -241.454077) (xy 123.25462 -241.489332) (xy 123.212736 -241.518242) (xy 123.166757 -241.540059)
			(xy 123.117873 -241.554219) (xy 123.067352 -241.560353) (xy 123.0165 -241.558304) (xy 122.966636 -241.548124)
			(xy 122.91905 -241.530077) (xy 122.874976 -241.504631) (xy 122.835554 -241.472444) (xy 122.801806 -241.43435)
			(xy 122.774605 -241.391336) (xy 122.754657 -241.344516) (xy 122.742478 -241.295102) (xy 122.738383 -241.244374)
			(xy 122.43054 -241.244374) (xy 122.430028 -241.26982) (xy 122.421864 -241.320054) (xy 122.405748 -241.368328)
			(xy 122.382097 -241.413391) (xy 122.351524 -241.454077) (xy 122.31482 -241.489332) (xy 122.272936 -241.518242)
			(xy 122.226957 -241.540059) (xy 122.178073 -241.554219) (xy 122.127552 -241.560353) (xy 122.0767 -241.558304)
			(xy 122.026836 -241.548124) (xy 121.97925 -241.530077) (xy 121.935176 -241.504631) (xy 121.895754 -241.472444)
			(xy 121.862006 -241.43435) (xy 121.834805 -241.391336) (xy 121.814857 -241.344516) (xy 121.802678 -241.295102)
			(xy 121.798583 -241.244374) (xy 121.492772 -241.244374) (xy 121.492282 -241.269363) (xy 121.484463 -241.318726)
			(xy 121.469019 -241.366258) (xy 121.446329 -241.41079) (xy 121.416953 -241.451223) (xy 121.381613 -241.486563)
			(xy 121.34118 -241.515939) (xy 121.296648 -241.538629) (xy 121.249116 -241.554073) (xy 121.199753 -241.561892)
			(xy 121.149775 -241.561892) (xy 121.100412 -241.554073) (xy 121.05288 -241.538629) (xy 121.008348 -241.515939)
			(xy 120.967915 -241.486563) (xy 120.932575 -241.451223) (xy 120.903199 -241.41079) (xy 120.880509 -241.366258)
			(xy 120.865065 -241.318726) (xy 120.857246 -241.269363) (xy 120.549929 -241.269363) (xy 120.54992 -241.26982)
			(xy 120.541756 -241.320054) (xy 120.52564 -241.368328) (xy 120.501989 -241.413391) (xy 120.471416 -241.454077)
			(xy 120.434712 -241.489332) (xy 120.392828 -241.518242) (xy 120.346849 -241.540059) (xy 120.297965 -241.554219)
			(xy 120.247444 -241.560353) (xy 120.196592 -241.558304) (xy 120.146728 -241.548124) (xy 120.099142 -241.530077)
			(xy 120.055068 -241.504631) (xy 120.015646 -241.472444) (xy 119.981898 -241.43435) (xy 119.954697 -241.391336)
			(xy 119.934749 -241.344516) (xy 119.92257 -241.295102) (xy 119.918475 -241.244374) (xy 119.610378 -241.244374)
			(xy 119.609866 -241.26982) (xy 119.601702 -241.320054) (xy 119.585586 -241.368328) (xy 119.561935 -241.413391)
			(xy 119.531362 -241.454077) (xy 119.494658 -241.489332) (xy 119.452774 -241.518242) (xy 119.406795 -241.540059)
			(xy 119.357911 -241.554219) (xy 119.30739 -241.560353) (xy 119.256538 -241.558304) (xy 119.206674 -241.548124)
			(xy 119.159088 -241.530077) (xy 119.115014 -241.504631) (xy 119.075592 -241.472444) (xy 119.041844 -241.43435)
			(xy 119.014643 -241.391336) (xy 118.994695 -241.344516) (xy 118.982516 -241.295102) (xy 118.978421 -241.244374)
			(xy 118.672864 -241.244374) (xy 118.672374 -241.269363) (xy 118.664555 -241.318726) (xy 118.649111 -241.366258)
			(xy 118.626421 -241.41079) (xy 118.597045 -241.451223) (xy 118.561705 -241.486563) (xy 118.521272 -241.515939)
			(xy 118.47674 -241.538629) (xy 118.429208 -241.554073) (xy 118.379845 -241.561892) (xy 118.329867 -241.561892)
			(xy 118.280504 -241.554073) (xy 118.232972 -241.538629) (xy 118.18844 -241.515939) (xy 118.148007 -241.486563)
			(xy 118.112667 -241.451223) (xy 118.083291 -241.41079) (xy 118.060601 -241.366258) (xy 118.045157 -241.318726)
			(xy 118.037338 -241.269363) (xy 117.730021 -241.269363) (xy 117.730012 -241.26982) (xy 117.721848 -241.320054)
			(xy 117.705732 -241.368328) (xy 117.682081 -241.413391) (xy 117.651508 -241.454077) (xy 117.614804 -241.489332)
			(xy 117.57292 -241.518242) (xy 117.526941 -241.540059) (xy 117.478057 -241.554219) (xy 117.427536 -241.560353)
			(xy 117.376684 -241.558304) (xy 117.32682 -241.548124) (xy 117.279234 -241.530077) (xy 117.23516 -241.504631)
			(xy 117.195738 -241.472444) (xy 117.16199 -241.43435) (xy 117.134789 -241.391336) (xy 117.114841 -241.344516)
			(xy 117.102662 -241.295102) (xy 117.098567 -241.244374) (xy 116.79047 -241.244374) (xy 116.789958 -241.26982)
			(xy 116.781794 -241.320054) (xy 116.765678 -241.368328) (xy 116.742027 -241.413391) (xy 116.711454 -241.454077)
			(xy 116.67475 -241.489332) (xy 116.632866 -241.518242) (xy 116.586887 -241.540059) (xy 116.538003 -241.554219)
			(xy 116.487482 -241.560353) (xy 116.43663 -241.558304) (xy 116.386766 -241.548124) (xy 116.33918 -241.530077)
			(xy 116.295106 -241.504631) (xy 116.255684 -241.472444) (xy 116.221936 -241.43435) (xy 116.194735 -241.391336)
			(xy 116.174787 -241.344516) (xy 116.162608 -241.295102) (xy 116.158513 -241.244374) (xy 115.852702 -241.244374)
			(xy 115.852212 -241.269363) (xy 115.844393 -241.318726) (xy 115.828949 -241.366258) (xy 115.806259 -241.41079)
			(xy 115.776883 -241.451223) (xy 115.741543 -241.486563) (xy 115.70111 -241.515939) (xy 115.656578 -241.538629)
			(xy 115.609046 -241.554073) (xy 115.559683 -241.561892) (xy 115.509705 -241.561892) (xy 115.460342 -241.554073)
			(xy 115.41281 -241.538629) (xy 115.368278 -241.515939) (xy 115.327845 -241.486563) (xy 115.292505 -241.451223)
			(xy 115.263129 -241.41079) (xy 115.240439 -241.366258) (xy 115.224995 -241.318726) (xy 115.217176 -241.269363)
			(xy 114.912158 -241.269363) (xy 114.904339 -241.318726) (xy 114.888895 -241.366258) (xy 114.866205 -241.41079)
			(xy 114.836829 -241.451223) (xy 114.801489 -241.486563) (xy 114.761056 -241.515939) (xy 114.716524 -241.538629)
			(xy 114.668992 -241.554073) (xy 114.619629 -241.561892) (xy 114.569651 -241.561892) (xy 114.520288 -241.554073)
			(xy 114.472756 -241.538629) (xy 114.428224 -241.515939) (xy 114.387791 -241.486563) (xy 114.352451 -241.451223)
			(xy 114.323075 -241.41079) (xy 114.300385 -241.366258) (xy 114.284941 -241.318726) (xy 114.277122 -241.269363)
			(xy 113.972358 -241.269363) (xy 113.964539 -241.318726) (xy 113.949095 -241.366258) (xy 113.926405 -241.41079)
			(xy 113.897029 -241.451223) (xy 113.861689 -241.486563) (xy 113.821256 -241.515939) (xy 113.776724 -241.538629)
			(xy 113.729192 -241.554073) (xy 113.679829 -241.561892) (xy 113.629851 -241.561892) (xy 113.580488 -241.554073)
			(xy 113.532956 -241.538629) (xy 113.488424 -241.515939) (xy 113.447991 -241.486563) (xy 113.412651 -241.451223)
			(xy 113.383275 -241.41079) (xy 113.360585 -241.366258) (xy 113.345141 -241.318726) (xy 113.337322 -241.269363)
			(xy 110.218492 -241.269363) (xy 110.210673 -241.318726) (xy 110.195229 -241.366258) (xy 110.172539 -241.41079)
			(xy 110.143163 -241.451223) (xy 110.107823 -241.486563) (xy 110.06739 -241.515939) (xy 110.022858 -241.538629)
			(xy 109.975326 -241.554073) (xy 109.925963 -241.561892) (xy 109.875985 -241.561892) (xy 109.826622 -241.554073)
			(xy 109.77909 -241.538629) (xy 109.734558 -241.515939) (xy 109.694125 -241.486563) (xy 109.658785 -241.451223)
			(xy 109.629409 -241.41079) (xy 109.606719 -241.366258) (xy 109.591275 -241.318726) (xy 109.583456 -241.269363)
			(xy 109.278692 -241.269363) (xy 109.270873 -241.318726) (xy 109.255429 -241.366258) (xy 109.232739 -241.41079)
			(xy 109.203363 -241.451223) (xy 109.168023 -241.486563) (xy 109.12759 -241.515939) (xy 109.083058 -241.538629)
			(xy 109.035526 -241.554073) (xy 108.986163 -241.561892) (xy 108.936185 -241.561892) (xy 108.886822 -241.554073)
			(xy 108.83929 -241.538629) (xy 108.794758 -241.515939) (xy 108.754325 -241.486563) (xy 108.718985 -241.451223)
			(xy 108.689609 -241.41079) (xy 108.666919 -241.366258) (xy 108.651475 -241.318726) (xy 108.643656 -241.269363)
			(xy 108.338638 -241.269363) (xy 108.330819 -241.318726) (xy 108.315375 -241.366258) (xy 108.292685 -241.41079)
			(xy 108.263309 -241.451223) (xy 108.227969 -241.486563) (xy 108.187536 -241.515939) (xy 108.143004 -241.538629)
			(xy 108.095472 -241.554073) (xy 108.046109 -241.561892) (xy 107.996131 -241.561892) (xy 107.946768 -241.554073)
			(xy 107.899236 -241.538629) (xy 107.854704 -241.515939) (xy 107.814271 -241.486563) (xy 107.778931 -241.451223)
			(xy 107.749555 -241.41079) (xy 107.726865 -241.366258) (xy 107.711421 -241.318726) (xy 107.703602 -241.269363)
			(xy 107.396285 -241.269363) (xy 107.396276 -241.26982) (xy 107.388112 -241.320054) (xy 107.371996 -241.368328)
			(xy 107.348345 -241.413391) (xy 107.317772 -241.454077) (xy 107.281068 -241.489332) (xy 107.239184 -241.518242)
			(xy 107.193205 -241.540059) (xy 107.144321 -241.554219) (xy 107.0938 -241.560353) (xy 107.042948 -241.558304)
			(xy 106.993084 -241.548124) (xy 106.945498 -241.530077) (xy 106.901424 -241.504631) (xy 106.862002 -241.472444)
			(xy 106.828254 -241.43435) (xy 106.801053 -241.391336) (xy 106.781105 -241.344516) (xy 106.768926 -241.295102)
			(xy 106.764831 -241.244374) (xy 106.456734 -241.244374) (xy 106.456222 -241.26982) (xy 106.448058 -241.320054)
			(xy 106.431942 -241.368328) (xy 106.408291 -241.413391) (xy 106.377718 -241.454077) (xy 106.341014 -241.489332)
			(xy 106.29913 -241.518242) (xy 106.253151 -241.540059) (xy 106.204267 -241.554219) (xy 106.153746 -241.560353)
			(xy 106.102894 -241.558304) (xy 106.05303 -241.548124) (xy 106.005444 -241.530077) (xy 105.96137 -241.504631)
			(xy 105.921948 -241.472444) (xy 105.8882 -241.43435) (xy 105.860999 -241.391336) (xy 105.841051 -241.344516)
			(xy 105.828872 -241.295102) (xy 105.824777 -241.244374) (xy 105.518966 -241.244374) (xy 105.518476 -241.269363)
			(xy 105.510657 -241.318726) (xy 105.495213 -241.366258) (xy 105.472523 -241.41079) (xy 105.443147 -241.451223)
			(xy 105.407807 -241.486563) (xy 105.367374 -241.515939) (xy 105.322842 -241.538629) (xy 105.27531 -241.554073)
			(xy 105.225947 -241.561892) (xy 105.175969 -241.561892) (xy 105.126606 -241.554073) (xy 105.079074 -241.538629)
			(xy 105.034542 -241.515939) (xy 104.994109 -241.486563) (xy 104.958769 -241.451223) (xy 104.929393 -241.41079)
			(xy 104.906703 -241.366258) (xy 104.891259 -241.318726) (xy 104.88344 -241.269363) (xy 104.576377 -241.269363)
			(xy 104.576368 -241.26982) (xy 104.568204 -241.320054) (xy 104.552088 -241.368328) (xy 104.528437 -241.413391)
			(xy 104.497864 -241.454077) (xy 104.46116 -241.489332) (xy 104.419276 -241.518242) (xy 104.373297 -241.540059)
			(xy 104.324413 -241.554219) (xy 104.273892 -241.560353) (xy 104.22304 -241.558304) (xy 104.173176 -241.548124)
			(xy 104.12559 -241.530077) (xy 104.081516 -241.504631) (xy 104.042094 -241.472444) (xy 104.008346 -241.43435)
			(xy 103.981145 -241.391336) (xy 103.961197 -241.344516) (xy 103.949018 -241.295102) (xy 103.944923 -241.244374)
			(xy 103.636826 -241.244374) (xy 103.636314 -241.26982) (xy 103.62815 -241.320054) (xy 103.612034 -241.368328)
			(xy 103.588383 -241.413391) (xy 103.55781 -241.454077) (xy 103.521106 -241.489332) (xy 103.479222 -241.518242)
			(xy 103.433243 -241.540059) (xy 103.384359 -241.554219) (xy 103.333838 -241.560353) (xy 103.282986 -241.558304)
			(xy 103.233122 -241.548124) (xy 103.185536 -241.530077) (xy 103.141462 -241.504631) (xy 103.10204 -241.472444)
			(xy 103.068292 -241.43435) (xy 103.041091 -241.391336) (xy 103.021143 -241.344516) (xy 103.008964 -241.295102)
			(xy 103.004869 -241.244374) (xy 102.699058 -241.244374) (xy 102.698568 -241.269363) (xy 102.690749 -241.318726)
			(xy 102.675305 -241.366258) (xy 102.652615 -241.41079) (xy 102.623239 -241.451223) (xy 102.587899 -241.486563)
			(xy 102.547466 -241.515939) (xy 102.502934 -241.538629) (xy 102.455402 -241.554073) (xy 102.406039 -241.561892)
			(xy 102.356061 -241.561892) (xy 102.306698 -241.554073) (xy 102.259166 -241.538629) (xy 102.214634 -241.515939)
			(xy 102.174201 -241.486563) (xy 102.138861 -241.451223) (xy 102.109485 -241.41079) (xy 102.086795 -241.366258)
			(xy 102.071351 -241.318726) (xy 102.063532 -241.269363) (xy 101.756215 -241.269363) (xy 101.756206 -241.26982)
			(xy 101.748042 -241.320054) (xy 101.731926 -241.368328) (xy 101.708275 -241.413391) (xy 101.677702 -241.454077)
			(xy 101.640998 -241.489332) (xy 101.599114 -241.518242) (xy 101.553135 -241.540059) (xy 101.504251 -241.554219)
			(xy 101.45373 -241.560353) (xy 101.402878 -241.558304) (xy 101.353014 -241.548124) (xy 101.305428 -241.530077)
			(xy 101.261354 -241.504631) (xy 101.221932 -241.472444) (xy 101.188184 -241.43435) (xy 101.160983 -241.391336)
			(xy 101.141035 -241.344516) (xy 101.128856 -241.295102) (xy 101.124761 -241.244374) (xy 100.816664 -241.244374)
			(xy 100.816152 -241.26982) (xy 100.807988 -241.320054) (xy 100.791872 -241.368328) (xy 100.768221 -241.413391)
			(xy 100.737648 -241.454077) (xy 100.700944 -241.489332) (xy 100.65906 -241.518242) (xy 100.613081 -241.540059)
			(xy 100.564197 -241.554219) (xy 100.513676 -241.560353) (xy 100.462824 -241.558304) (xy 100.41296 -241.548124)
			(xy 100.365374 -241.530077) (xy 100.3213 -241.504631) (xy 100.281878 -241.472444) (xy 100.24813 -241.43435)
			(xy 100.220929 -241.391336) (xy 100.200981 -241.344516) (xy 100.188802 -241.295102) (xy 100.184707 -241.244374)
			(xy 99.87915 -241.244374) (xy 99.87866 -241.269363) (xy 99.870841 -241.318726) (xy 99.855397 -241.366258)
			(xy 99.832707 -241.41079) (xy 99.803331 -241.451223) (xy 99.767991 -241.486563) (xy 99.727558 -241.515939)
			(xy 99.683026 -241.538629) (xy 99.635494 -241.554073) (xy 99.586131 -241.561892) (xy 99.536153 -241.561892)
			(xy 99.48679 -241.554073) (xy 99.439258 -241.538629) (xy 99.394726 -241.515939) (xy 99.354293 -241.486563)
			(xy 99.318953 -241.451223) (xy 99.289577 -241.41079) (xy 99.266887 -241.366258) (xy 99.251443 -241.318726)
			(xy 99.243624 -241.269363) (xy 98.936307 -241.269363) (xy 98.936298 -241.26982) (xy 98.928134 -241.320054)
			(xy 98.912018 -241.368328) (xy 98.888367 -241.413391) (xy 98.857794 -241.454077) (xy 98.82109 -241.489332)
			(xy 98.779206 -241.518242) (xy 98.733227 -241.540059) (xy 98.684343 -241.554219) (xy 98.633822 -241.560353)
			(xy 98.58297 -241.558304) (xy 98.533106 -241.548124) (xy 98.48552 -241.530077) (xy 98.441446 -241.504631)
			(xy 98.402024 -241.472444) (xy 98.368276 -241.43435) (xy 98.341075 -241.391336) (xy 98.321127 -241.344516)
			(xy 98.308948 -241.295102) (xy 98.304853 -241.244374) (xy 97.996756 -241.244374) (xy 97.996244 -241.26982)
			(xy 97.98808 -241.320054) (xy 97.971964 -241.368328) (xy 97.948313 -241.413391) (xy 97.91774 -241.454077)
			(xy 97.881036 -241.489332) (xy 97.839152 -241.518242) (xy 97.793173 -241.540059) (xy 97.744289 -241.554219)
			(xy 97.693768 -241.560353) (xy 97.642916 -241.558304) (xy 97.593052 -241.548124) (xy 97.545466 -241.530077)
			(xy 97.501392 -241.504631) (xy 97.46197 -241.472444) (xy 97.428222 -241.43435) (xy 97.401021 -241.391336)
			(xy 97.381073 -241.344516) (xy 97.368894 -241.295102) (xy 97.364799 -241.244374) (xy 97.058988 -241.244374)
			(xy 97.058988 -241.24793) (xy 97.057718 -241.277902) (xy 97.057464 -241.279426) (xy 97.057464 -242.079369)
			(xy 98.77347 -242.079369) (xy 98.77347 -242.029391) (xy 98.781289 -241.980028) (xy 98.796733 -241.932496)
			(xy 98.819423 -241.887964) (xy 98.848799 -241.847531) (xy 98.884139 -241.812191) (xy 98.924572 -241.782815)
			(xy 98.969104 -241.760125) (xy 99.016636 -241.744681) (xy 99.065999 -241.736862) (xy 99.115977 -241.736862)
			(xy 99.16534 -241.744681) (xy 99.212872 -241.760125) (xy 99.257404 -241.782815) (xy 99.297837 -241.812191)
			(xy 99.333177 -241.847531) (xy 99.362553 -241.887964) (xy 99.385243 -241.932496) (xy 99.400687 -241.980028)
			(xy 99.408506 -242.029391) (xy 99.408996 -242.05438) (xy 99.408506 -242.079369) (xy 101.593632 -242.079369)
			(xy 101.593632 -242.029391) (xy 101.601451 -241.980028) (xy 101.616895 -241.932496) (xy 101.639585 -241.887964)
			(xy 101.668961 -241.847531) (xy 101.704301 -241.812191) (xy 101.744734 -241.782815) (xy 101.789266 -241.760125)
			(xy 101.836798 -241.744681) (xy 101.886161 -241.736862) (xy 101.936139 -241.736862) (xy 101.985502 -241.744681)
			(xy 102.033034 -241.760125) (xy 102.077566 -241.782815) (xy 102.117999 -241.812191) (xy 102.153339 -241.847531)
			(xy 102.182715 -241.887964) (xy 102.205405 -241.932496) (xy 102.220849 -241.980028) (xy 102.228668 -242.029391)
			(xy 102.229158 -242.05438) (xy 102.228668 -242.079369) (xy 104.41354 -242.079369) (xy 104.41354 -242.029391)
			(xy 104.421359 -241.980028) (xy 104.436803 -241.932496) (xy 104.459493 -241.887964) (xy 104.488869 -241.847531)
			(xy 104.524209 -241.812191) (xy 104.564642 -241.782815) (xy 104.609174 -241.760125) (xy 104.656706 -241.744681)
			(xy 104.706069 -241.736862) (xy 104.756047 -241.736862) (xy 104.80541 -241.744681) (xy 104.852942 -241.760125)
			(xy 104.897474 -241.782815) (xy 104.937907 -241.812191) (xy 104.973247 -241.847531) (xy 105.002623 -241.887964)
			(xy 105.025313 -241.932496) (xy 105.040757 -241.980028) (xy 105.048576 -242.029391) (xy 105.049066 -242.05438)
			(xy 105.048576 -242.079369) (xy 107.233448 -242.079369) (xy 107.233448 -242.029391) (xy 107.241267 -241.980028)
			(xy 107.256711 -241.932496) (xy 107.279401 -241.887964) (xy 107.308777 -241.847531) (xy 107.344117 -241.812191)
			(xy 107.38455 -241.782815) (xy 107.429082 -241.760125) (xy 107.476614 -241.744681) (xy 107.525977 -241.736862)
			(xy 107.575955 -241.736862) (xy 107.625318 -241.744681) (xy 107.67285 -241.760125) (xy 107.717382 -241.782815)
			(xy 107.757815 -241.812191) (xy 107.793155 -241.847531) (xy 107.822531 -241.887964) (xy 107.845221 -241.932496)
			(xy 107.860665 -241.980028) (xy 107.868484 -242.029391) (xy 107.868974 -242.05438) (xy 108.174785 -242.05438)
			(xy 108.17888 -242.003652) (xy 108.191059 -241.954238) (xy 108.211007 -241.907418) (xy 108.238208 -241.864404)
			(xy 108.271956 -241.82631) (xy 108.311378 -241.794123) (xy 108.355452 -241.768677) (xy 108.403038 -241.75063)
			(xy 108.452902 -241.74045) (xy 108.503754 -241.738401) (xy 108.554275 -241.744535) (xy 108.603159 -241.758695)
			(xy 108.649138 -241.780512) (xy 108.691022 -241.809422) (xy 108.727726 -241.844677) (xy 108.758299 -241.885363)
			(xy 108.78195 -241.930426) (xy 108.798066 -241.9787) (xy 108.80623 -242.028934) (xy 108.806742 -242.05438)
			(xy 109.114839 -242.05438) (xy 109.118934 -242.003652) (xy 109.131113 -241.954238) (xy 109.151061 -241.907418)
			(xy 109.178262 -241.864404) (xy 109.21201 -241.82631) (xy 109.251432 -241.794123) (xy 109.295506 -241.768677)
			(xy 109.343092 -241.75063) (xy 109.392956 -241.74045) (xy 109.443808 -241.738401) (xy 109.494329 -241.744535)
			(xy 109.543213 -241.758695) (xy 109.589192 -241.780512) (xy 109.631076 -241.809422) (xy 109.66778 -241.844677)
			(xy 109.698353 -241.885363) (xy 109.722004 -241.930426) (xy 109.73812 -241.9787) (xy 109.746284 -242.028934)
			(xy 109.746796 -242.05438) (xy 109.746293 -242.079369) (xy 110.05361 -242.079369) (xy 110.05361 -242.029391)
			(xy 110.061429 -241.980028) (xy 110.076873 -241.932496) (xy 110.099563 -241.887964) (xy 110.128939 -241.847531)
			(xy 110.164279 -241.812191) (xy 110.204712 -241.782815) (xy 110.249244 -241.760125) (xy 110.296776 -241.744681)
			(xy 110.346139 -241.736862) (xy 110.396117 -241.736862) (xy 110.44548 -241.744681) (xy 110.493012 -241.760125)
			(xy 110.537544 -241.782815) (xy 110.577977 -241.812191) (xy 110.613317 -241.847531) (xy 110.642693 -241.887964)
			(xy 110.665383 -241.932496) (xy 110.680827 -241.980028) (xy 110.688646 -242.029391) (xy 110.689136 -242.05438)
			(xy 110.688646 -242.079369) (xy 112.867168 -242.079369) (xy 112.867168 -242.029391) (xy 112.874987 -241.980028)
			(xy 112.890431 -241.932496) (xy 112.913121 -241.887964) (xy 112.942497 -241.847531) (xy 112.977837 -241.812191)
			(xy 113.01827 -241.782815) (xy 113.062802 -241.760125) (xy 113.110334 -241.744681) (xy 113.159697 -241.736862)
			(xy 113.209675 -241.736862) (xy 113.259038 -241.744681) (xy 113.30657 -241.760125) (xy 113.351102 -241.782815)
			(xy 113.391535 -241.812191) (xy 113.426875 -241.847531) (xy 113.456251 -241.887964) (xy 113.478941 -241.932496)
			(xy 113.494385 -241.980028) (xy 113.502204 -242.029391) (xy 113.502694 -242.05438) (xy 113.808505 -242.05438)
			(xy 113.8126 -242.003652) (xy 113.824779 -241.954238) (xy 113.844727 -241.907418) (xy 113.871928 -241.864404)
			(xy 113.905676 -241.82631) (xy 113.945098 -241.794123) (xy 113.989172 -241.768677) (xy 114.036758 -241.75063)
			(xy 114.086622 -241.74045) (xy 114.137474 -241.738401) (xy 114.187995 -241.744535) (xy 114.236879 -241.758695)
			(xy 114.282858 -241.780512) (xy 114.324742 -241.809422) (xy 114.361446 -241.844677) (xy 114.392019 -241.885363)
			(xy 114.41567 -241.930426) (xy 114.431786 -241.9787) (xy 114.43995 -242.028934) (xy 114.440462 -242.05438)
			(xy 114.748559 -242.05438) (xy 114.752654 -242.003652) (xy 114.764833 -241.954238) (xy 114.784781 -241.907418)
			(xy 114.811982 -241.864404) (xy 114.84573 -241.82631) (xy 114.885152 -241.794123) (xy 114.929226 -241.768677)
			(xy 114.976812 -241.75063) (xy 115.026676 -241.74045) (xy 115.077528 -241.738401) (xy 115.128049 -241.744535)
			(xy 115.176933 -241.758695) (xy 115.222912 -241.780512) (xy 115.264796 -241.809422) (xy 115.3015 -241.844677)
			(xy 115.332073 -241.885363) (xy 115.355724 -241.930426) (xy 115.37184 -241.9787) (xy 115.380004 -242.028934)
			(xy 115.380516 -242.05438) (xy 115.380013 -242.079369) (xy 115.68733 -242.079369) (xy 115.68733 -242.029391)
			(xy 115.695149 -241.980028) (xy 115.710593 -241.932496) (xy 115.733283 -241.887964) (xy 115.762659 -241.847531)
			(xy 115.797999 -241.812191) (xy 115.838432 -241.782815) (xy 115.882964 -241.760125) (xy 115.930496 -241.744681)
			(xy 115.979859 -241.736862) (xy 116.029837 -241.736862) (xy 116.0792 -241.744681) (xy 116.126732 -241.760125)
			(xy 116.171264 -241.782815) (xy 116.211697 -241.812191) (xy 116.247037 -241.847531) (xy 116.276413 -241.887964)
			(xy 116.299103 -241.932496) (xy 116.314547 -241.980028) (xy 116.322366 -242.029391) (xy 116.322856 -242.05438)
			(xy 116.322366 -242.079369) (xy 118.507238 -242.079369) (xy 118.507238 -242.029391) (xy 118.515057 -241.980028)
			(xy 118.530501 -241.932496) (xy 118.553191 -241.887964) (xy 118.582567 -241.847531) (xy 118.617907 -241.812191)
			(xy 118.65834 -241.782815) (xy 118.702872 -241.760125) (xy 118.750404 -241.744681) (xy 118.799767 -241.736862)
			(xy 118.849745 -241.736862) (xy 118.899108 -241.744681) (xy 118.94664 -241.760125) (xy 118.991172 -241.782815)
			(xy 119.031605 -241.812191) (xy 119.066945 -241.847531) (xy 119.096321 -241.887964) (xy 119.119011 -241.932496)
			(xy 119.134455 -241.980028) (xy 119.142274 -242.029391) (xy 119.142764 -242.05438) (xy 119.142274 -242.079369)
			(xy 121.327146 -242.079369) (xy 121.327146 -242.029391) (xy 121.334965 -241.980028) (xy 121.350409 -241.932496)
			(xy 121.373099 -241.887964) (xy 121.402475 -241.847531) (xy 121.437815 -241.812191) (xy 121.478248 -241.782815)
			(xy 121.52278 -241.760125) (xy 121.570312 -241.744681) (xy 121.619675 -241.736862) (xy 121.669653 -241.736862)
			(xy 121.719016 -241.744681) (xy 121.766548 -241.760125) (xy 121.81108 -241.782815) (xy 121.851513 -241.812191)
			(xy 121.886853 -241.847531) (xy 121.916229 -241.887964) (xy 121.938919 -241.932496) (xy 121.954363 -241.980028)
			(xy 121.962182 -242.029391) (xy 121.962672 -242.05438) (xy 121.962182 -242.079369) (xy 124.147308 -242.079369)
			(xy 124.147308 -242.029391) (xy 124.155127 -241.980028) (xy 124.170571 -241.932496) (xy 124.193261 -241.887964)
			(xy 124.222637 -241.847531) (xy 124.257977 -241.812191) (xy 124.29841 -241.782815) (xy 124.342942 -241.760125)
			(xy 124.390474 -241.744681) (xy 124.439837 -241.736862) (xy 124.489815 -241.736862) (xy 124.539178 -241.744681)
			(xy 124.58671 -241.760125) (xy 124.631242 -241.782815) (xy 124.671675 -241.812191) (xy 124.707015 -241.847531)
			(xy 124.736391 -241.887964) (xy 124.759081 -241.932496) (xy 124.774525 -241.980028) (xy 124.782344 -242.029391)
			(xy 124.782834 -242.05438) (xy 124.782344 -242.079369) (xy 124.774525 -242.128732) (xy 124.759081 -242.176264)
			(xy 124.736391 -242.220796) (xy 124.707015 -242.261229) (xy 124.671675 -242.296569) (xy 124.631242 -242.325945)
			(xy 124.58671 -242.348635) (xy 124.539178 -242.364079) (xy 124.489815 -242.371898) (xy 124.439837 -242.371898)
			(xy 124.390474 -242.364079) (xy 124.342942 -242.348635) (xy 124.29841 -242.325945) (xy 124.257977 -242.296569)
			(xy 124.222637 -242.261229) (xy 124.193261 -242.220796) (xy 124.170571 -242.176264) (xy 124.155127 -242.128732)
			(xy 124.147308 -242.079369) (xy 121.962182 -242.079369) (xy 121.954363 -242.128732) (xy 121.938919 -242.176264)
			(xy 121.916229 -242.220796) (xy 121.886853 -242.261229) (xy 121.851513 -242.296569) (xy 121.81108 -242.325945)
			(xy 121.766548 -242.348635) (xy 121.719016 -242.364079) (xy 121.669653 -242.371898) (xy 121.619675 -242.371898)
			(xy 121.570312 -242.364079) (xy 121.52278 -242.348635) (xy 121.478248 -242.325945) (xy 121.437815 -242.296569)
			(xy 121.402475 -242.261229) (xy 121.373099 -242.220796) (xy 121.350409 -242.176264) (xy 121.334965 -242.128732)
			(xy 121.327146 -242.079369) (xy 119.142274 -242.079369) (xy 119.134455 -242.128732) (xy 119.119011 -242.176264)
			(xy 119.096321 -242.220796) (xy 119.066945 -242.261229) (xy 119.031605 -242.296569) (xy 118.991172 -242.325945)
			(xy 118.94664 -242.348635) (xy 118.899108 -242.364079) (xy 118.849745 -242.371898) (xy 118.799767 -242.371898)
			(xy 118.750404 -242.364079) (xy 118.702872 -242.348635) (xy 118.65834 -242.325945) (xy 118.617907 -242.296569)
			(xy 118.582567 -242.261229) (xy 118.553191 -242.220796) (xy 118.530501 -242.176264) (xy 118.515057 -242.128732)
			(xy 118.507238 -242.079369) (xy 116.322366 -242.079369) (xy 116.314547 -242.128732) (xy 116.299103 -242.176264)
			(xy 116.276413 -242.220796) (xy 116.247037 -242.261229) (xy 116.211697 -242.296569) (xy 116.171264 -242.325945)
			(xy 116.126732 -242.348635) (xy 116.0792 -242.364079) (xy 116.029837 -242.371898) (xy 115.979859 -242.371898)
			(xy 115.930496 -242.364079) (xy 115.882964 -242.348635) (xy 115.838432 -242.325945) (xy 115.797999 -242.296569)
			(xy 115.762659 -242.261229) (xy 115.733283 -242.220796) (xy 115.710593 -242.176264) (xy 115.695149 -242.128732)
			(xy 115.68733 -242.079369) (xy 115.380013 -242.079369) (xy 115.380004 -242.079826) (xy 115.37184 -242.13006)
			(xy 115.355724 -242.178334) (xy 115.332073 -242.223397) (xy 115.3015 -242.264083) (xy 115.264796 -242.299338)
			(xy 115.222912 -242.328248) (xy 115.176933 -242.350065) (xy 115.128049 -242.364225) (xy 115.077528 -242.370359)
			(xy 115.026676 -242.36831) (xy 114.976812 -242.35813) (xy 114.929226 -242.340083) (xy 114.885152 -242.314637)
			(xy 114.84573 -242.28245) (xy 114.811982 -242.244356) (xy 114.784781 -242.201342) (xy 114.764833 -242.154522)
			(xy 114.752654 -242.105108) (xy 114.748559 -242.05438) (xy 114.440462 -242.05438) (xy 114.43995 -242.079826)
			(xy 114.431786 -242.13006) (xy 114.41567 -242.178334) (xy 114.392019 -242.223397) (xy 114.361446 -242.264083)
			(xy 114.324742 -242.299338) (xy 114.282858 -242.328248) (xy 114.236879 -242.350065) (xy 114.187995 -242.364225)
			(xy 114.137474 -242.370359) (xy 114.086622 -242.36831) (xy 114.036758 -242.35813) (xy 113.989172 -242.340083)
			(xy 113.945098 -242.314637) (xy 113.905676 -242.28245) (xy 113.871928 -242.244356) (xy 113.844727 -242.201342)
			(xy 113.824779 -242.154522) (xy 113.8126 -242.105108) (xy 113.808505 -242.05438) (xy 113.502694 -242.05438)
			(xy 113.502204 -242.079369) (xy 113.494385 -242.128732) (xy 113.478941 -242.176264) (xy 113.456251 -242.220796)
			(xy 113.426875 -242.261229) (xy 113.391535 -242.296569) (xy 113.351102 -242.325945) (xy 113.30657 -242.348635)
			(xy 113.259038 -242.364079) (xy 113.209675 -242.371898) (xy 113.159697 -242.371898) (xy 113.110334 -242.364079)
			(xy 113.062802 -242.348635) (xy 113.01827 -242.325945) (xy 112.977837 -242.296569) (xy 112.942497 -242.261229)
			(xy 112.913121 -242.220796) (xy 112.890431 -242.176264) (xy 112.874987 -242.128732) (xy 112.867168 -242.079369)
			(xy 110.688646 -242.079369) (xy 110.680827 -242.128732) (xy 110.665383 -242.176264) (xy 110.642693 -242.220796)
			(xy 110.613317 -242.261229) (xy 110.577977 -242.296569) (xy 110.537544 -242.325945) (xy 110.493012 -242.348635)
			(xy 110.44548 -242.364079) (xy 110.396117 -242.371898) (xy 110.346139 -242.371898) (xy 110.296776 -242.364079)
			(xy 110.249244 -242.348635) (xy 110.204712 -242.325945) (xy 110.164279 -242.296569) (xy 110.128939 -242.261229)
			(xy 110.099563 -242.220796) (xy 110.076873 -242.176264) (xy 110.061429 -242.128732) (xy 110.05361 -242.079369)
			(xy 109.746293 -242.079369) (xy 109.746284 -242.079826) (xy 109.73812 -242.13006) (xy 109.722004 -242.178334)
			(xy 109.698353 -242.223397) (xy 109.66778 -242.264083) (xy 109.631076 -242.299338) (xy 109.589192 -242.328248)
			(xy 109.543213 -242.350065) (xy 109.494329 -242.364225) (xy 109.443808 -242.370359) (xy 109.392956 -242.36831)
			(xy 109.343092 -242.35813) (xy 109.295506 -242.340083) (xy 109.251432 -242.314637) (xy 109.21201 -242.28245)
			(xy 109.178262 -242.244356) (xy 109.151061 -242.201342) (xy 109.131113 -242.154522) (xy 109.118934 -242.105108)
			(xy 109.114839 -242.05438) (xy 108.806742 -242.05438) (xy 108.80623 -242.079826) (xy 108.798066 -242.13006)
			(xy 108.78195 -242.178334) (xy 108.758299 -242.223397) (xy 108.727726 -242.264083) (xy 108.691022 -242.299338)
			(xy 108.649138 -242.328248) (xy 108.603159 -242.350065) (xy 108.554275 -242.364225) (xy 108.503754 -242.370359)
			(xy 108.452902 -242.36831) (xy 108.403038 -242.35813) (xy 108.355452 -242.340083) (xy 108.311378 -242.314637)
			(xy 108.271956 -242.28245) (xy 108.238208 -242.244356) (xy 108.211007 -242.201342) (xy 108.191059 -242.154522)
			(xy 108.17888 -242.105108) (xy 108.174785 -242.05438) (xy 107.868974 -242.05438) (xy 107.868484 -242.079369)
			(xy 107.860665 -242.128732) (xy 107.845221 -242.176264) (xy 107.822531 -242.220796) (xy 107.793155 -242.261229)
			(xy 107.757815 -242.296569) (xy 107.717382 -242.325945) (xy 107.67285 -242.348635) (xy 107.625318 -242.364079)
			(xy 107.575955 -242.371898) (xy 107.525977 -242.371898) (xy 107.476614 -242.364079) (xy 107.429082 -242.348635)
			(xy 107.38455 -242.325945) (xy 107.344117 -242.296569) (xy 107.308777 -242.261229) (xy 107.279401 -242.220796)
			(xy 107.256711 -242.176264) (xy 107.241267 -242.128732) (xy 107.233448 -242.079369) (xy 105.048576 -242.079369)
			(xy 105.040757 -242.128732) (xy 105.025313 -242.176264) (xy 105.002623 -242.220796) (xy 104.973247 -242.261229)
			(xy 104.937907 -242.296569) (xy 104.897474 -242.325945) (xy 104.852942 -242.348635) (xy 104.80541 -242.364079)
			(xy 104.756047 -242.371898) (xy 104.706069 -242.371898) (xy 104.656706 -242.364079) (xy 104.609174 -242.348635)
			(xy 104.564642 -242.325945) (xy 104.524209 -242.296569) (xy 104.488869 -242.261229) (xy 104.459493 -242.220796)
			(xy 104.436803 -242.176264) (xy 104.421359 -242.128732) (xy 104.41354 -242.079369) (xy 102.228668 -242.079369)
			(xy 102.220849 -242.128732) (xy 102.205405 -242.176264) (xy 102.182715 -242.220796) (xy 102.153339 -242.261229)
			(xy 102.117999 -242.296569) (xy 102.077566 -242.325945) (xy 102.033034 -242.348635) (xy 101.985502 -242.364079)
			(xy 101.936139 -242.371898) (xy 101.886161 -242.371898) (xy 101.836798 -242.364079) (xy 101.789266 -242.348635)
			(xy 101.744734 -242.325945) (xy 101.704301 -242.296569) (xy 101.668961 -242.261229) (xy 101.639585 -242.220796)
			(xy 101.616895 -242.176264) (xy 101.601451 -242.128732) (xy 101.593632 -242.079369) (xy 99.408506 -242.079369)
			(xy 99.400687 -242.128732) (xy 99.385243 -242.176264) (xy 99.362553 -242.220796) (xy 99.333177 -242.261229)
			(xy 99.297837 -242.296569) (xy 99.257404 -242.325945) (xy 99.212872 -242.348635) (xy 99.16534 -242.364079)
			(xy 99.115977 -242.371898) (xy 99.065999 -242.371898) (xy 99.016636 -242.364079) (xy 98.969104 -242.348635)
			(xy 98.924572 -242.325945) (xy 98.884139 -242.296569) (xy 98.848799 -242.261229) (xy 98.819423 -242.220796)
			(xy 98.796733 -242.176264) (xy 98.781289 -242.128732) (xy 98.77347 -242.079369) (xy 97.057464 -242.079369)
			(xy 97.057464 -242.826794) (xy 97.057718 -242.831366) (xy 97.058988 -242.861846) (xy 97.058988 -242.864386)
			(xy 97.364799 -242.864386) (xy 97.368894 -242.813658) (xy 97.381073 -242.764244) (xy 97.401021 -242.717424)
			(xy 97.428222 -242.67441) (xy 97.46197 -242.636316) (xy 97.501392 -242.604129) (xy 97.545466 -242.578683)
			(xy 97.593052 -242.560636) (xy 97.642916 -242.550456) (xy 97.693768 -242.548407) (xy 97.744289 -242.554541)
			(xy 97.793173 -242.568701) (xy 97.839152 -242.590518) (xy 97.881036 -242.619428) (xy 97.91774 -242.654683)
			(xy 97.948313 -242.695369) (xy 97.971964 -242.740432) (xy 97.98808 -242.788706) (xy 97.996244 -242.83894)
			(xy 97.996756 -242.864386) (xy 98.304853 -242.864386) (xy 98.308948 -242.813658) (xy 98.321127 -242.764244)
			(xy 98.341075 -242.717424) (xy 98.368276 -242.67441) (xy 98.402024 -242.636316) (xy 98.441446 -242.604129)
			(xy 98.48552 -242.578683) (xy 98.533106 -242.560636) (xy 98.58297 -242.550456) (xy 98.633822 -242.548407)
			(xy 98.684343 -242.554541) (xy 98.733227 -242.568701) (xy 98.779206 -242.590518) (xy 98.82109 -242.619428)
			(xy 98.857794 -242.654683) (xy 98.888367 -242.695369) (xy 98.912018 -242.740432) (xy 98.928134 -242.788706)
			(xy 98.936298 -242.83894) (xy 98.93681 -242.864386) (xy 98.936307 -242.889375) (xy 99.243624 -242.889375)
			(xy 99.243624 -242.839397) (xy 99.251443 -242.790034) (xy 99.266887 -242.742502) (xy 99.289577 -242.69797)
			(xy 99.318953 -242.657537) (xy 99.354293 -242.622197) (xy 99.394726 -242.592821) (xy 99.439258 -242.570131)
			(xy 99.48679 -242.554687) (xy 99.536153 -242.546868) (xy 99.586131 -242.546868) (xy 99.635494 -242.554687)
			(xy 99.683026 -242.570131) (xy 99.727558 -242.592821) (xy 99.767991 -242.622197) (xy 99.803331 -242.657537)
			(xy 99.832707 -242.69797) (xy 99.855397 -242.742502) (xy 99.870841 -242.790034) (xy 99.87866 -242.839397)
			(xy 99.87915 -242.864386) (xy 100.184707 -242.864386) (xy 100.188802 -242.813658) (xy 100.200981 -242.764244)
			(xy 100.220929 -242.717424) (xy 100.24813 -242.67441) (xy 100.281878 -242.636316) (xy 100.3213 -242.604129)
			(xy 100.365374 -242.578683) (xy 100.41296 -242.560636) (xy 100.462824 -242.550456) (xy 100.513676 -242.548407)
			(xy 100.564197 -242.554541) (xy 100.613081 -242.568701) (xy 100.65906 -242.590518) (xy 100.700944 -242.619428)
			(xy 100.737648 -242.654683) (xy 100.768221 -242.695369) (xy 100.791872 -242.740432) (xy 100.807988 -242.788706)
			(xy 100.816152 -242.83894) (xy 100.816664 -242.864386) (xy 101.124761 -242.864386) (xy 101.128856 -242.813658)
			(xy 101.141035 -242.764244) (xy 101.160983 -242.717424) (xy 101.188184 -242.67441) (xy 101.221932 -242.636316)
			(xy 101.261354 -242.604129) (xy 101.305428 -242.578683) (xy 101.353014 -242.560636) (xy 101.402878 -242.550456)
			(xy 101.45373 -242.548407) (xy 101.504251 -242.554541) (xy 101.553135 -242.568701) (xy 101.599114 -242.590518)
			(xy 101.640998 -242.619428) (xy 101.677702 -242.654683) (xy 101.708275 -242.695369) (xy 101.731926 -242.740432)
			(xy 101.748042 -242.788706) (xy 101.756206 -242.83894) (xy 101.756718 -242.864386) (xy 101.756215 -242.889375)
			(xy 102.063532 -242.889375) (xy 102.063532 -242.839397) (xy 102.071351 -242.790034) (xy 102.086795 -242.742502)
			(xy 102.109485 -242.69797) (xy 102.138861 -242.657537) (xy 102.174201 -242.622197) (xy 102.214634 -242.592821)
			(xy 102.259166 -242.570131) (xy 102.306698 -242.554687) (xy 102.356061 -242.546868) (xy 102.406039 -242.546868)
			(xy 102.455402 -242.554687) (xy 102.502934 -242.570131) (xy 102.547466 -242.592821) (xy 102.587899 -242.622197)
			(xy 102.623239 -242.657537) (xy 102.652615 -242.69797) (xy 102.675305 -242.742502) (xy 102.690749 -242.790034)
			(xy 102.698568 -242.839397) (xy 102.699058 -242.864386) (xy 103.004869 -242.864386) (xy 103.008964 -242.813658)
			(xy 103.021143 -242.764244) (xy 103.041091 -242.717424) (xy 103.068292 -242.67441) (xy 103.10204 -242.636316)
			(xy 103.141462 -242.604129) (xy 103.185536 -242.578683) (xy 103.233122 -242.560636) (xy 103.282986 -242.550456)
			(xy 103.333838 -242.548407) (xy 103.384359 -242.554541) (xy 103.433243 -242.568701) (xy 103.479222 -242.590518)
			(xy 103.521106 -242.619428) (xy 103.55781 -242.654683) (xy 103.588383 -242.695369) (xy 103.612034 -242.740432)
			(xy 103.62815 -242.788706) (xy 103.636314 -242.83894) (xy 103.636826 -242.864386) (xy 103.944923 -242.864386)
			(xy 103.949018 -242.813658) (xy 103.961197 -242.764244) (xy 103.981145 -242.717424) (xy 104.008346 -242.67441)
			(xy 104.042094 -242.636316) (xy 104.081516 -242.604129) (xy 104.12559 -242.578683) (xy 104.173176 -242.560636)
			(xy 104.22304 -242.550456) (xy 104.273892 -242.548407) (xy 104.324413 -242.554541) (xy 104.373297 -242.568701)
			(xy 104.419276 -242.590518) (xy 104.46116 -242.619428) (xy 104.497864 -242.654683) (xy 104.528437 -242.695369)
			(xy 104.552088 -242.740432) (xy 104.568204 -242.788706) (xy 104.576368 -242.83894) (xy 104.57688 -242.864386)
			(xy 104.576377 -242.889375) (xy 104.88344 -242.889375) (xy 104.88344 -242.839397) (xy 104.891259 -242.790034)
			(xy 104.906703 -242.742502) (xy 104.929393 -242.69797) (xy 104.958769 -242.657537) (xy 104.994109 -242.622197)
			(xy 105.034542 -242.592821) (xy 105.079074 -242.570131) (xy 105.126606 -242.554687) (xy 105.175969 -242.546868)
			(xy 105.225947 -242.546868) (xy 105.27531 -242.554687) (xy 105.322842 -242.570131) (xy 105.367374 -242.592821)
			(xy 105.407807 -242.622197) (xy 105.443147 -242.657537) (xy 105.472523 -242.69797) (xy 105.495213 -242.742502)
			(xy 105.510657 -242.790034) (xy 105.518476 -242.839397) (xy 105.518966 -242.864386) (xy 105.824777 -242.864386)
			(xy 105.828872 -242.813658) (xy 105.841051 -242.764244) (xy 105.860999 -242.717424) (xy 105.8882 -242.67441)
			(xy 105.921948 -242.636316) (xy 105.96137 -242.604129) (xy 106.005444 -242.578683) (xy 106.05303 -242.560636)
			(xy 106.102894 -242.550456) (xy 106.153746 -242.548407) (xy 106.204267 -242.554541) (xy 106.253151 -242.568701)
			(xy 106.29913 -242.590518) (xy 106.341014 -242.619428) (xy 106.377718 -242.654683) (xy 106.408291 -242.695369)
			(xy 106.431942 -242.740432) (xy 106.448058 -242.788706) (xy 106.456222 -242.83894) (xy 106.456734 -242.864386)
			(xy 106.764831 -242.864386) (xy 106.768926 -242.813658) (xy 106.781105 -242.764244) (xy 106.801053 -242.717424)
			(xy 106.828254 -242.67441) (xy 106.862002 -242.636316) (xy 106.901424 -242.604129) (xy 106.945498 -242.578683)
			(xy 106.993084 -242.560636) (xy 107.042948 -242.550456) (xy 107.0938 -242.548407) (xy 107.144321 -242.554541)
			(xy 107.193205 -242.568701) (xy 107.239184 -242.590518) (xy 107.281068 -242.619428) (xy 107.317772 -242.654683)
			(xy 107.348345 -242.695369) (xy 107.371996 -242.740432) (xy 107.388112 -242.788706) (xy 107.396276 -242.83894)
			(xy 107.396788 -242.864386) (xy 107.396285 -242.889375) (xy 107.703602 -242.889375) (xy 107.703602 -242.839397)
			(xy 107.711421 -242.790034) (xy 107.726865 -242.742502) (xy 107.749555 -242.69797) (xy 107.778931 -242.657537)
			(xy 107.814271 -242.622197) (xy 107.854704 -242.592821) (xy 107.899236 -242.570131) (xy 107.946768 -242.554687)
			(xy 107.996131 -242.546868) (xy 108.046109 -242.546868) (xy 108.095472 -242.554687) (xy 108.143004 -242.570131)
			(xy 108.187536 -242.592821) (xy 108.227969 -242.622197) (xy 108.263309 -242.657537) (xy 108.292685 -242.69797)
			(xy 108.315375 -242.742502) (xy 108.330819 -242.790034) (xy 108.338638 -242.839397) (xy 108.339128 -242.864386)
			(xy 108.338638 -242.889375) (xy 115.217176 -242.889375) (xy 115.217176 -242.839397) (xy 115.224995 -242.790034)
			(xy 115.240439 -242.742502) (xy 115.263129 -242.69797) (xy 115.292505 -242.657537) (xy 115.327845 -242.622197)
			(xy 115.368278 -242.592821) (xy 115.41281 -242.570131) (xy 115.460342 -242.554687) (xy 115.509705 -242.546868)
			(xy 115.559683 -242.546868) (xy 115.609046 -242.554687) (xy 115.656578 -242.570131) (xy 115.70111 -242.592821)
			(xy 115.741543 -242.622197) (xy 115.776883 -242.657537) (xy 115.806259 -242.69797) (xy 115.828949 -242.742502)
			(xy 115.844393 -242.790034) (xy 115.852212 -242.839397) (xy 115.852702 -242.864386) (xy 116.158513 -242.864386)
			(xy 116.162608 -242.813658) (xy 116.174787 -242.764244) (xy 116.194735 -242.717424) (xy 116.221936 -242.67441)
			(xy 116.255684 -242.636316) (xy 116.295106 -242.604129) (xy 116.33918 -242.578683) (xy 116.386766 -242.560636)
			(xy 116.43663 -242.550456) (xy 116.487482 -242.548407) (xy 116.538003 -242.554541) (xy 116.586887 -242.568701)
			(xy 116.632866 -242.590518) (xy 116.67475 -242.619428) (xy 116.711454 -242.654683) (xy 116.742027 -242.695369)
			(xy 116.765678 -242.740432) (xy 116.781794 -242.788706) (xy 116.789958 -242.83894) (xy 116.79047 -242.864386)
			(xy 117.098567 -242.864386) (xy 117.102662 -242.813658) (xy 117.114841 -242.764244) (xy 117.134789 -242.717424)
			(xy 117.16199 -242.67441) (xy 117.195738 -242.636316) (xy 117.23516 -242.604129) (xy 117.279234 -242.578683)
			(xy 117.32682 -242.560636) (xy 117.376684 -242.550456) (xy 117.427536 -242.548407) (xy 117.478057 -242.554541)
			(xy 117.526941 -242.568701) (xy 117.57292 -242.590518) (xy 117.614804 -242.619428) (xy 117.651508 -242.654683)
			(xy 117.682081 -242.695369) (xy 117.705732 -242.740432) (xy 117.721848 -242.788706) (xy 117.730012 -242.83894)
			(xy 117.730524 -242.864386) (xy 117.730021 -242.889375) (xy 118.037338 -242.889375) (xy 118.037338 -242.839397)
			(xy 118.045157 -242.790034) (xy 118.060601 -242.742502) (xy 118.083291 -242.69797) (xy 118.112667 -242.657537)
			(xy 118.148007 -242.622197) (xy 118.18844 -242.592821) (xy 118.232972 -242.570131) (xy 118.280504 -242.554687)
			(xy 118.329867 -242.546868) (xy 118.379845 -242.546868) (xy 118.429208 -242.554687) (xy 118.47674 -242.570131)
			(xy 118.521272 -242.592821) (xy 118.561705 -242.622197) (xy 118.597045 -242.657537) (xy 118.626421 -242.69797)
			(xy 118.649111 -242.742502) (xy 118.664555 -242.790034) (xy 118.672374 -242.839397) (xy 118.672864 -242.864386)
			(xy 118.978421 -242.864386) (xy 118.982516 -242.813658) (xy 118.994695 -242.764244) (xy 119.014643 -242.717424)
			(xy 119.041844 -242.67441) (xy 119.075592 -242.636316) (xy 119.115014 -242.604129) (xy 119.159088 -242.578683)
			(xy 119.206674 -242.560636) (xy 119.256538 -242.550456) (xy 119.30739 -242.548407) (xy 119.357911 -242.554541)
			(xy 119.406795 -242.568701) (xy 119.452774 -242.590518) (xy 119.494658 -242.619428) (xy 119.531362 -242.654683)
			(xy 119.561935 -242.695369) (xy 119.585586 -242.740432) (xy 119.601702 -242.788706) (xy 119.609866 -242.83894)
			(xy 119.610378 -242.864386) (xy 119.918475 -242.864386) (xy 119.92257 -242.813658) (xy 119.934749 -242.764244)
			(xy 119.954697 -242.717424) (xy 119.981898 -242.67441) (xy 120.015646 -242.636316) (xy 120.055068 -242.604129)
			(xy 120.099142 -242.578683) (xy 120.146728 -242.560636) (xy 120.196592 -242.550456) (xy 120.247444 -242.548407)
			(xy 120.297965 -242.554541) (xy 120.346849 -242.568701) (xy 120.392828 -242.590518) (xy 120.434712 -242.619428)
			(xy 120.471416 -242.654683) (xy 120.501989 -242.695369) (xy 120.52564 -242.740432) (xy 120.541756 -242.788706)
			(xy 120.54992 -242.83894) (xy 120.550432 -242.864386) (xy 120.549929 -242.889375) (xy 120.857246 -242.889375)
			(xy 120.857246 -242.839397) (xy 120.865065 -242.790034) (xy 120.880509 -242.742502) (xy 120.903199 -242.69797)
			(xy 120.932575 -242.657537) (xy 120.967915 -242.622197) (xy 121.008348 -242.592821) (xy 121.05288 -242.570131)
			(xy 121.100412 -242.554687) (xy 121.149775 -242.546868) (xy 121.199753 -242.546868) (xy 121.249116 -242.554687)
			(xy 121.296648 -242.570131) (xy 121.34118 -242.592821) (xy 121.381613 -242.622197) (xy 121.416953 -242.657537)
			(xy 121.446329 -242.69797) (xy 121.469019 -242.742502) (xy 121.484463 -242.790034) (xy 121.492282 -242.839397)
			(xy 121.492772 -242.864386) (xy 121.798583 -242.864386) (xy 121.802678 -242.813658) (xy 121.814857 -242.764244)
			(xy 121.834805 -242.717424) (xy 121.862006 -242.67441) (xy 121.895754 -242.636316) (xy 121.935176 -242.604129)
			(xy 121.97925 -242.578683) (xy 122.026836 -242.560636) (xy 122.0767 -242.550456) (xy 122.127552 -242.548407)
			(xy 122.178073 -242.554541) (xy 122.226957 -242.568701) (xy 122.272936 -242.590518) (xy 122.31482 -242.619428)
			(xy 122.351524 -242.654683) (xy 122.382097 -242.695369) (xy 122.405748 -242.740432) (xy 122.421864 -242.788706)
			(xy 122.430028 -242.83894) (xy 122.43054 -242.864386) (xy 122.738383 -242.864386) (xy 122.742478 -242.813658)
			(xy 122.754657 -242.764244) (xy 122.774605 -242.717424) (xy 122.801806 -242.67441) (xy 122.835554 -242.636316)
			(xy 122.874976 -242.604129) (xy 122.91905 -242.578683) (xy 122.966636 -242.560636) (xy 123.0165 -242.550456)
			(xy 123.067352 -242.548407) (xy 123.117873 -242.554541) (xy 123.166757 -242.568701) (xy 123.212736 -242.590518)
			(xy 123.25462 -242.619428) (xy 123.291324 -242.654683) (xy 123.321897 -242.695369) (xy 123.345548 -242.740432)
			(xy 123.361664 -242.788706) (xy 123.369828 -242.83894) (xy 123.37034 -242.864386) (xy 123.369837 -242.889375)
			(xy 123.677154 -242.889375) (xy 123.677154 -242.839397) (xy 123.684973 -242.790034) (xy 123.700417 -242.742502)
			(xy 123.723107 -242.69797) (xy 123.752483 -242.657537) (xy 123.787823 -242.622197) (xy 123.828256 -242.592821)
			(xy 123.872788 -242.570131) (xy 123.92032 -242.554687) (xy 123.969683 -242.546868) (xy 124.019661 -242.546868)
			(xy 124.069024 -242.554687) (xy 124.116556 -242.570131) (xy 124.161088 -242.592821) (xy 124.201521 -242.622197)
			(xy 124.236861 -242.657537) (xy 124.266237 -242.69797) (xy 124.288927 -242.742502) (xy 124.304371 -242.790034)
			(xy 124.31219 -242.839397) (xy 124.31268 -242.864386) (xy 124.618491 -242.864386) (xy 124.622586 -242.813658)
			(xy 124.634765 -242.764244) (xy 124.654713 -242.717424) (xy 124.681914 -242.67441) (xy 124.715662 -242.636316)
			(xy 124.755084 -242.604129) (xy 124.799158 -242.578683) (xy 124.846744 -242.560636) (xy 124.896608 -242.550456)
			(xy 124.94746 -242.548407) (xy 124.997981 -242.554541) (xy 125.046865 -242.568701) (xy 125.092844 -242.590518)
			(xy 125.134728 -242.619428) (xy 125.171432 -242.654683) (xy 125.202005 -242.695369) (xy 125.225656 -242.740432)
			(xy 125.241772 -242.788706) (xy 125.249936 -242.83894) (xy 125.250448 -242.864386) (xy 125.558545 -242.864386)
			(xy 125.56264 -242.813658) (xy 125.574819 -242.764244) (xy 125.594767 -242.717424) (xy 125.621968 -242.67441)
			(xy 125.655716 -242.636316) (xy 125.695138 -242.604129) (xy 125.739212 -242.578683) (xy 125.786798 -242.560636)
			(xy 125.836662 -242.550456) (xy 125.887514 -242.548407) (xy 125.938035 -242.554541) (xy 125.986919 -242.568701)
			(xy 126.032898 -242.590518) (xy 126.074782 -242.619428) (xy 126.111486 -242.654683) (xy 126.142059 -242.695369)
			(xy 126.16571 -242.740432) (xy 126.181826 -242.788706) (xy 126.18999 -242.83894) (xy 126.190502 -242.864386)
			(xy 126.18999 -242.889832) (xy 126.181826 -242.940066) (xy 126.16571 -242.98834) (xy 126.142059 -243.033403)
			(xy 126.111486 -243.074089) (xy 126.074782 -243.109344) (xy 126.032898 -243.138254) (xy 125.986919 -243.160071)
			(xy 125.938035 -243.174231) (xy 125.887514 -243.180365) (xy 125.836662 -243.178316) (xy 125.786798 -243.168136)
			(xy 125.739212 -243.150089) (xy 125.695138 -243.124643) (xy 125.655716 -243.092456) (xy 125.621968 -243.054362)
			(xy 125.594767 -243.011348) (xy 125.574819 -242.964528) (xy 125.56264 -242.915114) (xy 125.558545 -242.864386)
			(xy 125.250448 -242.864386) (xy 125.249936 -242.889832) (xy 125.241772 -242.940066) (xy 125.225656 -242.98834)
			(xy 125.202005 -243.033403) (xy 125.171432 -243.074089) (xy 125.134728 -243.109344) (xy 125.092844 -243.138254)
			(xy 125.046865 -243.160071) (xy 124.997981 -243.174231) (xy 124.94746 -243.180365) (xy 124.896608 -243.178316)
			(xy 124.846744 -243.168136) (xy 124.799158 -243.150089) (xy 124.755084 -243.124643) (xy 124.715662 -243.092456)
			(xy 124.681914 -243.054362) (xy 124.654713 -243.011348) (xy 124.634765 -242.964528) (xy 124.622586 -242.915114)
			(xy 124.618491 -242.864386) (xy 124.31268 -242.864386) (xy 124.31219 -242.889375) (xy 124.304371 -242.938738)
			(xy 124.288927 -242.98627) (xy 124.266237 -243.030802) (xy 124.236861 -243.071235) (xy 124.201521 -243.106575)
			(xy 124.161088 -243.135951) (xy 124.116556 -243.158641) (xy 124.069024 -243.174085) (xy 124.019661 -243.181904)
			(xy 123.969683 -243.181904) (xy 123.92032 -243.174085) (xy 123.872788 -243.158641) (xy 123.828256 -243.135951)
			(xy 123.787823 -243.106575) (xy 123.752483 -243.071235) (xy 123.723107 -243.030802) (xy 123.700417 -242.98627)
			(xy 123.684973 -242.938738) (xy 123.677154 -242.889375) (xy 123.369837 -242.889375) (xy 123.369828 -242.889832)
			(xy 123.361664 -242.940066) (xy 123.345548 -242.98834) (xy 123.321897 -243.033403) (xy 123.291324 -243.074089)
			(xy 123.25462 -243.109344) (xy 123.212736 -243.138254) (xy 123.166757 -243.160071) (xy 123.117873 -243.174231)
			(xy 123.067352 -243.180365) (xy 123.0165 -243.178316) (xy 122.966636 -243.168136) (xy 122.91905 -243.150089)
			(xy 122.874976 -243.124643) (xy 122.835554 -243.092456) (xy 122.801806 -243.054362) (xy 122.774605 -243.011348)
			(xy 122.754657 -242.964528) (xy 122.742478 -242.915114) (xy 122.738383 -242.864386) (xy 122.43054 -242.864386)
			(xy 122.430028 -242.889832) (xy 122.421864 -242.940066) (xy 122.405748 -242.98834) (xy 122.382097 -243.033403)
			(xy 122.351524 -243.074089) (xy 122.31482 -243.109344) (xy 122.272936 -243.138254) (xy 122.226957 -243.160071)
			(xy 122.178073 -243.174231) (xy 122.127552 -243.180365) (xy 122.0767 -243.178316) (xy 122.026836 -243.168136)
			(xy 121.97925 -243.150089) (xy 121.935176 -243.124643) (xy 121.895754 -243.092456) (xy 121.862006 -243.054362)
			(xy 121.834805 -243.011348) (xy 121.814857 -242.964528) (xy 121.802678 -242.915114) (xy 121.798583 -242.864386)
			(xy 121.492772 -242.864386) (xy 121.492282 -242.889375) (xy 121.484463 -242.938738) (xy 121.469019 -242.98627)
			(xy 121.446329 -243.030802) (xy 121.416953 -243.071235) (xy 121.381613 -243.106575) (xy 121.34118 -243.135951)
			(xy 121.296648 -243.158641) (xy 121.249116 -243.174085) (xy 121.199753 -243.181904) (xy 121.149775 -243.181904)
			(xy 121.100412 -243.174085) (xy 121.05288 -243.158641) (xy 121.008348 -243.135951) (xy 120.967915 -243.106575)
			(xy 120.932575 -243.071235) (xy 120.903199 -243.030802) (xy 120.880509 -242.98627) (xy 120.865065 -242.938738)
			(xy 120.857246 -242.889375) (xy 120.549929 -242.889375) (xy 120.54992 -242.889832) (xy 120.541756 -242.940066)
			(xy 120.52564 -242.98834) (xy 120.501989 -243.033403) (xy 120.471416 -243.074089) (xy 120.434712 -243.109344)
			(xy 120.392828 -243.138254) (xy 120.346849 -243.160071) (xy 120.297965 -243.174231) (xy 120.247444 -243.180365)
			(xy 120.196592 -243.178316) (xy 120.146728 -243.168136) (xy 120.099142 -243.150089) (xy 120.055068 -243.124643)
			(xy 120.015646 -243.092456) (xy 119.981898 -243.054362) (xy 119.954697 -243.011348) (xy 119.934749 -242.964528)
			(xy 119.92257 -242.915114) (xy 119.918475 -242.864386) (xy 119.610378 -242.864386) (xy 119.609866 -242.889832)
			(xy 119.601702 -242.940066) (xy 119.585586 -242.98834) (xy 119.561935 -243.033403) (xy 119.531362 -243.074089)
			(xy 119.494658 -243.109344) (xy 119.452774 -243.138254) (xy 119.406795 -243.160071) (xy 119.357911 -243.174231)
			(xy 119.30739 -243.180365) (xy 119.256538 -243.178316) (xy 119.206674 -243.168136) (xy 119.159088 -243.150089)
			(xy 119.115014 -243.124643) (xy 119.075592 -243.092456) (xy 119.041844 -243.054362) (xy 119.014643 -243.011348)
			(xy 118.994695 -242.964528) (xy 118.982516 -242.915114) (xy 118.978421 -242.864386) (xy 118.672864 -242.864386)
			(xy 118.672374 -242.889375) (xy 118.664555 -242.938738) (xy 118.649111 -242.98627) (xy 118.626421 -243.030802)
			(xy 118.597045 -243.071235) (xy 118.561705 -243.106575) (xy 118.521272 -243.135951) (xy 118.47674 -243.158641)
			(xy 118.429208 -243.174085) (xy 118.379845 -243.181904) (xy 118.329867 -243.181904) (xy 118.280504 -243.174085)
			(xy 118.232972 -243.158641) (xy 118.18844 -243.135951) (xy 118.148007 -243.106575) (xy 118.112667 -243.071235)
			(xy 118.083291 -243.030802) (xy 118.060601 -242.98627) (xy 118.045157 -242.938738) (xy 118.037338 -242.889375)
			(xy 117.730021 -242.889375) (xy 117.730012 -242.889832) (xy 117.721848 -242.940066) (xy 117.705732 -242.98834)
			(xy 117.682081 -243.033403) (xy 117.651508 -243.074089) (xy 117.614804 -243.109344) (xy 117.57292 -243.138254)
			(xy 117.526941 -243.160071) (xy 117.478057 -243.174231) (xy 117.427536 -243.180365) (xy 117.376684 -243.178316)
			(xy 117.32682 -243.168136) (xy 117.279234 -243.150089) (xy 117.23516 -243.124643) (xy 117.195738 -243.092456)
			(xy 117.16199 -243.054362) (xy 117.134789 -243.011348) (xy 117.114841 -242.964528) (xy 117.102662 -242.915114)
			(xy 117.098567 -242.864386) (xy 116.79047 -242.864386) (xy 116.789958 -242.889832) (xy 116.781794 -242.940066)
			(xy 116.765678 -242.98834) (xy 116.742027 -243.033403) (xy 116.711454 -243.074089) (xy 116.67475 -243.109344)
			(xy 116.632866 -243.138254) (xy 116.586887 -243.160071) (xy 116.538003 -243.174231) (xy 116.487482 -243.180365)
			(xy 116.43663 -243.178316) (xy 116.386766 -243.168136) (xy 116.33918 -243.150089) (xy 116.295106 -243.124643)
			(xy 116.255684 -243.092456) (xy 116.221936 -243.054362) (xy 116.194735 -243.011348) (xy 116.174787 -242.964528)
			(xy 116.162608 -242.915114) (xy 116.158513 -242.864386) (xy 115.852702 -242.864386) (xy 115.852212 -242.889375)
			(xy 115.844393 -242.938738) (xy 115.828949 -242.98627) (xy 115.806259 -243.030802) (xy 115.776883 -243.071235)
			(xy 115.741543 -243.106575) (xy 115.70111 -243.135951) (xy 115.656578 -243.158641) (xy 115.609046 -243.174085)
			(xy 115.559683 -243.181904) (xy 115.509705 -243.181904) (xy 115.460342 -243.174085) (xy 115.41281 -243.158641)
			(xy 115.368278 -243.135951) (xy 115.327845 -243.106575) (xy 115.292505 -243.071235) (xy 115.263129 -243.030802)
			(xy 115.240439 -242.98627) (xy 115.224995 -242.938738) (xy 115.217176 -242.889375) (xy 108.338638 -242.889375)
			(xy 108.330819 -242.938738) (xy 108.315375 -242.98627) (xy 108.292685 -243.030802) (xy 108.263309 -243.071235)
			(xy 108.227969 -243.106575) (xy 108.187536 -243.135951) (xy 108.143004 -243.158641) (xy 108.095472 -243.174085)
			(xy 108.046109 -243.181904) (xy 107.996131 -243.181904) (xy 107.946768 -243.174085) (xy 107.899236 -243.158641)
			(xy 107.854704 -243.135951) (xy 107.814271 -243.106575) (xy 107.778931 -243.071235) (xy 107.749555 -243.030802)
			(xy 107.726865 -242.98627) (xy 107.711421 -242.938738) (xy 107.703602 -242.889375) (xy 107.396285 -242.889375)
			(xy 107.396276 -242.889832) (xy 107.388112 -242.940066) (xy 107.371996 -242.98834) (xy 107.348345 -243.033403)
			(xy 107.317772 -243.074089) (xy 107.281068 -243.109344) (xy 107.239184 -243.138254) (xy 107.193205 -243.160071)
			(xy 107.144321 -243.174231) (xy 107.0938 -243.180365) (xy 107.042948 -243.178316) (xy 106.993084 -243.168136)
			(xy 106.945498 -243.150089) (xy 106.901424 -243.124643) (xy 106.862002 -243.092456) (xy 106.828254 -243.054362)
			(xy 106.801053 -243.011348) (xy 106.781105 -242.964528) (xy 106.768926 -242.915114) (xy 106.764831 -242.864386)
			(xy 106.456734 -242.864386) (xy 106.456222 -242.889832) (xy 106.448058 -242.940066) (xy 106.431942 -242.98834)
			(xy 106.408291 -243.033403) (xy 106.377718 -243.074089) (xy 106.341014 -243.109344) (xy 106.29913 -243.138254)
			(xy 106.253151 -243.160071) (xy 106.204267 -243.174231) (xy 106.153746 -243.180365) (xy 106.102894 -243.178316)
			(xy 106.05303 -243.168136) (xy 106.005444 -243.150089) (xy 105.96137 -243.124643) (xy 105.921948 -243.092456)
			(xy 105.8882 -243.054362) (xy 105.860999 -243.011348) (xy 105.841051 -242.964528) (xy 105.828872 -242.915114)
			(xy 105.824777 -242.864386) (xy 105.518966 -242.864386) (xy 105.518476 -242.889375) (xy 105.510657 -242.938738)
			(xy 105.495213 -242.98627) (xy 105.472523 -243.030802) (xy 105.443147 -243.071235) (xy 105.407807 -243.106575)
			(xy 105.367374 -243.135951) (xy 105.322842 -243.158641) (xy 105.27531 -243.174085) (xy 105.225947 -243.181904)
			(xy 105.175969 -243.181904) (xy 105.126606 -243.174085) (xy 105.079074 -243.158641) (xy 105.034542 -243.135951)
			(xy 104.994109 -243.106575) (xy 104.958769 -243.071235) (xy 104.929393 -243.030802) (xy 104.906703 -242.98627)
			(xy 104.891259 -242.938738) (xy 104.88344 -242.889375) (xy 104.576377 -242.889375) (xy 104.576368 -242.889832)
			(xy 104.568204 -242.940066) (xy 104.552088 -242.98834) (xy 104.528437 -243.033403) (xy 104.497864 -243.074089)
			(xy 104.46116 -243.109344) (xy 104.419276 -243.138254) (xy 104.373297 -243.160071) (xy 104.324413 -243.174231)
			(xy 104.273892 -243.180365) (xy 104.22304 -243.178316) (xy 104.173176 -243.168136) (xy 104.12559 -243.150089)
			(xy 104.081516 -243.124643) (xy 104.042094 -243.092456) (xy 104.008346 -243.054362) (xy 103.981145 -243.011348)
			(xy 103.961197 -242.964528) (xy 103.949018 -242.915114) (xy 103.944923 -242.864386) (xy 103.636826 -242.864386)
			(xy 103.636314 -242.889832) (xy 103.62815 -242.940066) (xy 103.612034 -242.98834) (xy 103.588383 -243.033403)
			(xy 103.55781 -243.074089) (xy 103.521106 -243.109344) (xy 103.479222 -243.138254) (xy 103.433243 -243.160071)
			(xy 103.384359 -243.174231) (xy 103.333838 -243.180365) (xy 103.282986 -243.178316) (xy 103.233122 -243.168136)
			(xy 103.185536 -243.150089) (xy 103.141462 -243.124643) (xy 103.10204 -243.092456) (xy 103.068292 -243.054362)
			(xy 103.041091 -243.011348) (xy 103.021143 -242.964528) (xy 103.008964 -242.915114) (xy 103.004869 -242.864386)
			(xy 102.699058 -242.864386) (xy 102.698568 -242.889375) (xy 102.690749 -242.938738) (xy 102.675305 -242.98627)
			(xy 102.652615 -243.030802) (xy 102.623239 -243.071235) (xy 102.587899 -243.106575) (xy 102.547466 -243.135951)
			(xy 102.502934 -243.158641) (xy 102.455402 -243.174085) (xy 102.406039 -243.181904) (xy 102.356061 -243.181904)
			(xy 102.306698 -243.174085) (xy 102.259166 -243.158641) (xy 102.214634 -243.135951) (xy 102.174201 -243.106575)
			(xy 102.138861 -243.071235) (xy 102.109485 -243.030802) (xy 102.086795 -242.98627) (xy 102.071351 -242.938738)
			(xy 102.063532 -242.889375) (xy 101.756215 -242.889375) (xy 101.756206 -242.889832) (xy 101.748042 -242.940066)
			(xy 101.731926 -242.98834) (xy 101.708275 -243.033403) (xy 101.677702 -243.074089) (xy 101.640998 -243.109344)
			(xy 101.599114 -243.138254) (xy 101.553135 -243.160071) (xy 101.504251 -243.174231) (xy 101.45373 -243.180365)
			(xy 101.402878 -243.178316) (xy 101.353014 -243.168136) (xy 101.305428 -243.150089) (xy 101.261354 -243.124643)
			(xy 101.221932 -243.092456) (xy 101.188184 -243.054362) (xy 101.160983 -243.011348) (xy 101.141035 -242.964528)
			(xy 101.128856 -242.915114) (xy 101.124761 -242.864386) (xy 100.816664 -242.864386) (xy 100.816152 -242.889832)
			(xy 100.807988 -242.940066) (xy 100.791872 -242.98834) (xy 100.768221 -243.033403) (xy 100.737648 -243.074089)
			(xy 100.700944 -243.109344) (xy 100.65906 -243.138254) (xy 100.613081 -243.160071) (xy 100.564197 -243.174231)
			(xy 100.513676 -243.180365) (xy 100.462824 -243.178316) (xy 100.41296 -243.168136) (xy 100.365374 -243.150089)
			(xy 100.3213 -243.124643) (xy 100.281878 -243.092456) (xy 100.24813 -243.054362) (xy 100.220929 -243.011348)
			(xy 100.200981 -242.964528) (xy 100.188802 -242.915114) (xy 100.184707 -242.864386) (xy 99.87915 -242.864386)
			(xy 99.87866 -242.889375) (xy 99.870841 -242.938738) (xy 99.855397 -242.98627) (xy 99.832707 -243.030802)
			(xy 99.803331 -243.071235) (xy 99.767991 -243.106575) (xy 99.727558 -243.135951) (xy 99.683026 -243.158641)
			(xy 99.635494 -243.174085) (xy 99.586131 -243.181904) (xy 99.536153 -243.181904) (xy 99.48679 -243.174085)
			(xy 99.439258 -243.158641) (xy 99.394726 -243.135951) (xy 99.354293 -243.106575) (xy 99.318953 -243.071235)
			(xy 99.289577 -243.030802) (xy 99.266887 -242.98627) (xy 99.251443 -242.938738) (xy 99.243624 -242.889375)
			(xy 98.936307 -242.889375) (xy 98.936298 -242.889832) (xy 98.928134 -242.940066) (xy 98.912018 -242.98834)
			(xy 98.888367 -243.033403) (xy 98.857794 -243.074089) (xy 98.82109 -243.109344) (xy 98.779206 -243.138254)
			(xy 98.733227 -243.160071) (xy 98.684343 -243.174231) (xy 98.633822 -243.180365) (xy 98.58297 -243.178316)
			(xy 98.533106 -243.168136) (xy 98.48552 -243.150089) (xy 98.441446 -243.124643) (xy 98.402024 -243.092456)
			(xy 98.368276 -243.054362) (xy 98.341075 -243.011348) (xy 98.321127 -242.964528) (xy 98.308948 -242.915114)
			(xy 98.304853 -242.864386) (xy 97.996756 -242.864386) (xy 97.996244 -242.889832) (xy 97.98808 -242.940066)
			(xy 97.971964 -242.98834) (xy 97.948313 -243.033403) (xy 97.91774 -243.074089) (xy 97.881036 -243.109344)
			(xy 97.839152 -243.138254) (xy 97.793173 -243.160071) (xy 97.744289 -243.174231) (xy 97.693768 -243.180365)
			(xy 97.642916 -243.178316) (xy 97.593052 -243.168136) (xy 97.545466 -243.150089) (xy 97.501392 -243.124643)
			(xy 97.46197 -243.092456) (xy 97.428222 -243.054362) (xy 97.401021 -243.011348) (xy 97.381073 -242.964528)
			(xy 97.368894 -242.915114) (xy 97.364799 -242.864386) (xy 97.058988 -242.864386) (xy 97.058988 -242.867942)
			(xy 97.057718 -242.897914) (xy 97.057464 -242.899438) (xy 97.057464 -243.259102) (xy 97.057939 -243.269853)
			(xy 97.066747 -243.289467) (xy 97.074482 -243.296948) (xy 97.092516 -243.31295) (xy 97.130362 -243.346478)
			(xy 97.13087 -243.346478) (xy 97.131886 -243.347494) (xy 97.155508 -243.34343) (xy 97.169313 -243.341276)
			(xy 97.197162 -243.338984) (xy 97.211134 -243.338858) (xy 97.237499 -243.339378) (xy 97.28958 -243.347631)
			(xy 97.339729 -243.36393) (xy 97.38671 -243.387872) (xy 97.429368 -243.418869) (xy 97.466653 -243.456157)
			(xy 97.497645 -243.498819) (xy 97.521583 -243.545803) (xy 97.537877 -243.595953) (xy 97.546125 -243.648035)
			(xy 97.546125 -243.699381) (xy 97.833416 -243.699381) (xy 97.833416 -243.649403) (xy 97.841235 -243.60004)
			(xy 97.856679 -243.552508) (xy 97.879369 -243.507976) (xy 97.908745 -243.467543) (xy 97.944085 -243.432203)
			(xy 97.984518 -243.402827) (xy 98.02905 -243.380137) (xy 98.076582 -243.364693) (xy 98.125945 -243.356874)
			(xy 98.175923 -243.356874) (xy 98.225286 -243.364693) (xy 98.272818 -243.380137) (xy 98.31735 -243.402827)
			(xy 98.357783 -243.432203) (xy 98.393123 -243.467543) (xy 98.422499 -243.507976) (xy 98.445189 -243.552508)
			(xy 98.460633 -243.60004) (xy 98.468452 -243.649403) (xy 98.468942 -243.674392) (xy 98.468452 -243.699381)
			(xy 98.77347 -243.699381) (xy 98.77347 -243.649403) (xy 98.781289 -243.60004) (xy 98.796733 -243.552508)
			(xy 98.819423 -243.507976) (xy 98.848799 -243.467543) (xy 98.884139 -243.432203) (xy 98.924572 -243.402827)
			(xy 98.969104 -243.380137) (xy 99.016636 -243.364693) (xy 99.065999 -243.356874) (xy 99.115977 -243.356874)
			(xy 99.16534 -243.364693) (xy 99.212872 -243.380137) (xy 99.257404 -243.402827) (xy 99.297837 -243.432203)
			(xy 99.333177 -243.467543) (xy 99.362553 -243.507976) (xy 99.385243 -243.552508) (xy 99.400687 -243.60004)
			(xy 99.408506 -243.649403) (xy 99.408996 -243.674392) (xy 99.408506 -243.699381) (xy 99.713524 -243.699381)
			(xy 99.713524 -243.649403) (xy 99.721343 -243.60004) (xy 99.736787 -243.552508) (xy 99.759477 -243.507976)
			(xy 99.788853 -243.467543) (xy 99.824193 -243.432203) (xy 99.864626 -243.402827) (xy 99.909158 -243.380137)
			(xy 99.95669 -243.364693) (xy 100.006053 -243.356874) (xy 100.056031 -243.356874) (xy 100.105394 -243.364693)
			(xy 100.152926 -243.380137) (xy 100.197458 -243.402827) (xy 100.237891 -243.432203) (xy 100.273231 -243.467543)
			(xy 100.302607 -243.507976) (xy 100.325297 -243.552508) (xy 100.340741 -243.60004) (xy 100.34856 -243.649403)
			(xy 100.34905 -243.674392) (xy 100.34856 -243.699381) (xy 100.653578 -243.699381) (xy 100.653578 -243.649403)
			(xy 100.661397 -243.60004) (xy 100.676841 -243.552508) (xy 100.699531 -243.507976) (xy 100.728907 -243.467543)
			(xy 100.764247 -243.432203) (xy 100.80468 -243.402827) (xy 100.849212 -243.380137) (xy 100.896744 -243.364693)
			(xy 100.946107 -243.356874) (xy 100.996085 -243.356874) (xy 101.045448 -243.364693) (xy 101.09298 -243.380137)
			(xy 101.137512 -243.402827) (xy 101.177945 -243.432203) (xy 101.213285 -243.467543) (xy 101.242661 -243.507976)
			(xy 101.265351 -243.552508) (xy 101.280795 -243.60004) (xy 101.288614 -243.649403) (xy 101.289104 -243.674392)
			(xy 101.288614 -243.699381) (xy 101.593632 -243.699381) (xy 101.593632 -243.649403) (xy 101.601451 -243.60004)
			(xy 101.616895 -243.552508) (xy 101.639585 -243.507976) (xy 101.668961 -243.467543) (xy 101.704301 -243.432203)
			(xy 101.744734 -243.402827) (xy 101.789266 -243.380137) (xy 101.836798 -243.364693) (xy 101.886161 -243.356874)
			(xy 101.936139 -243.356874) (xy 101.985502 -243.364693) (xy 102.033034 -243.380137) (xy 102.077566 -243.402827)
			(xy 102.117999 -243.432203) (xy 102.153339 -243.467543) (xy 102.182715 -243.507976) (xy 102.205405 -243.552508)
			(xy 102.220849 -243.60004) (xy 102.228668 -243.649403) (xy 102.229158 -243.674392) (xy 102.228668 -243.699381)
			(xy 102.533432 -243.699381) (xy 102.533432 -243.649403) (xy 102.541251 -243.60004) (xy 102.556695 -243.552508)
			(xy 102.579385 -243.507976) (xy 102.608761 -243.467543) (xy 102.644101 -243.432203) (xy 102.684534 -243.402827)
			(xy 102.729066 -243.380137) (xy 102.776598 -243.364693) (xy 102.825961 -243.356874) (xy 102.875939 -243.356874)
			(xy 102.925302 -243.364693) (xy 102.972834 -243.380137) (xy 103.017366 -243.402827) (xy 103.057799 -243.432203)
			(xy 103.093139 -243.467543) (xy 103.122515 -243.507976) (xy 103.145205 -243.552508) (xy 103.160649 -243.60004)
			(xy 103.168468 -243.649403) (xy 103.168958 -243.674392) (xy 103.168468 -243.699381) (xy 103.473486 -243.699381)
			(xy 103.473486 -243.649403) (xy 103.481305 -243.60004) (xy 103.496749 -243.552508) (xy 103.519439 -243.507976)
			(xy 103.548815 -243.467543) (xy 103.584155 -243.432203) (xy 103.624588 -243.402827) (xy 103.66912 -243.380137)
			(xy 103.716652 -243.364693) (xy 103.766015 -243.356874) (xy 103.815993 -243.356874) (xy 103.865356 -243.364693)
			(xy 103.912888 -243.380137) (xy 103.95742 -243.402827) (xy 103.997853 -243.432203) (xy 104.033193 -243.467543)
			(xy 104.062569 -243.507976) (xy 104.085259 -243.552508) (xy 104.100703 -243.60004) (xy 104.108522 -243.649403)
			(xy 104.109012 -243.674392) (xy 104.108522 -243.699381) (xy 104.41354 -243.699381) (xy 104.41354 -243.649403)
			(xy 104.421359 -243.60004) (xy 104.436803 -243.552508) (xy 104.459493 -243.507976) (xy 104.488869 -243.467543)
			(xy 104.524209 -243.432203) (xy 104.564642 -243.402827) (xy 104.609174 -243.380137) (xy 104.656706 -243.364693)
			(xy 104.706069 -243.356874) (xy 104.756047 -243.356874) (xy 104.80541 -243.364693) (xy 104.852942 -243.380137)
			(xy 104.897474 -243.402827) (xy 104.937907 -243.432203) (xy 104.973247 -243.467543) (xy 105.002623 -243.507976)
			(xy 105.025313 -243.552508) (xy 105.040757 -243.60004) (xy 105.048576 -243.649403) (xy 105.049066 -243.674392)
			(xy 105.048576 -243.699381) (xy 105.353594 -243.699381) (xy 105.353594 -243.649403) (xy 105.361413 -243.60004)
			(xy 105.376857 -243.552508) (xy 105.399547 -243.507976) (xy 105.428923 -243.467543) (xy 105.464263 -243.432203)
			(xy 105.504696 -243.402827) (xy 105.549228 -243.380137) (xy 105.59676 -243.364693) (xy 105.646123 -243.356874)
			(xy 105.696101 -243.356874) (xy 105.745464 -243.364693) (xy 105.792996 -243.380137) (xy 105.837528 -243.402827)
			(xy 105.877961 -243.432203) (xy 105.913301 -243.467543) (xy 105.942677 -243.507976) (xy 105.965367 -243.552508)
			(xy 105.980811 -243.60004) (xy 105.98863 -243.649403) (xy 105.98912 -243.674392) (xy 105.98863 -243.699381)
			(xy 106.293648 -243.699381) (xy 106.293648 -243.649403) (xy 106.301467 -243.60004) (xy 106.316911 -243.552508)
			(xy 106.339601 -243.507976) (xy 106.368977 -243.467543) (xy 106.404317 -243.432203) (xy 106.44475 -243.402827)
			(xy 106.489282 -243.380137) (xy 106.536814 -243.364693) (xy 106.586177 -243.356874) (xy 106.636155 -243.356874)
			(xy 106.685518 -243.364693) (xy 106.73305 -243.380137) (xy 106.777582 -243.402827) (xy 106.818015 -243.432203)
			(xy 106.853355 -243.467543) (xy 106.882731 -243.507976) (xy 106.905421 -243.552508) (xy 106.920865 -243.60004)
			(xy 106.928684 -243.649403) (xy 106.929174 -243.674392) (xy 106.928684 -243.699381) (xy 107.233448 -243.699381)
			(xy 107.233448 -243.649403) (xy 107.241267 -243.60004) (xy 107.256711 -243.552508) (xy 107.279401 -243.507976)
			(xy 107.308777 -243.467543) (xy 107.344117 -243.432203) (xy 107.38455 -243.402827) (xy 107.429082 -243.380137)
			(xy 107.476614 -243.364693) (xy 107.525977 -243.356874) (xy 107.575955 -243.356874) (xy 107.625318 -243.364693)
			(xy 107.67285 -243.380137) (xy 107.717382 -243.402827) (xy 107.757815 -243.432203) (xy 107.793155 -243.467543)
			(xy 107.822531 -243.507976) (xy 107.845221 -243.552508) (xy 107.860665 -243.60004) (xy 107.868484 -243.649403)
			(xy 107.868974 -243.674392) (xy 108.174785 -243.674392) (xy 108.17888 -243.623664) (xy 108.191059 -243.57425)
			(xy 108.211007 -243.52743) (xy 108.238208 -243.484416) (xy 108.271956 -243.446322) (xy 108.311378 -243.414135)
			(xy 108.355452 -243.388689) (xy 108.403038 -243.370642) (xy 108.452902 -243.360462) (xy 108.503754 -243.358413)
			(xy 108.554275 -243.364547) (xy 108.603159 -243.378707) (xy 108.649138 -243.400524) (xy 108.691022 -243.429434)
			(xy 108.727726 -243.464689) (xy 108.758299 -243.505375) (xy 108.78195 -243.550438) (xy 108.798066 -243.598712)
			(xy 108.80623 -243.648946) (xy 108.806742 -243.674392) (xy 109.114839 -243.674392) (xy 109.118934 -243.623664)
			(xy 109.131113 -243.57425) (xy 109.151061 -243.52743) (xy 109.178262 -243.484416) (xy 109.21201 -243.446322)
			(xy 109.251432 -243.414135) (xy 109.295506 -243.388689) (xy 109.343092 -243.370642) (xy 109.392956 -243.360462)
			(xy 109.443808 -243.358413) (xy 109.494329 -243.364547) (xy 109.543213 -243.378707) (xy 109.589192 -243.400524)
			(xy 109.631076 -243.429434) (xy 109.66778 -243.464689) (xy 109.698353 -243.505375) (xy 109.722004 -243.550438)
			(xy 109.73812 -243.598712) (xy 109.746284 -243.648946) (xy 109.746796 -243.674392) (xy 109.746293 -243.699381)
			(xy 110.05361 -243.699381) (xy 110.05361 -243.649403) (xy 110.061429 -243.60004) (xy 110.076873 -243.552508)
			(xy 110.099563 -243.507976) (xy 110.128939 -243.467543) (xy 110.164279 -243.432203) (xy 110.204712 -243.402827)
			(xy 110.249244 -243.380137) (xy 110.296776 -243.364693) (xy 110.346139 -243.356874) (xy 110.396117 -243.356874)
			(xy 110.44548 -243.364693) (xy 110.493012 -243.380137) (xy 110.537544 -243.402827) (xy 110.577977 -243.432203)
			(xy 110.613317 -243.467543) (xy 110.642693 -243.507976) (xy 110.665383 -243.552508) (xy 110.680827 -243.60004)
			(xy 110.688646 -243.649403) (xy 110.689136 -243.674392) (xy 110.688646 -243.699381) (xy 112.867168 -243.699381)
			(xy 112.867168 -243.649403) (xy 112.874987 -243.60004) (xy 112.890431 -243.552508) (xy 112.913121 -243.507976)
			(xy 112.942497 -243.467543) (xy 112.977837 -243.432203) (xy 113.01827 -243.402827) (xy 113.062802 -243.380137)
			(xy 113.110334 -243.364693) (xy 113.159697 -243.356874) (xy 113.209675 -243.356874) (xy 113.259038 -243.364693)
			(xy 113.30657 -243.380137) (xy 113.351102 -243.402827) (xy 113.391535 -243.432203) (xy 113.426875 -243.467543)
			(xy 113.456251 -243.507976) (xy 113.478941 -243.552508) (xy 113.494385 -243.60004) (xy 113.502204 -243.649403)
			(xy 113.502694 -243.674392) (xy 113.808505 -243.674392) (xy 113.8126 -243.623664) (xy 113.824779 -243.57425)
			(xy 113.844727 -243.52743) (xy 113.871928 -243.484416) (xy 113.905676 -243.446322) (xy 113.945098 -243.414135)
			(xy 113.989172 -243.388689) (xy 114.036758 -243.370642) (xy 114.086622 -243.360462) (xy 114.137474 -243.358413)
			(xy 114.187995 -243.364547) (xy 114.236879 -243.378707) (xy 114.282858 -243.400524) (xy 114.324742 -243.429434)
			(xy 114.361446 -243.464689) (xy 114.392019 -243.505375) (xy 114.41567 -243.550438) (xy 114.431786 -243.598712)
			(xy 114.43995 -243.648946) (xy 114.440462 -243.674392) (xy 114.748559 -243.674392) (xy 114.752654 -243.623664)
			(xy 114.764833 -243.57425) (xy 114.784781 -243.52743) (xy 114.811982 -243.484416) (xy 114.84573 -243.446322)
			(xy 114.885152 -243.414135) (xy 114.929226 -243.388689) (xy 114.976812 -243.370642) (xy 115.026676 -243.360462)
			(xy 115.077528 -243.358413) (xy 115.128049 -243.364547) (xy 115.176933 -243.378707) (xy 115.222912 -243.400524)
			(xy 115.264796 -243.429434) (xy 115.3015 -243.464689) (xy 115.332073 -243.505375) (xy 115.355724 -243.550438)
			(xy 115.37184 -243.598712) (xy 115.380004 -243.648946) (xy 115.380516 -243.674392) (xy 115.380013 -243.699381)
			(xy 115.68733 -243.699381) (xy 115.68733 -243.649403) (xy 115.695149 -243.60004) (xy 115.710593 -243.552508)
			(xy 115.733283 -243.507976) (xy 115.762659 -243.467543) (xy 115.797999 -243.432203) (xy 115.838432 -243.402827)
			(xy 115.882964 -243.380137) (xy 115.930496 -243.364693) (xy 115.979859 -243.356874) (xy 116.029837 -243.356874)
			(xy 116.0792 -243.364693) (xy 116.126732 -243.380137) (xy 116.171264 -243.402827) (xy 116.211697 -243.432203)
			(xy 116.247037 -243.467543) (xy 116.276413 -243.507976) (xy 116.299103 -243.552508) (xy 116.314547 -243.60004)
			(xy 116.322366 -243.649403) (xy 116.322856 -243.674392) (xy 116.322366 -243.699381) (xy 116.62713 -243.699381)
			(xy 116.62713 -243.649403) (xy 116.634949 -243.60004) (xy 116.650393 -243.552508) (xy 116.673083 -243.507976)
			(xy 116.702459 -243.467543) (xy 116.737799 -243.432203) (xy 116.778232 -243.402827) (xy 116.822764 -243.380137)
			(xy 116.870296 -243.364693) (xy 116.919659 -243.356874) (xy 116.969637 -243.356874) (xy 117.019 -243.364693)
			(xy 117.066532 -243.380137) (xy 117.111064 -243.402827) (xy 117.151497 -243.432203) (xy 117.186837 -243.467543)
			(xy 117.216213 -243.507976) (xy 117.238903 -243.552508) (xy 117.254347 -243.60004) (xy 117.262166 -243.649403)
			(xy 117.262656 -243.674392) (xy 117.262166 -243.699381) (xy 117.567184 -243.699381) (xy 117.567184 -243.649403)
			(xy 117.575003 -243.60004) (xy 117.590447 -243.552508) (xy 117.613137 -243.507976) (xy 117.642513 -243.467543)
			(xy 117.677853 -243.432203) (xy 117.718286 -243.402827) (xy 117.762818 -243.380137) (xy 117.81035 -243.364693)
			(xy 117.859713 -243.356874) (xy 117.909691 -243.356874) (xy 117.959054 -243.364693) (xy 118.006586 -243.380137)
			(xy 118.051118 -243.402827) (xy 118.091551 -243.432203) (xy 118.126891 -243.467543) (xy 118.156267 -243.507976)
			(xy 118.178957 -243.552508) (xy 118.194401 -243.60004) (xy 118.20222 -243.649403) (xy 118.20271 -243.674392)
			(xy 118.20222 -243.699381) (xy 118.507238 -243.699381) (xy 118.507238 -243.649403) (xy 118.515057 -243.60004)
			(xy 118.530501 -243.552508) (xy 118.553191 -243.507976) (xy 118.582567 -243.467543) (xy 118.617907 -243.432203)
			(xy 118.65834 -243.402827) (xy 118.702872 -243.380137) (xy 118.750404 -243.364693) (xy 118.799767 -243.356874)
			(xy 118.849745 -243.356874) (xy 118.899108 -243.364693) (xy 118.94664 -243.380137) (xy 118.991172 -243.402827)
			(xy 119.031605 -243.432203) (xy 119.066945 -243.467543) (xy 119.096321 -243.507976) (xy 119.119011 -243.552508)
			(xy 119.134455 -243.60004) (xy 119.142274 -243.649403) (xy 119.142764 -243.674392) (xy 119.142274 -243.699381)
			(xy 119.447292 -243.699381) (xy 119.447292 -243.649403) (xy 119.455111 -243.60004) (xy 119.470555 -243.552508)
			(xy 119.493245 -243.507976) (xy 119.522621 -243.467543) (xy 119.557961 -243.432203) (xy 119.598394 -243.402827)
			(xy 119.642926 -243.380137) (xy 119.690458 -243.364693) (xy 119.739821 -243.356874) (xy 119.789799 -243.356874)
			(xy 119.839162 -243.364693) (xy 119.886694 -243.380137) (xy 119.931226 -243.402827) (xy 119.971659 -243.432203)
			(xy 120.006999 -243.467543) (xy 120.036375 -243.507976) (xy 120.059065 -243.552508) (xy 120.074509 -243.60004)
			(xy 120.082328 -243.649403) (xy 120.082818 -243.674392) (xy 120.082328 -243.699381) (xy 120.387092 -243.699381)
			(xy 120.387092 -243.649403) (xy 120.394911 -243.60004) (xy 120.410355 -243.552508) (xy 120.433045 -243.507976)
			(xy 120.462421 -243.467543) (xy 120.497761 -243.432203) (xy 120.538194 -243.402827) (xy 120.582726 -243.380137)
			(xy 120.630258 -243.364693) (xy 120.679621 -243.356874) (xy 120.729599 -243.356874) (xy 120.778962 -243.364693)
			(xy 120.826494 -243.380137) (xy 120.871026 -243.402827) (xy 120.911459 -243.432203) (xy 120.946799 -243.467543)
			(xy 120.976175 -243.507976) (xy 120.998865 -243.552508) (xy 121.014309 -243.60004) (xy 121.022128 -243.649403)
			(xy 121.022618 -243.674392) (xy 121.022128 -243.699381) (xy 121.327146 -243.699381) (xy 121.327146 -243.649403)
			(xy 121.334965 -243.60004) (xy 121.350409 -243.552508) (xy 121.373099 -243.507976) (xy 121.402475 -243.467543)
			(xy 121.437815 -243.432203) (xy 121.478248 -243.402827) (xy 121.52278 -243.380137) (xy 121.570312 -243.364693)
			(xy 121.619675 -243.356874) (xy 121.669653 -243.356874) (xy 121.719016 -243.364693) (xy 121.766548 -243.380137)
			(xy 121.81108 -243.402827) (xy 121.851513 -243.432203) (xy 121.886853 -243.467543) (xy 121.916229 -243.507976)
			(xy 121.938919 -243.552508) (xy 121.954363 -243.60004) (xy 121.962182 -243.649403) (xy 121.962672 -243.674392)
			(xy 121.962182 -243.699381) (xy 122.2672 -243.699381) (xy 122.2672 -243.649403) (xy 122.275019 -243.60004)
			(xy 122.290463 -243.552508) (xy 122.313153 -243.507976) (xy 122.342529 -243.467543) (xy 122.377869 -243.432203)
			(xy 122.418302 -243.402827) (xy 122.462834 -243.380137) (xy 122.510366 -243.364693) (xy 122.559729 -243.356874)
			(xy 122.609707 -243.356874) (xy 122.65907 -243.364693) (xy 122.706602 -243.380137) (xy 122.751134 -243.402827)
			(xy 122.791567 -243.432203) (xy 122.826907 -243.467543) (xy 122.856283 -243.507976) (xy 122.878973 -243.552508)
			(xy 122.894417 -243.60004) (xy 122.902236 -243.649403) (xy 122.902726 -243.674392) (xy 122.902236 -243.699381)
			(xy 123.207254 -243.699381) (xy 123.207254 -243.649403) (xy 123.215073 -243.60004) (xy 123.230517 -243.552508)
			(xy 123.253207 -243.507976) (xy 123.282583 -243.467543) (xy 123.317923 -243.432203) (xy 123.358356 -243.402827)
			(xy 123.402888 -243.380137) (xy 123.45042 -243.364693) (xy 123.499783 -243.356874) (xy 123.549761 -243.356874)
			(xy 123.599124 -243.364693) (xy 123.646656 -243.380137) (xy 123.691188 -243.402827) (xy 123.731621 -243.432203)
			(xy 123.766961 -243.467543) (xy 123.796337 -243.507976) (xy 123.819027 -243.552508) (xy 123.834471 -243.60004)
			(xy 123.84229 -243.649403) (xy 123.84278 -243.674392) (xy 123.84229 -243.699381) (xy 124.147308 -243.699381)
			(xy 124.147308 -243.649403) (xy 124.155127 -243.60004) (xy 124.170571 -243.552508) (xy 124.193261 -243.507976)
			(xy 124.222637 -243.467543) (xy 124.257977 -243.432203) (xy 124.29841 -243.402827) (xy 124.342942 -243.380137)
			(xy 124.390474 -243.364693) (xy 124.439837 -243.356874) (xy 124.489815 -243.356874) (xy 124.539178 -243.364693)
			(xy 124.58671 -243.380137) (xy 124.631242 -243.402827) (xy 124.671675 -243.432203) (xy 124.707015 -243.467543)
			(xy 124.736391 -243.507976) (xy 124.759081 -243.552508) (xy 124.774525 -243.60004) (xy 124.782344 -243.649403)
			(xy 124.782834 -243.674392) (xy 124.782344 -243.699381) (xy 125.087108 -243.699381) (xy 125.087108 -243.649403)
			(xy 125.094927 -243.60004) (xy 125.110371 -243.552508) (xy 125.133061 -243.507976) (xy 125.162437 -243.467543)
			(xy 125.197777 -243.432203) (xy 125.23821 -243.402827) (xy 125.282742 -243.380137) (xy 125.330274 -243.364693)
			(xy 125.379637 -243.356874) (xy 125.429615 -243.356874) (xy 125.478978 -243.364693) (xy 125.52651 -243.380137)
			(xy 125.571042 -243.402827) (xy 125.611475 -243.432203) (xy 125.646815 -243.467543) (xy 125.676191 -243.507976)
			(xy 125.698881 -243.552508) (xy 125.714325 -243.60004) (xy 125.722144 -243.649403) (xy 125.722634 -243.674392)
			(xy 125.722144 -243.699381) (xy 125.714325 -243.748744) (xy 125.698881 -243.796276) (xy 125.676191 -243.840808)
			(xy 125.646815 -243.881241) (xy 125.611475 -243.916581) (xy 125.571042 -243.945957) (xy 125.52651 -243.968647)
			(xy 125.478978 -243.984091) (xy 125.429615 -243.99191) (xy 125.379637 -243.99191) (xy 125.330274 -243.984091)
			(xy 125.282742 -243.968647) (xy 125.23821 -243.945957) (xy 125.197777 -243.916581) (xy 125.162437 -243.881241)
			(xy 125.133061 -243.840808) (xy 125.110371 -243.796276) (xy 125.094927 -243.748744) (xy 125.087108 -243.699381)
			(xy 124.782344 -243.699381) (xy 124.774525 -243.748744) (xy 124.759081 -243.796276) (xy 124.736391 -243.840808)
			(xy 124.707015 -243.881241) (xy 124.671675 -243.916581) (xy 124.631242 -243.945957) (xy 124.58671 -243.968647)
			(xy 124.539178 -243.984091) (xy 124.489815 -243.99191) (xy 124.439837 -243.99191) (xy 124.390474 -243.984091)
			(xy 124.342942 -243.968647) (xy 124.29841 -243.945957) (xy 124.257977 -243.916581) (xy 124.222637 -243.881241)
			(xy 124.193261 -243.840808) (xy 124.170571 -243.796276) (xy 124.155127 -243.748744) (xy 124.147308 -243.699381)
			(xy 123.84229 -243.699381) (xy 123.834471 -243.748744) (xy 123.819027 -243.796276) (xy 123.796337 -243.840808)
			(xy 123.766961 -243.881241) (xy 123.731621 -243.916581) (xy 123.691188 -243.945957) (xy 123.646656 -243.968647)
			(xy 123.599124 -243.984091) (xy 123.549761 -243.99191) (xy 123.499783 -243.99191) (xy 123.45042 -243.984091)
			(xy 123.402888 -243.968647) (xy 123.358356 -243.945957) (xy 123.317923 -243.916581) (xy 123.282583 -243.881241)
			(xy 123.253207 -243.840808) (xy 123.230517 -243.796276) (xy 123.215073 -243.748744) (xy 123.207254 -243.699381)
			(xy 122.902236 -243.699381) (xy 122.894417 -243.748744) (xy 122.878973 -243.796276) (xy 122.856283 -243.840808)
			(xy 122.826907 -243.881241) (xy 122.791567 -243.916581) (xy 122.751134 -243.945957) (xy 122.706602 -243.968647)
			(xy 122.65907 -243.984091) (xy 122.609707 -243.99191) (xy 122.559729 -243.99191) (xy 122.510366 -243.984091)
			(xy 122.462834 -243.968647) (xy 122.418302 -243.945957) (xy 122.377869 -243.916581) (xy 122.342529 -243.881241)
			(xy 122.313153 -243.840808) (xy 122.290463 -243.796276) (xy 122.275019 -243.748744) (xy 122.2672 -243.699381)
			(xy 121.962182 -243.699381) (xy 121.954363 -243.748744) (xy 121.938919 -243.796276) (xy 121.916229 -243.840808)
			(xy 121.886853 -243.881241) (xy 121.851513 -243.916581) (xy 121.81108 -243.945957) (xy 121.766548 -243.968647)
			(xy 121.719016 -243.984091) (xy 121.669653 -243.99191) (xy 121.619675 -243.99191) (xy 121.570312 -243.984091)
			(xy 121.52278 -243.968647) (xy 121.478248 -243.945957) (xy 121.437815 -243.916581) (xy 121.402475 -243.881241)
			(xy 121.373099 -243.840808) (xy 121.350409 -243.796276) (xy 121.334965 -243.748744) (xy 121.327146 -243.699381)
			(xy 121.022128 -243.699381) (xy 121.014309 -243.748744) (xy 120.998865 -243.796276) (xy 120.976175 -243.840808)
			(xy 120.946799 -243.881241) (xy 120.911459 -243.916581) (xy 120.871026 -243.945957) (xy 120.826494 -243.968647)
			(xy 120.778962 -243.984091) (xy 120.729599 -243.99191) (xy 120.679621 -243.99191) (xy 120.630258 -243.984091)
			(xy 120.582726 -243.968647) (xy 120.538194 -243.945957) (xy 120.497761 -243.916581) (xy 120.462421 -243.881241)
			(xy 120.433045 -243.840808) (xy 120.410355 -243.796276) (xy 120.394911 -243.748744) (xy 120.387092 -243.699381)
			(xy 120.082328 -243.699381) (xy 120.074509 -243.748744) (xy 120.059065 -243.796276) (xy 120.036375 -243.840808)
			(xy 120.006999 -243.881241) (xy 119.971659 -243.916581) (xy 119.931226 -243.945957) (xy 119.886694 -243.968647)
			(xy 119.839162 -243.984091) (xy 119.789799 -243.99191) (xy 119.739821 -243.99191) (xy 119.690458 -243.984091)
			(xy 119.642926 -243.968647) (xy 119.598394 -243.945957) (xy 119.557961 -243.916581) (xy 119.522621 -243.881241)
			(xy 119.493245 -243.840808) (xy 119.470555 -243.796276) (xy 119.455111 -243.748744) (xy 119.447292 -243.699381)
			(xy 119.142274 -243.699381) (xy 119.134455 -243.748744) (xy 119.119011 -243.796276) (xy 119.096321 -243.840808)
			(xy 119.066945 -243.881241) (xy 119.031605 -243.916581) (xy 118.991172 -243.945957) (xy 118.94664 -243.968647)
			(xy 118.899108 -243.984091) (xy 118.849745 -243.99191) (xy 118.799767 -243.99191) (xy 118.750404 -243.984091)
			(xy 118.702872 -243.968647) (xy 118.65834 -243.945957) (xy 118.617907 -243.916581) (xy 118.582567 -243.881241)
			(xy 118.553191 -243.840808) (xy 118.530501 -243.796276) (xy 118.515057 -243.748744) (xy 118.507238 -243.699381)
			(xy 118.20222 -243.699381) (xy 118.194401 -243.748744) (xy 118.178957 -243.796276) (xy 118.156267 -243.840808)
			(xy 118.126891 -243.881241) (xy 118.091551 -243.916581) (xy 118.051118 -243.945957) (xy 118.006586 -243.968647)
			(xy 117.959054 -243.984091) (xy 117.909691 -243.99191) (xy 117.859713 -243.99191) (xy 117.81035 -243.984091)
			(xy 117.762818 -243.968647) (xy 117.718286 -243.945957) (xy 117.677853 -243.916581) (xy 117.642513 -243.881241)
			(xy 117.613137 -243.840808) (xy 117.590447 -243.796276) (xy 117.575003 -243.748744) (xy 117.567184 -243.699381)
			(xy 117.262166 -243.699381) (xy 117.254347 -243.748744) (xy 117.238903 -243.796276) (xy 117.216213 -243.840808)
			(xy 117.186837 -243.881241) (xy 117.151497 -243.916581) (xy 117.111064 -243.945957) (xy 117.066532 -243.968647)
			(xy 117.019 -243.984091) (xy 116.969637 -243.99191) (xy 116.919659 -243.99191) (xy 116.870296 -243.984091)
			(xy 116.822764 -243.968647) (xy 116.778232 -243.945957) (xy 116.737799 -243.916581) (xy 116.702459 -243.881241)
			(xy 116.673083 -243.840808) (xy 116.650393 -243.796276) (xy 116.634949 -243.748744) (xy 116.62713 -243.699381)
			(xy 116.322366 -243.699381) (xy 116.314547 -243.748744) (xy 116.299103 -243.796276) (xy 116.276413 -243.840808)
			(xy 116.247037 -243.881241) (xy 116.211697 -243.916581) (xy 116.171264 -243.945957) (xy 116.126732 -243.968647)
			(xy 116.0792 -243.984091) (xy 116.029837 -243.99191) (xy 115.979859 -243.99191) (xy 115.930496 -243.984091)
			(xy 115.882964 -243.968647) (xy 115.838432 -243.945957) (xy 115.797999 -243.916581) (xy 115.762659 -243.881241)
			(xy 115.733283 -243.840808) (xy 115.710593 -243.796276) (xy 115.695149 -243.748744) (xy 115.68733 -243.699381)
			(xy 115.380013 -243.699381) (xy 115.380004 -243.699838) (xy 115.37184 -243.750072) (xy 115.355724 -243.798346)
			(xy 115.332073 -243.843409) (xy 115.3015 -243.884095) (xy 115.264796 -243.91935) (xy 115.222912 -243.94826)
			(xy 115.176933 -243.970077) (xy 115.128049 -243.984237) (xy 115.077528 -243.990371) (xy 115.026676 -243.988322)
			(xy 114.976812 -243.978142) (xy 114.929226 -243.960095) (xy 114.885152 -243.934649) (xy 114.84573 -243.902462)
			(xy 114.811982 -243.864368) (xy 114.784781 -243.821354) (xy 114.764833 -243.774534) (xy 114.752654 -243.72512)
			(xy 114.748559 -243.674392) (xy 114.440462 -243.674392) (xy 114.43995 -243.699838) (xy 114.431786 -243.750072)
			(xy 114.41567 -243.798346) (xy 114.392019 -243.843409) (xy 114.361446 -243.884095) (xy 114.324742 -243.91935)
			(xy 114.282858 -243.94826) (xy 114.236879 -243.970077) (xy 114.187995 -243.984237) (xy 114.137474 -243.990371)
			(xy 114.086622 -243.988322) (xy 114.036758 -243.978142) (xy 113.989172 -243.960095) (xy 113.945098 -243.934649)
			(xy 113.905676 -243.902462) (xy 113.871928 -243.864368) (xy 113.844727 -243.821354) (xy 113.824779 -243.774534)
			(xy 113.8126 -243.72512) (xy 113.808505 -243.674392) (xy 113.502694 -243.674392) (xy 113.502204 -243.699381)
			(xy 113.494385 -243.748744) (xy 113.478941 -243.796276) (xy 113.456251 -243.840808) (xy 113.426875 -243.881241)
			(xy 113.391535 -243.916581) (xy 113.351102 -243.945957) (xy 113.30657 -243.968647) (xy 113.259038 -243.984091)
			(xy 113.209675 -243.99191) (xy 113.159697 -243.99191) (xy 113.110334 -243.984091) (xy 113.062802 -243.968647)
			(xy 113.01827 -243.945957) (xy 112.977837 -243.916581) (xy 112.942497 -243.881241) (xy 112.913121 -243.840808)
			(xy 112.890431 -243.796276) (xy 112.874987 -243.748744) (xy 112.867168 -243.699381) (xy 110.688646 -243.699381)
			(xy 110.680827 -243.748744) (xy 110.665383 -243.796276) (xy 110.642693 -243.840808) (xy 110.613317 -243.881241)
			(xy 110.577977 -243.916581) (xy 110.537544 -243.945957) (xy 110.493012 -243.968647) (xy 110.44548 -243.984091)
			(xy 110.396117 -243.99191) (xy 110.346139 -243.99191) (xy 110.296776 -243.984091) (xy 110.249244 -243.968647)
			(xy 110.204712 -243.945957) (xy 110.164279 -243.916581) (xy 110.128939 -243.881241) (xy 110.099563 -243.840808)
			(xy 110.076873 -243.796276) (xy 110.061429 -243.748744) (xy 110.05361 -243.699381) (xy 109.746293 -243.699381)
			(xy 109.746284 -243.699838) (xy 109.73812 -243.750072) (xy 109.722004 -243.798346) (xy 109.698353 -243.843409)
			(xy 109.66778 -243.884095) (xy 109.631076 -243.91935) (xy 109.589192 -243.94826) (xy 109.543213 -243.970077)
			(xy 109.494329 -243.984237) (xy 109.443808 -243.990371) (xy 109.392956 -243.988322) (xy 109.343092 -243.978142)
			(xy 109.295506 -243.960095) (xy 109.251432 -243.934649) (xy 109.21201 -243.902462) (xy 109.178262 -243.864368)
			(xy 109.151061 -243.821354) (xy 109.131113 -243.774534) (xy 109.118934 -243.72512) (xy 109.114839 -243.674392)
			(xy 108.806742 -243.674392) (xy 108.80623 -243.699838) (xy 108.798066 -243.750072) (xy 108.78195 -243.798346)
			(xy 108.758299 -243.843409) (xy 108.727726 -243.884095) (xy 108.691022 -243.91935) (xy 108.649138 -243.94826)
			(xy 108.603159 -243.970077) (xy 108.554275 -243.984237) (xy 108.503754 -243.990371) (xy 108.452902 -243.988322)
			(xy 108.403038 -243.978142) (xy 108.355452 -243.960095) (xy 108.311378 -243.934649) (xy 108.271956 -243.902462)
			(xy 108.238208 -243.864368) (xy 108.211007 -243.821354) (xy 108.191059 -243.774534) (xy 108.17888 -243.72512)
			(xy 108.174785 -243.674392) (xy 107.868974 -243.674392) (xy 107.868484 -243.699381) (xy 107.860665 -243.748744)
			(xy 107.845221 -243.796276) (xy 107.822531 -243.840808) (xy 107.793155 -243.881241) (xy 107.757815 -243.916581)
			(xy 107.717382 -243.945957) (xy 107.67285 -243.968647) (xy 107.625318 -243.984091) (xy 107.575955 -243.99191)
			(xy 107.525977 -243.99191) (xy 107.476614 -243.984091) (xy 107.429082 -243.968647) (xy 107.38455 -243.945957)
			(xy 107.344117 -243.916581) (xy 107.308777 -243.881241) (xy 107.279401 -243.840808) (xy 107.256711 -243.796276)
			(xy 107.241267 -243.748744) (xy 107.233448 -243.699381) (xy 106.928684 -243.699381) (xy 106.920865 -243.748744)
			(xy 106.905421 -243.796276) (xy 106.882731 -243.840808) (xy 106.853355 -243.881241) (xy 106.818015 -243.916581)
			(xy 106.777582 -243.945957) (xy 106.73305 -243.968647) (xy 106.685518 -243.984091) (xy 106.636155 -243.99191)
			(xy 106.586177 -243.99191) (xy 106.536814 -243.984091) (xy 106.489282 -243.968647) (xy 106.44475 -243.945957)
			(xy 106.404317 -243.916581) (xy 106.368977 -243.881241) (xy 106.339601 -243.840808) (xy 106.316911 -243.796276)
			(xy 106.301467 -243.748744) (xy 106.293648 -243.699381) (xy 105.98863 -243.699381) (xy 105.980811 -243.748744)
			(xy 105.965367 -243.796276) (xy 105.942677 -243.840808) (xy 105.913301 -243.881241) (xy 105.877961 -243.916581)
			(xy 105.837528 -243.945957) (xy 105.792996 -243.968647) (xy 105.745464 -243.984091) (xy 105.696101 -243.99191)
			(xy 105.646123 -243.99191) (xy 105.59676 -243.984091) (xy 105.549228 -243.968647) (xy 105.504696 -243.945957)
			(xy 105.464263 -243.916581) (xy 105.428923 -243.881241) (xy 105.399547 -243.840808) (xy 105.376857 -243.796276)
			(xy 105.361413 -243.748744) (xy 105.353594 -243.699381) (xy 105.048576 -243.699381) (xy 105.040757 -243.748744)
			(xy 105.025313 -243.796276) (xy 105.002623 -243.840808) (xy 104.973247 -243.881241) (xy 104.937907 -243.916581)
			(xy 104.897474 -243.945957) (xy 104.852942 -243.968647) (xy 104.80541 -243.984091) (xy 104.756047 -243.99191)
			(xy 104.706069 -243.99191) (xy 104.656706 -243.984091) (xy 104.609174 -243.968647) (xy 104.564642 -243.945957)
			(xy 104.524209 -243.916581) (xy 104.488869 -243.881241) (xy 104.459493 -243.840808) (xy 104.436803 -243.796276)
			(xy 104.421359 -243.748744) (xy 104.41354 -243.699381) (xy 104.108522 -243.699381) (xy 104.100703 -243.748744)
			(xy 104.085259 -243.796276) (xy 104.062569 -243.840808) (xy 104.033193 -243.881241) (xy 103.997853 -243.916581)
			(xy 103.95742 -243.945957) (xy 103.912888 -243.968647) (xy 103.865356 -243.984091) (xy 103.815993 -243.99191)
			(xy 103.766015 -243.99191) (xy 103.716652 -243.984091) (xy 103.66912 -243.968647) (xy 103.624588 -243.945957)
			(xy 103.584155 -243.916581) (xy 103.548815 -243.881241) (xy 103.519439 -243.840808) (xy 103.496749 -243.796276)
			(xy 103.481305 -243.748744) (xy 103.473486 -243.699381) (xy 103.168468 -243.699381) (xy 103.160649 -243.748744)
			(xy 103.145205 -243.796276) (xy 103.122515 -243.840808) (xy 103.093139 -243.881241) (xy 103.057799 -243.916581)
			(xy 103.017366 -243.945957) (xy 102.972834 -243.968647) (xy 102.925302 -243.984091) (xy 102.875939 -243.99191)
			(xy 102.825961 -243.99191) (xy 102.776598 -243.984091) (xy 102.729066 -243.968647) (xy 102.684534 -243.945957)
			(xy 102.644101 -243.916581) (xy 102.608761 -243.881241) (xy 102.579385 -243.840808) (xy 102.556695 -243.796276)
			(xy 102.541251 -243.748744) (xy 102.533432 -243.699381) (xy 102.228668 -243.699381) (xy 102.220849 -243.748744)
			(xy 102.205405 -243.796276) (xy 102.182715 -243.840808) (xy 102.153339 -243.881241) (xy 102.117999 -243.916581)
			(xy 102.077566 -243.945957) (xy 102.033034 -243.968647) (xy 101.985502 -243.984091) (xy 101.936139 -243.99191)
			(xy 101.886161 -243.99191) (xy 101.836798 -243.984091) (xy 101.789266 -243.968647) (xy 101.744734 -243.945957)
			(xy 101.704301 -243.916581) (xy 101.668961 -243.881241) (xy 101.639585 -243.840808) (xy 101.616895 -243.796276)
			(xy 101.601451 -243.748744) (xy 101.593632 -243.699381) (xy 101.288614 -243.699381) (xy 101.280795 -243.748744)
			(xy 101.265351 -243.796276) (xy 101.242661 -243.840808) (xy 101.213285 -243.881241) (xy 101.177945 -243.916581)
			(xy 101.137512 -243.945957) (xy 101.09298 -243.968647) (xy 101.045448 -243.984091) (xy 100.996085 -243.99191)
			(xy 100.946107 -243.99191) (xy 100.896744 -243.984091) (xy 100.849212 -243.968647) (xy 100.80468 -243.945957)
			(xy 100.764247 -243.916581) (xy 100.728907 -243.881241) (xy 100.699531 -243.840808) (xy 100.676841 -243.796276)
			(xy 100.661397 -243.748744) (xy 100.653578 -243.699381) (xy 100.34856 -243.699381) (xy 100.340741 -243.748744)
			(xy 100.325297 -243.796276) (xy 100.302607 -243.840808) (xy 100.273231 -243.881241) (xy 100.237891 -243.916581)
			(xy 100.197458 -243.945957) (xy 100.152926 -243.968647) (xy 100.105394 -243.984091) (xy 100.056031 -243.99191)
			(xy 100.006053 -243.99191) (xy 99.95669 -243.984091) (xy 99.909158 -243.968647) (xy 99.864626 -243.945957)
			(xy 99.824193 -243.916581) (xy 99.788853 -243.881241) (xy 99.759477 -243.840808) (xy 99.736787 -243.796276)
			(xy 99.721343 -243.748744) (xy 99.713524 -243.699381) (xy 99.408506 -243.699381) (xy 99.400687 -243.748744)
			(xy 99.385243 -243.796276) (xy 99.362553 -243.840808) (xy 99.333177 -243.881241) (xy 99.297837 -243.916581)
			(xy 99.257404 -243.945957) (xy 99.212872 -243.968647) (xy 99.16534 -243.984091) (xy 99.115977 -243.99191)
			(xy 99.065999 -243.99191) (xy 99.016636 -243.984091) (xy 98.969104 -243.968647) (xy 98.924572 -243.945957)
			(xy 98.884139 -243.916581) (xy 98.848799 -243.881241) (xy 98.819423 -243.840808) (xy 98.796733 -243.796276)
			(xy 98.781289 -243.748744) (xy 98.77347 -243.699381) (xy 98.468452 -243.699381) (xy 98.460633 -243.748744)
			(xy 98.445189 -243.796276) (xy 98.422499 -243.840808) (xy 98.393123 -243.881241) (xy 98.357783 -243.916581)
			(xy 98.31735 -243.945957) (xy 98.272818 -243.968647) (xy 98.225286 -243.984091) (xy 98.175923 -243.99191)
			(xy 98.125945 -243.99191) (xy 98.076582 -243.984091) (xy 98.02905 -243.968647) (xy 97.984518 -243.945957)
			(xy 97.944085 -243.916581) (xy 97.908745 -243.881241) (xy 97.879369 -243.840808) (xy 97.856679 -243.796276)
			(xy 97.841235 -243.748744) (xy 97.833416 -243.699381) (xy 97.546125 -243.699381) (xy 97.546125 -243.700765)
			(xy 97.537877 -243.752847) (xy 97.521583 -243.802997) (xy 97.497645 -243.849981) (xy 97.466653 -243.892643)
			(xy 97.429368 -243.929931) (xy 97.38671 -243.960928) (xy 97.339729 -243.98487) (xy 97.28958 -244.001169)
			(xy 97.237499 -244.009422) (xy 97.211134 -244.009926) (xy 97.196124 -244.009702) (xy 97.166235 -244.006903)
			(xy 97.151444 -244.004338) (xy 97.14992 -244.004084) (xy 97.14865 -244.004084) (xy 97.131886 -244.00129)
			(xy 97.13087 -244.002052) (xy 97.10293 -244.02669) (xy 97.072958 -244.052852) (xy 97.066216 -244.059975)
			(xy 97.058243 -244.077874) (xy 97.057464 -244.08765) (xy 97.057464 -244.446806) (xy 97.057718 -244.451378)
			(xy 97.058988 -244.481858) (xy 97.058988 -244.484398) (xy 97.364799 -244.484398) (xy 97.368894 -244.43367)
			(xy 97.381073 -244.384256) (xy 97.401021 -244.337436) (xy 97.428222 -244.294422) (xy 97.46197 -244.256328)
			(xy 97.501392 -244.224141) (xy 97.545466 -244.198695) (xy 97.593052 -244.180648) (xy 97.642916 -244.170468)
			(xy 97.693768 -244.168419) (xy 97.744289 -244.174553) (xy 97.793173 -244.188713) (xy 97.839152 -244.21053)
			(xy 97.881036 -244.23944) (xy 97.91774 -244.274695) (xy 97.948313 -244.315381) (xy 97.971964 -244.360444)
			(xy 97.98808 -244.408718) (xy 97.996244 -244.458952) (xy 97.996756 -244.484398) (xy 98.304853 -244.484398)
			(xy 98.308948 -244.43367) (xy 98.321127 -244.384256) (xy 98.341075 -244.337436) (xy 98.368276 -244.294422)
			(xy 98.402024 -244.256328) (xy 98.441446 -244.224141) (xy 98.48552 -244.198695) (xy 98.533106 -244.180648)
			(xy 98.58297 -244.170468) (xy 98.633822 -244.168419) (xy 98.684343 -244.174553) (xy 98.733227 -244.188713)
			(xy 98.779206 -244.21053) (xy 98.82109 -244.23944) (xy 98.857794 -244.274695) (xy 98.888367 -244.315381)
			(xy 98.912018 -244.360444) (xy 98.928134 -244.408718) (xy 98.936298 -244.458952) (xy 98.93681 -244.484398)
			(xy 98.936307 -244.509387) (xy 99.243624 -244.509387) (xy 99.243624 -244.459409) (xy 99.251443 -244.410046)
			(xy 99.266887 -244.362514) (xy 99.289577 -244.317982) (xy 99.318953 -244.277549) (xy 99.354293 -244.242209)
			(xy 99.394726 -244.212833) (xy 99.439258 -244.190143) (xy 99.48679 -244.174699) (xy 99.536153 -244.16688)
			(xy 99.586131 -244.16688) (xy 99.635494 -244.174699) (xy 99.683026 -244.190143) (xy 99.727558 -244.212833)
			(xy 99.767991 -244.242209) (xy 99.803331 -244.277549) (xy 99.832707 -244.317982) (xy 99.855397 -244.362514)
			(xy 99.870841 -244.410046) (xy 99.87866 -244.459409) (xy 99.87915 -244.484398) (xy 100.184707 -244.484398)
			(xy 100.188802 -244.43367) (xy 100.200981 -244.384256) (xy 100.220929 -244.337436) (xy 100.24813 -244.294422)
			(xy 100.281878 -244.256328) (xy 100.3213 -244.224141) (xy 100.365374 -244.198695) (xy 100.41296 -244.180648)
			(xy 100.462824 -244.170468) (xy 100.513676 -244.168419) (xy 100.564197 -244.174553) (xy 100.613081 -244.188713)
			(xy 100.65906 -244.21053) (xy 100.700944 -244.23944) (xy 100.737648 -244.274695) (xy 100.768221 -244.315381)
			(xy 100.791872 -244.360444) (xy 100.807988 -244.408718) (xy 100.816152 -244.458952) (xy 100.816664 -244.484398)
			(xy 101.124761 -244.484398) (xy 101.128856 -244.43367) (xy 101.141035 -244.384256) (xy 101.160983 -244.337436)
			(xy 101.188184 -244.294422) (xy 101.221932 -244.256328) (xy 101.261354 -244.224141) (xy 101.305428 -244.198695)
			(xy 101.353014 -244.180648) (xy 101.402878 -244.170468) (xy 101.45373 -244.168419) (xy 101.504251 -244.174553)
			(xy 101.553135 -244.188713) (xy 101.599114 -244.21053) (xy 101.640998 -244.23944) (xy 101.677702 -244.274695)
			(xy 101.708275 -244.315381) (xy 101.731926 -244.360444) (xy 101.748042 -244.408718) (xy 101.756206 -244.458952)
			(xy 101.756718 -244.484398) (xy 101.756215 -244.509387) (xy 102.063532 -244.509387) (xy 102.063532 -244.459409)
			(xy 102.071351 -244.410046) (xy 102.086795 -244.362514) (xy 102.109485 -244.317982) (xy 102.138861 -244.277549)
			(xy 102.174201 -244.242209) (xy 102.214634 -244.212833) (xy 102.259166 -244.190143) (xy 102.306698 -244.174699)
			(xy 102.356061 -244.16688) (xy 102.406039 -244.16688) (xy 102.455402 -244.174699) (xy 102.502934 -244.190143)
			(xy 102.547466 -244.212833) (xy 102.587899 -244.242209) (xy 102.623239 -244.277549) (xy 102.652615 -244.317982)
			(xy 102.675305 -244.362514) (xy 102.690749 -244.410046) (xy 102.698568 -244.459409) (xy 102.699058 -244.484398)
			(xy 103.004869 -244.484398) (xy 103.008964 -244.43367) (xy 103.021143 -244.384256) (xy 103.041091 -244.337436)
			(xy 103.068292 -244.294422) (xy 103.10204 -244.256328) (xy 103.141462 -244.224141) (xy 103.185536 -244.198695)
			(xy 103.233122 -244.180648) (xy 103.282986 -244.170468) (xy 103.333838 -244.168419) (xy 103.384359 -244.174553)
			(xy 103.433243 -244.188713) (xy 103.479222 -244.21053) (xy 103.521106 -244.23944) (xy 103.55781 -244.274695)
			(xy 103.588383 -244.315381) (xy 103.612034 -244.360444) (xy 103.62815 -244.408718) (xy 103.636314 -244.458952)
			(xy 103.636826 -244.484398) (xy 103.944923 -244.484398) (xy 103.949018 -244.43367) (xy 103.961197 -244.384256)
			(xy 103.981145 -244.337436) (xy 104.008346 -244.294422) (xy 104.042094 -244.256328) (xy 104.081516 -244.224141)
			(xy 104.12559 -244.198695) (xy 104.173176 -244.180648) (xy 104.22304 -244.170468) (xy 104.273892 -244.168419)
			(xy 104.324413 -244.174553) (xy 104.373297 -244.188713) (xy 104.419276 -244.21053) (xy 104.46116 -244.23944)
			(xy 104.497864 -244.274695) (xy 104.528437 -244.315381) (xy 104.552088 -244.360444) (xy 104.568204 -244.408718)
			(xy 104.576368 -244.458952) (xy 104.57688 -244.484398) (xy 104.576377 -244.509387) (xy 104.88344 -244.509387)
			(xy 104.88344 -244.459409) (xy 104.891259 -244.410046) (xy 104.906703 -244.362514) (xy 104.929393 -244.317982)
			(xy 104.958769 -244.277549) (xy 104.994109 -244.242209) (xy 105.034542 -244.212833) (xy 105.079074 -244.190143)
			(xy 105.126606 -244.174699) (xy 105.175969 -244.16688) (xy 105.225947 -244.16688) (xy 105.27531 -244.174699)
			(xy 105.322842 -244.190143) (xy 105.367374 -244.212833) (xy 105.407807 -244.242209) (xy 105.443147 -244.277549)
			(xy 105.472523 -244.317982) (xy 105.495213 -244.362514) (xy 105.510657 -244.410046) (xy 105.518476 -244.459409)
			(xy 105.518966 -244.484398) (xy 105.824777 -244.484398) (xy 105.828872 -244.43367) (xy 105.841051 -244.384256)
			(xy 105.860999 -244.337436) (xy 105.8882 -244.294422) (xy 105.921948 -244.256328) (xy 105.96137 -244.224141)
			(xy 106.005444 -244.198695) (xy 106.05303 -244.180648) (xy 106.102894 -244.170468) (xy 106.153746 -244.168419)
			(xy 106.204267 -244.174553) (xy 106.253151 -244.188713) (xy 106.29913 -244.21053) (xy 106.341014 -244.23944)
			(xy 106.377718 -244.274695) (xy 106.408291 -244.315381) (xy 106.431942 -244.360444) (xy 106.448058 -244.408718)
			(xy 106.456222 -244.458952) (xy 106.456734 -244.484398) (xy 106.764831 -244.484398) (xy 106.768926 -244.43367)
			(xy 106.781105 -244.384256) (xy 106.801053 -244.337436) (xy 106.828254 -244.294422) (xy 106.862002 -244.256328)
			(xy 106.901424 -244.224141) (xy 106.945498 -244.198695) (xy 106.993084 -244.180648) (xy 107.042948 -244.170468)
			(xy 107.0938 -244.168419) (xy 107.144321 -244.174553) (xy 107.193205 -244.188713) (xy 107.239184 -244.21053)
			(xy 107.281068 -244.23944) (xy 107.317772 -244.274695) (xy 107.348345 -244.315381) (xy 107.371996 -244.360444)
			(xy 107.388112 -244.408718) (xy 107.396276 -244.458952) (xy 107.396788 -244.484398) (xy 107.396285 -244.509387)
			(xy 107.703602 -244.509387) (xy 107.703602 -244.459409) (xy 107.711421 -244.410046) (xy 107.726865 -244.362514)
			(xy 107.749555 -244.317982) (xy 107.778931 -244.277549) (xy 107.814271 -244.242209) (xy 107.854704 -244.212833)
			(xy 107.899236 -244.190143) (xy 107.946768 -244.174699) (xy 107.996131 -244.16688) (xy 108.046109 -244.16688)
			(xy 108.095472 -244.174699) (xy 108.143004 -244.190143) (xy 108.187536 -244.212833) (xy 108.227969 -244.242209)
			(xy 108.263309 -244.277549) (xy 108.292685 -244.317982) (xy 108.315375 -244.362514) (xy 108.330819 -244.410046)
			(xy 108.338638 -244.459409) (xy 108.339128 -244.484398) (xy 108.338638 -244.509387) (xy 108.643656 -244.509387)
			(xy 108.643656 -244.459409) (xy 108.651475 -244.410046) (xy 108.666919 -244.362514) (xy 108.689609 -244.317982)
			(xy 108.718985 -244.277549) (xy 108.754325 -244.242209) (xy 108.794758 -244.212833) (xy 108.83929 -244.190143)
			(xy 108.886822 -244.174699) (xy 108.936185 -244.16688) (xy 108.986163 -244.16688) (xy 109.035526 -244.174699)
			(xy 109.083058 -244.190143) (xy 109.12759 -244.212833) (xy 109.168023 -244.242209) (xy 109.203363 -244.277549)
			(xy 109.232739 -244.317982) (xy 109.255429 -244.362514) (xy 109.270873 -244.410046) (xy 109.278692 -244.459409)
			(xy 109.279182 -244.484398) (xy 109.278692 -244.509387) (xy 109.583456 -244.509387) (xy 109.583456 -244.459409)
			(xy 109.591275 -244.410046) (xy 109.606719 -244.362514) (xy 109.629409 -244.317982) (xy 109.658785 -244.277549)
			(xy 109.694125 -244.242209) (xy 109.734558 -244.212833) (xy 109.77909 -244.190143) (xy 109.826622 -244.174699)
			(xy 109.875985 -244.16688) (xy 109.925963 -244.16688) (xy 109.975326 -244.174699) (xy 110.022858 -244.190143)
			(xy 110.06739 -244.212833) (xy 110.107823 -244.242209) (xy 110.143163 -244.277549) (xy 110.172539 -244.317982)
			(xy 110.195229 -244.362514) (xy 110.210673 -244.410046) (xy 110.218492 -244.459409) (xy 110.218982 -244.484398)
			(xy 110.218492 -244.509387) (xy 113.337322 -244.509387) (xy 113.337322 -244.459409) (xy 113.345141 -244.410046)
			(xy 113.360585 -244.362514) (xy 113.383275 -244.317982) (xy 113.412651 -244.277549) (xy 113.447991 -244.242209)
			(xy 113.488424 -244.212833) (xy 113.532956 -244.190143) (xy 113.580488 -244.174699) (xy 113.629851 -244.16688)
			(xy 113.679829 -244.16688) (xy 113.729192 -244.174699) (xy 113.776724 -244.190143) (xy 113.821256 -244.212833)
			(xy 113.861689 -244.242209) (xy 113.897029 -244.277549) (xy 113.926405 -244.317982) (xy 113.949095 -244.362514)
			(xy 113.964539 -244.410046) (xy 113.972358 -244.459409) (xy 113.972848 -244.484398) (xy 113.972358 -244.509387)
			(xy 114.277122 -244.509387) (xy 114.277122 -244.459409) (xy 114.284941 -244.410046) (xy 114.300385 -244.362514)
			(xy 114.323075 -244.317982) (xy 114.352451 -244.277549) (xy 114.387791 -244.242209) (xy 114.428224 -244.212833)
			(xy 114.472756 -244.190143) (xy 114.520288 -244.174699) (xy 114.569651 -244.16688) (xy 114.619629 -244.16688)
			(xy 114.668992 -244.174699) (xy 114.716524 -244.190143) (xy 114.761056 -244.212833) (xy 114.801489 -244.242209)
			(xy 114.836829 -244.277549) (xy 114.866205 -244.317982) (xy 114.888895 -244.362514) (xy 114.904339 -244.410046)
			(xy 114.912158 -244.459409) (xy 114.912648 -244.484398) (xy 114.912158 -244.509387) (xy 115.217176 -244.509387)
			(xy 115.217176 -244.459409) (xy 115.224995 -244.410046) (xy 115.240439 -244.362514) (xy 115.263129 -244.317982)
			(xy 115.292505 -244.277549) (xy 115.327845 -244.242209) (xy 115.368278 -244.212833) (xy 115.41281 -244.190143)
			(xy 115.460342 -244.174699) (xy 115.509705 -244.16688) (xy 115.559683 -244.16688) (xy 115.609046 -244.174699)
			(xy 115.656578 -244.190143) (xy 115.70111 -244.212833) (xy 115.741543 -244.242209) (xy 115.776883 -244.277549)
			(xy 115.806259 -244.317982) (xy 115.828949 -244.362514) (xy 115.844393 -244.410046) (xy 115.852212 -244.459409)
			(xy 115.852702 -244.484398) (xy 116.158513 -244.484398) (xy 116.162608 -244.43367) (xy 116.174787 -244.384256)
			(xy 116.194735 -244.337436) (xy 116.221936 -244.294422) (xy 116.255684 -244.256328) (xy 116.295106 -244.224141)
			(xy 116.33918 -244.198695) (xy 116.386766 -244.180648) (xy 116.43663 -244.170468) (xy 116.487482 -244.168419)
			(xy 116.538003 -244.174553) (xy 116.586887 -244.188713) (xy 116.632866 -244.21053) (xy 116.67475 -244.23944)
			(xy 116.711454 -244.274695) (xy 116.742027 -244.315381) (xy 116.765678 -244.360444) (xy 116.781794 -244.408718)
			(xy 116.789958 -244.458952) (xy 116.79047 -244.484398) (xy 117.098567 -244.484398) (xy 117.102662 -244.43367)
			(xy 117.114841 -244.384256) (xy 117.134789 -244.337436) (xy 117.16199 -244.294422) (xy 117.195738 -244.256328)
			(xy 117.23516 -244.224141) (xy 117.279234 -244.198695) (xy 117.32682 -244.180648) (xy 117.376684 -244.170468)
			(xy 117.427536 -244.168419) (xy 117.478057 -244.174553) (xy 117.526941 -244.188713) (xy 117.57292 -244.21053)
			(xy 117.614804 -244.23944) (xy 117.651508 -244.274695) (xy 117.682081 -244.315381) (xy 117.705732 -244.360444)
			(xy 117.721848 -244.408718) (xy 117.730012 -244.458952) (xy 117.730524 -244.484398) (xy 117.730021 -244.509387)
			(xy 118.037338 -244.509387) (xy 118.037338 -244.459409) (xy 118.045157 -244.410046) (xy 118.060601 -244.362514)
			(xy 118.083291 -244.317982) (xy 118.112667 -244.277549) (xy 118.148007 -244.242209) (xy 118.18844 -244.212833)
			(xy 118.232972 -244.190143) (xy 118.280504 -244.174699) (xy 118.329867 -244.16688) (xy 118.379845 -244.16688)
			(xy 118.429208 -244.174699) (xy 118.47674 -244.190143) (xy 118.521272 -244.212833) (xy 118.561705 -244.242209)
			(xy 118.597045 -244.277549) (xy 118.626421 -244.317982) (xy 118.649111 -244.362514) (xy 118.664555 -244.410046)
			(xy 118.672374 -244.459409) (xy 118.672864 -244.484398) (xy 118.978421 -244.484398) (xy 118.982516 -244.43367)
			(xy 118.994695 -244.384256) (xy 119.014643 -244.337436) (xy 119.041844 -244.294422) (xy 119.075592 -244.256328)
			(xy 119.115014 -244.224141) (xy 119.159088 -244.198695) (xy 119.206674 -244.180648) (xy 119.256538 -244.170468)
			(xy 119.30739 -244.168419) (xy 119.357911 -244.174553) (xy 119.406795 -244.188713) (xy 119.452774 -244.21053)
			(xy 119.494658 -244.23944) (xy 119.531362 -244.274695) (xy 119.561935 -244.315381) (xy 119.585586 -244.360444)
			(xy 119.601702 -244.408718) (xy 119.609866 -244.458952) (xy 119.610378 -244.484398) (xy 119.918475 -244.484398)
			(xy 119.92257 -244.43367) (xy 119.934749 -244.384256) (xy 119.954697 -244.337436) (xy 119.981898 -244.294422)
			(xy 120.015646 -244.256328) (xy 120.055068 -244.224141) (xy 120.099142 -244.198695) (xy 120.146728 -244.180648)
			(xy 120.196592 -244.170468) (xy 120.247444 -244.168419) (xy 120.297965 -244.174553) (xy 120.346849 -244.188713)
			(xy 120.392828 -244.21053) (xy 120.434712 -244.23944) (xy 120.471416 -244.274695) (xy 120.501989 -244.315381)
			(xy 120.52564 -244.360444) (xy 120.541756 -244.408718) (xy 120.54992 -244.458952) (xy 120.550432 -244.484398)
			(xy 120.549929 -244.509387) (xy 120.857246 -244.509387) (xy 120.857246 -244.459409) (xy 120.865065 -244.410046)
			(xy 120.880509 -244.362514) (xy 120.903199 -244.317982) (xy 120.932575 -244.277549) (xy 120.967915 -244.242209)
			(xy 121.008348 -244.212833) (xy 121.05288 -244.190143) (xy 121.100412 -244.174699) (xy 121.149775 -244.16688)
			(xy 121.199753 -244.16688) (xy 121.249116 -244.174699) (xy 121.296648 -244.190143) (xy 121.34118 -244.212833)
			(xy 121.381613 -244.242209) (xy 121.416953 -244.277549) (xy 121.446329 -244.317982) (xy 121.469019 -244.362514)
			(xy 121.484463 -244.410046) (xy 121.492282 -244.459409) (xy 121.492772 -244.484398) (xy 121.798583 -244.484398)
			(xy 121.802678 -244.43367) (xy 121.814857 -244.384256) (xy 121.834805 -244.337436) (xy 121.862006 -244.294422)
			(xy 121.895754 -244.256328) (xy 121.935176 -244.224141) (xy 121.97925 -244.198695) (xy 122.026836 -244.180648)
			(xy 122.0767 -244.170468) (xy 122.127552 -244.168419) (xy 122.178073 -244.174553) (xy 122.226957 -244.188713)
			(xy 122.272936 -244.21053) (xy 122.31482 -244.23944) (xy 122.351524 -244.274695) (xy 122.382097 -244.315381)
			(xy 122.405748 -244.360444) (xy 122.421864 -244.408718) (xy 122.430028 -244.458952) (xy 122.43054 -244.484398)
			(xy 122.738383 -244.484398) (xy 122.742478 -244.43367) (xy 122.754657 -244.384256) (xy 122.774605 -244.337436)
			(xy 122.801806 -244.294422) (xy 122.835554 -244.256328) (xy 122.874976 -244.224141) (xy 122.91905 -244.198695)
			(xy 122.966636 -244.180648) (xy 123.0165 -244.170468) (xy 123.067352 -244.168419) (xy 123.117873 -244.174553)
			(xy 123.166757 -244.188713) (xy 123.212736 -244.21053) (xy 123.25462 -244.23944) (xy 123.291324 -244.274695)
			(xy 123.321897 -244.315381) (xy 123.345548 -244.360444) (xy 123.361664 -244.408718) (xy 123.369828 -244.458952)
			(xy 123.37034 -244.484398) (xy 123.369837 -244.509387) (xy 123.677154 -244.509387) (xy 123.677154 -244.459409)
			(xy 123.684973 -244.410046) (xy 123.700417 -244.362514) (xy 123.723107 -244.317982) (xy 123.752483 -244.277549)
			(xy 123.787823 -244.242209) (xy 123.828256 -244.212833) (xy 123.872788 -244.190143) (xy 123.92032 -244.174699)
			(xy 123.969683 -244.16688) (xy 124.019661 -244.16688) (xy 124.069024 -244.174699) (xy 124.116556 -244.190143)
			(xy 124.161088 -244.212833) (xy 124.201521 -244.242209) (xy 124.236861 -244.277549) (xy 124.266237 -244.317982)
			(xy 124.288927 -244.362514) (xy 124.304371 -244.410046) (xy 124.31219 -244.459409) (xy 124.31268 -244.484398)
			(xy 124.618491 -244.484398) (xy 124.622586 -244.43367) (xy 124.634765 -244.384256) (xy 124.654713 -244.337436)
			(xy 124.681914 -244.294422) (xy 124.715662 -244.256328) (xy 124.755084 -244.224141) (xy 124.799158 -244.198695)
			(xy 124.846744 -244.180648) (xy 124.896608 -244.170468) (xy 124.94746 -244.168419) (xy 124.997981 -244.174553)
			(xy 125.046865 -244.188713) (xy 125.092844 -244.21053) (xy 125.134728 -244.23944) (xy 125.171432 -244.274695)
			(xy 125.202005 -244.315381) (xy 125.225656 -244.360444) (xy 125.241772 -244.408718) (xy 125.249936 -244.458952)
			(xy 125.250448 -244.484398) (xy 125.558545 -244.484398) (xy 125.56264 -244.43367) (xy 125.574819 -244.384256)
			(xy 125.594767 -244.337436) (xy 125.621968 -244.294422) (xy 125.655716 -244.256328) (xy 125.695138 -244.224141)
			(xy 125.739212 -244.198695) (xy 125.786798 -244.180648) (xy 125.836662 -244.170468) (xy 125.887514 -244.168419)
			(xy 125.938035 -244.174553) (xy 125.986919 -244.188713) (xy 126.032898 -244.21053) (xy 126.074782 -244.23944)
			(xy 126.111486 -244.274695) (xy 126.142059 -244.315381) (xy 126.16571 -244.360444) (xy 126.181826 -244.408718)
			(xy 126.18999 -244.458952) (xy 126.190502 -244.484398) (xy 126.18999 -244.509844) (xy 126.181826 -244.560078)
			(xy 126.16571 -244.608352) (xy 126.142059 -244.653415) (xy 126.111486 -244.694101) (xy 126.074782 -244.729356)
			(xy 126.032898 -244.758266) (xy 125.986919 -244.780083) (xy 125.938035 -244.794243) (xy 125.887514 -244.800377)
			(xy 125.836662 -244.798328) (xy 125.786798 -244.788148) (xy 125.739212 -244.770101) (xy 125.695138 -244.744655)
			(xy 125.655716 -244.712468) (xy 125.621968 -244.674374) (xy 125.594767 -244.63136) (xy 125.574819 -244.58454)
			(xy 125.56264 -244.535126) (xy 125.558545 -244.484398) (xy 125.250448 -244.484398) (xy 125.249936 -244.509844)
			(xy 125.241772 -244.560078) (xy 125.225656 -244.608352) (xy 125.202005 -244.653415) (xy 125.171432 -244.694101)
			(xy 125.134728 -244.729356) (xy 125.092844 -244.758266) (xy 125.046865 -244.780083) (xy 124.997981 -244.794243)
			(xy 124.94746 -244.800377) (xy 124.896608 -244.798328) (xy 124.846744 -244.788148) (xy 124.799158 -244.770101)
			(xy 124.755084 -244.744655) (xy 124.715662 -244.712468) (xy 124.681914 -244.674374) (xy 124.654713 -244.63136)
			(xy 124.634765 -244.58454) (xy 124.622586 -244.535126) (xy 124.618491 -244.484398) (xy 124.31268 -244.484398)
			(xy 124.31219 -244.509387) (xy 124.304371 -244.55875) (xy 124.288927 -244.606282) (xy 124.266237 -244.650814)
			(xy 124.236861 -244.691247) (xy 124.201521 -244.726587) (xy 124.161088 -244.755963) (xy 124.116556 -244.778653)
			(xy 124.069024 -244.794097) (xy 124.019661 -244.801916) (xy 123.969683 -244.801916) (xy 123.92032 -244.794097)
			(xy 123.872788 -244.778653) (xy 123.828256 -244.755963) (xy 123.787823 -244.726587) (xy 123.752483 -244.691247)
			(xy 123.723107 -244.650814) (xy 123.700417 -244.606282) (xy 123.684973 -244.55875) (xy 123.677154 -244.509387)
			(xy 123.369837 -244.509387) (xy 123.369828 -244.509844) (xy 123.361664 -244.560078) (xy 123.345548 -244.608352)
			(xy 123.321897 -244.653415) (xy 123.291324 -244.694101) (xy 123.25462 -244.729356) (xy 123.212736 -244.758266)
			(xy 123.166757 -244.780083) (xy 123.117873 -244.794243) (xy 123.067352 -244.800377) (xy 123.0165 -244.798328)
			(xy 122.966636 -244.788148) (xy 122.91905 -244.770101) (xy 122.874976 -244.744655) (xy 122.835554 -244.712468)
			(xy 122.801806 -244.674374) (xy 122.774605 -244.63136) (xy 122.754657 -244.58454) (xy 122.742478 -244.535126)
			(xy 122.738383 -244.484398) (xy 122.43054 -244.484398) (xy 122.430028 -244.509844) (xy 122.421864 -244.560078)
			(xy 122.405748 -244.608352) (xy 122.382097 -244.653415) (xy 122.351524 -244.694101) (xy 122.31482 -244.729356)
			(xy 122.272936 -244.758266) (xy 122.226957 -244.780083) (xy 122.178073 -244.794243) (xy 122.127552 -244.800377)
			(xy 122.0767 -244.798328) (xy 122.026836 -244.788148) (xy 121.97925 -244.770101) (xy 121.935176 -244.744655)
			(xy 121.895754 -244.712468) (xy 121.862006 -244.674374) (xy 121.834805 -244.63136) (xy 121.814857 -244.58454)
			(xy 121.802678 -244.535126) (xy 121.798583 -244.484398) (xy 121.492772 -244.484398) (xy 121.492282 -244.509387)
			(xy 121.484463 -244.55875) (xy 121.469019 -244.606282) (xy 121.446329 -244.650814) (xy 121.416953 -244.691247)
			(xy 121.381613 -244.726587) (xy 121.34118 -244.755963) (xy 121.296648 -244.778653) (xy 121.249116 -244.794097)
			(xy 121.199753 -244.801916) (xy 121.149775 -244.801916) (xy 121.100412 -244.794097) (xy 121.05288 -244.778653)
			(xy 121.008348 -244.755963) (xy 120.967915 -244.726587) (xy 120.932575 -244.691247) (xy 120.903199 -244.650814)
			(xy 120.880509 -244.606282) (xy 120.865065 -244.55875) (xy 120.857246 -244.509387) (xy 120.549929 -244.509387)
			(xy 120.54992 -244.509844) (xy 120.541756 -244.560078) (xy 120.52564 -244.608352) (xy 120.501989 -244.653415)
			(xy 120.471416 -244.694101) (xy 120.434712 -244.729356) (xy 120.392828 -244.758266) (xy 120.346849 -244.780083)
			(xy 120.297965 -244.794243) (xy 120.247444 -244.800377) (xy 120.196592 -244.798328) (xy 120.146728 -244.788148)
			(xy 120.099142 -244.770101) (xy 120.055068 -244.744655) (xy 120.015646 -244.712468) (xy 119.981898 -244.674374)
			(xy 119.954697 -244.63136) (xy 119.934749 -244.58454) (xy 119.92257 -244.535126) (xy 119.918475 -244.484398)
			(xy 119.610378 -244.484398) (xy 119.609866 -244.509844) (xy 119.601702 -244.560078) (xy 119.585586 -244.608352)
			(xy 119.561935 -244.653415) (xy 119.531362 -244.694101) (xy 119.494658 -244.729356) (xy 119.452774 -244.758266)
			(xy 119.406795 -244.780083) (xy 119.357911 -244.794243) (xy 119.30739 -244.800377) (xy 119.256538 -244.798328)
			(xy 119.206674 -244.788148) (xy 119.159088 -244.770101) (xy 119.115014 -244.744655) (xy 119.075592 -244.712468)
			(xy 119.041844 -244.674374) (xy 119.014643 -244.63136) (xy 118.994695 -244.58454) (xy 118.982516 -244.535126)
			(xy 118.978421 -244.484398) (xy 118.672864 -244.484398) (xy 118.672374 -244.509387) (xy 118.664555 -244.55875)
			(xy 118.649111 -244.606282) (xy 118.626421 -244.650814) (xy 118.597045 -244.691247) (xy 118.561705 -244.726587)
			(xy 118.521272 -244.755963) (xy 118.47674 -244.778653) (xy 118.429208 -244.794097) (xy 118.379845 -244.801916)
			(xy 118.329867 -244.801916) (xy 118.280504 -244.794097) (xy 118.232972 -244.778653) (xy 118.18844 -244.755963)
			(xy 118.148007 -244.726587) (xy 118.112667 -244.691247) (xy 118.083291 -244.650814) (xy 118.060601 -244.606282)
			(xy 118.045157 -244.55875) (xy 118.037338 -244.509387) (xy 117.730021 -244.509387) (xy 117.730012 -244.509844)
			(xy 117.721848 -244.560078) (xy 117.705732 -244.608352) (xy 117.682081 -244.653415) (xy 117.651508 -244.694101)
			(xy 117.614804 -244.729356) (xy 117.57292 -244.758266) (xy 117.526941 -244.780083) (xy 117.478057 -244.794243)
			(xy 117.427536 -244.800377) (xy 117.376684 -244.798328) (xy 117.32682 -244.788148) (xy 117.279234 -244.770101)
			(xy 117.23516 -244.744655) (xy 117.195738 -244.712468) (xy 117.16199 -244.674374) (xy 117.134789 -244.63136)
			(xy 117.114841 -244.58454) (xy 117.102662 -244.535126) (xy 117.098567 -244.484398) (xy 116.79047 -244.484398)
			(xy 116.789958 -244.509844) (xy 116.781794 -244.560078) (xy 116.765678 -244.608352) (xy 116.742027 -244.653415)
			(xy 116.711454 -244.694101) (xy 116.67475 -244.729356) (xy 116.632866 -244.758266) (xy 116.586887 -244.780083)
			(xy 116.538003 -244.794243) (xy 116.487482 -244.800377) (xy 116.43663 -244.798328) (xy 116.386766 -244.788148)
			(xy 116.33918 -244.770101) (xy 116.295106 -244.744655) (xy 116.255684 -244.712468) (xy 116.221936 -244.674374)
			(xy 116.194735 -244.63136) (xy 116.174787 -244.58454) (xy 116.162608 -244.535126) (xy 116.158513 -244.484398)
			(xy 115.852702 -244.484398) (xy 115.852212 -244.509387) (xy 115.844393 -244.55875) (xy 115.828949 -244.606282)
			(xy 115.806259 -244.650814) (xy 115.776883 -244.691247) (xy 115.741543 -244.726587) (xy 115.70111 -244.755963)
			(xy 115.656578 -244.778653) (xy 115.609046 -244.794097) (xy 115.559683 -244.801916) (xy 115.509705 -244.801916)
			(xy 115.460342 -244.794097) (xy 115.41281 -244.778653) (xy 115.368278 -244.755963) (xy 115.327845 -244.726587)
			(xy 115.292505 -244.691247) (xy 115.263129 -244.650814) (xy 115.240439 -244.606282) (xy 115.224995 -244.55875)
			(xy 115.217176 -244.509387) (xy 114.912158 -244.509387) (xy 114.904339 -244.55875) (xy 114.888895 -244.606282)
			(xy 114.866205 -244.650814) (xy 114.836829 -244.691247) (xy 114.801489 -244.726587) (xy 114.761056 -244.755963)
			(xy 114.716524 -244.778653) (xy 114.668992 -244.794097) (xy 114.619629 -244.801916) (xy 114.569651 -244.801916)
			(xy 114.520288 -244.794097) (xy 114.472756 -244.778653) (xy 114.428224 -244.755963) (xy 114.387791 -244.726587)
			(xy 114.352451 -244.691247) (xy 114.323075 -244.650814) (xy 114.300385 -244.606282) (xy 114.284941 -244.55875)
			(xy 114.277122 -244.509387) (xy 113.972358 -244.509387) (xy 113.964539 -244.55875) (xy 113.949095 -244.606282)
			(xy 113.926405 -244.650814) (xy 113.897029 -244.691247) (xy 113.861689 -244.726587) (xy 113.821256 -244.755963)
			(xy 113.776724 -244.778653) (xy 113.729192 -244.794097) (xy 113.679829 -244.801916) (xy 113.629851 -244.801916)
			(xy 113.580488 -244.794097) (xy 113.532956 -244.778653) (xy 113.488424 -244.755963) (xy 113.447991 -244.726587)
			(xy 113.412651 -244.691247) (xy 113.383275 -244.650814) (xy 113.360585 -244.606282) (xy 113.345141 -244.55875)
			(xy 113.337322 -244.509387) (xy 110.218492 -244.509387) (xy 110.210673 -244.55875) (xy 110.195229 -244.606282)
			(xy 110.172539 -244.650814) (xy 110.143163 -244.691247) (xy 110.107823 -244.726587) (xy 110.06739 -244.755963)
			(xy 110.022858 -244.778653) (xy 109.975326 -244.794097) (xy 109.925963 -244.801916) (xy 109.875985 -244.801916)
			(xy 109.826622 -244.794097) (xy 109.77909 -244.778653) (xy 109.734558 -244.755963) (xy 109.694125 -244.726587)
			(xy 109.658785 -244.691247) (xy 109.629409 -244.650814) (xy 109.606719 -244.606282) (xy 109.591275 -244.55875)
			(xy 109.583456 -244.509387) (xy 109.278692 -244.509387) (xy 109.270873 -244.55875) (xy 109.255429 -244.606282)
			(xy 109.232739 -244.650814) (xy 109.203363 -244.691247) (xy 109.168023 -244.726587) (xy 109.12759 -244.755963)
			(xy 109.083058 -244.778653) (xy 109.035526 -244.794097) (xy 108.986163 -244.801916) (xy 108.936185 -244.801916)
			(xy 108.886822 -244.794097) (xy 108.83929 -244.778653) (xy 108.794758 -244.755963) (xy 108.754325 -244.726587)
			(xy 108.718985 -244.691247) (xy 108.689609 -244.650814) (xy 108.666919 -244.606282) (xy 108.651475 -244.55875)
			(xy 108.643656 -244.509387) (xy 108.338638 -244.509387) (xy 108.330819 -244.55875) (xy 108.315375 -244.606282)
			(xy 108.292685 -244.650814) (xy 108.263309 -244.691247) (xy 108.227969 -244.726587) (xy 108.187536 -244.755963)
			(xy 108.143004 -244.778653) (xy 108.095472 -244.794097) (xy 108.046109 -244.801916) (xy 107.996131 -244.801916)
			(xy 107.946768 -244.794097) (xy 107.899236 -244.778653) (xy 107.854704 -244.755963) (xy 107.814271 -244.726587)
			(xy 107.778931 -244.691247) (xy 107.749555 -244.650814) (xy 107.726865 -244.606282) (xy 107.711421 -244.55875)
			(xy 107.703602 -244.509387) (xy 107.396285 -244.509387) (xy 107.396276 -244.509844) (xy 107.388112 -244.560078)
			(xy 107.371996 -244.608352) (xy 107.348345 -244.653415) (xy 107.317772 -244.694101) (xy 107.281068 -244.729356)
			(xy 107.239184 -244.758266) (xy 107.193205 -244.780083) (xy 107.144321 -244.794243) (xy 107.0938 -244.800377)
			(xy 107.042948 -244.798328) (xy 106.993084 -244.788148) (xy 106.945498 -244.770101) (xy 106.901424 -244.744655)
			(xy 106.862002 -244.712468) (xy 106.828254 -244.674374) (xy 106.801053 -244.63136) (xy 106.781105 -244.58454)
			(xy 106.768926 -244.535126) (xy 106.764831 -244.484398) (xy 106.456734 -244.484398) (xy 106.456222 -244.509844)
			(xy 106.448058 -244.560078) (xy 106.431942 -244.608352) (xy 106.408291 -244.653415) (xy 106.377718 -244.694101)
			(xy 106.341014 -244.729356) (xy 106.29913 -244.758266) (xy 106.253151 -244.780083) (xy 106.204267 -244.794243)
			(xy 106.153746 -244.800377) (xy 106.102894 -244.798328) (xy 106.05303 -244.788148) (xy 106.005444 -244.770101)
			(xy 105.96137 -244.744655) (xy 105.921948 -244.712468) (xy 105.8882 -244.674374) (xy 105.860999 -244.63136)
			(xy 105.841051 -244.58454) (xy 105.828872 -244.535126) (xy 105.824777 -244.484398) (xy 105.518966 -244.484398)
			(xy 105.518476 -244.509387) (xy 105.510657 -244.55875) (xy 105.495213 -244.606282) (xy 105.472523 -244.650814)
			(xy 105.443147 -244.691247) (xy 105.407807 -244.726587) (xy 105.367374 -244.755963) (xy 105.322842 -244.778653)
			(xy 105.27531 -244.794097) (xy 105.225947 -244.801916) (xy 105.175969 -244.801916) (xy 105.126606 -244.794097)
			(xy 105.079074 -244.778653) (xy 105.034542 -244.755963) (xy 104.994109 -244.726587) (xy 104.958769 -244.691247)
			(xy 104.929393 -244.650814) (xy 104.906703 -244.606282) (xy 104.891259 -244.55875) (xy 104.88344 -244.509387)
			(xy 104.576377 -244.509387) (xy 104.576368 -244.509844) (xy 104.568204 -244.560078) (xy 104.552088 -244.608352)
			(xy 104.528437 -244.653415) (xy 104.497864 -244.694101) (xy 104.46116 -244.729356) (xy 104.419276 -244.758266)
			(xy 104.373297 -244.780083) (xy 104.324413 -244.794243) (xy 104.273892 -244.800377) (xy 104.22304 -244.798328)
			(xy 104.173176 -244.788148) (xy 104.12559 -244.770101) (xy 104.081516 -244.744655) (xy 104.042094 -244.712468)
			(xy 104.008346 -244.674374) (xy 103.981145 -244.63136) (xy 103.961197 -244.58454) (xy 103.949018 -244.535126)
			(xy 103.944923 -244.484398) (xy 103.636826 -244.484398) (xy 103.636314 -244.509844) (xy 103.62815 -244.560078)
			(xy 103.612034 -244.608352) (xy 103.588383 -244.653415) (xy 103.55781 -244.694101) (xy 103.521106 -244.729356)
			(xy 103.479222 -244.758266) (xy 103.433243 -244.780083) (xy 103.384359 -244.794243) (xy 103.333838 -244.800377)
			(xy 103.282986 -244.798328) (xy 103.233122 -244.788148) (xy 103.185536 -244.770101) (xy 103.141462 -244.744655)
			(xy 103.10204 -244.712468) (xy 103.068292 -244.674374) (xy 103.041091 -244.63136) (xy 103.021143 -244.58454)
			(xy 103.008964 -244.535126) (xy 103.004869 -244.484398) (xy 102.699058 -244.484398) (xy 102.698568 -244.509387)
			(xy 102.690749 -244.55875) (xy 102.675305 -244.606282) (xy 102.652615 -244.650814) (xy 102.623239 -244.691247)
			(xy 102.587899 -244.726587) (xy 102.547466 -244.755963) (xy 102.502934 -244.778653) (xy 102.455402 -244.794097)
			(xy 102.406039 -244.801916) (xy 102.356061 -244.801916) (xy 102.306698 -244.794097) (xy 102.259166 -244.778653)
			(xy 102.214634 -244.755963) (xy 102.174201 -244.726587) (xy 102.138861 -244.691247) (xy 102.109485 -244.650814)
			(xy 102.086795 -244.606282) (xy 102.071351 -244.55875) (xy 102.063532 -244.509387) (xy 101.756215 -244.509387)
			(xy 101.756206 -244.509844) (xy 101.748042 -244.560078) (xy 101.731926 -244.608352) (xy 101.708275 -244.653415)
			(xy 101.677702 -244.694101) (xy 101.640998 -244.729356) (xy 101.599114 -244.758266) (xy 101.553135 -244.780083)
			(xy 101.504251 -244.794243) (xy 101.45373 -244.800377) (xy 101.402878 -244.798328) (xy 101.353014 -244.788148)
			(xy 101.305428 -244.770101) (xy 101.261354 -244.744655) (xy 101.221932 -244.712468) (xy 101.188184 -244.674374)
			(xy 101.160983 -244.63136) (xy 101.141035 -244.58454) (xy 101.128856 -244.535126) (xy 101.124761 -244.484398)
			(xy 100.816664 -244.484398) (xy 100.816152 -244.509844) (xy 100.807988 -244.560078) (xy 100.791872 -244.608352)
			(xy 100.768221 -244.653415) (xy 100.737648 -244.694101) (xy 100.700944 -244.729356) (xy 100.65906 -244.758266)
			(xy 100.613081 -244.780083) (xy 100.564197 -244.794243) (xy 100.513676 -244.800377) (xy 100.462824 -244.798328)
			(xy 100.41296 -244.788148) (xy 100.365374 -244.770101) (xy 100.3213 -244.744655) (xy 100.281878 -244.712468)
			(xy 100.24813 -244.674374) (xy 100.220929 -244.63136) (xy 100.200981 -244.58454) (xy 100.188802 -244.535126)
			(xy 100.184707 -244.484398) (xy 99.87915 -244.484398) (xy 99.87866 -244.509387) (xy 99.870841 -244.55875)
			(xy 99.855397 -244.606282) (xy 99.832707 -244.650814) (xy 99.803331 -244.691247) (xy 99.767991 -244.726587)
			(xy 99.727558 -244.755963) (xy 99.683026 -244.778653) (xy 99.635494 -244.794097) (xy 99.586131 -244.801916)
			(xy 99.536153 -244.801916) (xy 99.48679 -244.794097) (xy 99.439258 -244.778653) (xy 99.394726 -244.755963)
			(xy 99.354293 -244.726587) (xy 99.318953 -244.691247) (xy 99.289577 -244.650814) (xy 99.266887 -244.606282)
			(xy 99.251443 -244.55875) (xy 99.243624 -244.509387) (xy 98.936307 -244.509387) (xy 98.936298 -244.509844)
			(xy 98.928134 -244.560078) (xy 98.912018 -244.608352) (xy 98.888367 -244.653415) (xy 98.857794 -244.694101)
			(xy 98.82109 -244.729356) (xy 98.779206 -244.758266) (xy 98.733227 -244.780083) (xy 98.684343 -244.794243)
			(xy 98.633822 -244.800377) (xy 98.58297 -244.798328) (xy 98.533106 -244.788148) (xy 98.48552 -244.770101)
			(xy 98.441446 -244.744655) (xy 98.402024 -244.712468) (xy 98.368276 -244.674374) (xy 98.341075 -244.63136)
			(xy 98.321127 -244.58454) (xy 98.308948 -244.535126) (xy 98.304853 -244.484398) (xy 97.996756 -244.484398)
			(xy 97.996244 -244.509844) (xy 97.98808 -244.560078) (xy 97.971964 -244.608352) (xy 97.948313 -244.653415)
			(xy 97.91774 -244.694101) (xy 97.881036 -244.729356) (xy 97.839152 -244.758266) (xy 97.793173 -244.780083)
			(xy 97.744289 -244.794243) (xy 97.693768 -244.800377) (xy 97.642916 -244.798328) (xy 97.593052 -244.788148)
			(xy 97.545466 -244.770101) (xy 97.501392 -244.744655) (xy 97.46197 -244.712468) (xy 97.428222 -244.674374)
			(xy 97.401021 -244.63136) (xy 97.381073 -244.58454) (xy 97.368894 -244.535126) (xy 97.364799 -244.484398)
			(xy 97.058988 -244.484398) (xy 97.058988 -244.487954) (xy 97.057718 -244.517926) (xy 97.057464 -244.51945)
			(xy 97.057464 -245.319393) (xy 98.77347 -245.319393) (xy 98.77347 -245.269415) (xy 98.781289 -245.220052)
			(xy 98.796733 -245.17252) (xy 98.819423 -245.127988) (xy 98.848799 -245.087555) (xy 98.884139 -245.052215)
			(xy 98.924572 -245.022839) (xy 98.969104 -245.000149) (xy 99.016636 -244.984705) (xy 99.065999 -244.976886)
			(xy 99.115977 -244.976886) (xy 99.16534 -244.984705) (xy 99.212872 -245.000149) (xy 99.257404 -245.022839)
			(xy 99.297837 -245.052215) (xy 99.333177 -245.087555) (xy 99.362553 -245.127988) (xy 99.385243 -245.17252)
			(xy 99.400687 -245.220052) (xy 99.408506 -245.269415) (xy 99.408996 -245.294404) (xy 99.408506 -245.319393)
			(xy 99.400687 -245.368756) (xy 99.385243 -245.416288) (xy 99.362553 -245.46082) (xy 99.333177 -245.501253)
			(xy 99.297837 -245.536593) (xy 99.257404 -245.565969) (xy 99.212872 -245.588659) (xy 99.16534 -245.604103)
			(xy 99.115977 -245.611922) (xy 99.065999 -245.611922) (xy 99.016636 -245.604103) (xy 98.969104 -245.588659)
			(xy 98.924572 -245.565969) (xy 98.884139 -245.536593) (xy 98.848799 -245.501253) (xy 98.819423 -245.46082)
			(xy 98.796733 -245.416288) (xy 98.781289 -245.368756) (xy 98.77347 -245.319393) (xy 97.057464 -245.319393)
			(xy 97.057464 -246.066818) (xy 97.057718 -246.07139) (xy 97.058988 -246.10187) (xy 97.058988 -246.10441)
			(xy 97.364799 -246.10441) (xy 97.368894 -246.053682) (xy 97.381073 -246.004268) (xy 97.401021 -245.957448)
			(xy 97.428222 -245.914434) (xy 97.46197 -245.87634) (xy 97.501392 -245.844153) (xy 97.545466 -245.818707)
			(xy 97.593052 -245.80066) (xy 97.642916 -245.79048) (xy 97.693768 -245.788431) (xy 97.744289 -245.794565)
			(xy 97.793173 -245.808725) (xy 97.839152 -245.830542) (xy 97.881036 -245.859452) (xy 97.91774 -245.894707)
			(xy 97.948313 -245.935393) (xy 97.971964 -245.980456) (xy 97.98808 -246.02873) (xy 97.996244 -246.078964)
			(xy 97.996756 -246.10441) (xy 98.304853 -246.10441) (xy 98.308948 -246.053682) (xy 98.321127 -246.004268)
			(xy 98.341075 -245.957448) (xy 98.368276 -245.914434) (xy 98.402024 -245.87634) (xy 98.441446 -245.844153)
			(xy 98.48552 -245.818707) (xy 98.533106 -245.80066) (xy 98.58297 -245.79048) (xy 98.633822 -245.788431)
			(xy 98.684343 -245.794565) (xy 98.733227 -245.808725) (xy 98.779206 -245.830542) (xy 98.82109 -245.859452)
			(xy 98.857794 -245.894707) (xy 98.888367 -245.935393) (xy 98.912018 -245.980456) (xy 98.928134 -246.02873)
			(xy 98.936298 -246.078964) (xy 98.93681 -246.10441) (xy 99.129088 -246.10441) (xy 99.129498 -246.076119)
			(xy 99.136883 -246.020022) (xy 99.151527 -245.965368) (xy 99.17318 -245.913093) (xy 99.201472 -245.864093)
			(xy 99.235918 -245.819204) (xy 99.275928 -245.779197) (xy 99.320819 -245.744754) (xy 99.369822 -245.716466)
			(xy 99.422098 -245.694817) (xy 99.476753 -245.680176) (xy 99.532851 -245.672796) (xy 99.561142 -245.672356)
			(xy 99.589432 -245.6728) (xy 99.645529 -245.680186) (xy 99.700182 -245.694826) (xy 99.752459 -245.71647)
			(xy 99.801466 -245.744749) (xy 99.846365 -245.779178) (xy 99.866704 -245.798848) (xy 99.890326 -245.822216)
			(xy 99.897492 -245.828693) (xy 99.915236 -245.83628) (xy 99.92487 -245.836948) (xy 99.953829 -245.837994)
			(xy 100.01109 -245.846886) (xy 100.06665 -245.86335) (xy 100.093272 -245.874794) (xy 100.103178 -245.879112)
			(xy 100.259896 -245.879112) (xy 100.268996 -245.878712) (xy 100.286046 -245.872341) (xy 100.29317 -245.866666)
			(xy 100.310533 -245.852059) (xy 100.348619 -245.8274) (xy 100.389842 -245.808446) (xy 100.433353 -245.795586)
			(xy 100.478256 -245.789084) (xy 100.500942 -245.788688) (xy 100.52575 -245.789158) (xy 100.574755 -245.796926)
			(xy 100.621941 -245.812263) (xy 100.666148 -245.834792) (xy 100.706286 -245.863959) (xy 100.741368 -245.899046)
			(xy 100.77053 -245.939188) (xy 100.793053 -245.983398) (xy 100.808384 -246.030586) (xy 100.816145 -246.079592)
			(xy 100.816145 -246.10441) (xy 101.125528 -246.10441) (xy 101.125961 -246.080067) (xy 101.133447 -246.031961)
			(xy 101.148227 -245.985573) (xy 101.169951 -245.942003) (xy 101.198105 -245.902283) (xy 101.232021 -245.867355)
			(xy 101.270896 -245.838046) (xy 101.313808 -245.81505) (xy 101.359741 -245.798912) (xy 101.383592 -245.794022)
			(xy 101.40188 -245.79072) (xy 101.425248 -245.762526) (xy 101.425248 -245.233952) (xy 101.42565 -245.223935)
			(xy 101.433334 -245.205433) (xy 101.447514 -245.19128) (xy 101.46603 -245.183631) (xy 101.476048 -245.183152)
			(xy 101.57968 -245.183152) (xy 101.589186 -245.182829) (xy 101.606908 -245.175956) (xy 101.62089 -245.16308)
			(xy 101.6254 -245.154704) (xy 101.636994 -245.132136) (xy 101.666247 -245.090685) (xy 101.701706 -245.054401)
			(xy 101.742474 -245.024202) (xy 101.787517 -245.000856) (xy 101.835693 -244.984952) (xy 101.885783 -244.976894)
			(xy 101.91115 -244.976396) (xy 101.93614 -244.976903) (xy 101.985506 -244.984715) (xy 102.033041 -245.000153)
			(xy 102.077576 -245.022839) (xy 102.118013 -245.052213) (xy 102.153357 -245.087552) (xy 102.182737 -245.127985)
			(xy 102.205429 -245.172516) (xy 102.220875 -245.220049) (xy 102.228693 -245.269414) (xy 102.229158 -245.294404)
			(xy 102.229158 -245.294658) (xy 104.41305 -245.294658) (xy 104.41305 -245.294404) (xy 104.413586 -245.269417)
			(xy 104.421402 -245.220058) (xy 104.436843 -245.17253) (xy 104.459529 -245.128001) (xy 104.4889 -245.08757)
			(xy 104.524235 -245.05223) (xy 104.564662 -245.022853) (xy 104.609187 -245.000161) (xy 104.656713 -244.984713)
			(xy 104.706071 -244.976889) (xy 104.731058 -244.976396) (xy 104.756428 -244.976886) (xy 104.806526 -244.984923)
			(xy 104.854711 -245.000816) (xy 104.899761 -245.024161) (xy 104.94053 -245.054365) (xy 104.975984 -245.090662)
			(xy 105.005223 -245.132129) (xy 105.016808 -245.154704) (xy 105.021328 -245.163059) (xy 105.03534 -245.175874)
			(xy 105.053035 -245.18276) (xy 105.062528 -245.183152) (xy 105.16362 -245.183152) (xy 105.173623 -245.18367)
			(xy 105.192106 -245.191328) (xy 105.206257 -245.20547) (xy 105.213924 -245.223949) (xy 105.21442 -245.233952)
			(xy 105.21442 -245.74119) (xy 105.214695 -245.750114) (xy 105.22084 -245.766873) (xy 105.232355 -245.780511)
			(xy 105.247846 -245.789379) (xy 105.256584 -245.791228) (xy 105.280774 -245.796041) (xy 105.327412 -245.812075)
			(xy 105.371017 -245.835114) (xy 105.410546 -245.864605) (xy 105.44505 -245.899842) (xy 105.473704 -245.939982)
			(xy 105.495821 -245.984062) (xy 105.510872 -246.031027) (xy 105.518496 -246.079751) (xy 105.518966 -246.10441)
			(xy 105.824777 -246.10441) (xy 105.828872 -246.053682) (xy 105.841051 -246.004268) (xy 105.860999 -245.957448)
			(xy 105.8882 -245.914434) (xy 105.921948 -245.87634) (xy 105.96137 -245.844153) (xy 106.005444 -245.818707)
			(xy 106.05303 -245.80066) (xy 106.102894 -245.79048) (xy 106.153746 -245.788431) (xy 106.204267 -245.794565)
			(xy 106.253151 -245.808725) (xy 106.29913 -245.830542) (xy 106.341014 -245.859452) (xy 106.377718 -245.894707)
			(xy 106.408291 -245.935393) (xy 106.431942 -245.980456) (xy 106.448058 -246.02873) (xy 106.456222 -246.078964)
			(xy 106.456734 -246.10441) (xy 106.765344 -246.10441) (xy 106.765845 -246.078638) (xy 106.774193 -246.027775)
			(xy 106.790702 -245.978946) (xy 106.814932 -245.933453) (xy 106.846238 -245.892505) (xy 106.883786 -245.857194)
			(xy 106.926577 -245.828459) (xy 106.973471 -245.807065) (xy 107.02322 -245.793582) (xy 107.048808 -245.790466)
			(xy 107.049062 -245.790466) (xy 107.058258 -245.78906) (xy 107.074804 -245.780595) (xy 107.08132 -245.773956)
			(xy 107.12704 -245.72341) (xy 107.133102 -245.716243) (xy 107.139886 -245.698754) (xy 107.140248 -245.689374)
			(xy 107.140248 -245.233952) (xy 107.14065 -245.223935) (xy 107.148334 -245.205433) (xy 107.162514 -245.19128)
			(xy 107.18103 -245.183631) (xy 107.191048 -245.183152) (xy 107.219496 -245.183152) (xy 107.229003 -245.182841)
			(xy 107.246725 -245.175962) (xy 107.260707 -245.163081) (xy 107.265216 -245.154704) (xy 107.276798 -245.13213)
			(xy 107.306053 -245.090678) (xy 107.341514 -245.054394) (xy 107.382284 -245.024196) (xy 107.427328 -245.000851)
			(xy 107.475507 -244.984948) (xy 107.525598 -244.976892) (xy 107.550966 -244.976396) (xy 107.575942 -244.976913)
			(xy 107.62528 -244.984718) (xy 107.67279 -245.000142) (xy 107.717304 -245.022806) (xy 107.757727 -245.052152)
			(xy 107.793064 -245.087457) (xy 107.822445 -245.127853) (xy 107.845149 -245.172347) (xy 107.860615 -245.219844)
			(xy 107.868465 -245.269175) (xy 107.868974 -245.29415) (xy 107.868974 -245.294404) (xy 108.174785 -245.294404)
			(xy 108.17888 -245.243676) (xy 108.191059 -245.194262) (xy 108.211007 -245.147442) (xy 108.238208 -245.104428)
			(xy 108.271956 -245.066334) (xy 108.311378 -245.034147) (xy 108.355452 -245.008701) (xy 108.403038 -244.990654)
			(xy 108.452902 -244.980474) (xy 108.503754 -244.978425) (xy 108.554275 -244.984559) (xy 108.603159 -244.998719)
			(xy 108.649138 -245.020536) (xy 108.691022 -245.049446) (xy 108.727726 -245.084701) (xy 108.758299 -245.125387)
			(xy 108.78195 -245.17045) (xy 108.798066 -245.218724) (xy 108.80623 -245.268958) (xy 108.806742 -245.294404)
			(xy 109.114839 -245.294404) (xy 109.118934 -245.243676) (xy 109.131113 -245.194262) (xy 109.151061 -245.147442)
			(xy 109.178262 -245.104428) (xy 109.21201 -245.066334) (xy 109.251432 -245.034147) (xy 109.295506 -245.008701)
			(xy 109.343092 -244.990654) (xy 109.392956 -244.980474) (xy 109.443808 -244.978425) (xy 109.494329 -244.984559)
			(xy 109.543213 -244.998719) (xy 109.589192 -245.020536) (xy 109.631076 -245.049446) (xy 109.66778 -245.084701)
			(xy 109.698353 -245.125387) (xy 109.722004 -245.17045) (xy 109.73812 -245.218724) (xy 109.746284 -245.268958)
			(xy 109.746796 -245.294404) (xy 109.746293 -245.319393) (xy 110.05361 -245.319393) (xy 110.05361 -245.269415)
			(xy 110.061429 -245.220052) (xy 110.076873 -245.17252) (xy 110.099563 -245.127988) (xy 110.128939 -245.087555)
			(xy 110.164279 -245.052215) (xy 110.204712 -245.022839) (xy 110.249244 -245.000149) (xy 110.296776 -244.984705)
			(xy 110.346139 -244.976886) (xy 110.396117 -244.976886) (xy 110.44548 -244.984705) (xy 110.493012 -245.000149)
			(xy 110.537544 -245.022839) (xy 110.577977 -245.052215) (xy 110.613317 -245.087555) (xy 110.642693 -245.127988)
			(xy 110.665383 -245.17252) (xy 110.680827 -245.220052) (xy 110.688646 -245.269415) (xy 110.689136 -245.294404)
			(xy 110.688646 -245.319393) (xy 110.680827 -245.368756) (xy 110.665383 -245.416288) (xy 110.642693 -245.46082)
			(xy 110.613317 -245.501253) (xy 110.577977 -245.536593) (xy 110.537544 -245.565969) (xy 110.493012 -245.588659)
			(xy 110.44548 -245.604103) (xy 110.396117 -245.611922) (xy 110.346139 -245.611922) (xy 110.296776 -245.604103)
			(xy 110.249244 -245.588659) (xy 110.204712 -245.565969) (xy 110.164279 -245.536593) (xy 110.128939 -245.501253)
			(xy 110.099563 -245.46082) (xy 110.076873 -245.416288) (xy 110.061429 -245.368756) (xy 110.05361 -245.319393)
			(xy 109.746293 -245.319393) (xy 109.746284 -245.31985) (xy 109.73812 -245.370084) (xy 109.722004 -245.418358)
			(xy 109.698353 -245.463421) (xy 109.66778 -245.504107) (xy 109.631076 -245.539362) (xy 109.589192 -245.568272)
			(xy 109.543213 -245.590089) (xy 109.494329 -245.604249) (xy 109.443808 -245.610383) (xy 109.392956 -245.608334)
			(xy 109.343092 -245.598154) (xy 109.295506 -245.580107) (xy 109.251432 -245.554661) (xy 109.21201 -245.522474)
			(xy 109.178262 -245.48438) (xy 109.151061 -245.441366) (xy 109.131113 -245.394546) (xy 109.118934 -245.345132)
			(xy 109.114839 -245.294404) (xy 108.806742 -245.294404) (xy 108.80623 -245.31985) (xy 108.798066 -245.370084)
			(xy 108.78195 -245.418358) (xy 108.758299 -245.463421) (xy 108.727726 -245.504107) (xy 108.691022 -245.539362)
			(xy 108.649138 -245.568272) (xy 108.603159 -245.590089) (xy 108.554275 -245.604249) (xy 108.503754 -245.610383)
			(xy 108.452902 -245.608334) (xy 108.403038 -245.598154) (xy 108.355452 -245.580107) (xy 108.311378 -245.554661)
			(xy 108.271956 -245.522474) (xy 108.238208 -245.48438) (xy 108.211007 -245.441366) (xy 108.191059 -245.394546)
			(xy 108.17888 -245.345132) (xy 108.174785 -245.294404) (xy 107.868974 -245.294404) (xy 107.868974 -245.294658)
			(xy 107.871028 -245.305398) (xy 107.873192 -245.327158) (xy 107.873292 -245.338092) (xy 107.873292 -245.637812)
			(xy 107.872784 -245.652798) (xy 107.872645 -245.664084) (xy 107.880968 -245.68504) (xy 107.888786 -245.693184)
			(xy 107.912916 -245.71579) (xy 107.921943 -245.723316) (xy 107.944421 -245.730077) (xy 107.956096 -245.728744)
			(xy 107.972224 -245.726126) (xy 108.004781 -245.723329) (xy 108.02112 -245.723156) (xy 108.051092 -245.723699)
			(xy 108.110307 -245.733013) (xy 108.133197 -245.740428) (xy 111.435896 -245.740428) (xy 111.435896 -245.536466)
			(xy 111.436332 -245.517143) (xy 111.443313 -245.479132) (xy 111.457006 -245.442991) (xy 111.46663 -245.42623)
			(xy 111.470186 -245.419118) (xy 111.480518 -245.394777) (xy 111.507323 -245.349197) (xy 111.540575 -245.308083)
			(xy 111.579542 -245.272339) (xy 111.623367 -245.242752) (xy 111.671087 -245.219973) (xy 111.721651 -245.204503)
			(xy 111.773947 -245.196682) (xy 111.826825 -245.196682) (xy 111.879121 -245.204503) (xy 111.929685 -245.219973)
			(xy 111.977405 -245.242752) (xy 112.02123 -245.272339) (xy 112.060197 -245.308083) (xy 112.069344 -245.319393)
			(xy 112.867168 -245.319393) (xy 112.867168 -245.269415) (xy 112.874987 -245.220052) (xy 112.890431 -245.17252)
			(xy 112.913121 -245.127988) (xy 112.942497 -245.087555) (xy 112.977837 -245.052215) (xy 113.01827 -245.022839)
			(xy 113.062802 -245.000149) (xy 113.110334 -244.984705) (xy 113.159697 -244.976886) (xy 113.209675 -244.976886)
			(xy 113.259038 -244.984705) (xy 113.30657 -245.000149) (xy 113.351102 -245.022839) (xy 113.391535 -245.052215)
			(xy 113.426875 -245.087555) (xy 113.456251 -245.127988) (xy 113.478941 -245.17252) (xy 113.494385 -245.220052)
			(xy 113.502204 -245.269415) (xy 113.502694 -245.294404) (xy 113.808505 -245.294404) (xy 113.8126 -245.243676)
			(xy 113.824779 -245.194262) (xy 113.844727 -245.147442) (xy 113.871928 -245.104428) (xy 113.905676 -245.066334)
			(xy 113.945098 -245.034147) (xy 113.989172 -245.008701) (xy 114.036758 -244.990654) (xy 114.086622 -244.980474)
			(xy 114.137474 -244.978425) (xy 114.187995 -244.984559) (xy 114.236879 -244.998719) (xy 114.282858 -245.020536)
			(xy 114.324742 -245.049446) (xy 114.361446 -245.084701) (xy 114.392019 -245.125387) (xy 114.41567 -245.17045)
			(xy 114.431786 -245.218724) (xy 114.43995 -245.268958) (xy 114.440462 -245.294404) (xy 114.748559 -245.294404)
			(xy 114.752654 -245.243676) (xy 114.764833 -245.194262) (xy 114.784781 -245.147442) (xy 114.811982 -245.104428)
			(xy 114.84573 -245.066334) (xy 114.885152 -245.034147) (xy 114.929226 -245.008701) (xy 114.976812 -244.990654)
			(xy 115.026676 -244.980474) (xy 115.077528 -244.978425) (xy 115.128049 -244.984559) (xy 115.176933 -244.998719)
			(xy 115.222912 -245.020536) (xy 115.264796 -245.049446) (xy 115.3015 -245.084701) (xy 115.332073 -245.125387)
			(xy 115.355724 -245.17045) (xy 115.37184 -245.218724) (xy 115.380004 -245.268958) (xy 115.380516 -245.294404)
			(xy 115.380004 -245.31985) (xy 115.37184 -245.370084) (xy 115.355724 -245.418358) (xy 115.332073 -245.463421)
			(xy 115.3015 -245.504107) (xy 115.264796 -245.539362) (xy 115.222912 -245.568272) (xy 115.176933 -245.590089)
			(xy 115.128049 -245.604249) (xy 115.077528 -245.610383) (xy 115.026676 -245.608334) (xy 114.976812 -245.598154)
			(xy 114.929226 -245.580107) (xy 114.885152 -245.554661) (xy 114.84573 -245.522474) (xy 114.811982 -245.48438)
			(xy 114.784781 -245.441366) (xy 114.764833 -245.394546) (xy 114.752654 -245.345132) (xy 114.748559 -245.294404)
			(xy 114.440462 -245.294404) (xy 114.43995 -245.31985) (xy 114.431786 -245.370084) (xy 114.41567 -245.418358)
			(xy 114.392019 -245.463421) (xy 114.361446 -245.504107) (xy 114.324742 -245.539362) (xy 114.282858 -245.568272)
			(xy 114.236879 -245.590089) (xy 114.187995 -245.604249) (xy 114.137474 -245.610383) (xy 114.086622 -245.608334)
			(xy 114.036758 -245.598154) (xy 113.989172 -245.580107) (xy 113.945098 -245.554661) (xy 113.905676 -245.522474)
			(xy 113.871928 -245.48438) (xy 113.844727 -245.441366) (xy 113.824779 -245.394546) (xy 113.8126 -245.345132)
			(xy 113.808505 -245.294404) (xy 113.502694 -245.294404) (xy 113.502204 -245.319393) (xy 113.494385 -245.368756)
			(xy 113.478941 -245.416288) (xy 113.456251 -245.46082) (xy 113.426875 -245.501253) (xy 113.391535 -245.536593)
			(xy 113.351102 -245.565969) (xy 113.30657 -245.588659) (xy 113.259038 -245.604103) (xy 113.209675 -245.611922)
			(xy 113.159697 -245.611922) (xy 113.110334 -245.604103) (xy 113.062802 -245.588659) (xy 113.01827 -245.565969)
			(xy 112.977837 -245.536593) (xy 112.942497 -245.501253) (xy 112.913121 -245.46082) (xy 112.890431 -245.416288)
			(xy 112.874987 -245.368756) (xy 112.867168 -245.319393) (xy 112.069344 -245.319393) (xy 112.093449 -245.349197)
			(xy 112.120254 -245.394777) (xy 112.130586 -245.419118) (xy 112.134142 -245.42623) (xy 112.143781 -245.442986)
			(xy 112.157495 -245.479122) (xy 112.16446 -245.51714) (xy 112.164876 -245.536466) (xy 112.164876 -245.791228)
			(xy 112.155732 -245.791228) (xy 112.145709 -245.791647) (xy 112.127188 -245.799311) (xy 112.113013 -245.813484)
			(xy 112.105347 -245.832005) (xy 112.104932 -245.842028) (xy 112.104932 -246.005604) (xy 112.104416 -246.015608)
			(xy 112.096761 -246.034094) (xy 112.082617 -246.048245) (xy 112.064136 -246.05591) (xy 112.054132 -246.056404)
			(xy 111.54664 -246.056404) (xy 111.536622 -246.055948) (xy 111.518107 -246.048292) (xy 111.503933 -246.03413)
			(xy 111.496261 -246.015622) (xy 111.49584 -246.005604) (xy 111.49584 -245.791228) (xy 111.486696 -245.791228)
			(xy 111.476692 -245.790716) (xy 111.458205 -245.78306) (xy 111.444053 -245.768915) (xy 111.436389 -245.750432)
			(xy 111.435896 -245.740428) (xy 108.133197 -245.740428) (xy 108.167332 -245.751486) (xy 108.22076 -245.778662)
			(xy 108.269273 -245.813871) (xy 108.290868 -245.834662) (xy 108.371132 -245.914926) (xy 108.39146 -245.936039)
			(xy 108.426045 -245.983353) (xy 108.452986 -246.035401) (xy 108.462826 -246.063008) (xy 108.469176 -246.081804)
			(xy 108.49102 -246.097552) (xy 108.49102 -246.551704) (xy 108.491425 -246.560786) (xy 108.497738 -246.577817)
			(xy 108.509602 -246.59157) (xy 108.525522 -246.600312) (xy 108.534454 -246.601996) (xy 108.534962 -246.601996)
			(xy 108.559747 -246.605968) (xy 108.607715 -246.620743) (xy 108.652739 -246.642928) (xy 108.693683 -246.671962)
			(xy 108.729513 -246.707112) (xy 108.759325 -246.747492) (xy 108.782368 -246.792083) (xy 108.798059 -246.83976)
			(xy 108.806004 -246.88932) (xy 108.806488 -246.914416) (xy 109.114839 -246.914416) (xy 109.118934 -246.863688)
			(xy 109.131113 -246.814274) (xy 109.151061 -246.767454) (xy 109.178262 -246.72444) (xy 109.21201 -246.686346)
			(xy 109.251432 -246.654159) (xy 109.295506 -246.628713) (xy 109.343092 -246.610666) (xy 109.392956 -246.600486)
			(xy 109.443808 -246.598437) (xy 109.494329 -246.604571) (xy 109.543213 -246.618731) (xy 109.554459 -246.624067)
			(xy 109.908684 -246.624067) (xy 109.913858 -246.60472) (xy 109.926042 -246.588827) (xy 109.934502 -246.583454)
			(xy 110.37443 -246.329454) (xy 110.383316 -246.324841) (xy 110.40315 -246.322229) (xy 110.422473 -246.327404)
			(xy 110.438346 -246.339579) (xy 110.443772 -246.347996) (xy 110.55096 -246.53367) (xy 110.559088 -246.529098)
			(xy 110.567966 -246.524447) (xy 110.58782 -246.521817) (xy 110.607168 -246.52699) (xy 110.623059 -246.539178)
			(xy 110.62843 -246.54764) (xy 110.73003 -246.723916) (xy 110.740031 -246.742107) (xy 110.753467 -246.78138)
			(xy 110.75907 -246.822509) (xy 110.759069 -246.82252) (xy 112.841782 -246.82252) (xy 112.847377 -246.781401)
			(xy 112.860797 -246.742133) (xy 112.870742 -246.723916) (xy 112.997742 -246.503698) (xy 113.00587 -246.50827)
			(xy 113.01479 -246.512807) (xy 113.034603 -246.515433) (xy 113.053913 -246.51028) (xy 113.069783 -246.498132)
			(xy 113.075212 -246.489728) (xy 113.157 -246.347996) (xy 113.16233 -246.339506) (xy 113.178239 -246.327325)
			(xy 113.197599 -246.32216) (xy 113.217461 -246.324798) (xy 113.226342 -246.329454) (xy 113.66627 -246.583454)
			(xy 113.674722 -246.588838) (xy 113.686909 -246.604725) (xy 113.692085 -246.624068) (xy 113.689461 -246.643919)
			(xy 113.684812 -246.652796) (xy 113.577624 -246.837962) (xy 113.585498 -246.842534) (xy 113.594019 -246.847853)
			(xy 113.606327 -246.863708) (xy 113.611578 -246.883081) (xy 113.608962 -246.902981) (xy 113.604294 -246.911876)
			(xy 113.602827 -246.914416) (xy 113.808505 -246.914416) (xy 113.8126 -246.863688) (xy 113.824779 -246.814274)
			(xy 113.844727 -246.767454) (xy 113.871928 -246.72444) (xy 113.905676 -246.686346) (xy 113.945098 -246.654159)
			(xy 113.989172 -246.628713) (xy 114.036758 -246.610666) (xy 114.086622 -246.600486) (xy 114.137474 -246.598437)
			(xy 114.187995 -246.604571) (xy 114.236879 -246.618731) (xy 114.282858 -246.640548) (xy 114.324742 -246.669458)
			(xy 114.361446 -246.704713) (xy 114.392019 -246.745399) (xy 114.41567 -246.790462) (xy 114.431786 -246.838736)
			(xy 114.43995 -246.88897) (xy 114.440462 -246.914416) (xy 114.749072 -246.914416) (xy 114.749632 -246.887911)
			(xy 114.758474 -246.835645) (xy 114.77593 -246.785592) (xy 114.801507 -246.739162) (xy 114.834487 -246.697661)
			(xy 114.87394 -246.662258) (xy 114.918757 -246.633948) (xy 114.967675 -246.613529) (xy 115.019319 -246.601575)
			(xy 115.045744 -246.599456) (xy 115.055275 -246.598459) (xy 115.072633 -246.590366) (xy 115.079526 -246.583708)
			(xy 115.127532 -246.532908) (xy 115.133766 -246.525585) (xy 115.140827 -246.507716) (xy 115.141248 -246.49811)
			(xy 115.141248 -246.072152) (xy 115.148868 -246.072152) (xy 115.15725 -246.031766) (xy 115.163327 -246.004597)
			(xy 115.182273 -245.95225) (xy 115.208625 -245.903212) (xy 115.241823 -245.858523) (xy 115.261136 -245.838472)
			(xy 115.264946 -245.834662) (xy 115.286573 -245.81391) (xy 115.33509 -245.778721) (xy 115.388512 -245.751551)
			(xy 115.445525 -245.733069) (xy 115.504727 -245.723728) (xy 115.534694 -245.723156) (xy 115.564458 -245.723709)
			(xy 115.623274 -245.732891) (xy 115.651788 -245.741444) (xy 115.663726 -245.745254) (xy 115.687602 -245.741444)
			(xy 115.764056 -245.684548) (xy 115.77334 -245.676819) (xy 115.784077 -245.655214) (xy 115.78463 -245.643146)
			(xy 115.78463 -245.642892) (xy 115.784376 -245.637812) (xy 115.784376 -245.54434) (xy 115.783968 -245.534876)
			(xy 115.777061 -245.517256) (xy 115.770914 -245.51005) (xy 115.75519 -245.492344) (xy 115.72863 -245.453142)
			(xy 115.70818 -245.410433) (xy 115.694292 -245.365163) (xy 115.687273 -245.318334) (xy 115.68684 -245.294658)
			(xy 115.68684 -245.294404) (xy 115.68726 -245.26941) (xy 115.69508 -245.220039) (xy 115.710528 -245.172499)
			(xy 115.733223 -245.127961) (xy 115.762607 -245.087522) (xy 115.797956 -245.052178) (xy 115.838398 -245.0228)
			(xy 115.882939 -245.000111) (xy 115.930482 -244.98467) (xy 115.979854 -244.976857) (xy 116.004848 -244.976396)
			(xy 116.030217 -244.976894) (xy 116.080315 -244.98493) (xy 116.128501 -245.000821) (xy 116.17355 -245.024165)
			(xy 116.214319 -245.054368) (xy 116.249774 -245.090663) (xy 116.279013 -245.132129) (xy 116.290598 -245.154704)
			(xy 116.295125 -245.163055) (xy 116.309134 -245.17587) (xy 116.326826 -245.182758) (xy 116.336318 -245.183152)
			(xy 116.46662 -245.183152) (xy 116.476623 -245.18367) (xy 116.495106 -245.191328) (xy 116.509257 -245.20547)
			(xy 116.516924 -245.223949) (xy 116.51742 -245.233952) (xy 116.51742 -245.750334) (xy 116.518044 -245.761447)
			(xy 116.527428 -245.781595) (xy 116.544432 -245.795909) (xy 116.555012 -245.799356) (xy 116.555266 -245.799356)
			(xy 116.580177 -245.806463) (xy 116.627425 -245.827693) (xy 116.670572 -245.856356) (xy 116.708457 -245.891681)
			(xy 116.740063 -245.93272) (xy 116.764542 -245.978371) (xy 116.781235 -246.027406) (xy 116.789694 -246.07851)
			(xy 116.790216 -246.10441) (xy 117.098567 -246.10441) (xy 117.102662 -246.053682) (xy 117.114841 -246.004268)
			(xy 117.134789 -245.957448) (xy 117.16199 -245.914434) (xy 117.195738 -245.87634) (xy 117.23516 -245.844153)
			(xy 117.279234 -245.818707) (xy 117.32682 -245.80066) (xy 117.376684 -245.79048) (xy 117.427536 -245.788431)
			(xy 117.478057 -245.794565) (xy 117.526941 -245.808725) (xy 117.57292 -245.830542) (xy 117.614804 -245.859452)
			(xy 117.651508 -245.894707) (xy 117.682081 -245.935393) (xy 117.705732 -245.980456) (xy 117.721848 -246.02873)
			(xy 117.730012 -246.078964) (xy 117.730524 -246.10441) (xy 118.036848 -246.10441) (xy 118.037257 -246.079932)
			(xy 118.044786 -246.031559) (xy 118.059637 -245.98491) (xy 118.08146 -245.941087) (xy 118.10974 -245.901125)
			(xy 118.143808 -245.865967) (xy 118.18286 -245.836443) (xy 118.225974 -245.813252) (xy 118.272132 -245.796939)
			(xy 118.320245 -245.787891) (xy 118.344696 -245.786656) (xy 118.34495 -245.786656) (xy 118.354657 -245.785823)
			(xy 118.37242 -245.777861) (xy 118.379494 -245.771162) (xy 118.42877 -245.720362) (xy 118.435324 -245.713042)
			(xy 118.442755 -245.69487) (xy 118.443248 -245.685056) (xy 118.443248 -245.21287) (xy 118.472966 -245.183152)
			(xy 118.493286 -245.183152) (xy 118.502792 -245.182834) (xy 118.520515 -245.175959) (xy 118.534497 -245.16308)
			(xy 118.539006 -245.154704) (xy 118.550595 -245.132134) (xy 118.579849 -245.090682) (xy 118.615309 -245.054398)
			(xy 118.656077 -245.0242) (xy 118.701121 -245.000854) (xy 118.749298 -244.98495) (xy 118.799389 -244.976893)
			(xy 118.824756 -244.976396) (xy 118.849711 -244.97684) (xy 118.899007 -244.984645) (xy 118.946479 -245.000054)
			(xy 118.990961 -245.022689) (xy 119.031362 -245.051994) (xy 119.066689 -245.087251) (xy 119.096076 -245.127592)
			(xy 119.1188 -245.172029) (xy 119.127016 -245.195598) (xy 119.128337 -245.1994) (xy 119.132047 -245.206543)
			(xy 119.134382 -245.209822) (xy 119.147525 -245.228542) (xy 119.166309 -245.270236) (xy 119.17144 -245.294404)
			(xy 121.326656 -245.294404) (xy 121.327186 -245.269417) (xy 121.335002 -245.220057) (xy 121.350444 -245.172528)
			(xy 121.37313 -245.128) (xy 121.402502 -245.087568) (xy 121.437837 -245.052228) (xy 121.478265 -245.022851)
			(xy 121.522791 -245.000159) (xy 121.570318 -244.984712) (xy 121.619677 -244.976889) (xy 121.644664 -244.976396)
			(xy 121.670044 -244.976859) (xy 121.720158 -244.984945) (xy 121.768351 -245.000886) (xy 121.813402 -245.024277)
			(xy 121.854167 -245.054525) (xy 121.889612 -245.090862) (xy 121.918837 -245.132366) (xy 121.930414 -245.154958)
			(xy 121.930414 -245.155212) (xy 121.934963 -245.163551) (xy 121.948957 -245.176375) (xy 121.966644 -245.183267)
			(xy 121.976134 -245.18366) (xy 122.121676 -245.18366) (xy 122.131677 -245.184207) (xy 122.150161 -245.191851)
			(xy 122.164313 -245.205985) (xy 122.171981 -245.224459) (xy 122.172476 -245.23446) (xy 122.172476 -245.319393)
			(xy 124.147308 -245.319393) (xy 124.147308 -245.269415) (xy 124.155127 -245.220052) (xy 124.170571 -245.17252)
			(xy 124.193261 -245.127988) (xy 124.222637 -245.087555) (xy 124.257977 -245.052215) (xy 124.29841 -245.022839)
			(xy 124.342942 -245.000149) (xy 124.390474 -244.984705) (xy 124.439837 -244.976886) (xy 124.489815 -244.976886)
			(xy 124.539178 -244.984705) (xy 124.58671 -245.000149) (xy 124.631242 -245.022839) (xy 124.671675 -245.052215)
			(xy 124.707015 -245.087555) (xy 124.736391 -245.127988) (xy 124.759081 -245.17252) (xy 124.774525 -245.220052)
			(xy 124.782344 -245.269415) (xy 124.782834 -245.294404) (xy 124.782344 -245.319393) (xy 124.774525 -245.368756)
			(xy 124.759081 -245.416288) (xy 124.736391 -245.46082) (xy 124.707015 -245.501253) (xy 124.671675 -245.536593)
			(xy 124.631242 -245.565969) (xy 124.58671 -245.588659) (xy 124.539178 -245.604103) (xy 124.489815 -245.611922)
			(xy 124.439837 -245.611922) (xy 124.390474 -245.604103) (xy 124.342942 -245.588659) (xy 124.29841 -245.565969)
			(xy 124.257977 -245.536593) (xy 124.222637 -245.501253) (xy 124.193261 -245.46082) (xy 124.170571 -245.416288)
			(xy 124.155127 -245.368756) (xy 124.147308 -245.319393) (xy 122.172476 -245.319393) (xy 122.172476 -245.771162)
			(xy 122.192288 -245.798086) (xy 122.20829 -245.802912) (xy 122.232086 -245.810835) (xy 122.277047 -245.833051)
			(xy 122.317928 -245.862099) (xy 122.3537 -245.897247) (xy 122.383461 -245.937611) (xy 122.406463 -245.982175)
			(xy 122.422127 -246.029816) (xy 122.430058 -246.079335) (xy 122.43054 -246.10441) (xy 122.430053 -246.129212)
			(xy 122.739349 -246.129212) (xy 122.739349 -246.079588) (xy 122.747112 -246.030576) (xy 122.762447 -245.983382)
			(xy 122.784977 -245.939167) (xy 122.814146 -245.899022) (xy 122.849236 -245.863934) (xy 122.889383 -245.834767)
			(xy 122.933598 -245.812241) (xy 122.980794 -245.796908) (xy 123.029806 -245.789148) (xy 123.054618 -245.788688)
			(xy 123.081093 -245.78919) (xy 123.133296 -245.798055) (xy 123.18329 -245.815501) (xy 123.229675 -245.841039)
			(xy 123.271152 -245.873954) (xy 123.30656 -245.913325) (xy 123.334908 -245.958048) (xy 123.355401 -246.006872)
			(xy 123.361958 -246.032528) (xy 123.366022 -246.0498) (xy 123.393454 -246.071644) (xy 123.44019 -246.071644)
			(xy 123.453144 -246.051578) (xy 123.457354 -246.045089) (xy 123.462016 -246.030351) (xy 123.462288 -246.022622)
			(xy 123.462288 -245.929912) (xy 123.462798 -245.919907) (xy 123.470451 -245.901417) (xy 123.484597 -245.887264)
			(xy 123.503083 -245.879602) (xy 123.513088 -245.879112) (xy 123.659392 -245.879112) (xy 123.669464 -245.878706)
			(xy 123.688063 -245.870974) (xy 123.69546 -245.864126) (xy 123.724924 -245.834662) (xy 123.746522 -245.813954)
			(xy 123.794945 -245.77881) (xy 123.848259 -245.751656) (xy 123.905159 -245.733156) (xy 123.964249 -245.723765)
			(xy 123.994164 -245.723156) (xy 123.994672 -245.723156) (xy 124.021909 -245.723703) (xy 124.075831 -245.731448)
			(xy 124.128102 -245.746785) (xy 124.177659 -245.769402) (xy 124.223496 -245.798838) (xy 124.264679 -245.834496)
			(xy 124.300371 -245.875649) (xy 124.329845 -245.921461) (xy 124.352503 -245.971) (xy 124.367884 -246.023258)
			(xy 124.375674 -246.077173) (xy 124.37618 -246.10441) (xy 124.618491 -246.10441) (xy 124.622586 -246.053682)
			(xy 124.634765 -246.004268) (xy 124.654713 -245.957448) (xy 124.681914 -245.914434) (xy 124.715662 -245.87634)
			(xy 124.755084 -245.844153) (xy 124.799158 -245.818707) (xy 124.846744 -245.80066) (xy 124.896608 -245.79048)
			(xy 124.94746 -245.788431) (xy 124.997981 -245.794565) (xy 125.046865 -245.808725) (xy 125.092844 -245.830542)
			(xy 125.134728 -245.859452) (xy 125.171432 -245.894707) (xy 125.202005 -245.935393) (xy 125.225656 -245.980456)
			(xy 125.241772 -246.02873) (xy 125.249936 -246.078964) (xy 125.250448 -246.10441) (xy 125.558545 -246.10441)
			(xy 125.56264 -246.053682) (xy 125.574819 -246.004268) (xy 125.594767 -245.957448) (xy 125.621968 -245.914434)
			(xy 125.655716 -245.87634) (xy 125.695138 -245.844153) (xy 125.739212 -245.818707) (xy 125.786798 -245.80066)
			(xy 125.836662 -245.79048) (xy 125.887514 -245.788431) (xy 125.938035 -245.794565) (xy 125.986919 -245.808725)
			(xy 126.032898 -245.830542) (xy 126.074782 -245.859452) (xy 126.111486 -245.894707) (xy 126.142059 -245.935393)
			(xy 126.16571 -245.980456) (xy 126.181826 -246.02873) (xy 126.18999 -246.078964) (xy 126.190502 -246.10441)
			(xy 126.18999 -246.129856) (xy 126.181826 -246.18009) (xy 126.16571 -246.228364) (xy 126.142059 -246.273427)
			(xy 126.111486 -246.314113) (xy 126.074782 -246.349368) (xy 126.032898 -246.378278) (xy 125.986919 -246.400095)
			(xy 125.938035 -246.414255) (xy 125.887514 -246.420389) (xy 125.836662 -246.41834) (xy 125.786798 -246.40816)
			(xy 125.739212 -246.390113) (xy 125.695138 -246.364667) (xy 125.655716 -246.33248) (xy 125.621968 -246.294386)
			(xy 125.594767 -246.251372) (xy 125.574819 -246.204552) (xy 125.56264 -246.155138) (xy 125.558545 -246.10441)
			(xy 125.250448 -246.10441) (xy 125.249936 -246.129856) (xy 125.241772 -246.18009) (xy 125.225656 -246.228364)
			(xy 125.202005 -246.273427) (xy 125.171432 -246.314113) (xy 125.134728 -246.349368) (xy 125.092844 -246.378278)
			(xy 125.046865 -246.400095) (xy 124.997981 -246.414255) (xy 124.94746 -246.420389) (xy 124.896608 -246.41834)
			(xy 124.846744 -246.40816) (xy 124.799158 -246.390113) (xy 124.755084 -246.364667) (xy 124.715662 -246.33248)
			(xy 124.681914 -246.294386) (xy 124.654713 -246.251372) (xy 124.634765 -246.204552) (xy 124.622586 -246.155138)
			(xy 124.618491 -246.10441) (xy 124.37618 -246.10441) (xy 124.375585 -246.134387) (xy 124.366194 -246.193601)
			(xy 124.347659 -246.250619) (xy 124.320438 -246.304038) (xy 124.285199 -246.352543) (xy 124.26442 -246.374158)
			(xy 124.107956 -246.530622) (xy 124.10694 -246.531638) (xy 124.088862 -246.550091) (xy 124.048586 -246.582441)
			(xy 124.004317 -246.609067) (xy 123.956864 -246.629484) (xy 123.907092 -246.643318) (xy 123.855909 -246.650318)
			(xy 123.83008 -246.650764) (xy 123.825762 -246.650764) (xy 123.815756 -246.651256) (xy 123.797271 -246.658921)
			(xy 123.78312 -246.673072) (xy 123.775456 -246.691558) (xy 123.774962 -246.701564) (xy 123.774962 -246.709184)
			(xy 123.779788 -246.723916) (xy 123.78436 -246.73052) (xy 123.798146 -246.750764) (xy 123.819979 -246.794604)
			(xy 123.834825 -246.841276) (xy 123.842332 -246.889674) (xy 123.84278 -246.914162) (xy 123.84278 -246.914416)
			(xy 123.84229 -246.939405) (xy 124.147308 -246.939405) (xy 124.147308 -246.889427) (xy 124.155127 -246.840064)
			(xy 124.170571 -246.792532) (xy 124.193261 -246.748) (xy 124.222637 -246.707567) (xy 124.257977 -246.672227)
			(xy 124.29841 -246.642851) (xy 124.342942 -246.620161) (xy 124.390474 -246.604717) (xy 124.439837 -246.596898)
			(xy 124.489815 -246.596898) (xy 124.539178 -246.604717) (xy 124.58671 -246.620161) (xy 124.631242 -246.642851)
			(xy 124.671675 -246.672227) (xy 124.707015 -246.707567) (xy 124.736391 -246.748) (xy 124.759081 -246.792532)
			(xy 124.774525 -246.840064) (xy 124.782344 -246.889427) (xy 124.782834 -246.914416) (xy 124.782344 -246.939405)
			(xy 125.087108 -246.939405) (xy 125.087108 -246.889427) (xy 125.094927 -246.840064) (xy 125.110371 -246.792532)
			(xy 125.133061 -246.748) (xy 125.162437 -246.707567) (xy 125.197777 -246.672227) (xy 125.23821 -246.642851)
			(xy 125.282742 -246.620161) (xy 125.330274 -246.604717) (xy 125.379637 -246.596898) (xy 125.429615 -246.596898)
			(xy 125.478978 -246.604717) (xy 125.52651 -246.620161) (xy 125.571042 -246.642851) (xy 125.611475 -246.672227)
			(xy 125.646815 -246.707567) (xy 125.676191 -246.748) (xy 125.698881 -246.792532) (xy 125.714325 -246.840064)
			(xy 125.722144 -246.889427) (xy 125.722634 -246.914416) (xy 125.722144 -246.939405) (xy 125.714325 -246.988768)
			(xy 125.698881 -247.0363) (xy 125.676191 -247.080832) (xy 125.646815 -247.121265) (xy 125.611475 -247.156605)
			(xy 125.571042 -247.185981) (xy 125.52651 -247.208671) (xy 125.478978 -247.224115) (xy 125.429615 -247.231934)
			(xy 125.379637 -247.231934) (xy 125.330274 -247.224115) (xy 125.282742 -247.208671) (xy 125.23821 -247.185981)
			(xy 125.197777 -247.156605) (xy 125.162437 -247.121265) (xy 125.133061 -247.080832) (xy 125.110371 -247.0363)
			(xy 125.094927 -246.988768) (xy 125.087108 -246.939405) (xy 124.782344 -246.939405) (xy 124.774525 -246.988768)
			(xy 124.759081 -247.0363) (xy 124.736391 -247.080832) (xy 124.707015 -247.121265) (xy 124.671675 -247.156605)
			(xy 124.631242 -247.185981) (xy 124.58671 -247.208671) (xy 124.539178 -247.224115) (xy 124.489815 -247.231934)
			(xy 124.439837 -247.231934) (xy 124.390474 -247.224115) (xy 124.342942 -247.208671) (xy 124.29841 -247.185981)
			(xy 124.257977 -247.156605) (xy 124.222637 -247.121265) (xy 124.193261 -247.080832) (xy 124.170571 -247.0363)
			(xy 124.155127 -246.988768) (xy 124.147308 -246.939405) (xy 123.84229 -246.939405) (xy 123.834471 -246.988768)
			(xy 123.819027 -247.0363) (xy 123.796337 -247.080832) (xy 123.766961 -247.121265) (xy 123.731621 -247.156605)
			(xy 123.691188 -247.185981) (xy 123.646656 -247.208671) (xy 123.599124 -247.224115) (xy 123.549761 -247.231934)
			(xy 123.499783 -247.231934) (xy 123.45042 -247.224115) (xy 123.402888 -247.208671) (xy 123.358356 -247.185981)
			(xy 123.317923 -247.156605) (xy 123.282583 -247.121265) (xy 123.253207 -247.080832) (xy 123.230517 -247.0363)
			(xy 123.215073 -246.988768) (xy 123.207254 -246.939405) (xy 123.206764 -246.914416) (xy 123.207172 -246.889409)
			(xy 123.214986 -246.840009) (xy 123.23044 -246.792441) (xy 123.253151 -246.747881) (xy 123.28256 -246.707427)
			(xy 123.317941 -246.672077) (xy 123.358421 -246.642704) (xy 123.3805 -246.630952) (xy 123.38939 -246.62638)
			(xy 123.402344 -246.61114) (xy 123.427744 -246.533416) (xy 123.430365 -246.523799) (xy 123.428942 -246.50394)
			(xy 123.42495 -246.494808) (xy 123.414412 -246.472355) (xy 123.402996 -246.424099) (xy 123.402344 -246.399304)
			(xy 123.402344 -246.389398) (xy 123.400312 -246.375428) (xy 123.396616 -246.362286) (xy 123.390898 -246.33559)
			(xy 123.388882 -246.322088) (xy 123.386166 -246.313111) (xy 123.375243 -246.297879) (xy 123.35958 -246.287586)
			(xy 123.341265 -246.283603) (xy 123.322741 -246.286462) (xy 123.306479 -246.295782) (xy 123.300236 -246.302784)
			(xy 123.285151 -246.320762) (xy 123.250587 -246.352503) (xy 123.211706 -246.37878) (xy 123.169363 -246.399011)
			(xy 123.124492 -246.412753) (xy 123.078082 -246.419701) (xy 123.054618 -246.420132) (xy 123.029806 -246.419652)
			(xy 122.980794 -246.411892) (xy 122.933598 -246.396559) (xy 122.889383 -246.374033) (xy 122.849236 -246.344866)
			(xy 122.814146 -246.309778) (xy 122.784977 -246.269633) (xy 122.762447 -246.225418) (xy 122.747112 -246.178224)
			(xy 122.739349 -246.129212) (xy 122.430053 -246.129212) (xy 122.430053 -246.12922) (xy 122.422291 -246.178228)
			(xy 122.406958 -246.225418) (xy 122.384431 -246.269629) (xy 122.355266 -246.309772) (xy 122.32018 -246.344858)
			(xy 122.280037 -246.374023) (xy 122.235826 -246.39655) (xy 122.188636 -246.411883) (xy 122.139628 -246.419645)
			(xy 122.090008 -246.419645) (xy 122.041 -246.411883) (xy 121.99381 -246.39655) (xy 121.949599 -246.374023)
			(xy 121.909456 -246.344858) (xy 121.87437 -246.309772) (xy 121.845205 -246.269629) (xy 121.822678 -246.225418)
			(xy 121.807345 -246.178228) (xy 121.799583 -246.12922) (xy 121.799096 -246.10441) (xy 121.799802 -246.075345)
			(xy 121.810546 -246.018214) (xy 121.820432 -245.990872) (xy 121.824144 -245.979123) (xy 121.821203 -245.954693)
			(xy 121.814844 -245.944136) (xy 121.7676 -245.874794) (xy 121.760035 -245.864847) (xy 121.737921 -245.853264)
			(xy 121.725436 -245.852696) (xy 121.652792 -245.852696) (xy 121.631748 -245.852183) (xy 121.590474 -245.843941)
			(xy 121.551612 -245.827777) (xy 121.516668 -245.804317) (xy 121.486994 -245.774469) (xy 121.463737 -245.739389)
			(xy 121.4478 -245.700434) (xy 121.439798 -245.659113) (xy 121.439432 -245.638066) (xy 121.439432 -245.637812)
			(xy 121.439432 -245.560088) (xy 121.439004 -245.549836) (xy 121.430996 -245.530962) (xy 121.423938 -245.523512)
			(xy 121.405899 -245.505359) (xy 121.375233 -245.464396) (xy 121.351513 -245.419054) (xy 121.335353 -245.370502)
			(xy 121.327166 -245.31999) (xy 121.326656 -245.294404) (xy 119.17144 -245.294404) (xy 119.175807 -245.31497)
			(xy 119.176292 -245.337838) (xy 119.176292 -245.338346) (xy 119.176292 -245.637812) (xy 119.176218 -245.646424)
			(xy 119.174815 -245.663591) (xy 119.173498 -245.672102) (xy 119.173498 -245.672356) (xy 119.172414 -245.683539)
			(xy 119.178873 -245.705027) (xy 119.185944 -245.713758) (xy 119.24665 -245.781068) (xy 119.267732 -245.789704)
			(xy 119.278908 -245.789196) (xy 119.294402 -245.788688) (xy 119.29491 -245.788688) (xy 119.319696 -245.78919)
			(xy 119.368653 -245.796975) (xy 119.41579 -245.812321) (xy 119.459947 -245.83485) (xy 119.500038 -245.864007)
			(xy 119.535075 -245.899076) (xy 119.564197 -245.939192) (xy 119.586686 -245.983369) (xy 119.60199 -246.03052)
			(xy 119.609732 -246.079484) (xy 119.609726 -246.10441) (xy 119.918475 -246.10441) (xy 119.92257 -246.053682)
			(xy 119.934749 -246.004268) (xy 119.954697 -245.957448) (xy 119.981898 -245.914434) (xy 120.015646 -245.87634)
			(xy 120.055068 -245.844153) (xy 120.099142 -245.818707) (xy 120.146728 -245.80066) (xy 120.196592 -245.79048)
			(xy 120.247444 -245.788431) (xy 120.297965 -245.794565) (xy 120.346849 -245.808725) (xy 120.392828 -245.830542)
			(xy 120.434712 -245.859452) (xy 120.471416 -245.894707) (xy 120.501989 -245.935393) (xy 120.52564 -245.980456)
			(xy 120.541756 -246.02873) (xy 120.54992 -246.078964) (xy 120.550432 -246.10441) (xy 120.549929 -246.129399)
			(xy 120.857246 -246.129399) (xy 120.857246 -246.079421) (xy 120.865065 -246.030058) (xy 120.880509 -245.982526)
			(xy 120.903199 -245.937994) (xy 120.932575 -245.897561) (xy 120.967915 -245.862221) (xy 121.008348 -245.832845)
			(xy 121.05288 -245.810155) (xy 121.100412 -245.794711) (xy 121.149775 -245.786892) (xy 121.199753 -245.786892)
			(xy 121.249116 -245.794711) (xy 121.296648 -245.810155) (xy 121.34118 -245.832845) (xy 121.381613 -245.862221)
			(xy 121.416953 -245.897561) (xy 121.446329 -245.937994) (xy 121.469019 -245.982526) (xy 121.484463 -246.030058)
			(xy 121.492282 -246.079421) (xy 121.492772 -246.10441) (xy 121.492282 -246.129399) (xy 121.484463 -246.178762)
			(xy 121.469019 -246.226294) (xy 121.446329 -246.270826) (xy 121.416953 -246.311259) (xy 121.381613 -246.346599)
			(xy 121.34118 -246.375975) (xy 121.296648 -246.398665) (xy 121.249116 -246.414109) (xy 121.199753 -246.421928)
			(xy 121.149775 -246.421928) (xy 121.100412 -246.414109) (xy 121.05288 -246.398665) (xy 121.008348 -246.375975)
			(xy 120.967915 -246.346599) (xy 120.932575 -246.311259) (xy 120.903199 -246.270826) (xy 120.880509 -246.226294)
			(xy 120.865065 -246.178762) (xy 120.857246 -246.129399) (xy 120.549929 -246.129399) (xy 120.54992 -246.129856)
			(xy 120.541756 -246.18009) (xy 120.52564 -246.228364) (xy 120.501989 -246.273427) (xy 120.471416 -246.314113)
			(xy 120.434712 -246.349368) (xy 120.392828 -246.378278) (xy 120.346849 -246.400095) (xy 120.297965 -246.414255)
			(xy 120.247444 -246.420389) (xy 120.196592 -246.41834) (xy 120.146728 -246.40816) (xy 120.099142 -246.390113)
			(xy 120.055068 -246.364667) (xy 120.015646 -246.33248) (xy 119.981898 -246.294386) (xy 119.954697 -246.251372)
			(xy 119.934749 -246.204552) (xy 119.92257 -246.155138) (xy 119.918475 -246.10441) (xy 119.609726 -246.10441)
			(xy 119.609721 -246.129056) (xy 119.601958 -246.178016) (xy 119.586633 -246.22516) (xy 119.564123 -246.269328)
			(xy 119.534984 -246.309431) (xy 119.499931 -246.344484) (xy 119.459828 -246.373623) (xy 119.41566 -246.396133)
			(xy 119.368516 -246.411458) (xy 119.319556 -246.419221) (xy 119.269984 -246.419232) (xy 119.22102 -246.41149)
			(xy 119.173869 -246.396186) (xy 119.129692 -246.373697) (xy 119.089576 -246.344575) (xy 119.054507 -246.309538)
			(xy 119.02535 -246.269447) (xy 119.002821 -246.22529) (xy 118.987475 -246.178153) (xy 118.97969 -246.129196)
			(xy 118.979188 -246.10441) (xy 118.979188 -246.103902) (xy 118.979615 -246.080886) (xy 118.986347 -246.035349)
			(xy 118.999624 -245.991273) (xy 119.019165 -245.949595) (xy 119.031512 -245.930166) (xy 119.036681 -245.921613)
			(xy 119.040626 -245.90204) (xy 119.036789 -245.882447) (xy 119.025753 -245.865808) (xy 119.009194 -245.854653)
			(xy 118.999508 -245.852188) (xy 118.995612 -245.851482) (xy 118.987705 -245.851094) (xy 118.98376 -245.851426)
			(xy 118.962932 -245.852696) (xy 118.746524 -245.852696) (xy 118.73411 -245.853333) (xy 118.712142 -245.864903)
			(xy 118.704614 -245.874794) (xy 118.65737 -245.943374) (xy 118.650798 -245.953918) (xy 118.647879 -245.978567)
			(xy 118.651782 -245.990364) (xy 118.651782 -245.990618) (xy 118.661616 -246.018032) (xy 118.672218 -246.075293)
			(xy 118.672864 -246.10441) (xy 118.672374 -246.129399) (xy 118.664555 -246.178762) (xy 118.649111 -246.226294)
			(xy 118.626421 -246.270826) (xy 118.597045 -246.311259) (xy 118.561705 -246.346599) (xy 118.521272 -246.375975)
			(xy 118.47674 -246.398665) (xy 118.429208 -246.414109) (xy 118.379845 -246.421928) (xy 118.329867 -246.421928)
			(xy 118.280504 -246.414109) (xy 118.232972 -246.398665) (xy 118.18844 -246.375975) (xy 118.148007 -246.346599)
			(xy 118.112667 -246.311259) (xy 118.083291 -246.270826) (xy 118.060601 -246.226294) (xy 118.045157 -246.178762)
			(xy 118.037338 -246.129399) (xy 118.036848 -246.10441) (xy 117.730524 -246.10441) (xy 117.730012 -246.129856)
			(xy 117.721848 -246.18009) (xy 117.705732 -246.228364) (xy 117.682081 -246.273427) (xy 117.651508 -246.314113)
			(xy 117.614804 -246.349368) (xy 117.57292 -246.378278) (xy 117.526941 -246.400095) (xy 117.478057 -246.414255)
			(xy 117.427536 -246.420389) (xy 117.376684 -246.41834) (xy 117.32682 -246.40816) (xy 117.279234 -246.390113)
			(xy 117.23516 -246.364667) (xy 117.195738 -246.33248) (xy 117.16199 -246.294386) (xy 117.134789 -246.251372)
			(xy 117.114841 -246.204552) (xy 117.102662 -246.155138) (xy 117.098567 -246.10441) (xy 116.790216 -246.10441)
			(xy 116.78973 -246.1292) (xy 116.781974 -246.178168) (xy 116.766653 -246.225321) (xy 116.744144 -246.269496)
			(xy 116.715002 -246.309607) (xy 116.679945 -246.344664) (xy 116.639834 -246.373806) (xy 116.595659 -246.396315)
			(xy 116.548506 -246.411636) (xy 116.499538 -246.419392) (xy 116.449958 -246.419392) (xy 116.40099 -246.411636)
			(xy 116.353837 -246.396315) (xy 116.309662 -246.373806) (xy 116.269551 -246.344664) (xy 116.234494 -246.309607)
			(xy 116.205352 -246.269496) (xy 116.182843 -246.225321) (xy 116.167522 -246.178168) (xy 116.159766 -246.1292)
			(xy 116.15928 -246.10441) (xy 116.15928 -246.104156) (xy 116.159945 -246.075166) (xy 116.170561 -246.018164)
			(xy 116.180362 -245.990872) (xy 116.180362 -245.990618) (xy 116.18406 -245.978801) (xy 116.181138 -245.95425)
			(xy 116.174774 -245.943628) (xy 116.12753 -245.874794) (xy 116.119998 -245.864904) (xy 116.098035 -245.853318)
			(xy 116.08562 -245.852696) (xy 115.997736 -245.852696) (xy 115.994942 -245.852442) (xy 115.98275 -245.852442)
			(xy 115.960906 -245.86311) (xy 115.904518 -245.939818) (xy 115.897885 -245.950023) (xy 115.894044 -245.974024)
			(xy 115.897152 -245.985792) (xy 115.905942 -246.014655) (xy 115.915387 -246.074244) (xy 115.915948 -246.10441)
			(xy 115.91586 -246.117084) (xy 115.914206 -246.142378) (xy 115.912646 -246.154956) (xy 115.912392 -246.158258)
			(xy 115.912392 -246.376952) (xy 115.912022 -246.400507) (xy 115.906158 -246.447251) (xy 115.900708 -246.47017)
			(xy 115.897914 -246.4816) (xy 115.90274 -246.504714) (xy 115.96751 -246.586502) (xy 115.988592 -246.596408)
			(xy 116.004848 -246.596408) (xy 116.029832 -246.596934) (xy 116.079185 -246.604758) (xy 116.126706 -246.620206)
			(xy 116.171225 -246.642897) (xy 116.211647 -246.672273) (xy 116.246976 -246.70761) (xy 116.276342 -246.748039)
			(xy 116.299023 -246.792563) (xy 116.31446 -246.840088) (xy 116.322272 -246.889442) (xy 116.322268 -246.939405)
			(xy 116.62713 -246.939405) (xy 116.62713 -246.889427) (xy 116.634949 -246.840064) (xy 116.650393 -246.792532)
			(xy 116.673083 -246.748) (xy 116.702459 -246.707567) (xy 116.737799 -246.672227) (xy 116.778232 -246.642851)
			(xy 116.822764 -246.620161) (xy 116.870296 -246.604717) (xy 116.919659 -246.596898) (xy 116.969637 -246.596898)
			(xy 117.019 -246.604717) (xy 117.066532 -246.620161) (xy 117.111064 -246.642851) (xy 117.151497 -246.672227)
			(xy 117.186837 -246.707567) (xy 117.216213 -246.748) (xy 117.238903 -246.792532) (xy 117.254347 -246.840064)
			(xy 117.262166 -246.889427) (xy 117.262656 -246.914416) (xy 117.262166 -246.939405) (xy 117.567184 -246.939405)
			(xy 117.567184 -246.889427) (xy 117.575003 -246.840064) (xy 117.590447 -246.792532) (xy 117.613137 -246.748)
			(xy 117.642513 -246.707567) (xy 117.677853 -246.672227) (xy 117.718286 -246.642851) (xy 117.762818 -246.620161)
			(xy 117.81035 -246.604717) (xy 117.859713 -246.596898) (xy 117.909691 -246.596898) (xy 117.959054 -246.604717)
			(xy 118.006586 -246.620161) (xy 118.051118 -246.642851) (xy 118.091551 -246.672227) (xy 118.126891 -246.707567)
			(xy 118.156267 -246.748) (xy 118.178957 -246.792532) (xy 118.194401 -246.840064) (xy 118.20222 -246.889427)
			(xy 118.20271 -246.914416) (xy 118.20222 -246.939405) (xy 118.507238 -246.939405) (xy 118.507238 -246.889427)
			(xy 118.515057 -246.840064) (xy 118.530501 -246.792532) (xy 118.553191 -246.748) (xy 118.582567 -246.707567)
			(xy 118.617907 -246.672227) (xy 118.65834 -246.642851) (xy 118.702872 -246.620161) (xy 118.750404 -246.604717)
			(xy 118.799767 -246.596898) (xy 118.849745 -246.596898) (xy 118.899108 -246.604717) (xy 118.94664 -246.620161)
			(xy 118.991172 -246.642851) (xy 119.031605 -246.672227) (xy 119.066945 -246.707567) (xy 119.096321 -246.748)
			(xy 119.119011 -246.792532) (xy 119.134455 -246.840064) (xy 119.142274 -246.889427) (xy 119.142764 -246.914416)
			(xy 119.142274 -246.939405) (xy 119.447292 -246.939405) (xy 119.447292 -246.889427) (xy 119.455111 -246.840064)
			(xy 119.470555 -246.792532) (xy 119.493245 -246.748) (xy 119.522621 -246.707567) (xy 119.557961 -246.672227)
			(xy 119.598394 -246.642851) (xy 119.642926 -246.620161) (xy 119.690458 -246.604717) (xy 119.739821 -246.596898)
			(xy 119.789799 -246.596898) (xy 119.839162 -246.604717) (xy 119.886694 -246.620161) (xy 119.931226 -246.642851)
			(xy 119.971659 -246.672227) (xy 120.006999 -246.707567) (xy 120.036375 -246.748) (xy 120.059065 -246.792532)
			(xy 120.074509 -246.840064) (xy 120.082328 -246.889427) (xy 120.082818 -246.914416) (xy 120.082328 -246.939405)
			(xy 120.387092 -246.939405) (xy 120.387092 -246.889427) (xy 120.394911 -246.840064) (xy 120.410355 -246.792532)
			(xy 120.433045 -246.748) (xy 120.462421 -246.707567) (xy 120.497761 -246.672227) (xy 120.538194 -246.642851)
			(xy 120.582726 -246.620161) (xy 120.630258 -246.604717) (xy 120.679621 -246.596898) (xy 120.729599 -246.596898)
			(xy 120.778962 -246.604717) (xy 120.826494 -246.620161) (xy 120.871026 -246.642851) (xy 120.911459 -246.672227)
			(xy 120.946799 -246.707567) (xy 120.976175 -246.748) (xy 120.998865 -246.792532) (xy 121.014309 -246.840064)
			(xy 121.022128 -246.889427) (xy 121.022618 -246.914416) (xy 121.022128 -246.939405) (xy 121.327146 -246.939405)
			(xy 121.327146 -246.889427) (xy 121.334965 -246.840064) (xy 121.350409 -246.792532) (xy 121.373099 -246.748)
			(xy 121.402475 -246.707567) (xy 121.437815 -246.672227) (xy 121.478248 -246.642851) (xy 121.52278 -246.620161)
			(xy 121.570312 -246.604717) (xy 121.619675 -246.596898) (xy 121.669653 -246.596898) (xy 121.719016 -246.604717)
			(xy 121.766548 -246.620161) (xy 121.81108 -246.642851) (xy 121.851513 -246.672227) (xy 121.886853 -246.707567)
			(xy 121.916229 -246.748) (xy 121.938919 -246.792532) (xy 121.954363 -246.840064) (xy 121.962182 -246.889427)
			(xy 121.962672 -246.914416) (xy 121.962182 -246.939405) (xy 122.2672 -246.939405) (xy 122.2672 -246.889427)
			(xy 122.275019 -246.840064) (xy 122.290463 -246.792532) (xy 122.313153 -246.748) (xy 122.342529 -246.707567)
			(xy 122.377869 -246.672227) (xy 122.418302 -246.642851) (xy 122.462834 -246.620161) (xy 122.510366 -246.604717)
			(xy 122.559729 -246.596898) (xy 122.609707 -246.596898) (xy 122.65907 -246.604717) (xy 122.706602 -246.620161)
			(xy 122.751134 -246.642851) (xy 122.791567 -246.672227) (xy 122.826907 -246.707567) (xy 122.856283 -246.748)
			(xy 122.878973 -246.792532) (xy 122.894417 -246.840064) (xy 122.902236 -246.889427) (xy 122.902726 -246.914416)
			(xy 122.902236 -246.939405) (xy 122.894417 -246.988768) (xy 122.878973 -247.0363) (xy 122.856283 -247.080832)
			(xy 122.826907 -247.121265) (xy 122.791567 -247.156605) (xy 122.751134 -247.185981) (xy 122.706602 -247.208671)
			(xy 122.65907 -247.224115) (xy 122.609707 -247.231934) (xy 122.559729 -247.231934) (xy 122.510366 -247.224115)
			(xy 122.462834 -247.208671) (xy 122.418302 -247.185981) (xy 122.377869 -247.156605) (xy 122.342529 -247.121265)
			(xy 122.313153 -247.080832) (xy 122.290463 -247.0363) (xy 122.275019 -246.988768) (xy 122.2672 -246.939405)
			(xy 121.962182 -246.939405) (xy 121.954363 -246.988768) (xy 121.938919 -247.0363) (xy 121.916229 -247.080832)
			(xy 121.886853 -247.121265) (xy 121.851513 -247.156605) (xy 121.81108 -247.185981) (xy 121.766548 -247.208671)
			(xy 121.719016 -247.224115) (xy 121.669653 -247.231934) (xy 121.619675 -247.231934) (xy 121.570312 -247.224115)
			(xy 121.52278 -247.208671) (xy 121.478248 -247.185981) (xy 121.437815 -247.156605) (xy 121.402475 -247.121265)
			(xy 121.373099 -247.080832) (xy 121.350409 -247.0363) (xy 121.334965 -246.988768) (xy 121.327146 -246.939405)
			(xy 121.022128 -246.939405) (xy 121.014309 -246.988768) (xy 120.998865 -247.0363) (xy 120.976175 -247.080832)
			(xy 120.946799 -247.121265) (xy 120.911459 -247.156605) (xy 120.871026 -247.185981) (xy 120.826494 -247.208671)
			(xy 120.778962 -247.224115) (xy 120.729599 -247.231934) (xy 120.679621 -247.231934) (xy 120.630258 -247.224115)
			(xy 120.582726 -247.208671) (xy 120.538194 -247.185981) (xy 120.497761 -247.156605) (xy 120.462421 -247.121265)
			(xy 120.433045 -247.080832) (xy 120.410355 -247.0363) (xy 120.394911 -246.988768) (xy 120.387092 -246.939405)
			(xy 120.082328 -246.939405) (xy 120.074509 -246.988768) (xy 120.059065 -247.0363) (xy 120.036375 -247.080832)
			(xy 120.006999 -247.121265) (xy 119.971659 -247.156605) (xy 119.931226 -247.185981) (xy 119.886694 -247.208671)
			(xy 119.839162 -247.224115) (xy 119.789799 -247.231934) (xy 119.739821 -247.231934) (xy 119.690458 -247.224115)
			(xy 119.642926 -247.208671) (xy 119.598394 -247.185981) (xy 119.557961 -247.156605) (xy 119.522621 -247.121265)
			(xy 119.493245 -247.080832) (xy 119.470555 -247.0363) (xy 119.455111 -246.988768) (xy 119.447292 -246.939405)
			(xy 119.142274 -246.939405) (xy 119.134455 -246.988768) (xy 119.119011 -247.0363) (xy 119.096321 -247.080832)
			(xy 119.066945 -247.121265) (xy 119.031605 -247.156605) (xy 118.991172 -247.185981) (xy 118.94664 -247.208671)
			(xy 118.899108 -247.224115) (xy 118.849745 -247.231934) (xy 118.799767 -247.231934) (xy 118.750404 -247.224115)
			(xy 118.702872 -247.208671) (xy 118.65834 -247.185981) (xy 118.617907 -247.156605) (xy 118.582567 -247.121265)
			(xy 118.553191 -247.080832) (xy 118.530501 -247.0363) (xy 118.515057 -246.988768) (xy 118.507238 -246.939405)
			(xy 118.20222 -246.939405) (xy 118.194401 -246.988768) (xy 118.178957 -247.0363) (xy 118.156267 -247.080832)
			(xy 118.126891 -247.121265) (xy 118.091551 -247.156605) (xy 118.051118 -247.185981) (xy 118.006586 -247.208671)
			(xy 117.959054 -247.224115) (xy 117.909691 -247.231934) (xy 117.859713 -247.231934) (xy 117.81035 -247.224115)
			(xy 117.762818 -247.208671) (xy 117.718286 -247.185981) (xy 117.677853 -247.156605) (xy 117.642513 -247.121265)
			(xy 117.613137 -247.080832) (xy 117.590447 -247.0363) (xy 117.575003 -246.988768) (xy 117.567184 -246.939405)
			(xy 117.262166 -246.939405) (xy 117.254347 -246.988768) (xy 117.238903 -247.0363) (xy 117.216213 -247.080832)
			(xy 117.186837 -247.121265) (xy 117.151497 -247.156605) (xy 117.111064 -247.185981) (xy 117.066532 -247.208671)
			(xy 117.019 -247.224115) (xy 116.969637 -247.231934) (xy 116.919659 -247.231934) (xy 116.870296 -247.224115)
			(xy 116.822764 -247.208671) (xy 116.778232 -247.185981) (xy 116.737799 -247.156605) (xy 116.702459 -247.121265)
			(xy 116.673083 -247.080832) (xy 116.650393 -247.0363) (xy 116.634949 -246.988768) (xy 116.62713 -246.939405)
			(xy 116.322268 -246.939405) (xy 116.322268 -246.939411) (xy 116.314447 -246.988764) (xy 116.299003 -247.036286)
			(xy 116.276314 -247.080807) (xy 116.246941 -247.121231) (xy 116.211606 -247.156562) (xy 116.17118 -247.185931)
			(xy 116.126656 -247.208615) (xy 116.079133 -247.224055) (xy 116.029779 -247.23187) (xy 115.97981 -247.231869)
			(xy 115.930457 -247.224052) (xy 115.882934 -247.208611) (xy 115.838411 -247.185926) (xy 115.797986 -247.156555)
			(xy 115.762652 -247.121223) (xy 115.73328 -247.080798) (xy 115.710593 -247.036276) (xy 115.69515 -246.988753)
			(xy 115.687331 -246.9394) (xy 115.68684 -246.914416) (xy 115.687433 -246.8876) (xy 115.696491 -246.834738)
			(xy 115.704874 -246.80926) (xy 115.707668 -246.801132) (xy 115.707668 -246.792496) (xy 115.707283 -246.78247)
			(xy 115.699606 -246.763947) (xy 115.685422 -246.749774) (xy 115.666894 -246.74211) (xy 115.656868 -246.741696)
			(xy 115.642898 -246.741696) (xy 115.63604 -246.743474) (xy 115.610306 -246.750424) (xy 115.557535 -246.757942)
			(xy 115.530884 -246.75846) (xy 115.504231 -246.757963) (xy 115.451457 -246.750446) (xy 115.425728 -246.743474)
			(xy 115.41887 -246.741696) (xy 115.410234 -246.741696) (xy 115.400215 -246.742147) (xy 115.3817 -246.749805)
			(xy 115.367527 -246.763968) (xy 115.359855 -246.782478) (xy 115.359434 -246.792496) (xy 115.359434 -246.801132)
			(xy 115.362482 -246.80926) (xy 115.37091 -246.834727) (xy 115.37998 -246.887596) (xy 115.380516 -246.914416)
			(xy 115.380029 -246.939226) (xy 115.372267 -246.988234) (xy 115.356934 -247.035424) (xy 115.334407 -247.079635)
			(xy 115.305242 -247.119778) (xy 115.270156 -247.154864) (xy 115.230013 -247.184029) (xy 115.185802 -247.206556)
			(xy 115.138612 -247.221889) (xy 115.089604 -247.229651) (xy 115.039984 -247.229651) (xy 114.990976 -247.221889)
			(xy 114.943786 -247.206556) (xy 114.899575 -247.184029) (xy 114.859432 -247.154864) (xy 114.824346 -247.119778)
			(xy 114.795181 -247.079635) (xy 114.772654 -247.035424) (xy 114.757321 -246.988234) (xy 114.749559 -246.939226)
			(xy 114.749072 -246.914416) (xy 114.440462 -246.914416) (xy 114.43995 -246.939862) (xy 114.431786 -246.990096)
			(xy 114.41567 -247.03837) (xy 114.392019 -247.083433) (xy 114.361446 -247.124119) (xy 114.324742 -247.159374)
			(xy 114.282858 -247.188284) (xy 114.236879 -247.210101) (xy 114.187995 -247.224261) (xy 114.137474 -247.230395)
			(xy 114.086622 -247.228346) (xy 114.036758 -247.218166) (xy 113.989172 -247.200119) (xy 113.945098 -247.174673)
			(xy 113.905676 -247.142486) (xy 113.871928 -247.104392) (xy 113.844727 -247.061378) (xy 113.824779 -247.014558)
			(xy 113.8126 -246.965144) (xy 113.808505 -246.914416) (xy 113.602827 -246.914416) (xy 113.502186 -247.08866)
			(xy 113.491943 -247.10557) (xy 113.466241 -247.135605) (xy 113.435462 -247.160411) (xy 113.400651 -247.179144)
			(xy 113.362992 -247.191167) (xy 113.343436 -247.19407) (xy 113.339146 -247.19463) (xy 113.330844 -247.197062)
			(xy 113.326926 -247.198896) (xy 113.304762 -247.209454) (xy 113.257991 -247.224372) (xy 113.209486 -247.231946)
			(xy 113.18494 -247.232424) (xy 113.184686 -247.232424) (xy 113.158378 -247.2319) (xy 113.106478 -247.223246)
			(xy 113.056713 -247.206159) (xy 113.010443 -247.181107) (xy 112.968933 -247.148775) (xy 112.933316 -247.110046)
			(xy 112.904567 -247.065978) (xy 112.883471 -247.017776) (xy 112.870604 -246.966757) (xy 112.867948 -246.940578)
			(xy 112.867442 -246.936032) (xy 112.865022 -246.927212) (xy 112.863122 -246.923052) (xy 112.854605 -246.904125)
			(xy 112.844222 -246.863947) (xy 112.841782 -246.82252) (xy 110.759069 -246.82252) (xy 110.756629 -246.863945)
			(xy 110.746236 -246.904131) (xy 110.728281 -246.941555) (xy 110.70344 -246.97481) (xy 110.688374 -246.989092)
			(xy 110.683499 -246.993762) (xy 110.676151 -247.005081) (xy 110.673896 -247.011444) (xy 110.66582 -247.035183)
			(xy 110.643231 -247.079948) (xy 110.613894 -247.120611) (xy 110.578536 -247.156163) (xy 110.538034 -247.185723)
			(xy 110.493393 -247.208556) (xy 110.44572 -247.224096) (xy 110.396199 -247.231958) (xy 110.371128 -247.232424)
			(xy 110.370874 -247.232424) (xy 110.345722 -247.231963) (xy 110.296045 -247.224051) (xy 110.248234 -247.208413)
			(xy 110.203483 -247.185439) (xy 110.182914 -247.170956) (xy 110.178088 -247.167654) (xy 110.161857 -247.157937)
			(xy 110.132773 -247.133755) (xy 110.108394 -247.104835) (xy 110.098586 -247.08866) (xy 109.971078 -246.867934)
			(xy 109.978952 -246.863362) (xy 109.987481 -246.858011) (xy 109.999763 -246.842074) (xy 110.005004 -246.822647)
			(xy 110.002404 -246.802695) (xy 109.997748 -246.793766) (xy 109.91596 -246.652796) (xy 109.911307 -246.64392)
			(xy 109.908684 -246.624067) (xy 109.554459 -246.624067) (xy 109.589192 -246.640548) (xy 109.631076 -246.669458)
			(xy 109.66778 -246.704713) (xy 109.698353 -246.745399) (xy 109.722004 -246.790462) (xy 109.73812 -246.838736)
			(xy 109.746284 -246.88897) (xy 109.746796 -246.914416) (xy 109.746284 -246.939862) (xy 109.73812 -246.990096)
			(xy 109.722004 -247.03837) (xy 109.698353 -247.083433) (xy 109.66778 -247.124119) (xy 109.631076 -247.159374)
			(xy 109.589192 -247.188284) (xy 109.543213 -247.210101) (xy 109.494329 -247.224261) (xy 109.443808 -247.230395)
			(xy 109.392956 -247.228346) (xy 109.343092 -247.218166) (xy 109.295506 -247.200119) (xy 109.251432 -247.174673)
			(xy 109.21201 -247.142486) (xy 109.178262 -247.104392) (xy 109.151061 -247.061378) (xy 109.131113 -247.014558)
			(xy 109.118934 -246.965144) (xy 109.114839 -246.914416) (xy 108.806488 -246.914416) (xy 108.806002 -246.939206)
			(xy 108.798246 -246.988174) (xy 108.782925 -247.035327) (xy 108.760416 -247.079502) (xy 108.731274 -247.119613)
			(xy 108.696217 -247.15467) (xy 108.656106 -247.183812) (xy 108.611931 -247.206321) (xy 108.564778 -247.221642)
			(xy 108.51581 -247.229398) (xy 108.46623 -247.229398) (xy 108.417262 -247.221642) (xy 108.370109 -247.206321)
			(xy 108.325934 -247.183812) (xy 108.285823 -247.15467) (xy 108.250766 -247.119613) (xy 108.221624 -247.079502)
			(xy 108.199115 -247.035327) (xy 108.183794 -246.988174) (xy 108.176038 -246.939206) (xy 108.175552 -246.914416)
			(xy 108.176314 -246.89181) (xy 108.177076 -246.88165) (xy 108.170726 -246.8626) (xy 108.10875 -246.792496)
			(xy 108.090716 -246.783606) (xy 108.08081 -246.783098) (xy 108.080556 -246.783098) (xy 108.059173 -246.781632)
			(xy 108.016908 -246.774504) (xy 107.996228 -246.768874) (xy 107.98937 -246.767096) (xy 107.971336 -246.767096)
			(xy 107.96905 -246.766842) (xy 107.958128 -246.766842) (xy 107.938316 -246.775478) (xy 107.87253 -246.848376)
			(xy 107.865926 -246.868696) (xy 107.866942 -246.879364) (xy 107.866942 -246.879872) (xy 107.868974 -246.914416)
			(xy 107.868501 -246.939403) (xy 107.860681 -246.988762) (xy 107.845236 -247.036289) (xy 107.822547 -247.080816)
			(xy 107.793171 -247.121245) (xy 107.757833 -247.156581) (xy 107.717403 -247.185955) (xy 107.672875 -247.208642)
			(xy 107.625347 -247.224084) (xy 107.575988 -247.231902) (xy 107.526014 -247.231902) (xy 107.476655 -247.224085)
			(xy 107.429126 -247.208642) (xy 107.384598 -247.185955) (xy 107.344168 -247.156582) (xy 107.30883 -247.121246)
			(xy 107.279454 -247.080817) (xy 107.256765 -247.036291) (xy 107.24132 -246.988763) (xy 107.2335 -246.939404)
			(xy 107.233497 -246.88943) (xy 107.241312 -246.840071) (xy 107.256751 -246.792542) (xy 107.279436 -246.748013)
			(xy 107.308807 -246.70758) (xy 107.344141 -246.67224) (xy 107.384569 -246.642863) (xy 107.429094 -246.620171)
			(xy 107.476621 -246.604724) (xy 107.525979 -246.596901) (xy 107.550966 -246.596408) (xy 107.565788 -246.596592)
			(xy 107.595301 -246.599391) (xy 107.609894 -246.601996) (xy 107.622594 -246.604536) (xy 107.64647 -246.596916)
			(xy 107.714796 -246.527066) (xy 107.723127 -246.517638) (xy 107.730192 -246.493524) (xy 107.728258 -246.481092)
			(xy 107.724373 -246.461638) (xy 107.72017 -246.422188) (xy 107.719876 -246.402352) (xy 107.719876 -246.347234)
			(xy 107.71505 -246.332502) (xy 107.710478 -246.325898) (xy 107.693774 -246.30151) (xy 107.667296 -246.248664)
			(xy 107.649283 -246.192366) (xy 107.640167 -246.133964) (xy 107.639612 -246.10441) (xy 107.64021 -246.074232)
			(xy 107.649782 -246.01464) (xy 107.658662 -245.985792) (xy 107.662472 -245.974108) (xy 107.658662 -245.949978)
			(xy 107.60329 -245.873778) (xy 107.5957 -245.864368) (xy 107.574213 -245.853364) (xy 107.562142 -245.852696)
			(xy 107.470194 -245.852696) (xy 107.457777 -245.853315) (xy 107.435809 -245.864898) (xy 107.428284 -245.874794)
			(xy 107.38104 -245.943628) (xy 107.374497 -245.954187) (xy 107.371561 -245.978822) (xy 107.375452 -245.990618)
			(xy 107.375452 -245.990872) (xy 107.385336 -246.018214) (xy 107.396078 -246.075345) (xy 107.396788 -246.10441)
			(xy 107.396301 -246.12922) (xy 107.388539 -246.178228) (xy 107.373206 -246.225418) (xy 107.350679 -246.269629)
			(xy 107.321514 -246.309772) (xy 107.286428 -246.344858) (xy 107.246285 -246.374023) (xy 107.202074 -246.39655)
			(xy 107.154884 -246.411883) (xy 107.105876 -246.419645) (xy 107.056256 -246.419645) (xy 107.007248 -246.411883)
			(xy 106.960058 -246.39655) (xy 106.915847 -246.374023) (xy 106.875704 -246.344858) (xy 106.840618 -246.309772)
			(xy 106.811453 -246.269629) (xy 106.788926 -246.225418) (xy 106.773593 -246.178228) (xy 106.765831 -246.12922)
			(xy 106.765344 -246.10441) (xy 106.456734 -246.10441) (xy 106.456222 -246.129856) (xy 106.448058 -246.18009)
			(xy 106.431942 -246.228364) (xy 106.408291 -246.273427) (xy 106.377718 -246.314113) (xy 106.341014 -246.349368)
			(xy 106.29913 -246.378278) (xy 106.253151 -246.400095) (xy 106.204267 -246.414255) (xy 106.153746 -246.420389)
			(xy 106.102894 -246.41834) (xy 106.05303 -246.40816) (xy 106.005444 -246.390113) (xy 105.96137 -246.364667)
			(xy 105.921948 -246.33248) (xy 105.8882 -246.294386) (xy 105.860999 -246.251372) (xy 105.841051 -246.204552)
			(xy 105.828872 -246.155138) (xy 105.824777 -246.10441) (xy 105.518966 -246.10441) (xy 105.518476 -246.129399)
			(xy 105.510657 -246.178762) (xy 105.495213 -246.226294) (xy 105.472523 -246.270826) (xy 105.443147 -246.311259)
			(xy 105.407807 -246.346599) (xy 105.367374 -246.375975) (xy 105.322842 -246.398665) (xy 105.27531 -246.414109)
			(xy 105.225947 -246.421928) (xy 105.175969 -246.421928) (xy 105.126606 -246.414109) (xy 105.079074 -246.398665)
			(xy 105.034542 -246.375975) (xy 104.994109 -246.346599) (xy 104.958769 -246.311259) (xy 104.929393 -246.270826)
			(xy 104.906703 -246.226294) (xy 104.891259 -246.178762) (xy 104.88344 -246.129399) (xy 104.88295 -246.10441)
			(xy 104.883619 -246.075295) (xy 104.894224 -246.018039) (xy 104.904032 -245.990618) (xy 104.904032 -245.990364)
			(xy 104.907703 -245.97854) (xy 104.9048 -245.953996) (xy 104.898444 -245.943374) (xy 104.8512 -245.874794)
			(xy 104.843683 -245.86489) (xy 104.821709 -245.853311) (xy 104.80929 -245.852696) (xy 104.694736 -245.852696)
			(xy 104.673693 -245.852143) (xy 104.632421 -245.843909) (xy 104.59356 -245.827752) (xy 104.558615 -245.804299)
			(xy 104.52894 -245.774456) (xy 104.505683 -245.73938) (xy 104.489744 -245.700429) (xy 104.481742 -245.659111)
			(xy 104.481376 -245.638066) (xy 104.481376 -245.637558) (xy 104.481376 -245.508526) (xy 104.481108 -245.50065)
			(xy 104.47631 -245.485646) (xy 104.471978 -245.479062) (xy 104.458073 -245.45876) (xy 104.436056 -245.414754)
			(xy 104.421082 -245.367881) (xy 104.413507 -245.319261) (xy 104.41305 -245.294658) (xy 102.229158 -245.294658)
			(xy 102.229158 -245.294912) (xy 102.228643 -245.319958) (xy 102.220756 -245.369424) (xy 102.205195 -245.417037)
			(xy 102.182347 -245.461614) (xy 102.167944 -245.48211) (xy 102.163465 -245.488777) (xy 102.158537 -245.504054)
			(xy 102.158292 -245.512082) (xy 102.158292 -245.638066) (xy 102.157927 -245.659114) (xy 102.149925 -245.700437)
			(xy 102.133988 -245.739394) (xy 102.110732 -245.774477) (xy 102.081058 -245.804327) (xy 102.046114 -245.827791)
			(xy 102.007252 -245.843959) (xy 101.965977 -245.852206) (xy 101.944932 -245.852696) (xy 101.830124 -245.852696)
			(xy 101.81771 -245.853333) (xy 101.795742 -245.864903) (xy 101.788214 -245.874794) (xy 101.74097 -245.943628)
			(xy 101.734427 -245.954187) (xy 101.73149 -245.978823) (xy 101.735382 -245.990618) (xy 101.735382 -245.990872)
			(xy 101.745216 -246.018154) (xy 101.755815 -246.075163) (xy 101.756464 -246.104156) (xy 101.756464 -246.10441)
			(xy 101.755978 -246.1292) (xy 101.755946 -246.129399) (xy 102.063532 -246.129399) (xy 102.063532 -246.079421)
			(xy 102.071351 -246.030058) (xy 102.086795 -245.982526) (xy 102.109485 -245.937994) (xy 102.138861 -245.897561)
			(xy 102.174201 -245.862221) (xy 102.214634 -245.832845) (xy 102.259166 -245.810155) (xy 102.306698 -245.794711)
			(xy 102.356061 -245.786892) (xy 102.406039 -245.786892) (xy 102.455402 -245.794711) (xy 102.502934 -245.810155)
			(xy 102.547466 -245.832845) (xy 102.587899 -245.862221) (xy 102.623239 -245.897561) (xy 102.652615 -245.937994)
			(xy 102.675305 -245.982526) (xy 102.690749 -246.030058) (xy 102.698568 -246.079421) (xy 102.699058 -246.10441)
			(xy 103.004869 -246.10441) (xy 103.008964 -246.053682) (xy 103.021143 -246.004268) (xy 103.041091 -245.957448)
			(xy 103.068292 -245.914434) (xy 103.10204 -245.87634) (xy 103.141462 -245.844153) (xy 103.185536 -245.818707)
			(xy 103.233122 -245.80066) (xy 103.282986 -245.79048) (xy 103.333838 -245.788431) (xy 103.384359 -245.794565)
			(xy 103.433243 -245.808725) (xy 103.479222 -245.830542) (xy 103.521106 -245.859452) (xy 103.55781 -245.894707)
			(xy 103.588383 -245.935393) (xy 103.612034 -245.980456) (xy 103.62815 -246.02873) (xy 103.636314 -246.078964)
			(xy 103.636826 -246.10441) (xy 103.944923 -246.10441) (xy 103.949018 -246.053682) (xy 103.961197 -246.004268)
			(xy 103.981145 -245.957448) (xy 104.008346 -245.914434) (xy 104.042094 -245.87634) (xy 104.081516 -245.844153)
			(xy 104.12559 -245.818707) (xy 104.173176 -245.80066) (xy 104.22304 -245.79048) (xy 104.273892 -245.788431)
			(xy 104.324413 -245.794565) (xy 104.373297 -245.808725) (xy 104.419276 -245.830542) (xy 104.46116 -245.859452)
			(xy 104.497864 -245.894707) (xy 104.528437 -245.935393) (xy 104.552088 -245.980456) (xy 104.568204 -246.02873)
			(xy 104.576368 -246.078964) (xy 104.57688 -246.10441) (xy 104.576368 -246.129856) (xy 104.568204 -246.18009)
			(xy 104.552088 -246.228364) (xy 104.528437 -246.273427) (xy 104.497864 -246.314113) (xy 104.46116 -246.349368)
			(xy 104.419276 -246.378278) (xy 104.373297 -246.400095) (xy 104.324413 -246.414255) (xy 104.273892 -246.420389)
			(xy 104.22304 -246.41834) (xy 104.173176 -246.40816) (xy 104.12559 -246.390113) (xy 104.081516 -246.364667)
			(xy 104.042094 -246.33248) (xy 104.008346 -246.294386) (xy 103.981145 -246.251372) (xy 103.961197 -246.204552)
			(xy 103.949018 -246.155138) (xy 103.944923 -246.10441) (xy 103.636826 -246.10441) (xy 103.636314 -246.129856)
			(xy 103.62815 -246.18009) (xy 103.612034 -246.228364) (xy 103.588383 -246.273427) (xy 103.55781 -246.314113)
			(xy 103.521106 -246.349368) (xy 103.479222 -246.378278) (xy 103.433243 -246.400095) (xy 103.384359 -246.414255)
			(xy 103.333838 -246.420389) (xy 103.282986 -246.41834) (xy 103.233122 -246.40816) (xy 103.185536 -246.390113)
			(xy 103.141462 -246.364667) (xy 103.10204 -246.33248) (xy 103.068292 -246.294386) (xy 103.041091 -246.251372)
			(xy 103.021143 -246.204552) (xy 103.008964 -246.155138) (xy 103.004869 -246.10441) (xy 102.699058 -246.10441)
			(xy 102.698568 -246.129399) (xy 102.690749 -246.178762) (xy 102.675305 -246.226294) (xy 102.652615 -246.270826)
			(xy 102.623239 -246.311259) (xy 102.587899 -246.346599) (xy 102.547466 -246.375975) (xy 102.502934 -246.398665)
			(xy 102.455402 -246.414109) (xy 102.406039 -246.421928) (xy 102.356061 -246.421928) (xy 102.306698 -246.414109)
			(xy 102.259166 -246.398665) (xy 102.214634 -246.375975) (xy 102.174201 -246.346599) (xy 102.138861 -246.311259)
			(xy 102.109485 -246.270826) (xy 102.086795 -246.226294) (xy 102.071351 -246.178762) (xy 102.063532 -246.129399)
			(xy 101.755946 -246.129399) (xy 101.748222 -246.178168) (xy 101.732901 -246.225321) (xy 101.710392 -246.269496)
			(xy 101.68125 -246.309607) (xy 101.646193 -246.344664) (xy 101.606082 -246.373806) (xy 101.561907 -246.396315)
			(xy 101.514754 -246.411636) (xy 101.465786 -246.419392) (xy 101.416206 -246.419392) (xy 101.367238 -246.411636)
			(xy 101.320085 -246.396315) (xy 101.27591 -246.373806) (xy 101.235799 -246.344664) (xy 101.200742 -246.309607)
			(xy 101.1716 -246.269496) (xy 101.149091 -246.225321) (xy 101.13377 -246.178168) (xy 101.126014 -246.1292)
			(xy 101.125528 -246.10441) (xy 100.816145 -246.10441) (xy 100.816145 -246.129208) (xy 100.808384 -246.178214)
			(xy 100.793053 -246.225402) (xy 100.77053 -246.269612) (xy 100.741368 -246.309754) (xy 100.706286 -246.344841)
			(xy 100.666148 -246.374008) (xy 100.621941 -246.396537) (xy 100.574755 -246.411874) (xy 100.52575 -246.419642)
			(xy 100.500942 -246.420132) (xy 100.475799 -246.419609) (xy 100.426157 -246.411575) (xy 100.402136 -246.40413)
			(xy 100.39321 -246.401639) (xy 100.374713 -246.402567) (xy 100.366068 -246.405908) (xy 100.337366 -246.418354)
			(xy 100.328816 -246.42243) (xy 100.315375 -246.435757) (xy 100.311204 -246.444262) (xy 100.298244 -246.472159)
			(xy 100.265609 -246.5243) (xy 100.24618 -246.548148) (xy 100.23983 -246.555768) (xy 100.233734 -246.573548)
			(xy 100.238052 -246.662448) (xy 100.245926 -246.67972) (xy 100.252784 -246.686578) (xy 100.27067 -246.704648)
			(xy 100.301015 -246.745439) (xy 100.324477 -246.790541) (xy 100.340459 -246.838804) (xy 100.348552 -246.888996)
			(xy 100.34905 -246.914416) (xy 100.34856 -246.939405) (xy 100.653578 -246.939405) (xy 100.653578 -246.889427)
			(xy 100.661397 -246.840064) (xy 100.676841 -246.792532) (xy 100.699531 -246.748) (xy 100.728907 -246.707567)
			(xy 100.764247 -246.672227) (xy 100.80468 -246.642851) (xy 100.849212 -246.620161) (xy 100.896744 -246.604717)
			(xy 100.946107 -246.596898) (xy 100.996085 -246.596898) (xy 101.045448 -246.604717) (xy 101.09298 -246.620161)
			(xy 101.137512 -246.642851) (xy 101.177945 -246.672227) (xy 101.213285 -246.707567) (xy 101.242661 -246.748)
			(xy 101.265351 -246.792532) (xy 101.280795 -246.840064) (xy 101.288614 -246.889427) (xy 101.289104 -246.914416)
			(xy 101.288614 -246.939405) (xy 101.593632 -246.939405) (xy 101.593632 -246.889427) (xy 101.601451 -246.840064)
			(xy 101.616895 -246.792532) (xy 101.639585 -246.748) (xy 101.668961 -246.707567) (xy 101.704301 -246.672227)
			(xy 101.744734 -246.642851) (xy 101.789266 -246.620161) (xy 101.836798 -246.604717) (xy 101.886161 -246.596898)
			(xy 101.936139 -246.596898) (xy 101.985502 -246.604717) (xy 102.033034 -246.620161) (xy 102.077566 -246.642851)
			(xy 102.117999 -246.672227) (xy 102.153339 -246.707567) (xy 102.182715 -246.748) (xy 102.205405 -246.792532)
			(xy 102.220849 -246.840064) (xy 102.228668 -246.889427) (xy 102.229158 -246.914416) (xy 102.228668 -246.939405)
			(xy 102.533432 -246.939405) (xy 102.533432 -246.889427) (xy 102.541251 -246.840064) (xy 102.556695 -246.792532)
			(xy 102.579385 -246.748) (xy 102.608761 -246.707567) (xy 102.644101 -246.672227) (xy 102.684534 -246.642851)
			(xy 102.729066 -246.620161) (xy 102.776598 -246.604717) (xy 102.825961 -246.596898) (xy 102.875939 -246.596898)
			(xy 102.925302 -246.604717) (xy 102.972834 -246.620161) (xy 103.017366 -246.642851) (xy 103.057799 -246.672227)
			(xy 103.093139 -246.707567) (xy 103.122515 -246.748) (xy 103.145205 -246.792532) (xy 103.160649 -246.840064)
			(xy 103.168468 -246.889427) (xy 103.168958 -246.914416) (xy 103.168468 -246.939405) (xy 103.473486 -246.939405)
			(xy 103.473486 -246.889427) (xy 103.481305 -246.840064) (xy 103.496749 -246.792532) (xy 103.519439 -246.748)
			(xy 103.548815 -246.707567) (xy 103.584155 -246.672227) (xy 103.624588 -246.642851) (xy 103.66912 -246.620161)
			(xy 103.716652 -246.604717) (xy 103.766015 -246.596898) (xy 103.815993 -246.596898) (xy 103.865356 -246.604717)
			(xy 103.912888 -246.620161) (xy 103.95742 -246.642851) (xy 103.997853 -246.672227) (xy 104.033193 -246.707567)
			(xy 104.062569 -246.748) (xy 104.085259 -246.792532) (xy 104.100703 -246.840064) (xy 104.108522 -246.889427)
			(xy 104.109012 -246.914416) (xy 104.108522 -246.939405) (xy 104.41354 -246.939405) (xy 104.41354 -246.889427)
			(xy 104.421359 -246.840064) (xy 104.436803 -246.792532) (xy 104.459493 -246.748) (xy 104.488869 -246.707567)
			(xy 104.524209 -246.672227) (xy 104.564642 -246.642851) (xy 104.609174 -246.620161) (xy 104.656706 -246.604717)
			(xy 104.706069 -246.596898) (xy 104.756047 -246.596898) (xy 104.80541 -246.604717) (xy 104.852942 -246.620161)
			(xy 104.897474 -246.642851) (xy 104.937907 -246.672227) (xy 104.973247 -246.707567) (xy 105.002623 -246.748)
			(xy 105.025313 -246.792532) (xy 105.040757 -246.840064) (xy 105.048576 -246.889427) (xy 105.049066 -246.914416)
			(xy 105.048576 -246.939405) (xy 105.353594 -246.939405) (xy 105.353594 -246.889427) (xy 105.361413 -246.840064)
			(xy 105.376857 -246.792532) (xy 105.399547 -246.748) (xy 105.428923 -246.707567) (xy 105.464263 -246.672227)
			(xy 105.504696 -246.642851) (xy 105.549228 -246.620161) (xy 105.59676 -246.604717) (xy 105.646123 -246.596898)
			(xy 105.696101 -246.596898) (xy 105.745464 -246.604717) (xy 105.792996 -246.620161) (xy 105.837528 -246.642851)
			(xy 105.877961 -246.672227) (xy 105.913301 -246.707567) (xy 105.942677 -246.748) (xy 105.965367 -246.792532)
			(xy 105.980811 -246.840064) (xy 105.98863 -246.889427) (xy 105.98912 -246.914416) (xy 105.98863 -246.939405)
			(xy 106.293648 -246.939405) (xy 106.293648 -246.889427) (xy 106.301467 -246.840064) (xy 106.316911 -246.792532)
			(xy 106.339601 -246.748) (xy 106.368977 -246.707567) (xy 106.404317 -246.672227) (xy 106.44475 -246.642851)
			(xy 106.489282 -246.620161) (xy 106.536814 -246.604717) (xy 106.586177 -246.596898) (xy 106.636155 -246.596898)
			(xy 106.685518 -246.604717) (xy 106.73305 -246.620161) (xy 106.777582 -246.642851) (xy 106.818015 -246.672227)
			(xy 106.853355 -246.707567) (xy 106.882731 -246.748) (xy 106.905421 -246.792532) (xy 106.920865 -246.840064)
			(xy 106.928684 -246.889427) (xy 106.929174 -246.914416) (xy 106.928684 -246.939405) (xy 106.920865 -246.988768)
			(xy 106.905421 -247.0363) (xy 106.882731 -247.080832) (xy 106.853355 -247.121265) (xy 106.818015 -247.156605)
			(xy 106.777582 -247.185981) (xy 106.73305 -247.208671) (xy 106.685518 -247.224115) (xy 106.636155 -247.231934)
			(xy 106.586177 -247.231934) (xy 106.536814 -247.224115) (xy 106.489282 -247.208671) (xy 106.44475 -247.185981)
			(xy 106.404317 -247.156605) (xy 106.368977 -247.121265) (xy 106.339601 -247.080832) (xy 106.316911 -247.0363)
			(xy 106.301467 -246.988768) (xy 106.293648 -246.939405) (xy 105.98863 -246.939405) (xy 105.980811 -246.988768)
			(xy 105.965367 -247.0363) (xy 105.942677 -247.080832) (xy 105.913301 -247.121265) (xy 105.877961 -247.156605)
			(xy 105.837528 -247.185981) (xy 105.792996 -247.208671) (xy 105.745464 -247.224115) (xy 105.696101 -247.231934)
			(xy 105.646123 -247.231934) (xy 105.59676 -247.224115) (xy 105.549228 -247.208671) (xy 105.504696 -247.185981)
			(xy 105.464263 -247.156605) (xy 105.428923 -247.121265) (xy 105.399547 -247.080832) (xy 105.376857 -247.0363)
			(xy 105.361413 -246.988768) (xy 105.353594 -246.939405) (xy 105.048576 -246.939405) (xy 105.040757 -246.988768)
			(xy 105.025313 -247.0363) (xy 105.002623 -247.080832) (xy 104.973247 -247.121265) (xy 104.937907 -247.156605)
			(xy 104.897474 -247.185981) (xy 104.852942 -247.208671) (xy 104.80541 -247.224115) (xy 104.756047 -247.231934)
			(xy 104.706069 -247.231934) (xy 104.656706 -247.224115) (xy 104.609174 -247.208671) (xy 104.564642 -247.185981)
			(xy 104.524209 -247.156605) (xy 104.488869 -247.121265) (xy 104.459493 -247.080832) (xy 104.436803 -247.0363)
			(xy 104.421359 -246.988768) (xy 104.41354 -246.939405) (xy 104.108522 -246.939405) (xy 104.100703 -246.988768)
			(xy 104.085259 -247.0363) (xy 104.062569 -247.080832) (xy 104.033193 -247.121265) (xy 103.997853 -247.156605)
			(xy 103.95742 -247.185981) (xy 103.912888 -247.208671) (xy 103.865356 -247.224115) (xy 103.815993 -247.231934)
			(xy 103.766015 -247.231934) (xy 103.716652 -247.224115) (xy 103.66912 -247.208671) (xy 103.624588 -247.185981)
			(xy 103.584155 -247.156605) (xy 103.548815 -247.121265) (xy 103.519439 -247.080832) (xy 103.496749 -247.0363)
			(xy 103.481305 -246.988768) (xy 103.473486 -246.939405) (xy 103.168468 -246.939405) (xy 103.160649 -246.988768)
			(xy 103.145205 -247.0363) (xy 103.122515 -247.080832) (xy 103.093139 -247.121265) (xy 103.057799 -247.156605)
			(xy 103.017366 -247.185981) (xy 102.972834 -247.208671) (xy 102.925302 -247.224115) (xy 102.875939 -247.231934)
			(xy 102.825961 -247.231934) (xy 102.776598 -247.224115) (xy 102.729066 -247.208671) (xy 102.684534 -247.185981)
			(xy 102.644101 -247.156605) (xy 102.608761 -247.121265) (xy 102.579385 -247.080832) (xy 102.556695 -247.0363)
			(xy 102.541251 -246.988768) (xy 102.533432 -246.939405) (xy 102.228668 -246.939405) (xy 102.220849 -246.988768)
			(xy 102.205405 -247.0363) (xy 102.182715 -247.080832) (xy 102.153339 -247.121265) (xy 102.117999 -247.156605)
			(xy 102.077566 -247.185981) (xy 102.033034 -247.208671) (xy 101.985502 -247.224115) (xy 101.936139 -247.231934)
			(xy 101.886161 -247.231934) (xy 101.836798 -247.224115) (xy 101.789266 -247.208671) (xy 101.744734 -247.185981)
			(xy 101.704301 -247.156605) (xy 101.668961 -247.121265) (xy 101.639585 -247.080832) (xy 101.616895 -247.0363)
			(xy 101.601451 -246.988768) (xy 101.593632 -246.939405) (xy 101.288614 -246.939405) (xy 101.280795 -246.988768)
			(xy 101.265351 -247.0363) (xy 101.242661 -247.080832) (xy 101.213285 -247.121265) (xy 101.177945 -247.156605)
			(xy 101.137512 -247.185981) (xy 101.09298 -247.208671) (xy 101.045448 -247.224115) (xy 100.996085 -247.231934)
			(xy 100.946107 -247.231934) (xy 100.896744 -247.224115) (xy 100.849212 -247.208671) (xy 100.80468 -247.185981)
			(xy 100.764247 -247.156605) (xy 100.728907 -247.121265) (xy 100.699531 -247.080832) (xy 100.676841 -247.0363)
			(xy 100.661397 -246.988768) (xy 100.653578 -246.939405) (xy 100.34856 -246.939405) (xy 100.340741 -246.988768)
			(xy 100.325297 -247.0363) (xy 100.302607 -247.080832) (xy 100.273231 -247.121265) (xy 100.237891 -247.156605)
			(xy 100.197458 -247.185981) (xy 100.152926 -247.208671) (xy 100.105394 -247.224115) (xy 100.056031 -247.231934)
			(xy 100.006053 -247.231934) (xy 99.95669 -247.224115) (xy 99.909158 -247.208671) (xy 99.864626 -247.185981)
			(xy 99.824193 -247.156605) (xy 99.788853 -247.121265) (xy 99.759477 -247.080832) (xy 99.736787 -247.0363)
			(xy 99.721343 -246.988768) (xy 99.713524 -246.939405) (xy 99.713034 -246.914416) (xy 99.713484 -246.891282)
			(xy 99.720243 -246.845508) (xy 99.726496 -246.82323) (xy 99.726496 -246.822976) (xy 99.728975 -246.812665)
			(xy 99.726212 -246.791662) (xy 99.721162 -246.782336) (xy 99.681538 -246.717312) (xy 99.675526 -246.708552)
			(xy 99.658074 -246.696479) (xy 99.647756 -246.693944) (xy 99.647248 -246.693944) (xy 99.615325 -246.687431)
			(xy 99.553759 -246.666118) (xy 99.49609 -246.635805) (xy 99.443626 -246.597178) (xy 99.420172 -246.574564)
			(xy 99.25558 -246.409972) (xy 99.235916 -246.389629) (xy 99.201488 -246.34473) (xy 99.173212 -246.295724)
			(xy 99.15157 -246.243448) (xy 99.136933 -246.188795) (xy 99.12955 -246.132699) (xy 99.129088 -246.10441)
			(xy 98.93681 -246.10441) (xy 98.936298 -246.129856) (xy 98.928134 -246.18009) (xy 98.912018 -246.228364)
			(xy 98.888367 -246.273427) (xy 98.857794 -246.314113) (xy 98.82109 -246.349368) (xy 98.779206 -246.378278)
			(xy 98.733227 -246.400095) (xy 98.684343 -246.414255) (xy 98.633822 -246.420389) (xy 98.58297 -246.41834)
			(xy 98.533106 -246.40816) (xy 98.48552 -246.390113) (xy 98.441446 -246.364667) (xy 98.402024 -246.33248)
			(xy 98.368276 -246.294386) (xy 98.341075 -246.251372) (xy 98.321127 -246.204552) (xy 98.308948 -246.155138)
			(xy 98.304853 -246.10441) (xy 97.996756 -246.10441) (xy 97.996244 -246.129856) (xy 97.98808 -246.18009)
			(xy 97.971964 -246.228364) (xy 97.948313 -246.273427) (xy 97.91774 -246.314113) (xy 97.881036 -246.349368)
			(xy 97.839152 -246.378278) (xy 97.793173 -246.400095) (xy 97.744289 -246.414255) (xy 97.693768 -246.420389)
			(xy 97.642916 -246.41834) (xy 97.593052 -246.40816) (xy 97.545466 -246.390113) (xy 97.501392 -246.364667)
			(xy 97.46197 -246.33248) (xy 97.428222 -246.294386) (xy 97.401021 -246.251372) (xy 97.381073 -246.204552)
			(xy 97.368894 -246.155138) (xy 97.364799 -246.10441) (xy 97.058988 -246.10441) (xy 97.058988 -246.107966)
			(xy 97.057718 -246.137938) (xy 97.057464 -246.139462) (xy 97.057464 -246.499126) (xy 97.057943 -246.509875)
			(xy 97.066758 -246.529481) (xy 97.074482 -246.536972) (xy 97.092516 -246.552974) (xy 97.130362 -246.586502)
			(xy 97.13087 -246.586502) (xy 97.131886 -246.587518) (xy 97.155508 -246.583454) (xy 97.169313 -246.5813)
			(xy 97.197162 -246.579008) (xy 97.211134 -246.578882) (xy 97.237497 -246.579402) (xy 97.289574 -246.587655)
			(xy 97.339719 -246.603953) (xy 97.386697 -246.627893) (xy 97.429352 -246.658888) (xy 97.466634 -246.696173)
			(xy 97.497624 -246.738832) (xy 97.521561 -246.785812) (xy 97.537853 -246.835959) (xy 97.546101 -246.888037)
			(xy 97.546101 -246.939405) (xy 97.833416 -246.939405) (xy 97.833416 -246.889427) (xy 97.841235 -246.840064)
			(xy 97.856679 -246.792532) (xy 97.879369 -246.748) (xy 97.908745 -246.707567) (xy 97.944085 -246.672227)
			(xy 97.984518 -246.642851) (xy 98.02905 -246.620161) (xy 98.076582 -246.604717) (xy 98.125945 -246.596898)
			(xy 98.175923 -246.596898) (xy 98.225286 -246.604717) (xy 98.272818 -246.620161) (xy 98.31735 -246.642851)
			(xy 98.357783 -246.672227) (xy 98.393123 -246.707567) (xy 98.422499 -246.748) (xy 98.445189 -246.792532)
			(xy 98.460633 -246.840064) (xy 98.468452 -246.889427) (xy 98.468942 -246.914416) (xy 98.468452 -246.939405)
			(xy 98.77347 -246.939405) (xy 98.77347 -246.889427) (xy 98.781289 -246.840064) (xy 98.796733 -246.792532)
			(xy 98.819423 -246.748) (xy 98.848799 -246.707567) (xy 98.884139 -246.672227) (xy 98.924572 -246.642851)
			(xy 98.969104 -246.620161) (xy 99.016636 -246.604717) (xy 99.065999 -246.596898) (xy 99.115977 -246.596898)
			(xy 99.16534 -246.604717) (xy 99.212872 -246.620161) (xy 99.257404 -246.642851) (xy 99.297837 -246.672227)
			(xy 99.333177 -246.707567) (xy 99.362553 -246.748) (xy 99.385243 -246.792532) (xy 99.400687 -246.840064)
			(xy 99.408506 -246.889427) (xy 99.408996 -246.914416) (xy 99.408506 -246.939405) (xy 99.400687 -246.988768)
			(xy 99.385243 -247.0363) (xy 99.362553 -247.080832) (xy 99.333177 -247.121265) (xy 99.297837 -247.156605)
			(xy 99.257404 -247.185981) (xy 99.212872 -247.208671) (xy 99.16534 -247.224115) (xy 99.115977 -247.231934)
			(xy 99.065999 -247.231934) (xy 99.016636 -247.224115) (xy 98.969104 -247.208671) (xy 98.924572 -247.185981)
			(xy 98.884139 -247.156605) (xy 98.848799 -247.121265) (xy 98.819423 -247.080832) (xy 98.796733 -247.0363)
			(xy 98.781289 -246.988768) (xy 98.77347 -246.939405) (xy 98.468452 -246.939405) (xy 98.460633 -246.988768)
			(xy 98.445189 -247.0363) (xy 98.422499 -247.080832) (xy 98.393123 -247.121265) (xy 98.357783 -247.156605)
			(xy 98.31735 -247.185981) (xy 98.272818 -247.208671) (xy 98.225286 -247.224115) (xy 98.175923 -247.231934)
			(xy 98.125945 -247.231934) (xy 98.076582 -247.224115) (xy 98.02905 -247.208671) (xy 97.984518 -247.185981)
			(xy 97.944085 -247.156605) (xy 97.908745 -247.121265) (xy 97.879369 -247.080832) (xy 97.856679 -247.0363)
			(xy 97.841235 -246.988768) (xy 97.833416 -246.939405) (xy 97.546101 -246.939405) (xy 97.546101 -246.940763)
			(xy 97.537853 -246.992841) (xy 97.521561 -247.042988) (xy 97.497624 -247.089968) (xy 97.466634 -247.132627)
			(xy 97.429352 -247.169912) (xy 97.386697 -247.200907) (xy 97.339719 -247.224847) (xy 97.289574 -247.241145)
			(xy 97.237497 -247.249398) (xy 97.211134 -247.24995) (xy 97.196124 -247.249726) (xy 97.166235 -247.246926)
			(xy 97.151444 -247.244362) (xy 97.14992 -247.244108) (xy 97.14865 -247.244108) (xy 97.131886 -247.241314)
			(xy 97.13087 -247.242076) (xy 97.10293 -247.266714) (xy 97.072958 -247.292876) (xy 97.06622 -247.3)
			(xy 97.058256 -247.3179) (xy 97.057464 -247.327674) (xy 97.057464 -247.68683) (xy 97.057718 -247.691402)
			(xy 97.058988 -247.721882) (xy 97.058988 -247.724422) (xy 97.364799 -247.724422) (xy 97.368894 -247.673694)
			(xy 97.381073 -247.62428) (xy 97.401021 -247.57746) (xy 97.428222 -247.534446) (xy 97.46197 -247.496352)
			(xy 97.501392 -247.464165) (xy 97.545466 -247.438719) (xy 97.593052 -247.420672) (xy 97.642916 -247.410492)
			(xy 97.693768 -247.408443) (xy 97.744289 -247.414577) (xy 97.793173 -247.428737) (xy 97.839152 -247.450554)
			(xy 97.881036 -247.479464) (xy 97.91774 -247.514719) (xy 97.948313 -247.555405) (xy 97.971964 -247.600468)
			(xy 97.98808 -247.648742) (xy 97.996244 -247.698976) (xy 97.996756 -247.724422) (xy 98.304853 -247.724422)
			(xy 98.308948 -247.673694) (xy 98.321127 -247.62428) (xy 98.341075 -247.57746) (xy 98.368276 -247.534446)
			(xy 98.402024 -247.496352) (xy 98.441446 -247.464165) (xy 98.48552 -247.438719) (xy 98.533106 -247.420672)
			(xy 98.58297 -247.410492) (xy 98.633822 -247.408443) (xy 98.684343 -247.414577) (xy 98.733227 -247.428737)
			(xy 98.779206 -247.450554) (xy 98.82109 -247.479464) (xy 98.857794 -247.514719) (xy 98.888367 -247.555405)
			(xy 98.912018 -247.600468) (xy 98.928134 -247.648742) (xy 98.936298 -247.698976) (xy 98.93681 -247.724422)
			(xy 98.936307 -247.749411) (xy 99.243624 -247.749411) (xy 99.243624 -247.699433) (xy 99.251443 -247.65007)
			(xy 99.266887 -247.602538) (xy 99.289577 -247.558006) (xy 99.318953 -247.517573) (xy 99.354293 -247.482233)
			(xy 99.394726 -247.452857) (xy 99.439258 -247.430167) (xy 99.48679 -247.414723) (xy 99.536153 -247.406904)
			(xy 99.586131 -247.406904) (xy 99.635494 -247.414723) (xy 99.683026 -247.430167) (xy 99.727558 -247.452857)
			(xy 99.767991 -247.482233) (xy 99.803331 -247.517573) (xy 99.832707 -247.558006) (xy 99.855397 -247.602538)
			(xy 99.870841 -247.65007) (xy 99.87866 -247.699433) (xy 99.87915 -247.724422) (xy 100.184707 -247.724422)
			(xy 100.188802 -247.673694) (xy 100.200981 -247.62428) (xy 100.220929 -247.57746) (xy 100.24813 -247.534446)
			(xy 100.281878 -247.496352) (xy 100.3213 -247.464165) (xy 100.365374 -247.438719) (xy 100.41296 -247.420672)
			(xy 100.462824 -247.410492) (xy 100.513676 -247.408443) (xy 100.564197 -247.414577) (xy 100.613081 -247.428737)
			(xy 100.65906 -247.450554) (xy 100.700944 -247.479464) (xy 100.737648 -247.514719) (xy 100.768221 -247.555405)
			(xy 100.791872 -247.600468) (xy 100.807988 -247.648742) (xy 100.816152 -247.698976) (xy 100.816664 -247.724422)
			(xy 101.124761 -247.724422) (xy 101.128856 -247.673694) (xy 101.141035 -247.62428) (xy 101.160983 -247.57746)
			(xy 101.188184 -247.534446) (xy 101.221932 -247.496352) (xy 101.261354 -247.464165) (xy 101.305428 -247.438719)
			(xy 101.353014 -247.420672) (xy 101.402878 -247.410492) (xy 101.45373 -247.408443) (xy 101.504251 -247.414577)
			(xy 101.553135 -247.428737) (xy 101.599114 -247.450554) (xy 101.640998 -247.479464) (xy 101.677702 -247.514719)
			(xy 101.708275 -247.555405) (xy 101.731926 -247.600468) (xy 101.748042 -247.648742) (xy 101.756206 -247.698976)
			(xy 101.756718 -247.724422) (xy 101.756215 -247.749411) (xy 102.063532 -247.749411) (xy 102.063532 -247.699433)
			(xy 102.071351 -247.65007) (xy 102.086795 -247.602538) (xy 102.109485 -247.558006) (xy 102.138861 -247.517573)
			(xy 102.174201 -247.482233) (xy 102.214634 -247.452857) (xy 102.259166 -247.430167) (xy 102.306698 -247.414723)
			(xy 102.356061 -247.406904) (xy 102.406039 -247.406904) (xy 102.455402 -247.414723) (xy 102.502934 -247.430167)
			(xy 102.547466 -247.452857) (xy 102.587899 -247.482233) (xy 102.623239 -247.517573) (xy 102.652615 -247.558006)
			(xy 102.675305 -247.602538) (xy 102.690749 -247.65007) (xy 102.698568 -247.699433) (xy 102.699058 -247.724422)
			(xy 103.004869 -247.724422) (xy 103.008964 -247.673694) (xy 103.021143 -247.62428) (xy 103.041091 -247.57746)
			(xy 103.068292 -247.534446) (xy 103.10204 -247.496352) (xy 103.141462 -247.464165) (xy 103.185536 -247.438719)
			(xy 103.233122 -247.420672) (xy 103.282986 -247.410492) (xy 103.333838 -247.408443) (xy 103.384359 -247.414577)
			(xy 103.433243 -247.428737) (xy 103.479222 -247.450554) (xy 103.521106 -247.479464) (xy 103.55781 -247.514719)
			(xy 103.588383 -247.555405) (xy 103.612034 -247.600468) (xy 103.62815 -247.648742) (xy 103.636314 -247.698976)
			(xy 103.636826 -247.724422) (xy 103.944923 -247.724422) (xy 103.949018 -247.673694) (xy 103.961197 -247.62428)
			(xy 103.981145 -247.57746) (xy 104.008346 -247.534446) (xy 104.042094 -247.496352) (xy 104.081516 -247.464165)
			(xy 104.12559 -247.438719) (xy 104.173176 -247.420672) (xy 104.22304 -247.410492) (xy 104.273892 -247.408443)
			(xy 104.324413 -247.414577) (xy 104.373297 -247.428737) (xy 104.419276 -247.450554) (xy 104.46116 -247.479464)
			(xy 104.497864 -247.514719) (xy 104.528437 -247.555405) (xy 104.552088 -247.600468) (xy 104.568204 -247.648742)
			(xy 104.576368 -247.698976) (xy 104.57688 -247.724422) (xy 104.576377 -247.749411) (xy 104.88344 -247.749411)
			(xy 104.88344 -247.699433) (xy 104.891259 -247.65007) (xy 104.906703 -247.602538) (xy 104.929393 -247.558006)
			(xy 104.958769 -247.517573) (xy 104.994109 -247.482233) (xy 105.034542 -247.452857) (xy 105.079074 -247.430167)
			(xy 105.126606 -247.414723) (xy 105.175969 -247.406904) (xy 105.225947 -247.406904) (xy 105.27531 -247.414723)
			(xy 105.322842 -247.430167) (xy 105.367374 -247.452857) (xy 105.407807 -247.482233) (xy 105.443147 -247.517573)
			(xy 105.472523 -247.558006) (xy 105.495213 -247.602538) (xy 105.510657 -247.65007) (xy 105.518476 -247.699433)
			(xy 105.518966 -247.724422) (xy 105.824777 -247.724422) (xy 105.828872 -247.673694) (xy 105.841051 -247.62428)
			(xy 105.860999 -247.57746) (xy 105.8882 -247.534446) (xy 105.921948 -247.496352) (xy 105.96137 -247.464165)
			(xy 106.005444 -247.438719) (xy 106.05303 -247.420672) (xy 106.102894 -247.410492) (xy 106.153746 -247.408443)
			(xy 106.204267 -247.414577) (xy 106.253151 -247.428737) (xy 106.29913 -247.450554) (xy 106.341014 -247.479464)
			(xy 106.377718 -247.514719) (xy 106.408291 -247.555405) (xy 106.431942 -247.600468) (xy 106.448058 -247.648742)
			(xy 106.456222 -247.698976) (xy 106.456734 -247.724422) (xy 106.764831 -247.724422) (xy 106.768926 -247.673694)
			(xy 106.781105 -247.62428) (xy 106.801053 -247.57746) (xy 106.828254 -247.534446) (xy 106.862002 -247.496352)
			(xy 106.901424 -247.464165) (xy 106.945498 -247.438719) (xy 106.993084 -247.420672) (xy 107.042948 -247.410492)
			(xy 107.0938 -247.408443) (xy 107.144321 -247.414577) (xy 107.193205 -247.428737) (xy 107.239184 -247.450554)
			(xy 107.281068 -247.479464) (xy 107.317772 -247.514719) (xy 107.348345 -247.555405) (xy 107.371996 -247.600468)
			(xy 107.388112 -247.648742) (xy 107.396276 -247.698976) (xy 107.396788 -247.724422) (xy 107.396285 -247.749411)
			(xy 107.703602 -247.749411) (xy 107.703602 -247.699433) (xy 107.711421 -247.65007) (xy 107.726865 -247.602538)
			(xy 107.749555 -247.558006) (xy 107.778931 -247.517573) (xy 107.814271 -247.482233) (xy 107.854704 -247.452857)
			(xy 107.899236 -247.430167) (xy 107.946768 -247.414723) (xy 107.996131 -247.406904) (xy 108.046109 -247.406904)
			(xy 108.095472 -247.414723) (xy 108.143004 -247.430167) (xy 108.187536 -247.452857) (xy 108.227969 -247.482233)
			(xy 108.263309 -247.517573) (xy 108.292685 -247.558006) (xy 108.315375 -247.602538) (xy 108.330819 -247.65007)
			(xy 108.338638 -247.699433) (xy 108.339128 -247.724422) (xy 108.338638 -247.749411) (xy 108.643656 -247.749411)
			(xy 108.643656 -247.699433) (xy 108.651475 -247.65007) (xy 108.666919 -247.602538) (xy 108.689609 -247.558006)
			(xy 108.718985 -247.517573) (xy 108.754325 -247.482233) (xy 108.794758 -247.452857) (xy 108.83929 -247.430167)
			(xy 108.886822 -247.414723) (xy 108.936185 -247.406904) (xy 108.986163 -247.406904) (xy 109.035526 -247.414723)
			(xy 109.083058 -247.430167) (xy 109.12759 -247.452857) (xy 109.168023 -247.482233) (xy 109.203363 -247.517573)
			(xy 109.232739 -247.558006) (xy 109.255429 -247.602538) (xy 109.270873 -247.65007) (xy 109.278692 -247.699433)
			(xy 109.279182 -247.724422) (xy 109.278692 -247.749411) (xy 109.583456 -247.749411) (xy 109.583456 -247.699433)
			(xy 109.591275 -247.65007) (xy 109.606719 -247.602538) (xy 109.629409 -247.558006) (xy 109.658785 -247.517573)
			(xy 109.694125 -247.482233) (xy 109.734558 -247.452857) (xy 109.77909 -247.430167) (xy 109.826622 -247.414723)
			(xy 109.875985 -247.406904) (xy 109.925963 -247.406904) (xy 109.975326 -247.414723) (xy 110.022858 -247.430167)
			(xy 110.06739 -247.452857) (xy 110.107823 -247.482233) (xy 110.143163 -247.517573) (xy 110.172539 -247.558006)
			(xy 110.195229 -247.602538) (xy 110.209165 -247.645428) (xy 111.435896 -247.645428) (xy 111.435896 -247.441466)
			(xy 111.436332 -247.422143) (xy 111.443313 -247.384132) (xy 111.457006 -247.347991) (xy 111.46663 -247.33123)
			(xy 111.470186 -247.324118) (xy 111.480518 -247.299777) (xy 111.507323 -247.254197) (xy 111.540575 -247.213083)
			(xy 111.579542 -247.177339) (xy 111.623367 -247.147752) (xy 111.671087 -247.124973) (xy 111.721651 -247.109503)
			(xy 111.773947 -247.101682) (xy 111.826825 -247.101682) (xy 111.879121 -247.109503) (xy 111.929685 -247.124973)
			(xy 111.977405 -247.147752) (xy 112.02123 -247.177339) (xy 112.060197 -247.213083) (xy 112.093449 -247.254197)
			(xy 112.120254 -247.299777) (xy 112.130586 -247.324118) (xy 112.134142 -247.33123) (xy 112.143781 -247.347986)
			(xy 112.157495 -247.384122) (xy 112.16446 -247.42214) (xy 112.164876 -247.441466) (xy 112.164876 -247.696228)
			(xy 112.155732 -247.696228) (xy 112.145709 -247.696647) (xy 112.127188 -247.704311) (xy 112.113013 -247.718484)
			(xy 112.105347 -247.737005) (xy 112.104932 -247.747028) (xy 112.104932 -247.749411) (xy 113.337322 -247.749411)
			(xy 113.337322 -247.699433) (xy 113.345141 -247.65007) (xy 113.360585 -247.602538) (xy 113.383275 -247.558006)
			(xy 113.412651 -247.517573) (xy 113.447991 -247.482233) (xy 113.488424 -247.452857) (xy 113.532956 -247.430167)
			(xy 113.580488 -247.414723) (xy 113.629851 -247.406904) (xy 113.679829 -247.406904) (xy 113.729192 -247.414723)
			(xy 113.776724 -247.430167) (xy 113.821256 -247.452857) (xy 113.861689 -247.482233) (xy 113.897029 -247.517573)
			(xy 113.926405 -247.558006) (xy 113.949095 -247.602538) (xy 113.964539 -247.65007) (xy 113.972358 -247.699433)
			(xy 113.972848 -247.724422) (xy 113.972358 -247.749411) (xy 114.277122 -247.749411) (xy 114.277122 -247.699433)
			(xy 114.284941 -247.65007) (xy 114.300385 -247.602538) (xy 114.323075 -247.558006) (xy 114.352451 -247.517573)
			(xy 114.387791 -247.482233) (xy 114.428224 -247.452857) (xy 114.472756 -247.430167) (xy 114.520288 -247.414723)
			(xy 114.569651 -247.406904) (xy 114.619629 -247.406904) (xy 114.668992 -247.414723) (xy 114.716524 -247.430167)
			(xy 114.761056 -247.452857) (xy 114.801489 -247.482233) (xy 114.836829 -247.517573) (xy 114.866205 -247.558006)
			(xy 114.888895 -247.602538) (xy 114.904339 -247.65007) (xy 114.912158 -247.699433) (xy 114.912648 -247.724422)
			(xy 114.912158 -247.749411) (xy 115.217176 -247.749411) (xy 115.217176 -247.699433) (xy 115.224995 -247.65007)
			(xy 115.240439 -247.602538) (xy 115.263129 -247.558006) (xy 115.292505 -247.517573) (xy 115.327845 -247.482233)
			(xy 115.368278 -247.452857) (xy 115.41281 -247.430167) (xy 115.460342 -247.414723) (xy 115.509705 -247.406904)
			(xy 115.559683 -247.406904) (xy 115.609046 -247.414723) (xy 115.656578 -247.430167) (xy 115.70111 -247.452857)
			(xy 115.741543 -247.482233) (xy 115.776883 -247.517573) (xy 115.806259 -247.558006) (xy 115.828949 -247.602538)
			(xy 115.844393 -247.65007) (xy 115.852212 -247.699433) (xy 115.852702 -247.724422) (xy 116.158513 -247.724422)
			(xy 116.162608 -247.673694) (xy 116.174787 -247.62428) (xy 116.194735 -247.57746) (xy 116.221936 -247.534446)
			(xy 116.255684 -247.496352) (xy 116.295106 -247.464165) (xy 116.33918 -247.438719) (xy 116.386766 -247.420672)
			(xy 116.43663 -247.410492) (xy 116.487482 -247.408443) (xy 116.538003 -247.414577) (xy 116.586887 -247.428737)
			(xy 116.632866 -247.450554) (xy 116.67475 -247.479464) (xy 116.711454 -247.514719) (xy 116.742027 -247.555405)
			(xy 116.765678 -247.600468) (xy 116.781794 -247.648742) (xy 116.789958 -247.698976) (xy 116.79047 -247.724422)
			(xy 117.098567 -247.724422) (xy 117.102662 -247.673694) (xy 117.114841 -247.62428) (xy 117.134789 -247.57746)
			(xy 117.16199 -247.534446) (xy 117.195738 -247.496352) (xy 117.23516 -247.464165) (xy 117.279234 -247.438719)
			(xy 117.32682 -247.420672) (xy 117.376684 -247.410492) (xy 117.427536 -247.408443) (xy 117.478057 -247.414577)
			(xy 117.526941 -247.428737) (xy 117.57292 -247.450554) (xy 117.614804 -247.479464) (xy 117.651508 -247.514719)
			(xy 117.682081 -247.555405) (xy 117.705732 -247.600468) (xy 117.721848 -247.648742) (xy 117.730012 -247.698976)
			(xy 117.730524 -247.724422) (xy 117.730021 -247.749411) (xy 118.037338 -247.749411) (xy 118.037338 -247.699433)
			(xy 118.045157 -247.65007) (xy 118.060601 -247.602538) (xy 118.083291 -247.558006) (xy 118.112667 -247.517573)
			(xy 118.148007 -247.482233) (xy 118.18844 -247.452857) (xy 118.232972 -247.430167) (xy 118.280504 -247.414723)
			(xy 118.329867 -247.406904) (xy 118.379845 -247.406904) (xy 118.429208 -247.414723) (xy 118.47674 -247.430167)
			(xy 118.521272 -247.452857) (xy 118.561705 -247.482233) (xy 118.597045 -247.517573) (xy 118.626421 -247.558006)
			(xy 118.649111 -247.602538) (xy 118.664555 -247.65007) (xy 118.672374 -247.699433) (xy 118.672864 -247.724422)
			(xy 118.978421 -247.724422) (xy 118.982516 -247.673694) (xy 118.994695 -247.62428) (xy 119.014643 -247.57746)
			(xy 119.041844 -247.534446) (xy 119.075592 -247.496352) (xy 119.115014 -247.464165) (xy 119.159088 -247.438719)
			(xy 119.206674 -247.420672) (xy 119.256538 -247.410492) (xy 119.30739 -247.408443) (xy 119.357911 -247.414577)
			(xy 119.406795 -247.428737) (xy 119.452774 -247.450554) (xy 119.494658 -247.479464) (xy 119.531362 -247.514719)
			(xy 119.561935 -247.555405) (xy 119.585586 -247.600468) (xy 119.601702 -247.648742) (xy 119.609866 -247.698976)
			(xy 119.610378 -247.724422) (xy 119.918475 -247.724422) (xy 119.92257 -247.673694) (xy 119.934749 -247.62428)
			(xy 119.954697 -247.57746) (xy 119.981898 -247.534446) (xy 120.015646 -247.496352) (xy 120.055068 -247.464165)
			(xy 120.099142 -247.438719) (xy 120.146728 -247.420672) (xy 120.196592 -247.410492) (xy 120.247444 -247.408443)
			(xy 120.297965 -247.414577) (xy 120.346849 -247.428737) (xy 120.392828 -247.450554) (xy 120.434712 -247.479464)
			(xy 120.471416 -247.514719) (xy 120.501989 -247.555405) (xy 120.52564 -247.600468) (xy 120.541756 -247.648742)
			(xy 120.54992 -247.698976) (xy 120.550432 -247.724422) (xy 120.549929 -247.749411) (xy 120.857246 -247.749411)
			(xy 120.857246 -247.699433) (xy 120.865065 -247.65007) (xy 120.880509 -247.602538) (xy 120.903199 -247.558006)
			(xy 120.932575 -247.517573) (xy 120.967915 -247.482233) (xy 121.008348 -247.452857) (xy 121.05288 -247.430167)
			(xy 121.100412 -247.414723) (xy 121.149775 -247.406904) (xy 121.199753 -247.406904) (xy 121.249116 -247.414723)
			(xy 121.296648 -247.430167) (xy 121.34118 -247.452857) (xy 121.381613 -247.482233) (xy 121.416953 -247.517573)
			(xy 121.446329 -247.558006) (xy 121.469019 -247.602538) (xy 121.484463 -247.65007) (xy 121.492282 -247.699433)
			(xy 121.492772 -247.724422) (xy 121.798583 -247.724422) (xy 121.802678 -247.673694) (xy 121.814857 -247.62428)
			(xy 121.834805 -247.57746) (xy 121.862006 -247.534446) (xy 121.895754 -247.496352) (xy 121.935176 -247.464165)
			(xy 121.97925 -247.438719) (xy 122.026836 -247.420672) (xy 122.0767 -247.410492) (xy 122.127552 -247.408443)
			(xy 122.178073 -247.414577) (xy 122.226957 -247.428737) (xy 122.272936 -247.450554) (xy 122.31482 -247.479464)
			(xy 122.351524 -247.514719) (xy 122.382097 -247.555405) (xy 122.405748 -247.600468) (xy 122.421864 -247.648742)
			(xy 122.430028 -247.698976) (xy 122.43054 -247.724422) (xy 122.738383 -247.724422) (xy 122.742478 -247.673694)
			(xy 122.754657 -247.62428) (xy 122.774605 -247.57746) (xy 122.801806 -247.534446) (xy 122.835554 -247.496352)
			(xy 122.874976 -247.464165) (xy 122.91905 -247.438719) (xy 122.966636 -247.420672) (xy 123.0165 -247.410492)
			(xy 123.067352 -247.408443) (xy 123.117873 -247.414577) (xy 123.166757 -247.428737) (xy 123.212736 -247.450554)
			(xy 123.25462 -247.479464) (xy 123.291324 -247.514719) (xy 123.321897 -247.555405) (xy 123.345548 -247.600468)
			(xy 123.361664 -247.648742) (xy 123.369828 -247.698976) (xy 123.37034 -247.724422) (xy 123.369837 -247.749411)
			(xy 123.677154 -247.749411) (xy 123.677154 -247.699433) (xy 123.684973 -247.65007) (xy 123.700417 -247.602538)
			(xy 123.723107 -247.558006) (xy 123.752483 -247.517573) (xy 123.787823 -247.482233) (xy 123.828256 -247.452857)
			(xy 123.872788 -247.430167) (xy 123.92032 -247.414723) (xy 123.969683 -247.406904) (xy 124.019661 -247.406904)
			(xy 124.069024 -247.414723) (xy 124.116556 -247.430167) (xy 124.161088 -247.452857) (xy 124.201521 -247.482233)
			(xy 124.236861 -247.517573) (xy 124.266237 -247.558006) (xy 124.288927 -247.602538) (xy 124.304371 -247.65007)
			(xy 124.31219 -247.699433) (xy 124.31268 -247.724422) (xy 124.618491 -247.724422) (xy 124.622586 -247.673694)
			(xy 124.634765 -247.62428) (xy 124.654713 -247.57746) (xy 124.681914 -247.534446) (xy 124.715662 -247.496352)
			(xy 124.755084 -247.464165) (xy 124.799158 -247.438719) (xy 124.846744 -247.420672) (xy 124.896608 -247.410492)
			(xy 124.94746 -247.408443) (xy 124.997981 -247.414577) (xy 125.046865 -247.428737) (xy 125.092844 -247.450554)
			(xy 125.134728 -247.479464) (xy 125.171432 -247.514719) (xy 125.202005 -247.555405) (xy 125.225656 -247.600468)
			(xy 125.241772 -247.648742) (xy 125.249936 -247.698976) (xy 125.250448 -247.724422) (xy 125.558545 -247.724422)
			(xy 125.56264 -247.673694) (xy 125.574819 -247.62428) (xy 125.594767 -247.57746) (xy 125.621968 -247.534446)
			(xy 125.655716 -247.496352) (xy 125.695138 -247.464165) (xy 125.739212 -247.438719) (xy 125.786798 -247.420672)
			(xy 125.836662 -247.410492) (xy 125.887514 -247.408443) (xy 125.938035 -247.414577) (xy 125.986919 -247.428737)
			(xy 126.032898 -247.450554) (xy 126.074782 -247.479464) (xy 126.111486 -247.514719) (xy 126.142059 -247.555405)
			(xy 126.16571 -247.600468) (xy 126.181826 -247.648742) (xy 126.18999 -247.698976) (xy 126.190502 -247.724422)
			(xy 126.18999 -247.749868) (xy 126.181826 -247.800102) (xy 126.16571 -247.848376) (xy 126.142059 -247.893439)
			(xy 126.111486 -247.934125) (xy 126.074782 -247.96938) (xy 126.032898 -247.99829) (xy 125.986919 -248.020107)
			(xy 125.938035 -248.034267) (xy 125.887514 -248.040401) (xy 125.836662 -248.038352) (xy 125.786798 -248.028172)
			(xy 125.739212 -248.010125) (xy 125.695138 -247.984679) (xy 125.655716 -247.952492) (xy 125.621968 -247.914398)
			(xy 125.594767 -247.871384) (xy 125.574819 -247.824564) (xy 125.56264 -247.77515) (xy 125.558545 -247.724422)
			(xy 125.250448 -247.724422) (xy 125.249936 -247.749868) (xy 125.241772 -247.800102) (xy 125.225656 -247.848376)
			(xy 125.202005 -247.893439) (xy 125.171432 -247.934125) (xy 125.134728 -247.96938) (xy 125.092844 -247.99829)
			(xy 125.046865 -248.020107) (xy 124.997981 -248.034267) (xy 124.94746 -248.040401) (xy 124.896608 -248.038352)
			(xy 124.846744 -248.028172) (xy 124.799158 -248.010125) (xy 124.755084 -247.984679) (xy 124.715662 -247.952492)
			(xy 124.681914 -247.914398) (xy 124.654713 -247.871384) (xy 124.634765 -247.824564) (xy 124.622586 -247.77515)
			(xy 124.618491 -247.724422) (xy 124.31268 -247.724422) (xy 124.31219 -247.749411) (xy 124.304371 -247.798774)
			(xy 124.288927 -247.846306) (xy 124.266237 -247.890838) (xy 124.236861 -247.931271) (xy 124.201521 -247.966611)
			(xy 124.161088 -247.995987) (xy 124.116556 -248.018677) (xy 124.069024 -248.034121) (xy 124.019661 -248.04194)
			(xy 123.969683 -248.04194) (xy 123.92032 -248.034121) (xy 123.872788 -248.018677) (xy 123.828256 -247.995987)
			(xy 123.787823 -247.966611) (xy 123.752483 -247.931271) (xy 123.723107 -247.890838) (xy 123.700417 -247.846306)
			(xy 123.684973 -247.798774) (xy 123.677154 -247.749411) (xy 123.369837 -247.749411) (xy 123.369828 -247.749868)
			(xy 123.361664 -247.800102) (xy 123.345548 -247.848376) (xy 123.321897 -247.893439) (xy 123.291324 -247.934125)
			(xy 123.25462 -247.96938) (xy 123.212736 -247.99829) (xy 123.166757 -248.020107) (xy 123.117873 -248.034267)
			(xy 123.067352 -248.040401) (xy 123.0165 -248.038352) (xy 122.966636 -248.028172) (xy 122.91905 -248.010125)
			(xy 122.874976 -247.984679) (xy 122.835554 -247.952492) (xy 122.801806 -247.914398) (xy 122.774605 -247.871384)
			(xy 122.754657 -247.824564) (xy 122.742478 -247.77515) (xy 122.738383 -247.724422) (xy 122.43054 -247.724422)
			(xy 122.430028 -247.749868) (xy 122.421864 -247.800102) (xy 122.405748 -247.848376) (xy 122.382097 -247.893439)
			(xy 122.351524 -247.934125) (xy 122.31482 -247.96938) (xy 122.272936 -247.99829) (xy 122.226957 -248.020107)
			(xy 122.178073 -248.034267) (xy 122.127552 -248.040401) (xy 122.0767 -248.038352) (xy 122.026836 -248.028172)
			(xy 121.97925 -248.010125) (xy 121.935176 -247.984679) (xy 121.895754 -247.952492) (xy 121.862006 -247.914398)
			(xy 121.834805 -247.871384) (xy 121.814857 -247.824564) (xy 121.802678 -247.77515) (xy 121.798583 -247.724422)
			(xy 121.492772 -247.724422) (xy 121.492282 -247.749411) (xy 121.484463 -247.798774) (xy 121.469019 -247.846306)
			(xy 121.446329 -247.890838) (xy 121.416953 -247.931271) (xy 121.381613 -247.966611) (xy 121.34118 -247.995987)
			(xy 121.296648 -248.018677) (xy 121.249116 -248.034121) (xy 121.199753 -248.04194) (xy 121.149775 -248.04194)
			(xy 121.100412 -248.034121) (xy 121.05288 -248.018677) (xy 121.008348 -247.995987) (xy 120.967915 -247.966611)
			(xy 120.932575 -247.931271) (xy 120.903199 -247.890838) (xy 120.880509 -247.846306) (xy 120.865065 -247.798774)
			(xy 120.857246 -247.749411) (xy 120.549929 -247.749411) (xy 120.54992 -247.749868) (xy 120.541756 -247.800102)
			(xy 120.52564 -247.848376) (xy 120.501989 -247.893439) (xy 120.471416 -247.934125) (xy 120.434712 -247.96938)
			(xy 120.392828 -247.99829) (xy 120.346849 -248.020107) (xy 120.297965 -248.034267) (xy 120.247444 -248.040401)
			(xy 120.196592 -248.038352) (xy 120.146728 -248.028172) (xy 120.099142 -248.010125) (xy 120.055068 -247.984679)
			(xy 120.015646 -247.952492) (xy 119.981898 -247.914398) (xy 119.954697 -247.871384) (xy 119.934749 -247.824564)
			(xy 119.92257 -247.77515) (xy 119.918475 -247.724422) (xy 119.610378 -247.724422) (xy 119.609866 -247.749868)
			(xy 119.601702 -247.800102) (xy 119.585586 -247.848376) (xy 119.561935 -247.893439) (xy 119.531362 -247.934125)
			(xy 119.494658 -247.96938) (xy 119.452774 -247.99829) (xy 119.406795 -248.020107) (xy 119.357911 -248.034267)
			(xy 119.30739 -248.040401) (xy 119.256538 -248.038352) (xy 119.206674 -248.028172) (xy 119.159088 -248.010125)
			(xy 119.115014 -247.984679) (xy 119.075592 -247.952492) (xy 119.041844 -247.914398) (xy 119.014643 -247.871384)
			(xy 118.994695 -247.824564) (xy 118.982516 -247.77515) (xy 118.978421 -247.724422) (xy 118.672864 -247.724422)
			(xy 118.672374 -247.749411) (xy 118.664555 -247.798774) (xy 118.649111 -247.846306) (xy 118.626421 -247.890838)
			(xy 118.597045 -247.931271) (xy 118.561705 -247.966611) (xy 118.521272 -247.995987) (xy 118.47674 -248.018677)
			(xy 118.429208 -248.034121) (xy 118.379845 -248.04194) (xy 118.329867 -248.04194) (xy 118.280504 -248.034121)
			(xy 118.232972 -248.018677) (xy 118.18844 -247.995987) (xy 118.148007 -247.966611) (xy 118.112667 -247.931271)
			(xy 118.083291 -247.890838) (xy 118.060601 -247.846306) (xy 118.045157 -247.798774) (xy 118.037338 -247.749411)
			(xy 117.730021 -247.749411) (xy 117.730012 -247.749868) (xy 117.721848 -247.800102) (xy 117.705732 -247.848376)
			(xy 117.682081 -247.893439) (xy 117.651508 -247.934125) (xy 117.614804 -247.96938) (xy 117.57292 -247.99829)
			(xy 117.526941 -248.020107) (xy 117.478057 -248.034267) (xy 117.427536 -248.040401) (xy 117.376684 -248.038352)
			(xy 117.32682 -248.028172) (xy 117.279234 -248.010125) (xy 117.23516 -247.984679) (xy 117.195738 -247.952492)
			(xy 117.16199 -247.914398) (xy 117.134789 -247.871384) (xy 117.114841 -247.824564) (xy 117.102662 -247.77515)
			(xy 117.098567 -247.724422) (xy 116.79047 -247.724422) (xy 116.789958 -247.749868) (xy 116.781794 -247.800102)
			(xy 116.765678 -247.848376) (xy 116.742027 -247.893439) (xy 116.711454 -247.934125) (xy 116.67475 -247.96938)
			(xy 116.632866 -247.99829) (xy 116.586887 -248.020107) (xy 116.538003 -248.034267) (xy 116.487482 -248.040401)
			(xy 116.43663 -248.038352) (xy 116.386766 -248.028172) (xy 116.33918 -248.010125) (xy 116.295106 -247.984679)
			(xy 116.255684 -247.952492) (xy 116.221936 -247.914398) (xy 116.194735 -247.871384) (xy 116.174787 -247.824564)
			(xy 116.162608 -247.77515) (xy 116.158513 -247.724422) (xy 115.852702 -247.724422) (xy 115.852212 -247.749411)
			(xy 115.844393 -247.798774) (xy 115.828949 -247.846306) (xy 115.806259 -247.890838) (xy 115.776883 -247.931271)
			(xy 115.741543 -247.966611) (xy 115.70111 -247.995987) (xy 115.656578 -248.018677) (xy 115.609046 -248.034121)
			(xy 115.559683 -248.04194) (xy 115.509705 -248.04194) (xy 115.460342 -248.034121) (xy 115.41281 -248.018677)
			(xy 115.368278 -247.995987) (xy 115.327845 -247.966611) (xy 115.292505 -247.931271) (xy 115.263129 -247.890838)
			(xy 115.240439 -247.846306) (xy 115.224995 -247.798774) (xy 115.217176 -247.749411) (xy 114.912158 -247.749411)
			(xy 114.904339 -247.798774) (xy 114.888895 -247.846306) (xy 114.866205 -247.890838) (xy 114.836829 -247.931271)
			(xy 114.801489 -247.966611) (xy 114.761056 -247.995987) (xy 114.716524 -248.018677) (xy 114.668992 -248.034121)
			(xy 114.619629 -248.04194) (xy 114.569651 -248.04194) (xy 114.520288 -248.034121) (xy 114.472756 -248.018677)
			(xy 114.428224 -247.995987) (xy 114.387791 -247.966611) (xy 114.352451 -247.931271) (xy 114.323075 -247.890838)
			(xy 114.300385 -247.846306) (xy 114.284941 -247.798774) (xy 114.277122 -247.749411) (xy 113.972358 -247.749411)
			(xy 113.964539 -247.798774) (xy 113.949095 -247.846306) (xy 113.926405 -247.890838) (xy 113.897029 -247.931271)
			(xy 113.861689 -247.966611) (xy 113.821256 -247.995987) (xy 113.776724 -248.018677) (xy 113.729192 -248.034121)
			(xy 113.679829 -248.04194) (xy 113.629851 -248.04194) (xy 113.580488 -248.034121) (xy 113.532956 -248.018677)
			(xy 113.488424 -247.995987) (xy 113.447991 -247.966611) (xy 113.412651 -247.931271) (xy 113.383275 -247.890838)
			(xy 113.360585 -247.846306) (xy 113.345141 -247.798774) (xy 113.337322 -247.749411) (xy 112.104932 -247.749411)
			(xy 112.104932 -247.910604) (xy 112.104416 -247.920608) (xy 112.096761 -247.939094) (xy 112.082617 -247.953245)
			(xy 112.064136 -247.96091) (xy 112.054132 -247.961404) (xy 111.54664 -247.961404) (xy 111.536622 -247.960948)
			(xy 111.518107 -247.953292) (xy 111.503933 -247.93913) (xy 111.496261 -247.920622) (xy 111.49584 -247.910604)
			(xy 111.49584 -247.696228) (xy 111.486696 -247.696228) (xy 111.476692 -247.695716) (xy 111.458205 -247.68806)
			(xy 111.444053 -247.673915) (xy 111.436389 -247.655432) (xy 111.435896 -247.645428) (xy 110.209165 -247.645428)
			(xy 110.210673 -247.65007) (xy 110.218492 -247.699433) (xy 110.218982 -247.724422) (xy 110.218492 -247.749411)
			(xy 110.210673 -247.798774) (xy 110.195229 -247.846306) (xy 110.172539 -247.890838) (xy 110.143163 -247.931271)
			(xy 110.107823 -247.966611) (xy 110.06739 -247.995987) (xy 110.022858 -248.018677) (xy 109.975326 -248.034121)
			(xy 109.925963 -248.04194) (xy 109.875985 -248.04194) (xy 109.826622 -248.034121) (xy 109.77909 -248.018677)
			(xy 109.734558 -247.995987) (xy 109.694125 -247.966611) (xy 109.658785 -247.931271) (xy 109.629409 -247.890838)
			(xy 109.606719 -247.846306) (xy 109.591275 -247.798774) (xy 109.583456 -247.749411) (xy 109.278692 -247.749411)
			(xy 109.270873 -247.798774) (xy 109.255429 -247.846306) (xy 109.232739 -247.890838) (xy 109.203363 -247.931271)
			(xy 109.168023 -247.966611) (xy 109.12759 -247.995987) (xy 109.083058 -248.018677) (xy 109.035526 -248.034121)
			(xy 108.986163 -248.04194) (xy 108.936185 -248.04194) (xy 108.886822 -248.034121) (xy 108.83929 -248.018677)
			(xy 108.794758 -247.995987) (xy 108.754325 -247.966611) (xy 108.718985 -247.931271) (xy 108.689609 -247.890838)
			(xy 108.666919 -247.846306) (xy 108.651475 -247.798774) (xy 108.643656 -247.749411) (xy 108.338638 -247.749411)
			(xy 108.330819 -247.798774) (xy 108.315375 -247.846306) (xy 108.292685 -247.890838) (xy 108.263309 -247.931271)
			(xy 108.227969 -247.966611) (xy 108.187536 -247.995987) (xy 108.143004 -248.018677) (xy 108.095472 -248.034121)
			(xy 108.046109 -248.04194) (xy 107.996131 -248.04194) (xy 107.946768 -248.034121) (xy 107.899236 -248.018677)
			(xy 107.854704 -247.995987) (xy 107.814271 -247.966611) (xy 107.778931 -247.931271) (xy 107.749555 -247.890838)
			(xy 107.726865 -247.846306) (xy 107.711421 -247.798774) (xy 107.703602 -247.749411) (xy 107.396285 -247.749411)
			(xy 107.396276 -247.749868) (xy 107.388112 -247.800102) (xy 107.371996 -247.848376) (xy 107.348345 -247.893439)
			(xy 107.317772 -247.934125) (xy 107.281068 -247.96938) (xy 107.239184 -247.99829) (xy 107.193205 -248.020107)
			(xy 107.144321 -248.034267) (xy 107.0938 -248.040401) (xy 107.042948 -248.038352) (xy 106.993084 -248.028172)
			(xy 106.945498 -248.010125) (xy 106.901424 -247.984679) (xy 106.862002 -247.952492) (xy 106.828254 -247.914398)
			(xy 106.801053 -247.871384) (xy 106.781105 -247.824564) (xy 106.768926 -247.77515) (xy 106.764831 -247.724422)
			(xy 106.456734 -247.724422) (xy 106.456222 -247.749868) (xy 106.448058 -247.800102) (xy 106.431942 -247.848376)
			(xy 106.408291 -247.893439) (xy 106.377718 -247.934125) (xy 106.341014 -247.96938) (xy 106.29913 -247.99829)
			(xy 106.253151 -248.020107) (xy 106.204267 -248.034267) (xy 106.153746 -248.040401) (xy 106.102894 -248.038352)
			(xy 106.05303 -248.028172) (xy 106.005444 -248.010125) (xy 105.96137 -247.984679) (xy 105.921948 -247.952492)
			(xy 105.8882 -247.914398) (xy 105.860999 -247.871384) (xy 105.841051 -247.824564) (xy 105.828872 -247.77515)
			(xy 105.824777 -247.724422) (xy 105.518966 -247.724422) (xy 105.518476 -247.749411) (xy 105.510657 -247.798774)
			(xy 105.495213 -247.846306) (xy 105.472523 -247.890838) (xy 105.443147 -247.931271) (xy 105.407807 -247.966611)
			(xy 105.367374 -247.995987) (xy 105.322842 -248.018677) (xy 105.27531 -248.034121) (xy 105.225947 -248.04194)
			(xy 105.175969 -248.04194) (xy 105.126606 -248.034121) (xy 105.079074 -248.018677) (xy 105.034542 -247.995987)
			(xy 104.994109 -247.966611) (xy 104.958769 -247.931271) (xy 104.929393 -247.890838) (xy 104.906703 -247.846306)
			(xy 104.891259 -247.798774) (xy 104.88344 -247.749411) (xy 104.576377 -247.749411) (xy 104.576368 -247.749868)
			(xy 104.568204 -247.800102) (xy 104.552088 -247.848376) (xy 104.528437 -247.893439) (xy 104.497864 -247.934125)
			(xy 104.46116 -247.96938) (xy 104.419276 -247.99829) (xy 104.373297 -248.020107) (xy 104.324413 -248.034267)
			(xy 104.273892 -248.040401) (xy 104.22304 -248.038352) (xy 104.173176 -248.028172) (xy 104.12559 -248.010125)
			(xy 104.081516 -247.984679) (xy 104.042094 -247.952492) (xy 104.008346 -247.914398) (xy 103.981145 -247.871384)
			(xy 103.961197 -247.824564) (xy 103.949018 -247.77515) (xy 103.944923 -247.724422) (xy 103.636826 -247.724422)
			(xy 103.636314 -247.749868) (xy 103.62815 -247.800102) (xy 103.612034 -247.848376) (xy 103.588383 -247.893439)
			(xy 103.55781 -247.934125) (xy 103.521106 -247.96938) (xy 103.479222 -247.99829) (xy 103.433243 -248.020107)
			(xy 103.384359 -248.034267) (xy 103.333838 -248.040401) (xy 103.282986 -248.038352) (xy 103.233122 -248.028172)
			(xy 103.185536 -248.010125) (xy 103.141462 -247.984679) (xy 103.10204 -247.952492) (xy 103.068292 -247.914398)
			(xy 103.041091 -247.871384) (xy 103.021143 -247.824564) (xy 103.008964 -247.77515) (xy 103.004869 -247.724422)
			(xy 102.699058 -247.724422) (xy 102.698568 -247.749411) (xy 102.690749 -247.798774) (xy 102.675305 -247.846306)
			(xy 102.652615 -247.890838) (xy 102.623239 -247.931271) (xy 102.587899 -247.966611) (xy 102.547466 -247.995987)
			(xy 102.502934 -248.018677) (xy 102.455402 -248.034121) (xy 102.406039 -248.04194) (xy 102.356061 -248.04194)
			(xy 102.306698 -248.034121) (xy 102.259166 -248.018677) (xy 102.214634 -247.995987) (xy 102.174201 -247.966611)
			(xy 102.138861 -247.931271) (xy 102.109485 -247.890838) (xy 102.086795 -247.846306) (xy 102.071351 -247.798774)
			(xy 102.063532 -247.749411) (xy 101.756215 -247.749411) (xy 101.756206 -247.749868) (xy 101.748042 -247.800102)
			(xy 101.731926 -247.848376) (xy 101.708275 -247.893439) (xy 101.677702 -247.934125) (xy 101.640998 -247.96938)
			(xy 101.599114 -247.99829) (xy 101.553135 -248.020107) (xy 101.504251 -248.034267) (xy 101.45373 -248.040401)
			(xy 101.402878 -248.038352) (xy 101.353014 -248.028172) (xy 101.305428 -248.010125) (xy 101.261354 -247.984679)
			(xy 101.221932 -247.952492) (xy 101.188184 -247.914398) (xy 101.160983 -247.871384) (xy 101.141035 -247.824564)
			(xy 101.128856 -247.77515) (xy 101.124761 -247.724422) (xy 100.816664 -247.724422) (xy 100.816152 -247.749868)
			(xy 100.807988 -247.800102) (xy 100.791872 -247.848376) (xy 100.768221 -247.893439) (xy 100.737648 -247.934125)
			(xy 100.700944 -247.96938) (xy 100.65906 -247.99829) (xy 100.613081 -248.020107) (xy 100.564197 -248.034267)
			(xy 100.513676 -248.040401) (xy 100.462824 -248.038352) (xy 100.41296 -248.028172) (xy 100.365374 -248.010125)
			(xy 100.3213 -247.984679) (xy 100.281878 -247.952492) (xy 100.24813 -247.914398) (xy 100.220929 -247.871384)
			(xy 100.200981 -247.824564) (xy 100.188802 -247.77515) (xy 100.184707 -247.724422) (xy 99.87915 -247.724422)
			(xy 99.87866 -247.749411) (xy 99.870841 -247.798774) (xy 99.855397 -247.846306) (xy 99.832707 -247.890838)
			(xy 99.803331 -247.931271) (xy 99.767991 -247.966611) (xy 99.727558 -247.995987) (xy 99.683026 -248.018677)
			(xy 99.635494 -248.034121) (xy 99.586131 -248.04194) (xy 99.536153 -248.04194) (xy 99.48679 -248.034121)
			(xy 99.439258 -248.018677) (xy 99.394726 -247.995987) (xy 99.354293 -247.966611) (xy 99.318953 -247.931271)
			(xy 99.289577 -247.890838) (xy 99.266887 -247.846306) (xy 99.251443 -247.798774) (xy 99.243624 -247.749411)
			(xy 98.936307 -247.749411) (xy 98.936298 -247.749868) (xy 98.928134 -247.800102) (xy 98.912018 -247.848376)
			(xy 98.888367 -247.893439) (xy 98.857794 -247.934125) (xy 98.82109 -247.96938) (xy 98.779206 -247.99829)
			(xy 98.733227 -248.020107) (xy 98.684343 -248.034267) (xy 98.633822 -248.040401) (xy 98.58297 -248.038352)
			(xy 98.533106 -248.028172) (xy 98.48552 -248.010125) (xy 98.441446 -247.984679) (xy 98.402024 -247.952492)
			(xy 98.368276 -247.914398) (xy 98.341075 -247.871384) (xy 98.321127 -247.824564) (xy 98.308948 -247.77515)
			(xy 98.304853 -247.724422) (xy 97.996756 -247.724422) (xy 97.996244 -247.749868) (xy 97.98808 -247.800102)
			(xy 97.971964 -247.848376) (xy 97.948313 -247.893439) (xy 97.91774 -247.934125) (xy 97.881036 -247.96938)
			(xy 97.839152 -247.99829) (xy 97.793173 -248.020107) (xy 97.744289 -248.034267) (xy 97.693768 -248.040401)
			(xy 97.642916 -248.038352) (xy 97.593052 -248.028172) (xy 97.545466 -248.010125) (xy 97.501392 -247.984679)
			(xy 97.46197 -247.952492) (xy 97.428222 -247.914398) (xy 97.401021 -247.871384) (xy 97.381073 -247.824564)
			(xy 97.368894 -247.77515) (xy 97.364799 -247.724422) (xy 97.058988 -247.724422) (xy 97.058988 -247.727978)
			(xy 97.057718 -247.75795) (xy 97.057464 -247.759474) (xy 97.057464 -248.585482) (xy 97.058226 -248.59361)
			(xy 97.058226 -248.594118) (xy 97.059826 -248.601637) (xy 97.066802 -248.615326) (xy 97.071942 -248.621042)
			(xy 97.296986 -248.846086) (xy 97.302662 -248.851284) (xy 97.316367 -248.858274) (xy 97.32391 -248.859802)
			(xy 97.324418 -248.859802) (xy 97.332546 -248.860564) (xy 98.469704 -248.860564) (xy 98.479722 -248.860143)
			(xy 98.498231 -248.852471) (xy 98.512394 -248.838298) (xy 98.520051 -248.819782) (xy 98.520504 -248.809764)
			(xy 98.520504 -248.225564) (xy 98.520998 -248.215561) (xy 98.528664 -248.197083) (xy 98.542816 -248.182942)
			(xy 98.561301 -248.175291) (xy 98.571304 -248.174764) (xy 98.734626 -248.174764) (xy 98.744627 -248.174336)
			(xy 98.763094 -248.166653) (xy 98.7772 -248.152473) (xy 98.784788 -248.133967) (xy 98.785172 -248.123964)
			(xy 98.785172 -248.11482) (xy 99.040188 -248.11482) (xy 99.052888 -248.115328) (xy 99.053904 -248.115328)
			(xy 99.056444 -248.115582) (xy 99.062794 -248.115328) (xy 99.066604 -248.115328) (xy 99.078288 -248.11482)
			(xy 99.282758 -248.11482) (xy 99.292823 -248.115254) (xy 99.31141 -248.122986) (xy 99.318826 -248.129806)
			(xy 99.32543 -248.13641) (xy 99.328986 -248.144792) (xy 99.331946 -248.150936) (xy 99.340575 -248.161492)
			(xy 99.346004 -248.16562) (xy 99.34829 -248.16689) (xy 99.354433 -248.170491) (xy 99.368098 -248.174475)
			(xy 99.375214 -248.174764) (xy 99.548188 -248.174764) (xy 99.55806 -248.175175) (xy 99.576303 -248.182728)
			(xy 99.590266 -248.196688) (xy 99.597823 -248.21493) (xy 99.598226 -248.224802) (xy 99.598226 -248.733564)
			(xy 101.390704 -248.733564) (xy 101.390704 -248.225564) (xy 101.391159 -248.215554) (xy 101.398831 -248.19706)
			(xy 101.412994 -248.182908) (xy 101.431493 -248.175251) (xy 101.441504 -248.174764) (xy 101.655372 -248.174764)
			(xy 101.655372 -248.16562) (xy 101.655904 -248.155617) (xy 101.663551 -248.137131) (xy 101.677691 -248.122978)
			(xy 101.69617 -248.115313) (xy 101.706172 -248.11482) (xy 101.910388 -248.11482) (xy 101.930944 -248.115301)
			(xy 101.971301 -248.123138) (xy 102.009408 -248.138561) (xy 102.043855 -248.161001) (xy 102.073364 -248.189624)
			(xy 102.096842 -248.223371) (xy 102.113419 -248.260991) (xy 102.118414 -248.280936) (xy 102.120284 -248.288038)
			(xy 102.127521 -248.300812) (xy 102.132638 -248.306082) (xy 102.150544 -248.324213) (xy 102.180968 -248.365087)
			(xy 102.204496 -248.410283) (xy 102.220526 -248.458649) (xy 102.228651 -248.508951) (xy 102.229158 -248.534428)
			(xy 104.41305 -248.534428) (xy 104.41355 -248.509504) (xy 104.421363 -248.460271) (xy 104.43674 -248.412852)
			(xy 104.447594 -248.39041) (xy 104.447848 -248.390156) (xy 104.450237 -248.384881) (xy 104.452801 -248.373593)
			(xy 104.452928 -248.367804) (xy 104.452928 -248.32945) (xy 104.453288 -248.308402) (xy 104.461288 -248.267077)
			(xy 104.477224 -248.228118) (xy 104.50048 -248.193034) (xy 104.530156 -248.163183) (xy 104.565102 -248.139719)
			(xy 104.603965 -248.123553) (xy 104.645242 -248.115309) (xy 104.666288 -248.11482) (xy 104.921304 -248.11482)
			(xy 104.921304 -248.123964) (xy 104.921749 -248.133983) (xy 104.929408 -248.1525) (xy 104.943573 -248.166674)
			(xy 104.962085 -248.174344) (xy 104.972104 -248.174764) (xy 105.135172 -248.174764) (xy 105.145173 -248.17531)
			(xy 105.163658 -248.182954) (xy 105.177811 -248.197088) (xy 105.185477 -248.215563) (xy 105.185972 -248.225564)
			(xy 105.185972 -248.733564) (xy 107.1118 -248.733564) (xy 107.1118 -248.225564) (xy 107.112259 -248.215554)
			(xy 107.11993 -248.197061) (xy 107.134092 -248.18291) (xy 107.15259 -248.175251) (xy 107.1626 -248.174764)
			(xy 107.376468 -248.174764) (xy 107.376468 -248.16562) (xy 107.377004 -248.155618) (xy 107.384651 -248.137132)
			(xy 107.398789 -248.12298) (xy 107.417266 -248.115314) (xy 107.427268 -248.11482) (xy 107.631484 -248.11482)
			(xy 107.652529 -248.115339) (xy 107.693804 -248.123577) (xy 107.732666 -248.139739) (xy 107.767612 -248.163198)
			(xy 107.797287 -248.193045) (xy 107.820543 -248.228126) (xy 107.83648 -248.267081) (xy 107.84448 -248.308403)
			(xy 107.844844 -248.32945) (xy 107.844844 -248.329958) (xy 107.844844 -248.412254) (xy 107.848146 -248.42089)
			(xy 107.857861 -248.448264) (xy 107.868347 -248.505388) (xy 107.868974 -248.534428) (xy 108.174785 -248.534428)
			(xy 108.17888 -248.4837) (xy 108.191059 -248.434286) (xy 108.211007 -248.387466) (xy 108.238208 -248.344452)
			(xy 108.271956 -248.306358) (xy 108.311378 -248.274171) (xy 108.355452 -248.248725) (xy 108.403038 -248.230678)
			(xy 108.452902 -248.220498) (xy 108.503754 -248.218449) (xy 108.554275 -248.224583) (xy 108.603159 -248.238743)
			(xy 108.649138 -248.26056) (xy 108.691022 -248.28947) (xy 108.727726 -248.324725) (xy 108.758299 -248.365411)
			(xy 108.78195 -248.410474) (xy 108.798066 -248.458748) (xy 108.80623 -248.508982) (xy 108.806742 -248.534428)
			(xy 109.114839 -248.534428) (xy 109.118934 -248.4837) (xy 109.131113 -248.434286) (xy 109.151061 -248.387466)
			(xy 109.178262 -248.344452) (xy 109.21201 -248.306358) (xy 109.251432 -248.274171) (xy 109.295506 -248.248725)
			(xy 109.343092 -248.230678) (xy 109.392956 -248.220498) (xy 109.443808 -248.218449) (xy 109.494329 -248.224583)
			(xy 109.543213 -248.238743) (xy 109.589192 -248.26056) (xy 109.631076 -248.28947) (xy 109.66778 -248.324725)
			(xy 109.698353 -248.365411) (xy 109.722004 -248.410474) (xy 109.73812 -248.458748) (xy 109.746284 -248.508982)
			(xy 109.746796 -248.534428) (xy 109.746284 -248.559874) (xy 109.73812 -248.610108) (xy 109.722004 -248.658382)
			(xy 109.698353 -248.703445) (xy 109.670552 -248.740442) (xy 109.937223 -248.740442) (xy 109.939834 -248.720621)
			(xy 109.944408 -248.71172) (xy 110.051596 -248.526554) (xy 110.043722 -248.521982) (xy 110.035215 -248.516643)
			(xy 110.022903 -248.500796) (xy 110.017648 -248.48143) (xy 110.020261 -248.461533) (xy 110.024926 -248.45264)
			(xy 110.127034 -248.275856) (xy 110.137937 -248.257819) (xy 110.165753 -248.226157) (xy 110.199231 -248.200558)
			(xy 110.237076 -248.182014) (xy 110.277821 -248.171243) (xy 110.319886 -248.168662) (xy 110.361642 -248.174372)
			(xy 110.40147 -248.188151) (xy 110.419896 -248.198386) (xy 110.42015 -248.198386) (xy 110.49381 -248.241058)
			(xy 110.496604 -248.242328) (xy 110.513783 -248.249956) (xy 110.54638 -248.268675) (xy 110.561628 -248.279666)
			(xy 110.563914 -248.281444) (xy 110.678976 -248.347992) (xy 110.67923 -248.347992) (xy 110.69734 -248.358806)
			(xy 110.729197 -248.386446) (xy 110.755019 -248.419794) (xy 110.773804 -248.457555) (xy 110.784825 -248.498266)
			(xy 110.787654 -248.540347) (xy 110.785158 -248.559417) (xy 112.867168 -248.559417) (xy 112.867168 -248.509439)
			(xy 112.874987 -248.460076) (xy 112.890431 -248.412544) (xy 112.913121 -248.368012) (xy 112.942497 -248.327579)
			(xy 112.977837 -248.292239) (xy 113.01827 -248.262863) (xy 113.062802 -248.240173) (xy 113.110334 -248.224729)
			(xy 113.159697 -248.21691) (xy 113.209675 -248.21691) (xy 113.259038 -248.224729) (xy 113.30657 -248.240173)
			(xy 113.351102 -248.262863) (xy 113.391535 -248.292239) (xy 113.426875 -248.327579) (xy 113.456251 -248.368012)
			(xy 113.478941 -248.412544) (xy 113.494385 -248.460076) (xy 113.502204 -248.509439) (xy 113.502694 -248.534428)
			(xy 113.808505 -248.534428) (xy 113.8126 -248.4837) (xy 113.824779 -248.434286) (xy 113.844727 -248.387466)
			(xy 113.871928 -248.344452) (xy 113.905676 -248.306358) (xy 113.945098 -248.274171) (xy 113.989172 -248.248725)
			(xy 114.036758 -248.230678) (xy 114.086622 -248.220498) (xy 114.137474 -248.218449) (xy 114.187995 -248.224583)
			(xy 114.236879 -248.238743) (xy 114.282858 -248.26056) (xy 114.324742 -248.28947) (xy 114.361446 -248.324725)
			(xy 114.392019 -248.365411) (xy 114.41567 -248.410474) (xy 114.431786 -248.458748) (xy 114.43995 -248.508982)
			(xy 114.440462 -248.534428) (xy 114.748559 -248.534428) (xy 114.752654 -248.4837) (xy 114.764833 -248.434286)
			(xy 114.784781 -248.387466) (xy 114.811982 -248.344452) (xy 114.84573 -248.306358) (xy 114.885152 -248.274171)
			(xy 114.929226 -248.248725) (xy 114.976812 -248.230678) (xy 115.026676 -248.220498) (xy 115.077528 -248.218449)
			(xy 115.128049 -248.224583) (xy 115.176933 -248.238743) (xy 115.222912 -248.26056) (xy 115.264796 -248.28947)
			(xy 115.3015 -248.324725) (xy 115.332073 -248.365411) (xy 115.355724 -248.410474) (xy 115.37184 -248.458748)
			(xy 115.380004 -248.508982) (xy 115.380516 -248.534428) (xy 115.68684 -248.534428) (xy 115.68684 -248.534174)
			(xy 115.687399 -248.507462) (xy 115.696341 -248.45479) (xy 115.713951 -248.404351) (xy 115.739737 -248.357561)
			(xy 115.755928 -248.336308) (xy 115.755928 -248.329958) (xy 115.756244 -248.308877) (xy 115.76417 -248.267473)
			(xy 115.780061 -248.228428) (xy 115.803299 -248.193256) (xy 115.832984 -248.163324) (xy 115.867961 -248.139795)
			(xy 115.906874 -248.123581) (xy 115.94821 -248.115312) (xy 115.969288 -248.11482) (xy 116.224304 -248.11482)
			(xy 116.224304 -248.123964) (xy 116.224749 -248.133983) (xy 116.232408 -248.1525) (xy 116.246573 -248.166674)
			(xy 116.265085 -248.174344) (xy 116.275104 -248.174764) (xy 116.438172 -248.174764) (xy 116.448173 -248.17531)
			(xy 116.466658 -248.182954) (xy 116.480811 -248.197088) (xy 116.488477 -248.215563) (xy 116.488972 -248.225564)
			(xy 116.488972 -248.733564) (xy 118.2878 -248.733564) (xy 118.2878 -248.225564) (xy 118.288259 -248.215554)
			(xy 118.29593 -248.197061) (xy 118.310092 -248.18291) (xy 118.32859 -248.175251) (xy 118.3386 -248.174764)
			(xy 118.552468 -248.174764) (xy 118.552468 -248.16562) (xy 118.553004 -248.155618) (xy 118.560651 -248.137132)
			(xy 118.574789 -248.12298) (xy 118.593266 -248.115314) (xy 118.603268 -248.11482) (xy 118.807484 -248.11482)
			(xy 118.826845 -248.115248) (xy 118.864922 -248.122288) (xy 118.901104 -248.136085) (xy 118.934201 -248.156186)
			(xy 118.963126 -248.18193) (xy 118.98693 -248.212473) (xy 119.00483 -248.24681) (xy 119.010938 -248.265188)
			(xy 119.013351 -248.272183) (xy 119.021625 -248.284444) (xy 119.027194 -248.289318) (xy 119.044944 -248.304482)
			(xy 119.076227 -248.339134) (xy 119.102102 -248.377992) (xy 119.122011 -248.420218) (xy 119.135525 -248.464904)
			(xy 119.142354 -248.511086) (xy 119.142764 -248.534428) (xy 119.14276 -248.534682) (xy 121.326656 -248.534682)
			(xy 121.326656 -248.534428) (xy 121.327141 -248.510589) (xy 121.334315 -248.463452) (xy 121.348434 -248.41791)
			(xy 121.358406 -248.396252) (xy 121.35866 -248.39549) (xy 121.360771 -248.390543) (xy 121.363072 -248.380038)
			(xy 121.363232 -248.374662) (xy 121.363232 -248.32945) (xy 121.363588 -248.308401) (xy 121.371588 -248.267076)
			(xy 121.387525 -248.228117) (xy 121.410781 -248.193033) (xy 121.440457 -248.163181) (xy 121.475404 -248.139718)
			(xy 121.514268 -248.123552) (xy 121.555546 -248.115309) (xy 121.576592 -248.11482) (xy 121.831608 -248.11482)
			(xy 121.831608 -248.123964) (xy 121.832049 -248.133984) (xy 121.839709 -248.152502) (xy 121.853875 -248.166675)
			(xy 121.872388 -248.174345) (xy 121.882408 -248.174764) (xy 122.045476 -248.174764) (xy 122.055478 -248.175307)
			(xy 122.073962 -248.182952) (xy 122.088115 -248.197088) (xy 122.095781 -248.215563) (xy 122.096276 -248.225564)
			(xy 122.096276 -248.534428) (xy 124.146818 -248.534428) (xy 124.147431 -248.506195) (xy 124.157374 -248.450611)
			(xy 124.176969 -248.397654) (xy 124.205603 -248.348987) (xy 124.223526 -248.327164) (xy 124.228143 -248.321422)
			(xy 124.234218 -248.308009) (xy 124.235464 -248.300748) (xy 124.238763 -248.279011) (xy 124.253211 -248.237491)
			(xy 124.27584 -248.1998) (xy 124.305695 -248.16753) (xy 124.341514 -248.142042) (xy 124.381786 -248.124413)
			(xy 124.424812 -248.115386) (xy 124.446792 -248.11482) (xy 124.701808 -248.11482) (xy 124.701808 -248.123964)
			(xy 124.702249 -248.133984) (xy 124.709909 -248.152502) (xy 124.724075 -248.166675) (xy 124.742588 -248.174345)
			(xy 124.752608 -248.174764) (xy 124.915676 -248.174764) (xy 124.925678 -248.175307) (xy 124.944162 -248.182952)
			(xy 124.958315 -248.197088) (xy 124.965981 -248.215563) (xy 124.966476 -248.225564) (xy 124.966476 -248.733564)
			(xy 124.96605 -248.743586) (xy 124.958388 -248.762107) (xy 124.944217 -248.776281) (xy 124.925698 -248.783948)
			(xy 124.915676 -248.784364) (xy 124.701808 -248.784364) (xy 124.701808 -248.793508) (xy 124.701318 -248.803515)
			(xy 124.693658 -248.822005) (xy 124.679505 -248.836158) (xy 124.661015 -248.843818) (xy 124.651008 -248.844308)
			(xy 124.536962 -248.844308) (xy 124.531628 -248.845324) (xy 124.515128 -248.848653) (xy 124.481657 -248.852217)
			(xy 124.464826 -248.852436) (xy 124.439839 -248.851894) (xy 124.390479 -248.84408) (xy 124.34295 -248.828641)
			(xy 124.298421 -248.805957) (xy 124.257988 -248.776587) (xy 124.222648 -248.741253) (xy 124.193271 -248.700825)
			(xy 124.170579 -248.6563) (xy 124.155132 -248.608773) (xy 124.14731 -248.559415) (xy 124.146818 -248.534428)
			(xy 122.096276 -248.534428) (xy 122.096276 -248.733564) (xy 122.09585 -248.743586) (xy 122.088188 -248.762107)
			(xy 122.074017 -248.776281) (xy 122.055498 -248.783948) (xy 122.045476 -248.784364) (xy 121.841514 -248.784364)
			(xy 121.831608 -248.79173) (xy 121.831608 -248.793508) (xy 121.831118 -248.803515) (xy 121.823458 -248.822005)
			(xy 121.809305 -248.836158) (xy 121.790815 -248.843818) (xy 121.780808 -248.844308) (xy 121.7168 -248.844308)
			(xy 121.711466 -248.845324) (xy 121.694965 -248.848647) (xy 121.661494 -248.852215) (xy 121.644664 -248.852436)
			(xy 121.627572 -248.852207) (xy 121.593589 -248.848511) (xy 121.576846 -248.84507) (xy 121.56821 -248.8438)
			(xy 121.547822 -248.842573) (xy 121.50805 -248.833297) (xy 121.470772 -248.816616) (xy 121.437354 -248.793142)
			(xy 121.409017 -248.763733) (xy 121.386799 -248.729466) (xy 121.378726 -248.710704) (xy 121.374916 -248.70283)
			(xy 121.363526 -248.683816) (xy 121.345491 -248.643329) (xy 121.333257 -248.600729) (xy 121.32706 -248.556843)
			(xy 121.326656 -248.534682) (xy 119.14276 -248.534682) (xy 119.142369 -248.559422) (xy 119.134545 -248.608794)
			(xy 119.119093 -248.656335) (xy 119.096394 -248.700872) (xy 119.067007 -248.741311) (xy 119.031656 -248.776654)
			(xy 118.991211 -248.806032) (xy 118.946668 -248.82872) (xy 118.899124 -248.844162) (xy 118.84975 -248.851975)
			(xy 118.824756 -248.852436) (xy 118.807926 -248.852209) (xy 118.774455 -248.848644) (xy 118.757954 -248.845324)
			(xy 118.75262 -248.844308) (xy 118.552468 -248.844308) (xy 118.552468 -248.835164) (xy 118.552041 -248.82515)
			(xy 118.544363 -248.806651) (xy 118.530191 -248.792499) (xy 118.511683 -248.784846) (xy 118.501668 -248.784364)
			(xy 118.3386 -248.784364) (xy 118.328574 -248.78398) (xy 118.31005 -248.776303) (xy 118.295877 -248.762119)
			(xy 118.288213 -248.74359) (xy 118.2878 -248.733564) (xy 116.488972 -248.733564) (xy 116.48855 -248.743586)
			(xy 116.480887 -248.762108) (xy 116.466715 -248.776282) (xy 116.448194 -248.783949) (xy 116.438172 -248.784364)
			(xy 116.224304 -248.784364) (xy 116.224304 -248.793508) (xy 116.223818 -248.803516) (xy 116.216157 -248.822007)
			(xy 116.202003 -248.836159) (xy 116.183512 -248.843819) (xy 116.173504 -248.844308) (xy 116.076984 -248.844308)
			(xy 116.07165 -248.845324) (xy 116.05515 -248.848649) (xy 116.021678 -248.852216) (xy 116.004848 -248.852436)
			(xy 115.97986 -248.851899) (xy 115.930497 -248.844088) (xy 115.882964 -248.828651) (xy 115.838431 -248.805968)
			(xy 115.797995 -248.776597) (xy 115.762652 -248.741262) (xy 115.733272 -248.700834) (xy 115.710578 -248.656306)
			(xy 115.69513 -248.608777) (xy 115.687307 -248.559416) (xy 115.68684 -248.534428) (xy 115.380516 -248.534428)
			(xy 115.380004 -248.559874) (xy 115.37184 -248.610108) (xy 115.355724 -248.658382) (xy 115.332073 -248.703445)
			(xy 115.3015 -248.744131) (xy 115.264796 -248.779386) (xy 115.222912 -248.808296) (xy 115.176933 -248.830113)
			(xy 115.128049 -248.844273) (xy 115.077528 -248.850407) (xy 115.026676 -248.848358) (xy 114.976812 -248.838178)
			(xy 114.929226 -248.820131) (xy 114.885152 -248.794685) (xy 114.84573 -248.762498) (xy 114.811982 -248.724404)
			(xy 114.784781 -248.68139) (xy 114.764833 -248.63457) (xy 114.752654 -248.585156) (xy 114.748559 -248.534428)
			(xy 114.440462 -248.534428) (xy 114.43995 -248.559874) (xy 114.431786 -248.610108) (xy 114.41567 -248.658382)
			(xy 114.392019 -248.703445) (xy 114.361446 -248.744131) (xy 114.324742 -248.779386) (xy 114.282858 -248.808296)
			(xy 114.236879 -248.830113) (xy 114.187995 -248.844273) (xy 114.137474 -248.850407) (xy 114.086622 -248.848358)
			(xy 114.036758 -248.838178) (xy 113.989172 -248.820131) (xy 113.945098 -248.794685) (xy 113.905676 -248.762498)
			(xy 113.871928 -248.724404) (xy 113.844727 -248.68139) (xy 113.824779 -248.63457) (xy 113.8126 -248.585156)
			(xy 113.808505 -248.534428) (xy 113.502694 -248.534428) (xy 113.502204 -248.559417) (xy 113.494385 -248.60878)
			(xy 113.478941 -248.656312) (xy 113.456251 -248.700844) (xy 113.426875 -248.741277) (xy 113.391535 -248.776617)
			(xy 113.351102 -248.805993) (xy 113.30657 -248.828683) (xy 113.259038 -248.844127) (xy 113.209675 -248.851946)
			(xy 113.159697 -248.851946) (xy 113.110334 -248.844127) (xy 113.062802 -248.828683) (xy 113.01827 -248.805993)
			(xy 112.977837 -248.776617) (xy 112.942497 -248.741277) (xy 112.913121 -248.700844) (xy 112.890431 -248.656312)
			(xy 112.874987 -248.60878) (xy 112.867168 -248.559417) (xy 110.785158 -248.559417) (xy 110.78218 -248.582167)
			(xy 110.768617 -248.622103) (xy 110.758478 -248.6406) (xy 110.631478 -248.860818) (xy 110.62335 -248.856246)
			(xy 110.614472 -248.851615) (xy 110.594634 -248.849009) (xy 110.575308 -248.85419) (xy 110.559434 -248.866369)
			(xy 110.554008 -248.874788) (xy 110.47222 -249.01652) (xy 110.46682 -249.024951) (xy 110.450938 -249.037113)
			(xy 110.431611 -249.042274) (xy 110.41178 -249.039647) (xy 110.402878 -249.035062) (xy 109.96295 -248.781062)
			(xy 109.954547 -248.775625) (xy 109.942389 -248.759755) (xy 109.937223 -248.740442) (xy 109.670552 -248.740442)
			(xy 109.66778 -248.744131) (xy 109.631076 -248.779386) (xy 109.589192 -248.808296) (xy 109.543213 -248.830113)
			(xy 109.494329 -248.844273) (xy 109.443808 -248.850407) (xy 109.392956 -248.848358) (xy 109.343092 -248.838178)
			(xy 109.295506 -248.820131) (xy 109.251432 -248.794685) (xy 109.21201 -248.762498) (xy 109.178262 -248.724404)
			(xy 109.151061 -248.68139) (xy 109.131113 -248.63457) (xy 109.118934 -248.585156) (xy 109.114839 -248.534428)
			(xy 108.806742 -248.534428) (xy 108.80623 -248.559874) (xy 108.798066 -248.610108) (xy 108.78195 -248.658382)
			(xy 108.758299 -248.703445) (xy 108.727726 -248.744131) (xy 108.691022 -248.779386) (xy 108.649138 -248.808296)
			(xy 108.603159 -248.830113) (xy 108.554275 -248.844273) (xy 108.503754 -248.850407) (xy 108.452902 -248.848358)
			(xy 108.403038 -248.838178) (xy 108.355452 -248.820131) (xy 108.311378 -248.794685) (xy 108.271956 -248.762498)
			(xy 108.238208 -248.724404) (xy 108.211007 -248.68139) (xy 108.191059 -248.63457) (xy 108.17888 -248.585156)
			(xy 108.174785 -248.534428) (xy 107.868974 -248.534428) (xy 107.868211 -248.565661) (xy 107.85606 -248.626934)
			(xy 107.844844 -248.656094) (xy 107.841796 -248.667016) (xy 107.837649 -248.687989) (xy 107.82221 -248.727848)
			(xy 107.79915 -248.763839) (xy 107.76939 -248.794521) (xy 107.73412 -248.818669) (xy 107.694751 -248.835317)
			(xy 107.652856 -248.843799) (xy 107.631484 -248.844308) (xy 107.623102 -248.844308) (xy 107.617768 -248.845324)
			(xy 107.601267 -248.848647) (xy 107.567796 -248.852215) (xy 107.550966 -248.852436) (xy 107.534136 -248.852208)
			(xy 107.500665 -248.848644) (xy 107.484164 -248.845324) (xy 107.47883 -248.844308) (xy 107.406186 -248.844308)
			(xy 107.376468 -248.81459) (xy 107.376468 -248.800366) (xy 107.366562 -248.793762) (xy 107.360035 -248.789463)
			(xy 107.345162 -248.784684) (xy 107.337352 -248.784364) (xy 107.1626 -248.784364) (xy 107.152574 -248.78398)
			(xy 107.13405 -248.776303) (xy 107.119877 -248.762119) (xy 107.112213 -248.74359) (xy 107.1118 -248.733564)
			(xy 105.185972 -248.733564) (xy 105.18555 -248.743586) (xy 105.177887 -248.762108) (xy 105.163715 -248.776282)
			(xy 105.145194 -248.783949) (xy 105.135172 -248.784364) (xy 104.927908 -248.784364) (xy 104.921304 -248.789444)
			(xy 104.921304 -248.793508) (xy 104.920818 -248.803516) (xy 104.913157 -248.822007) (xy 104.899003 -248.836159)
			(xy 104.880512 -248.843819) (xy 104.870504 -248.844308) (xy 104.803194 -248.844308) (xy 104.79786 -248.845324)
			(xy 104.78136 -248.848648) (xy 104.747888 -248.852215) (xy 104.731058 -248.852436) (xy 104.730804 -248.852436)
			(xy 104.713585 -248.852232) (xy 104.679346 -248.848538) (xy 104.662478 -248.84507) (xy 104.65435 -248.8438)
			(xy 104.635391 -248.842325) (xy 104.59841 -248.833473) (xy 104.563587 -248.818201) (xy 104.532025 -248.796994)
			(xy 104.504726 -248.770524) (xy 104.482556 -248.739631) (xy 104.47401 -248.722642) (xy 104.469946 -248.715784)
			(xy 104.456542 -248.695701) (xy 104.435276 -248.652357) (xy 104.420818 -248.606292) (xy 104.413503 -248.558568)
			(xy 104.41305 -248.534428) (xy 102.229158 -248.534428) (xy 102.228769 -248.559422) (xy 102.220945 -248.608795)
			(xy 102.205492 -248.656336) (xy 102.182793 -248.700874) (xy 102.153405 -248.741313) (xy 102.118053 -248.776656)
			(xy 102.077608 -248.806034) (xy 102.033064 -248.828722) (xy 101.985519 -248.844163) (xy 101.936145 -248.851975)
			(xy 101.91115 -248.852436) (xy 101.89432 -248.85221) (xy 101.860849 -248.848645) (xy 101.844348 -248.845324)
			(xy 101.839014 -248.844308) (xy 101.655372 -248.844308) (xy 101.655372 -248.835164) (xy 101.654941 -248.825151)
			(xy 101.647264 -248.806653) (xy 101.633094 -248.7925) (xy 101.614586 -248.784847) (xy 101.604572 -248.784364)
			(xy 101.441504 -248.784364) (xy 101.431478 -248.783976) (xy 101.412955 -248.776301) (xy 101.398781 -248.762118)
			(xy 101.391117 -248.74359) (xy 101.390704 -248.733564) (xy 99.598226 -248.733564) (xy 99.598226 -248.810526)
			(xy 99.598711 -248.820383) (xy 99.606259 -248.838594) (xy 99.620197 -248.852536) (xy 99.638407 -248.860087)
			(xy 99.648264 -248.860564) (xy 99.95789 -248.860564) (xy 99.967727 -248.861103) (xy 99.985886 -248.868691)
			(xy 99.993196 -248.875296) (xy 100.090732 -248.972832) (xy 100.09744 -248.980072) (xy 100.105023 -248.998277)
			(xy 100.105464 -249.008138) (xy 100.105464 -249.622564) (xy 100.917248 -249.622564) (xy 100.917248 -249.114564)
			(xy 100.917591 -249.104534) (xy 100.925282 -249.086007) (xy 100.939478 -249.071835) (xy 100.958018 -249.064175)
			(xy 100.968048 -249.063764) (xy 101.181916 -249.063764) (xy 101.181916 -249.05462) (xy 101.182337 -249.044598)
			(xy 101.190003 -249.026079) (xy 101.204175 -249.011905) (xy 101.222694 -249.004237) (xy 101.232716 -249.00382)
			(xy 101.436932 -249.00382) (xy 101.455508 -249.004259) (xy 101.492086 -249.010784) (xy 101.526974 -249.02356)
			(xy 101.559115 -249.042199) (xy 101.573584 -249.053858) (xy 101.58349 -249.060462) (xy 101.605767 -249.072089)
			(xy 101.646609 -249.101362) (xy 101.68233 -249.136703) (xy 101.712038 -249.177229) (xy 101.734993 -249.221929)
			(xy 101.75062 -249.269687) (xy 101.758529 -249.319309) (xy 101.759004 -249.344434) (xy 101.758417 -249.372162)
			(xy 101.748796 -249.426776) (xy 101.729851 -249.478896) (xy 101.702157 -249.526941) (xy 101.666552 -249.569457)
			(xy 101.64572 -249.587766) (xy 101.6414 -249.591597) (xy 101.634479 -249.600837) (xy 101.632004 -249.606054)
			(xy 101.624275 -249.622564) (xy 102.822248 -249.622564) (xy 102.822248 -249.114564) (xy 102.822591 -249.104534)
			(xy 102.830282 -249.086007) (xy 102.844478 -249.071835) (xy 102.863018 -249.064175) (xy 102.873048 -249.063764)
			(xy 103.086916 -249.063764) (xy 103.086916 -249.05462) (xy 103.087337 -249.044598) (xy 103.095003 -249.026079)
			(xy 103.109175 -249.011905) (xy 103.127694 -249.004237) (xy 103.137716 -249.00382) (xy 103.341932 -249.00382)
			(xy 103.361454 -249.004249) (xy 103.39984 -249.011392) (xy 103.436286 -249.025399) (xy 103.469577 -249.045801)
			(xy 103.498601 -249.071918) (xy 103.510842 -249.087132) (xy 103.519478 -249.095768) (xy 103.537803 -249.110956)
			(xy 103.570152 -249.145865) (xy 103.596942 -249.185202) (xy 103.617573 -249.228091) (xy 103.631587 -249.273574)
			(xy 103.638671 -249.320637) (xy 103.639112 -249.344434) (xy 103.639112 -249.344688) (xy 103.638681 -249.36782)
			(xy 103.63197 -249.413595) (xy 103.618689 -249.457911) (xy 103.599119 -249.499832) (xy 103.573673 -249.53847)
			(xy 103.558594 -249.556016) (xy 103.554851 -249.560484) (xy 103.54934 -249.570751) (xy 103.547672 -249.576336)
			(xy 103.542052 -249.59541) (xy 103.528814 -249.622564) (xy 104.727248 -249.622564) (xy 104.727248 -249.114564)
			(xy 104.727591 -249.104534) (xy 104.735282 -249.086007) (xy 104.749478 -249.071835) (xy 104.768018 -249.064175)
			(xy 104.778048 -249.063764) (xy 104.991916 -249.063764) (xy 104.991916 -249.05462) (xy 104.992337 -249.044598)
			(xy 105.000003 -249.026079) (xy 105.014175 -249.011905) (xy 105.032694 -249.004237) (xy 105.042716 -249.00382)
			(xy 105.246932 -249.00382) (xy 105.267933 -249.004292) (xy 105.309115 -249.012562) (xy 105.347888 -249.028718)
			(xy 105.382757 -249.052137) (xy 105.41238 -249.081916) (xy 105.435614 -249.116909) (xy 105.444036 -249.136154)
			(xy 105.451148 -249.148092) (xy 105.467059 -249.169249) (xy 105.492383 -249.215732) (xy 105.509667 -249.265765)
			(xy 105.518436 -249.317967) (xy 105.518966 -249.344434) (xy 105.518583 -249.367458) (xy 105.511937 -249.413025)
			(xy 105.498787 -249.457157) (xy 105.479409 -249.49893) (xy 105.46715 -249.518424) (xy 105.463996 -249.523592)
			(xy 105.460009 -249.53502) (xy 105.459276 -249.54103) (xy 105.456903 -249.560537) (xy 105.445951 -249.598272)
			(xy 105.433714 -249.622564) (xy 106.632248 -249.622564) (xy 106.632248 -249.114564) (xy 106.632591 -249.104534)
			(xy 106.640282 -249.086007) (xy 106.654478 -249.071835) (xy 106.673018 -249.064175) (xy 106.683048 -249.063764)
			(xy 106.896916 -249.063764) (xy 106.896916 -249.05462) (xy 106.897337 -249.044598) (xy 106.905003 -249.026079)
			(xy 106.919175 -249.011905) (xy 106.937694 -249.004237) (xy 106.947716 -249.00382) (xy 107.151932 -249.00382)
			(xy 107.171318 -249.004275) (xy 107.209457 -249.011253) (xy 107.245705 -249.025012) (xy 107.278869 -249.045096)
			(xy 107.307856 -249.070844) (xy 107.331711 -249.101409) (xy 107.349648 -249.135782) (xy 107.361075 -249.172831)
			(xy 107.363768 -249.192034) (xy 107.364344 -249.196115) (xy 107.366638 -249.204029) (xy 107.36834 -249.207782)
			(xy 107.378035 -249.2292) (xy 107.391727 -249.274174) (xy 107.39865 -249.320674) (xy 107.399074 -249.34418)
			(xy 107.399074 -249.344434) (xy 107.398674 -249.367333) (xy 107.392104 -249.412658) (xy 107.379092 -249.456569)
			(xy 107.369864 -249.47753) (xy 107.365292 -249.48769) (xy 107.365292 -249.51817) (xy 107.365292 -249.518678)
			(xy 107.364938 -249.539726) (xy 107.356934 -249.58105) (xy 107.340995 -249.620007) (xy 107.3393 -249.622564)
			(xy 108.537248 -249.622564) (xy 108.537248 -249.114564) (xy 108.537591 -249.104534) (xy 108.545282 -249.086007)
			(xy 108.559478 -249.071835) (xy 108.578018 -249.064175) (xy 108.588048 -249.063764) (xy 108.801916 -249.063764)
			(xy 108.801916 -249.05462) (xy 108.802337 -249.044598) (xy 108.810003 -249.026079) (xy 108.824175 -249.011905)
			(xy 108.842694 -249.004237) (xy 108.852716 -249.00382) (xy 109.056932 -249.00382) (xy 109.077978 -249.004295)
			(xy 109.119255 -249.012542) (xy 109.158118 -249.028712) (xy 109.193063 -249.052177) (xy 109.222738 -249.082031)
			(xy 109.245993 -249.117116) (xy 109.261929 -249.156076) (xy 109.269928 -249.197401) (xy 109.270292 -249.21845)
			(xy 109.270292 -249.218958) (xy 109.270292 -249.268996) (xy 109.271308 -249.274584) (xy 109.274965 -249.291816)
			(xy 109.278915 -249.326821) (xy 109.279182 -249.344434) (xy 109.278922 -249.362048) (xy 109.274975 -249.397054)
			(xy 109.271308 -249.414284) (xy 109.270292 -249.419872) (xy 109.270292 -249.51817) (xy 109.270292 -249.518678)
			(xy 109.269938 -249.539726) (xy 109.267865 -249.550428) (xy 111.435896 -249.550428) (xy 111.435896 -249.346466)
			(xy 111.436332 -249.327143) (xy 111.443313 -249.289132) (xy 111.457006 -249.252991) (xy 111.46663 -249.23623)
			(xy 111.470186 -249.229118) (xy 111.480518 -249.204777) (xy 111.507323 -249.159197) (xy 111.540575 -249.118083)
			(xy 111.579542 -249.082339) (xy 111.623367 -249.052752) (xy 111.671087 -249.029973) (xy 111.721651 -249.014503)
			(xy 111.773947 -249.006682) (xy 111.826825 -249.006682) (xy 111.879121 -249.014503) (xy 111.929685 -249.029973)
			(xy 111.977405 -249.052752) (xy 112.02123 -249.082339) (xy 112.060197 -249.118083) (xy 112.093449 -249.159197)
			(xy 112.120254 -249.204777) (xy 112.130586 -249.229118) (xy 112.134142 -249.23623) (xy 112.143781 -249.252986)
			(xy 112.157495 -249.289122) (xy 112.16446 -249.32714) (xy 112.164832 -249.344434) (xy 113.336832 -249.344434)
			(xy 113.337003 -249.329809) (xy 113.339669 -249.30068) (xy 113.342166 -249.286268) (xy 113.342928 -249.281696)
			(xy 113.342928 -249.21845) (xy 113.343288 -249.197402) (xy 113.351288 -249.156077) (xy 113.367224 -249.117118)
			(xy 113.39048 -249.082034) (xy 113.420156 -249.052183) (xy 113.455102 -249.028719) (xy 113.493965 -249.012553)
			(xy 113.535242 -249.004309) (xy 113.556288 -249.00382) (xy 113.811304 -249.00382) (xy 113.811304 -249.012964)
			(xy 113.811749 -249.022983) (xy 113.819408 -249.0415) (xy 113.833573 -249.055674) (xy 113.852085 -249.063344)
			(xy 113.862104 -249.063764) (xy 114.025172 -249.063764) (xy 114.035173 -249.06431) (xy 114.053658 -249.071954)
			(xy 114.067811 -249.086088) (xy 114.075477 -249.104563) (xy 114.075972 -249.114564) (xy 114.075972 -249.344942)
			(xy 115.216686 -249.344942) (xy 115.216686 -249.344434) (xy 115.217075 -249.321995) (xy 115.223433 -249.27757)
			(xy 115.235985 -249.234483) (xy 115.24488 -249.213878) (xy 115.24647 -249.209979) (xy 115.248516 -249.201811)
			(xy 115.248944 -249.197622) (xy 115.251216 -249.178023) (xy 115.262016 -249.14008) (xy 115.279596 -249.104764)
			(xy 115.303359 -249.073275) (xy 115.332498 -249.046681) (xy 115.366023 -249.025887) (xy 115.402795 -249.011599)
			(xy 115.441564 -249.004302) (xy 115.461288 -249.00382) (xy 115.716304 -249.00382) (xy 115.716304 -249.012964)
			(xy 115.716749 -249.022983) (xy 115.724408 -249.0415) (xy 115.738573 -249.055674) (xy 115.757085 -249.063344)
			(xy 115.767104 -249.063764) (xy 115.930172 -249.063764) (xy 115.940173 -249.06431) (xy 115.958658 -249.071954)
			(xy 115.972811 -249.086088) (xy 115.980477 -249.104563) (xy 115.980972 -249.114564) (xy 115.980972 -249.344434)
			(xy 117.096794 -249.344434) (xy 117.097292 -249.318881) (xy 117.105486 -249.268435) (xy 117.121652 -249.219953)
			(xy 117.145372 -249.174684) (xy 117.160294 -249.153934) (xy 117.162338 -249.151047) (xy 117.165645 -249.144796)
			(xy 117.166898 -249.141488) (xy 117.175066 -249.121609) (xy 117.198064 -249.085313) (xy 117.227841 -249.054333)
			(xy 117.263198 -249.029916) (xy 117.302715 -249.013042) (xy 117.344804 -249.00439) (xy 117.366288 -249.00382)
			(xy 117.621304 -249.00382) (xy 117.621304 -249.012964) (xy 117.621749 -249.022983) (xy 117.629408 -249.0415)
			(xy 117.643573 -249.055674) (xy 117.662085 -249.063344) (xy 117.672104 -249.063764) (xy 117.835172 -249.063764)
			(xy 117.845173 -249.06431) (xy 117.863658 -249.071954) (xy 117.877811 -249.086088) (xy 117.885477 -249.104563)
			(xy 117.885972 -249.114564) (xy 117.885972 -249.344434) (xy 118.976648 -249.344434) (xy 118.977077 -249.32126)
			(xy 118.983818 -249.275405) (xy 118.997148 -249.231015) (xy 119.016783 -249.189031) (xy 119.042307 -249.150345)
			(xy 119.07318 -249.115776) (xy 119.090694 -249.100594) (xy 119.099076 -249.09145) (xy 119.111271 -249.075508)
			(xy 119.140578 -249.048088) (xy 119.174486 -249.026618) (xy 119.211804 -249.011851) (xy 119.251222 -249.004305)
			(xy 119.271288 -249.00382) (xy 119.526304 -249.00382) (xy 119.526304 -249.012964) (xy 119.526749 -249.022983)
			(xy 119.534408 -249.0415) (xy 119.548573 -249.055674) (xy 119.567085 -249.063344) (xy 119.577104 -249.063764)
			(xy 119.740172 -249.063764) (xy 119.750173 -249.06431) (xy 119.768658 -249.071954) (xy 119.782811 -249.086088)
			(xy 119.790477 -249.104563) (xy 119.790972 -249.114564) (xy 119.790972 -249.344434) (xy 120.856756 -249.344434)
			(xy 120.857265 -249.319744) (xy 120.864892 -249.270957) (xy 120.87997 -249.223936) (xy 120.902134 -249.17981)
			(xy 120.930853 -249.139641) (xy 120.965436 -249.104393) (xy 121.005051 -249.074915) (xy 121.026682 -249.063002)
			(xy 121.036334 -249.056398) (xy 121.051012 -249.044158) (xy 121.083815 -249.024556) (xy 121.119587 -249.011115)
			(xy 121.157182 -249.004265) (xy 121.176288 -249.00382) (xy 121.431304 -249.00382) (xy 121.431304 -249.012964)
			(xy 121.431749 -249.022983) (xy 121.439408 -249.0415) (xy 121.453573 -249.055674) (xy 121.472085 -249.063344)
			(xy 121.482104 -249.063764) (xy 121.645172 -249.063764) (xy 121.655173 -249.06431) (xy 121.673658 -249.071954)
			(xy 121.687811 -249.086088) (xy 121.695477 -249.104563) (xy 121.695972 -249.114564) (xy 121.695972 -249.344434)
			(xy 122.73661 -249.344434) (xy 122.737096 -249.319429) (xy 122.74492 -249.270034) (xy 122.760379 -249.222473)
			(xy 122.783093 -249.177918) (xy 122.812502 -249.137468) (xy 122.84788 -249.102121) (xy 122.888356 -249.072747)
			(xy 122.93293 -249.050072) (xy 122.956574 -249.04192) (xy 122.968004 -249.036586) (xy 122.985111 -249.026349)
			(xy 123.0222 -249.011742) (xy 123.061358 -249.004289) (xy 123.081288 -249.00382) (xy 123.336304 -249.00382)
			(xy 123.336304 -249.012964) (xy 123.336749 -249.022983) (xy 123.344408 -249.0415) (xy 123.358573 -249.055674)
			(xy 123.377085 -249.063344) (xy 123.387104 -249.063764) (xy 123.550172 -249.063764) (xy 123.560173 -249.06431)
			(xy 123.578658 -249.071954) (xy 123.592811 -249.086088) (xy 123.600477 -249.104563) (xy 123.600972 -249.114564)
			(xy 123.600972 -249.344434) (xy 124.616718 -249.344434) (xy 124.617083 -249.322924) (xy 124.622919 -249.280302)
			(xy 124.634447 -249.238856) (xy 124.642626 -249.218958) (xy 124.644233 -249.214998) (xy 124.64628 -249.206702)
			(xy 124.64669 -249.202448) (xy 124.648469 -249.182495) (xy 124.658642 -249.143751) (xy 124.675862 -249.107584)
			(xy 124.699524 -249.075263) (xy 124.728798 -249.047921) (xy 124.762657 -249.026517) (xy 124.799913 -249.011803)
			(xy 124.83926 -249.004294) (xy 124.859288 -249.00382) (xy 125.114304 -249.00382) (xy 125.114304 -249.012964)
			(xy 125.114749 -249.022983) (xy 125.122408 -249.0415) (xy 125.136573 -249.055674) (xy 125.155085 -249.063344)
			(xy 125.165104 -249.063764) (xy 125.328172 -249.063764) (xy 125.338173 -249.06431) (xy 125.356658 -249.071954)
			(xy 125.370811 -249.086088) (xy 125.378477 -249.104563) (xy 125.378972 -249.114564) (xy 125.378972 -249.622564)
			(xy 125.37855 -249.632586) (xy 125.370887 -249.651108) (xy 125.356715 -249.665282) (xy 125.338194 -249.672949)
			(xy 125.328172 -249.673364) (xy 125.114304 -249.673364) (xy 125.114304 -249.682508) (xy 125.113818 -249.692516)
			(xy 125.106157 -249.711007) (xy 125.092003 -249.725159) (xy 125.073512 -249.732819) (xy 125.063504 -249.733308)
			(xy 124.859288 -249.733308) (xy 124.838244 -249.732787) (xy 124.796972 -249.724544) (xy 124.758111 -249.708381)
			(xy 124.723168 -249.684922) (xy 124.693494 -249.655075) (xy 124.670237 -249.619997) (xy 124.654299 -249.581044)
			(xy 124.646295 -249.539724) (xy 124.645928 -249.518678) (xy 124.645928 -249.51817) (xy 124.645928 -249.478292)
			(xy 124.642118 -249.46864) (xy 124.634075 -249.448934) (xy 124.622779 -249.407896) (xy 124.61707 -249.365716)
			(xy 124.616718 -249.344434) (xy 123.600972 -249.344434) (xy 123.600972 -249.622564) (xy 123.60055 -249.632586)
			(xy 123.592887 -249.651108) (xy 123.578715 -249.665282) (xy 123.560194 -249.672949) (xy 123.550172 -249.673364)
			(xy 123.336304 -249.673364) (xy 123.336304 -249.682508) (xy 123.335818 -249.692516) (xy 123.328157 -249.711007)
			(xy 123.314003 -249.725159) (xy 123.295512 -249.732819) (xy 123.285504 -249.733308) (xy 123.081288 -249.733308)
			(xy 123.05911 -249.732686) (xy 123.015717 -249.723484) (xy 122.97516 -249.70552) (xy 122.939186 -249.679569)
			(xy 122.909346 -249.646748) (xy 122.897646 -249.627898) (xy 122.894492 -249.622857) (xy 122.886281 -249.614262)
			(xy 122.88139 -249.61088) (xy 122.859565 -249.596086) (xy 122.820675 -249.560489) (xy 122.788197 -249.518959)
			(xy 122.763023 -249.472636) (xy 122.745845 -249.422792) (xy 122.737133 -249.370795) (xy 122.73661 -249.344434)
			(xy 121.695972 -249.344434) (xy 121.695972 -249.622564) (xy 121.69555 -249.632586) (xy 121.687887 -249.651108)
			(xy 121.673715 -249.665282) (xy 121.655194 -249.672949) (xy 121.645172 -249.673364) (xy 121.431304 -249.673364)
			(xy 121.431304 -249.682508) (xy 121.430818 -249.692516) (xy 121.423157 -249.711007) (xy 121.409003 -249.725159)
			(xy 121.390512 -249.732819) (xy 121.380504 -249.733308) (xy 121.176288 -249.733308) (xy 121.155515 -249.732811)
			(xy 121.114761 -249.724736) (xy 121.076337 -249.708934) (xy 121.041693 -249.686) (xy 121.012139 -249.656799)
			(xy 120.988788 -249.622435) (xy 120.9802 -249.603514) (xy 120.977801 -249.598247) (xy 120.971005 -249.588882)
			(xy 120.966738 -249.584972) (xy 120.946475 -249.566676) (xy 120.911886 -249.524442) (xy 120.885014 -249.476924)
			(xy 120.866646 -249.425517) (xy 120.857323 -249.371729) (xy 120.856756 -249.344434) (xy 119.790972 -249.344434)
			(xy 119.790972 -249.622564) (xy 119.79055 -249.632586) (xy 119.782887 -249.651108) (xy 119.768715 -249.665282)
			(xy 119.750194 -249.672949) (xy 119.740172 -249.673364) (xy 119.526304 -249.673364) (xy 119.526304 -249.682508)
			(xy 119.525818 -249.692516) (xy 119.518157 -249.711007) (xy 119.504003 -249.725159) (xy 119.485512 -249.732819)
			(xy 119.475504 -249.733308) (xy 119.271288 -249.733308) (xy 119.25116 -249.732861) (xy 119.211624 -249.725276)
			(xy 119.17421 -249.710416) (xy 119.140245 -249.688806) (xy 119.110931 -249.661214) (xy 119.087309 -249.628616)
			(xy 119.070216 -249.592168) (xy 119.064786 -249.57278) (xy 119.063172 -249.567153) (xy 119.057793 -249.556762)
			(xy 119.054118 -249.552206) (xy 119.036042 -249.530379) (xy 119.007158 -249.481627) (xy 118.987365 -249.42853)
			(xy 118.977288 -249.372767) (xy 118.976648 -249.344434) (xy 117.885972 -249.344434) (xy 117.885972 -249.622564)
			(xy 117.88555 -249.632586) (xy 117.877887 -249.651108) (xy 117.863715 -249.665282) (xy 117.845194 -249.672949)
			(xy 117.835172 -249.673364) (xy 117.621304 -249.673364) (xy 117.621304 -249.682508) (xy 117.620818 -249.692516)
			(xy 117.613157 -249.711007) (xy 117.599003 -249.725159) (xy 117.580512 -249.732819) (xy 117.570504 -249.733308)
			(xy 117.366288 -249.733308) (xy 117.346443 -249.732814) (xy 117.307445 -249.725423) (xy 117.270485 -249.710952)
			(xy 117.236835 -249.6899) (xy 117.207656 -249.662993) (xy 117.183951 -249.631157) (xy 117.166537 -249.595488)
			(xy 117.156014 -249.557217) (xy 117.153944 -249.537474) (xy 117.153247 -249.531337) (xy 117.149263 -249.519648)
			(xy 117.14607 -249.51436) (xy 117.134407 -249.495206) (xy 117.115974 -249.454325) (xy 117.103481 -249.411255)
			(xy 117.097176 -249.366856) (xy 117.096794 -249.344434) (xy 115.980972 -249.344434) (xy 115.980972 -249.622564)
			(xy 115.98055 -249.632586) (xy 115.972887 -249.651108) (xy 115.958715 -249.665282) (xy 115.940194 -249.672949)
			(xy 115.930172 -249.673364) (xy 115.716304 -249.673364) (xy 115.716304 -249.682508) (xy 115.715818 -249.692516)
			(xy 115.708157 -249.711007) (xy 115.694003 -249.725159) (xy 115.675512 -249.732819) (xy 115.665504 -249.733308)
			(xy 115.461288 -249.733308) (xy 115.440244 -249.732787) (xy 115.398972 -249.724544) (xy 115.360111 -249.708381)
			(xy 115.325168 -249.684922) (xy 115.295494 -249.655075) (xy 115.272237 -249.619997) (xy 115.256299 -249.581044)
			(xy 115.248295 -249.539724) (xy 115.247928 -249.518678) (xy 115.247928 -249.51817) (xy 115.247928 -249.48261)
			(xy 115.24361 -249.472704) (xy 115.235121 -249.452484) (xy 115.223138 -249.4103) (xy 115.217072 -249.366868)
			(xy 115.216686 -249.344942) (xy 114.075972 -249.344942) (xy 114.075972 -249.622564) (xy 114.07555 -249.632586)
			(xy 114.067887 -249.651108) (xy 114.053715 -249.665282) (xy 114.035194 -249.672949) (xy 114.025172 -249.673364)
			(xy 113.811304 -249.673364) (xy 113.811304 -249.682508) (xy 113.810818 -249.692516) (xy 113.803157 -249.711007)
			(xy 113.789003 -249.725159) (xy 113.770512 -249.732819) (xy 113.760504 -249.733308) (xy 113.556288 -249.733308)
			(xy 113.535244 -249.732787) (xy 113.493972 -249.724544) (xy 113.455111 -249.708381) (xy 113.420168 -249.684922)
			(xy 113.390494 -249.655075) (xy 113.367237 -249.619997) (xy 113.351299 -249.581044) (xy 113.343295 -249.539724)
			(xy 113.342928 -249.518678) (xy 113.342928 -249.51817) (xy 113.342928 -249.407172) (xy 113.342166 -249.4026)
			(xy 113.339648 -249.388191) (xy 113.336979 -249.359061) (xy 113.336832 -249.344434) (xy 112.164832 -249.344434)
			(xy 112.164876 -249.346466) (xy 112.164876 -249.601228) (xy 112.155732 -249.601228) (xy 112.145709 -249.601647)
			(xy 112.127188 -249.609311) (xy 112.113013 -249.623484) (xy 112.105347 -249.642005) (xy 112.104932 -249.652028)
			(xy 112.104932 -249.815604) (xy 112.104416 -249.825608) (xy 112.096761 -249.844094) (xy 112.082617 -249.858245)
			(xy 112.064136 -249.86591) (xy 112.054132 -249.866404) (xy 111.54664 -249.866404) (xy 111.536622 -249.865948)
			(xy 111.518107 -249.858292) (xy 111.503933 -249.84413) (xy 111.496261 -249.825622) (xy 111.49584 -249.815604)
			(xy 111.49584 -249.601228) (xy 111.486696 -249.601228) (xy 111.476692 -249.600716) (xy 111.458205 -249.59306)
			(xy 111.444053 -249.578915) (xy 111.436389 -249.560432) (xy 111.435896 -249.550428) (xy 109.267865 -249.550428)
			(xy 109.261934 -249.58105) (xy 109.245995 -249.620007) (xy 109.222737 -249.65509) (xy 109.193062 -249.68494)
			(xy 109.158116 -249.708403) (xy 109.119254 -249.724571) (xy 109.077978 -249.732818) (xy 109.056932 -249.733308)
			(xy 108.801916 -249.733308) (xy 108.801916 -249.724164) (xy 108.801442 -249.714156) (xy 108.793773 -249.695666)
			(xy 108.779617 -249.681515) (xy 108.761124 -249.673854) (xy 108.751116 -249.673364) (xy 108.588048 -249.673364)
			(xy 108.578025 -249.67294) (xy 108.559503 -249.665279) (xy 108.545327 -249.651108) (xy 108.537662 -249.632587)
			(xy 108.537248 -249.622564) (xy 107.3393 -249.622564) (xy 107.317737 -249.65509) (xy 107.288062 -249.68494)
			(xy 107.253116 -249.708403) (xy 107.214254 -249.724571) (xy 107.172978 -249.732818) (xy 107.151932 -249.733308)
			(xy 106.896916 -249.733308) (xy 106.896916 -249.724164) (xy 106.896442 -249.714156) (xy 106.888773 -249.695666)
			(xy 106.874617 -249.681515) (xy 106.856124 -249.673854) (xy 106.846116 -249.673364) (xy 106.683048 -249.673364)
			(xy 106.673025 -249.67294) (xy 106.654503 -249.665279) (xy 106.640327 -249.651108) (xy 106.632662 -249.632587)
			(xy 106.632248 -249.622564) (xy 105.433714 -249.622564) (xy 105.428274 -249.633364) (xy 105.404469 -249.664625)
			(xy 105.375343 -249.690998) (xy 105.34188 -249.711592) (xy 105.305212 -249.72571) (xy 105.266578 -249.732875)
			(xy 105.246932 -249.733308) (xy 104.991916 -249.733308) (xy 104.991916 -249.724164) (xy 104.991442 -249.714156)
			(xy 104.983773 -249.695666) (xy 104.969617 -249.681515) (xy 104.951124 -249.673854) (xy 104.941116 -249.673364)
			(xy 104.778048 -249.673364) (xy 104.768025 -249.67294) (xy 104.749503 -249.665279) (xy 104.735327 -249.651108)
			(xy 104.727662 -249.632587) (xy 104.727248 -249.622564) (xy 103.528814 -249.622564) (xy 103.524628 -249.631151)
			(xy 103.500887 -249.663047) (xy 103.47165 -249.689995) (xy 103.437929 -249.711063) (xy 103.400889 -249.725522)
			(xy 103.361813 -249.732873) (xy 103.341932 -249.733308) (xy 103.086916 -249.733308) (xy 103.086916 -249.724164)
			(xy 103.086442 -249.714156) (xy 103.078773 -249.695666) (xy 103.064617 -249.681515) (xy 103.046124 -249.673854)
			(xy 103.036116 -249.673364) (xy 102.873048 -249.673364) (xy 102.863025 -249.67294) (xy 102.844503 -249.665279)
			(xy 102.830327 -249.651108) (xy 102.822662 -249.632587) (xy 102.822248 -249.622564) (xy 101.624275 -249.622564)
			(xy 101.623291 -249.624667) (xy 101.599795 -249.65838) (xy 101.570295 -249.686986) (xy 101.535875 -249.709434)
			(xy 101.497802 -249.724897) (xy 101.457478 -249.732805) (xy 101.436932 -249.733308) (xy 101.181916 -249.733308)
			(xy 101.181916 -249.724164) (xy 101.181442 -249.714156) (xy 101.173773 -249.695666) (xy 101.159617 -249.681515)
			(xy 101.141124 -249.673854) (xy 101.131116 -249.673364) (xy 100.968048 -249.673364) (xy 100.958025 -249.67294)
			(xy 100.939503 -249.665279) (xy 100.925327 -249.651108) (xy 100.917662 -249.632587) (xy 100.917248 -249.622564)
			(xy 100.105464 -249.622564) (xy 100.105464 -249.728482) (xy 100.106226 -249.73661) (xy 100.106226 -249.737118)
			(xy 100.107826 -249.744637) (xy 100.114802 -249.758326) (xy 100.119942 -249.764042) (xy 100.54971 -250.19381)
			(xy 100.55225 -250.19635) (xy 100.725986 -250.370086) (xy 100.731662 -250.375284) (xy 100.745367 -250.382274)
			(xy 100.75291 -250.383802) (xy 100.753418 -250.383802) (xy 100.761546 -250.384564) (xy 101.513386 -250.384564)
			(xy 101.521514 -250.383802) (xy 101.522022 -250.383802) (xy 101.529541 -250.382202) (xy 101.543232 -250.375228)
			(xy 101.548946 -250.370086) (xy 101.552756 -250.366276) (xy 101.570028 -250.342654) (xy 101.570028 -250.342146)
			(xy 101.603556 -250.295918) (xy 101.606176 -250.291513) (xy 101.609757 -250.281912) (xy 101.610668 -250.276868)
			(xy 101.611684 -250.267978) (xy 101.612192 -250.263406) (xy 101.60889 -250.252992) (xy 101.601549 -250.229018)
			(xy 101.593637 -250.179508) (xy 101.593142 -250.15444) (xy 101.593632 -250.129451) (xy 101.601451 -250.080088)
			(xy 101.616895 -250.032556) (xy 101.639585 -249.988024) (xy 101.668961 -249.947591) (xy 101.704301 -249.912251)
			(xy 101.744734 -249.882875) (xy 101.789266 -249.860185) (xy 101.836798 -249.844741) (xy 101.886161 -249.836922)
			(xy 101.936139 -249.836922) (xy 101.985502 -249.844741) (xy 102.033034 -249.860185) (xy 102.077566 -249.882875)
			(xy 102.117999 -249.912251) (xy 102.153339 -249.947591) (xy 102.182715 -249.988024) (xy 102.205405 -250.032556)
			(xy 102.220849 -250.080088) (xy 102.228668 -250.129451) (xy 102.229158 -250.15444) (xy 102.228715 -250.178458)
			(xy 102.228567 -250.179429) (xy 103.473486 -250.179429) (xy 103.473486 -250.129451) (xy 103.481305 -250.080088)
			(xy 103.496749 -250.032556) (xy 103.519439 -249.988024) (xy 103.548815 -249.947591) (xy 103.584155 -249.912251)
			(xy 103.624588 -249.882875) (xy 103.66912 -249.860185) (xy 103.716652 -249.844741) (xy 103.766015 -249.836922)
			(xy 103.815993 -249.836922) (xy 103.865356 -249.844741) (xy 103.912888 -249.860185) (xy 103.95742 -249.882875)
			(xy 103.997853 -249.912251) (xy 104.033193 -249.947591) (xy 104.062569 -249.988024) (xy 104.085259 -250.032556)
			(xy 104.100703 -250.080088) (xy 104.108522 -250.129451) (xy 104.109012 -250.15444) (xy 104.108522 -250.179429)
			(xy 105.353594 -250.179429) (xy 105.353594 -250.129451) (xy 105.361413 -250.080088) (xy 105.376857 -250.032556)
			(xy 105.399547 -249.988024) (xy 105.428923 -249.947591) (xy 105.464263 -249.912251) (xy 105.504696 -249.882875)
			(xy 105.549228 -249.860185) (xy 105.59676 -249.844741) (xy 105.646123 -249.836922) (xy 105.696101 -249.836922)
			(xy 105.745464 -249.844741) (xy 105.792996 -249.860185) (xy 105.837528 -249.882875) (xy 105.877961 -249.912251)
			(xy 105.913301 -249.947591) (xy 105.942677 -249.988024) (xy 105.965367 -250.032556) (xy 105.980811 -250.080088)
			(xy 105.98863 -250.129451) (xy 105.98912 -250.15444) (xy 107.232958 -250.15444) (xy 107.233494 -250.129452)
			(xy 107.241306 -250.080089) (xy 107.256743 -250.032557) (xy 107.279427 -249.988024) (xy 107.308798 -249.947589)
			(xy 107.344133 -249.912246) (xy 107.384561 -249.882866) (xy 107.429088 -249.860172) (xy 107.476617 -249.844723)
			(xy 107.525978 -249.836899) (xy 107.550966 -249.836432) (xy 107.573264 -249.836806) (xy 107.61743 -249.842987)
			(xy 107.660299 -249.855276) (xy 107.701032 -249.873431) (xy 107.72013 -249.884946) (xy 107.726272 -249.888553)
			(xy 107.739937 -249.892549) (xy 107.747054 -249.89282) (xy 107.870752 -249.89282) (xy 107.870752 -249.901964)
			(xy 107.871316 -249.911964) (xy 107.878955 -249.930445) (xy 107.893084 -249.944598) (xy 107.911553 -249.952267)
			(xy 107.921552 -249.952764) (xy 108.08462 -249.952764) (xy 108.094625 -249.953271) (xy 108.11311 -249.96093)
			(xy 108.127261 -249.975077) (xy 108.134926 -249.99356) (xy 108.13542 -250.003564) (xy 108.13542 -250.511564)
			(xy 108.134951 -250.52158) (xy 108.127297 -250.540093) (xy 108.11314 -250.554266) (xy 108.094636 -250.56194)
			(xy 108.08462 -250.562364) (xy 107.870752 -250.562364) (xy 107.870752 -250.571508) (xy 107.870386 -250.581536)
			(xy 107.862704 -250.600062) (xy 107.848515 -250.614236) (xy 107.82998 -250.621897) (xy 107.819952 -250.622308)
			(xy 107.615736 -250.622308) (xy 107.595306 -250.621841) (xy 107.555198 -250.614038) (xy 107.517306 -250.598749)
			(xy 107.483014 -250.576532) (xy 107.453574 -250.548197) (xy 107.430061 -250.51478) (xy 107.413334 -250.477501)
			(xy 107.408218 -250.457716) (xy 107.405545 -250.447923) (xy 107.393753 -250.431419) (xy 107.385358 -250.425712)
			(xy 107.362479 -250.411145) (xy 107.321621 -250.375482) (xy 107.287413 -250.333396) (xy 107.260851 -250.286113)
			(xy 107.242705 -250.235005) (xy 107.233504 -250.181557) (xy 107.232958 -250.15444) (xy 105.98912 -250.15444)
			(xy 105.98863 -250.179429) (xy 105.980811 -250.228792) (xy 105.965367 -250.276324) (xy 105.942677 -250.320856)
			(xy 105.913301 -250.361289) (xy 105.877961 -250.396629) (xy 105.837528 -250.426005) (xy 105.792996 -250.448695)
			(xy 105.745464 -250.464139) (xy 105.696101 -250.471958) (xy 105.646123 -250.471958) (xy 105.59676 -250.464139)
			(xy 105.549228 -250.448695) (xy 105.504696 -250.426005) (xy 105.464263 -250.396629) (xy 105.428923 -250.361289)
			(xy 105.399547 -250.320856) (xy 105.376857 -250.276324) (xy 105.361413 -250.228792) (xy 105.353594 -250.179429)
			(xy 104.108522 -250.179429) (xy 104.100703 -250.228792) (xy 104.085259 -250.276324) (xy 104.062569 -250.320856)
			(xy 104.033193 -250.361289) (xy 103.997853 -250.396629) (xy 103.95742 -250.426005) (xy 103.912888 -250.448695)
			(xy 103.865356 -250.464139) (xy 103.815993 -250.471958) (xy 103.766015 -250.471958) (xy 103.716652 -250.464139)
			(xy 103.66912 -250.448695) (xy 103.624588 -250.426005) (xy 103.584155 -250.396629) (xy 103.548815 -250.361289)
			(xy 103.519439 -250.320856) (xy 103.496749 -250.276324) (xy 103.481305 -250.228792) (xy 103.473486 -250.179429)
			(xy 102.228567 -250.179429) (xy 102.221478 -250.225946) (xy 102.207177 -250.271804) (xy 102.186135 -250.314987)
			(xy 102.158834 -250.35451) (xy 102.125894 -250.389474) (xy 102.088067 -250.419081) (xy 102.046215 -250.442658)
			(xy 102.023926 -250.45162) (xy 102.013766 -250.455684) (xy 102.005892 -250.463558) (xy 102.000938 -250.468886)
			(xy 101.993977 -250.481654) (xy 101.992176 -250.488704) (xy 101.979222 -250.548648) (xy 101.979222 -250.549156)
			(xy 101.974142 -250.56973) (xy 101.972609 -250.579781) (xy 101.976678 -250.599684) (xy 101.982016 -250.608338)
			(xy 101.98735 -250.61545) (xy 101.995732 -250.623832) (xy 102.00244 -250.631072) (xy 102.010023 -250.649277)
			(xy 102.010464 -250.659138) (xy 102.010464 -250.998482) (xy 102.011226 -251.00661) (xy 102.011226 -251.007118)
			(xy 102.012826 -251.014637) (xy 102.019802 -251.028326) (xy 102.024942 -251.034042) (xy 102.122986 -251.132086)
			(xy 102.128662 -251.137284) (xy 102.142367 -251.144274) (xy 102.14991 -251.145802) (xy 102.150418 -251.145802)
			(xy 102.158546 -251.146564) (xy 102.898956 -251.146564) (xy 102.908835 -251.146159) (xy 102.927093 -251.138612)
			(xy 102.941073 -251.124652) (xy 102.948645 -251.106404) (xy 102.948994 -251.096526) (xy 102.948994 -250.635262)
			(xy 102.949248 -250.633992) (xy 102.949248 -250.617482) (xy 102.978966 -250.587764) (xy 103.164386 -250.587764)
			(xy 103.173759 -250.587334) (xy 103.191176 -250.580397) (xy 103.204839 -250.567559) (xy 103.212845 -250.550606)
			(xy 103.213916 -250.541282) (xy 103.213916 -250.52782) (xy 103.468932 -250.52782) (xy 103.490088 -250.528322)
			(xy 103.53157 -250.536655) (xy 103.570601 -250.55299) (xy 103.605654 -250.576687) (xy 103.635357 -250.606819)
			(xy 103.658549 -250.642208) (xy 103.674322 -250.681469) (xy 103.68206 -250.723067) (xy 103.682292 -250.744228)
			(xy 103.682292 -250.747022) (xy 103.682292 -250.747784) (xy 103.682292 -251.04598) (xy 103.682781 -251.055941)
			(xy 103.690371 -251.074363) (xy 103.697024 -251.081794) (xy 103.721662 -251.106432) (xy 103.747824 -251.132848)
			(xy 103.753966 -251.138199) (xy 103.76873 -251.145064) (xy 103.77678 -251.14631) (xy 103.781098 -251.146564)
			(xy 104.676956 -251.146564) (xy 104.686835 -251.146159) (xy 104.705093 -251.138612) (xy 104.719073 -251.124652)
			(xy 104.726645 -251.106404) (xy 104.726994 -251.096526) (xy 104.726994 -250.635262) (xy 104.727248 -250.633992)
			(xy 104.727248 -250.617482) (xy 104.756966 -250.587764) (xy 104.942386 -250.587764) (xy 104.951759 -250.587334)
			(xy 104.969176 -250.580397) (xy 104.982839 -250.567559) (xy 104.990845 -250.550606) (xy 104.991916 -250.541282)
			(xy 104.991916 -250.52782) (xy 105.246932 -250.52782) (xy 105.268088 -250.528322) (xy 105.30957 -250.536655)
			(xy 105.348601 -250.55299) (xy 105.383654 -250.576687) (xy 105.413357 -250.606819) (xy 105.436549 -250.642208)
			(xy 105.452322 -250.681469) (xy 105.46006 -250.723067) (xy 105.460292 -250.744228) (xy 105.460292 -250.747022)
			(xy 105.460292 -250.747784) (xy 105.460292 -250.764548) (xy 105.462324 -250.778518) (xy 105.464102 -250.784868)
			(xy 105.46842 -250.791726) (xy 105.468674 -250.79198) (xy 105.480663 -250.811325) (xy 105.499582 -250.852717)
			(xy 105.5124 -250.896385) (xy 105.518855 -250.941436) (xy 105.51922 -250.964192) (xy 105.51922 -250.9647)
			(xy 105.519106 -250.974443) (xy 105.517832 -250.993887) (xy 105.51668 -251.003562) (xy 105.516426 -251.004578)
			(xy 105.515918 -251.007118) (xy 105.515918 -251.008642) (xy 105.51287 -251.026422) (xy 105.512108 -251.030486)
			(xy 105.511512 -251.038694) (xy 105.51501 -251.054765) (xy 105.518966 -251.061982) (xy 105.518966 -251.062236)
			(xy 105.519982 -251.06376) (xy 105.521252 -251.065792) (xy 105.523538 -251.06884) (xy 105.572306 -251.128022)
			(xy 105.579872 -251.136359) (xy 105.60018 -251.146008) (xy 105.611422 -251.146564) (xy 106.454956 -251.146564)
			(xy 106.463815 -251.146227) (xy 106.480457 -251.140145) (xy 106.493989 -251.128708) (xy 106.498644 -251.121164)
			(xy 106.498644 -250.637548) (xy 106.499056 -250.627524) (xy 106.506719 -250.608998) (xy 106.520894 -250.594821)
			(xy 106.53942 -250.587157) (xy 106.549444 -250.586748) (xy 106.7308 -250.586748) (xy 106.740852 -250.583959)
			(xy 106.757656 -250.571635) (xy 106.763312 -250.562872) (xy 106.763312 -250.556522) (xy 106.79303 -250.526804)
			(xy 107.018328 -250.526804) (xy 107.027385 -250.526835) (xy 107.045443 -250.528232) (xy 107.054396 -250.529598)
			(xy 107.05592 -250.530106) (xy 107.056428 -250.530106) (xy 107.057698 -250.53036) (xy 107.060746 -250.530868)
			(xy 107.083455 -250.53549) (xy 107.126299 -250.553124) (xy 107.164352 -250.579555) (xy 107.195834 -250.613548)
			(xy 107.208066 -250.63323) (xy 107.211368 -250.638818) (xy 107.21467 -250.64466) (xy 107.217972 -250.65101)
			(xy 107.221528 -250.65863) (xy 107.225338 -250.66752) (xy 107.245658 -250.692158) (xy 107.252516 -250.696476)
			(xy 107.274592 -250.711258) (xy 107.313937 -250.746953) (xy 107.346809 -250.788686) (xy 107.372294 -250.835298)
			(xy 107.389686 -250.885495) (xy 107.3985 -250.937884) (xy 107.399074 -250.964446) (xy 107.398885 -250.979656)
			(xy 107.395962 -251.009934) (xy 107.393232 -251.024898) (xy 107.392978 -251.026422) (xy 107.39247 -251.030486)
			(xy 107.391912 -251.040579) (xy 107.397657 -251.059936) (xy 107.403646 -251.068078) (xy 107.429808 -251.100336)
			(xy 107.429808 -251.100844) (xy 107.452668 -251.128276) (xy 107.460224 -251.136487) (xy 107.480388 -251.145979)
			(xy 107.49153 -251.146564) (xy 108.46689 -251.146564) (xy 108.476638 -251.146044) (xy 108.494663 -251.138592)
			(xy 108.501942 -251.132086) (xy 108.599986 -251.034042) (xy 108.606538 -251.026793) (xy 108.613988 -251.00875)
			(xy 108.614464 -250.99899) (xy 108.614464 -250.786138) (xy 108.614998 -250.776299) (xy 108.622579 -250.758133)
			(xy 108.629196 -250.750832) (xy 108.726732 -250.653296) (xy 108.733971 -250.646585) (xy 108.752176 -250.638997)
			(xy 108.762038 -250.638564) (xy 109.079284 -250.638564) (xy 109.085437 -250.638393) (xy 109.097381 -250.635436)
			(xy 109.102906 -250.632722) (xy 109.111542 -250.627388) (xy 109.11967 -250.619514) (xy 109.123226 -250.613672)
			(xy 109.125258 -250.610624) (xy 109.125512 -250.610116) (xy 109.125766 -250.609862) (xy 109.127036 -250.608084)
			(xy 109.127544 -250.607322) (xy 109.151928 -250.569984) (xy 109.151928 -250.569476) (xy 109.163866 -250.550934)
			(xy 109.167126 -250.545025) (xy 109.170727 -250.532024) (xy 109.170978 -250.52528) (xy 109.170978 -250.497848)
			(xy 109.167422 -250.488704) (xy 109.166152 -250.485402) (xy 109.163104 -250.47702) (xy 109.16285 -250.476512)
			(xy 109.16158 -250.472956) (xy 109.15777 -250.458986) (xy 109.157516 -250.45797) (xy 109.157516 -250.457462)
			(xy 109.157008 -250.454922) (xy 109.155992 -250.449842) (xy 109.154468 -250.44146) (xy 109.154214 -250.439936)
			(xy 109.154214 -250.439682) (xy 109.152436 -250.425712) (xy 109.152182 -250.424442) (xy 109.151928 -250.408694)
			(xy 109.151928 -250.31319) (xy 109.149388 -250.302522) (xy 109.146594 -250.29668) (xy 109.14634 -250.296172)
			(xy 109.145832 -250.29541) (xy 109.135463 -250.27342) (xy 109.120839 -250.227056) (xy 109.113464 -250.179002)
			(xy 109.113066 -250.154694) (xy 109.113066 -250.15063) (xy 109.113819 -250.126024) (xy 109.121979 -250.077479)
			(xy 109.137521 -250.03077) (xy 109.160075 -249.987014) (xy 109.1891 -249.947256) (xy 109.223905 -249.912444)
			(xy 109.263657 -249.88341) (xy 109.307409 -249.860847) (xy 109.354114 -249.845295) (xy 109.402657 -249.837124)
			(xy 109.427264 -249.836432) (xy 109.431328 -249.836432) (xy 109.459252 -249.837041) (xy 109.514235 -249.846835)
			(xy 109.566669 -249.866064) (xy 109.591094 -249.879612) (xy 109.592364 -249.880374) (xy 109.59338 -249.880882)
			(xy 109.596428 -249.88266) (xy 109.612938 -249.89282) (xy 109.620304 -249.89282) (xy 109.620304 -249.897392)
			(xy 109.63783 -249.912632) (xy 109.638846 -249.913648) (xy 109.64037 -249.914918) (xy 109.642402 -249.916696)
			(xy 109.64291 -249.917204) (xy 109.653324 -249.926856) (xy 109.654086 -249.927618) (xy 109.65688 -249.930412)
			(xy 109.663992 -249.937524) (xy 109.690154 -249.9487) (xy 109.694893 -249.950574) (xy 109.704872 -249.952629)
			(xy 109.709966 -249.952764) (xy 109.855254 -249.952764) (xy 109.884972 -249.982482) (xy 109.884972 -249.998992)
			(xy 109.885226 -250.000262) (xy 109.885226 -250.588526) (xy 109.885711 -250.598383) (xy 109.893259 -250.616594)
			(xy 109.907197 -250.630536) (xy 109.925407 -250.638087) (xy 109.935264 -250.638564) (xy 112.891316 -250.638564)
			(xy 112.903329 -250.637478) (xy 112.924407 -250.625817) (xy 112.931702 -250.616212) (xy 112.940338 -250.602242)
			(xy 112.943386 -250.59767) (xy 112.948046 -250.589049) (xy 112.951061 -250.569704) (xy 112.949228 -250.560078)
			(xy 112.945164 -250.544838) (xy 112.940338 -250.535694) (xy 112.936782 -250.528836) (xy 112.927766 -250.509974)
			(xy 112.91505 -250.470151) (xy 112.908674 -250.428835) (xy 112.908334 -250.407932) (xy 112.908334 -250.330716)
			(xy 112.907064 -250.320302) (xy 112.902746 -250.302014) (xy 112.900206 -250.29668) (xy 112.899698 -250.295664)
			(xy 112.898428 -250.293124) (xy 112.888459 -250.271465) (xy 112.874348 -250.225923) (xy 112.867179 -250.178786)
			(xy 112.866678 -250.154948) (xy 112.866678 -250.146058) (xy 112.867761 -250.121917) (xy 112.876319 -250.074358)
			(xy 112.891971 -250.028641) (xy 112.914357 -249.985817) (xy 112.942962 -249.946871) (xy 112.977128 -249.912698)
			(xy 113.01607 -249.884087) (xy 113.05889 -249.861693) (xy 113.104605 -249.846033) (xy 113.152162 -249.837467)
			(xy 113.176304 -249.836432) (xy 113.193068 -249.836432) (xy 113.203319 -249.836487) (xy 113.223783 -249.837756)
			(xy 113.233962 -249.838972) (xy 113.237264 -249.83948) (xy 113.43386 -249.83948) (xy 113.44351 -249.839913)
			(xy 113.461407 -249.847137) (xy 113.475287 -249.860546) (xy 113.47958 -249.869198) (xy 113.481866 -249.873516)
			(xy 113.484984 -249.878803) (xy 113.493332 -249.887798) (xy 113.498376 -249.891296) (xy 113.504472 -249.89536)
			(xy 113.511584 -249.897392) (xy 113.515063 -249.89834) (xy 113.522202 -249.899358) (xy 113.525808 -249.899424)
			(xy 113.698528 -249.899424) (xy 113.708385 -249.899909) (xy 113.726596 -249.907457) (xy 113.740537 -249.921396)
			(xy 113.748089 -249.939605) (xy 113.748566 -249.949462) (xy 113.748566 -250.179429) (xy 114.747276 -250.179429)
			(xy 114.747276 -250.129451) (xy 114.755095 -250.080088) (xy 114.770539 -250.032556) (xy 114.793229 -249.988024)
			(xy 114.822605 -249.947591) (xy 114.857945 -249.912251) (xy 114.898378 -249.882875) (xy 114.94291 -249.860185)
			(xy 114.990442 -249.844741) (xy 115.039805 -249.836922) (xy 115.089783 -249.836922) (xy 115.139146 -249.844741)
			(xy 115.186678 -249.860185) (xy 115.23121 -249.882875) (xy 115.271643 -249.912251) (xy 115.306983 -249.947591)
			(xy 115.336359 -249.988024) (xy 115.359049 -250.032556) (xy 115.374493 -250.080088) (xy 115.382312 -250.129451)
			(xy 115.382802 -250.15444) (xy 115.382312 -250.179429) (xy 115.374493 -250.228792) (xy 115.359049 -250.276324)
			(xy 115.336359 -250.320856) (xy 115.306983 -250.361289) (xy 115.271643 -250.396629) (xy 115.23121 -250.426005)
			(xy 115.186678 -250.448695) (xy 115.139146 -250.464139) (xy 115.089783 -250.471958) (xy 115.039805 -250.471958)
			(xy 114.990442 -250.464139) (xy 114.94291 -250.448695) (xy 114.898378 -250.426005) (xy 114.857945 -250.396629)
			(xy 114.822605 -250.361289) (xy 114.793229 -250.320856) (xy 114.770539 -250.276324) (xy 114.755095 -250.228792)
			(xy 114.747276 -250.179429) (xy 113.748566 -250.179429) (xy 113.748566 -250.587764) (xy 113.748979 -250.597793)
			(xy 113.756641 -250.616328) (xy 113.770813 -250.63052) (xy 113.789338 -250.638208) (xy 113.799366 -250.638564)
			(xy 115.245388 -250.638564) (xy 115.253516 -250.637802) (xy 115.254024 -250.637802) (xy 115.261543 -250.636202)
			(xy 115.275233 -250.629228) (xy 115.280948 -250.624086) (xy 115.287552 -250.617482) (xy 115.299735 -250.601209)
			(xy 115.32915 -250.57316) (xy 115.363336 -250.551176) (xy 115.401062 -250.536051) (xy 115.440966 -250.528328)
			(xy 115.461288 -250.52782) (xy 115.687094 -250.52782) (xy 115.71605 -250.556776) (xy 115.716558 -250.557284)
			(xy 115.744752 -250.585986) (xy 115.75796 -250.587764) (xy 115.951254 -250.587764) (xy 115.980972 -250.617482)
			(xy 115.980972 -250.633992) (xy 115.981226 -250.635262) (xy 115.981226 -250.999244) (xy 115.981988 -251.007372)
			(xy 115.981988 -251.00788) (xy 115.983582 -251.015402) (xy 115.990547 -251.029102) (xy 115.995704 -251.034804)
			(xy 116.092986 -251.132086) (xy 116.098662 -251.137284) (xy 116.112367 -251.144274) (xy 116.11991 -251.145802)
			(xy 116.120418 -251.145802) (xy 116.128546 -251.146564) (xy 116.72189 -251.146564) (xy 116.731638 -251.146044)
			(xy 116.749663 -251.138592) (xy 116.756942 -251.132086) (xy 116.854986 -251.034042) (xy 116.861538 -251.026793)
			(xy 116.868988 -251.00875) (xy 116.869464 -250.99899) (xy 116.869464 -250.659138) (xy 116.869998 -250.649299)
			(xy 116.877579 -250.631133) (xy 116.884196 -250.623832) (xy 116.885466 -250.622562) (xy 116.893396 -250.613653)
			(xy 116.900786 -250.591007) (xy 116.89969 -250.579128) (xy 116.890038 -250.53925) (xy 116.887498 -250.528836)
			(xy 116.884958 -250.518168) (xy 116.878862 -250.493022) (xy 116.877188 -250.486769) (xy 116.871142 -250.475327)
			(xy 116.866924 -250.470416) (xy 116.866924 -250.470162) (xy 116.862459 -250.465672) (xy 116.851798 -250.458849)
			(xy 116.845842 -250.4567) (xy 116.845334 -250.456446) (xy 116.84508 -250.456446) (xy 116.821582 -250.448187)
			(xy 116.777294 -250.425405) (xy 116.737098 -250.395999) (xy 116.701976 -250.360686) (xy 116.672789 -250.320331)
			(xy 116.650248 -250.275919) (xy 116.634906 -250.228537) (xy 116.627136 -250.179342) (xy 116.62664 -250.15444)
			(xy 116.627102 -250.129448) (xy 116.634916 -250.080079) (xy 116.650359 -250.032541) (xy 116.673049 -249.988004)
			(xy 116.702428 -249.947566) (xy 116.737772 -249.912223) (xy 116.778211 -249.882845) (xy 116.822748 -249.860156)
			(xy 116.870287 -249.844714) (xy 116.919656 -249.836901) (xy 116.944648 -249.836432) (xy 116.969332 -249.836902)
			(xy 117.018107 -249.844537) (xy 117.065116 -249.859616) (xy 117.10923 -249.881778) (xy 117.149391 -249.91049)
			(xy 117.184633 -249.945062) (xy 117.214111 -249.984664) (xy 117.237115 -250.028345) (xy 117.253095 -250.075055)
			(xy 117.261665 -250.123674) (xy 117.262656 -250.148344) (xy 117.262656 -250.157742) (xy 117.261885 -250.183595)
			(xy 117.252992 -250.234543) (xy 117.235969 -250.283379) (xy 117.224048 -250.306332) (xy 117.223032 -250.307856)
			(xy 117.222778 -250.308618) (xy 117.222778 -250.308872) (xy 117.221 -250.312174) (xy 117.220746 -250.312428)
			(xy 117.220492 -250.312936) (xy 117.219984 -250.313698) (xy 117.219222 -250.314968) (xy 117.214904 -250.32335)
			(xy 117.21084 -250.330462) (xy 117.206522 -250.336304) (xy 117.20449 -250.338844) (xy 117.197886 -250.346718)
			(xy 117.19687 -250.348242) (xy 117.1956 -250.35002) (xy 117.188742 -250.37034) (xy 117.185948 -250.378214)
			(xy 117.185186 -250.380754) (xy 117.185311 -250.385566) (xy 117.187105 -250.395023) (xy 117.188742 -250.39955)
			(xy 117.226334 -250.47702) (xy 117.22735 -250.479052) (xy 117.22735 -250.479306) (xy 117.230906 -250.487434)
			(xy 117.235478 -250.492768) (xy 117.241574 -250.499118) (xy 117.250718 -250.505468) (xy 117.254786 -250.507546)
			(xy 117.263475 -250.510362) (xy 117.26799 -250.511056) (xy 117.268498 -250.511056) (xy 117.275102 -250.511564)
			(xy 118.494556 -250.511564) (xy 118.50384 -250.511169) (xy 118.521181 -250.504535) (xy 118.528338 -250.49861)
			(xy 118.531665 -250.495578) (xy 118.53729 -250.488553) (xy 118.539514 -250.48464) (xy 118.557294 -250.447556)
			(xy 118.578884 -250.403106) (xy 118.58289 -250.392622) (xy 118.582359 -250.370212) (xy 118.577868 -250.359926)
			(xy 118.573296 -250.350782) (xy 118.569232 -250.343924) (xy 118.56212 -250.334018) (xy 118.56085 -250.33224)
			(xy 118.560342 -250.331224) (xy 118.559834 -250.330462) (xy 118.55958 -250.330208) (xy 118.54408 -250.305618)
			(xy 118.521346 -250.252128) (xy 118.508718 -250.195395) (xy 118.507002 -250.166378) (xy 118.507002 -250.165616)
			(xy 118.506748 -250.163076) (xy 118.506748 -250.160028) (xy 118.506494 -250.152916) (xy 118.506494 -250.14682)
			(xy 118.507256 -250.134628) (xy 118.50751 -250.132596) (xy 118.509863 -250.106139) (xy 118.522256 -250.054492)
			(xy 118.543057 -250.005621) (xy 118.571687 -249.960885) (xy 118.60735 -249.921527) (xy 118.649057 -249.888639)
			(xy 118.695647 -249.863137) (xy 118.745826 -249.845729) (xy 118.7982 -249.836899) (xy 118.824756 -249.836432)
			(xy 118.84944 -249.836902) (xy 118.898213 -249.844538) (xy 118.945221 -249.859618) (xy 118.989335 -249.881781)
			(xy 119.029494 -249.910492) (xy 119.064736 -249.945064) (xy 119.094212 -249.984666) (xy 119.117216 -250.028347)
			(xy 119.133195 -250.075057) (xy 119.141765 -250.123675) (xy 119.142764 -250.148344) (xy 119.142764 -250.157742)
			(xy 119.142117 -250.179429) (xy 120.387092 -250.179429) (xy 120.387092 -250.129451) (xy 120.394911 -250.080088)
			(xy 120.410355 -250.032556) (xy 120.433045 -249.988024) (xy 120.462421 -249.947591) (xy 120.497761 -249.912251)
			(xy 120.538194 -249.882875) (xy 120.582726 -249.860185) (xy 120.630258 -249.844741) (xy 120.679621 -249.836922)
			(xy 120.729599 -249.836922) (xy 120.778962 -249.844741) (xy 120.826494 -249.860185) (xy 120.871026 -249.882875)
			(xy 120.911459 -249.912251) (xy 120.946799 -249.947591) (xy 120.976175 -249.988024) (xy 120.998865 -250.032556)
			(xy 121.014309 -250.080088) (xy 121.022128 -250.129451) (xy 121.022618 -250.15444) (xy 121.022128 -250.179429)
			(xy 121.014309 -250.228792) (xy 120.998865 -250.276324) (xy 120.976175 -250.320856) (xy 120.946799 -250.361289)
			(xy 120.911459 -250.396629) (xy 120.871026 -250.426005) (xy 120.826494 -250.448695) (xy 120.778962 -250.464139)
			(xy 120.729599 -250.471958) (xy 120.679621 -250.471958) (xy 120.630258 -250.464139) (xy 120.582726 -250.448695)
			(xy 120.538194 -250.426005) (xy 120.497761 -250.396629) (xy 120.462421 -250.361289) (xy 120.433045 -250.320856)
			(xy 120.410355 -250.276324) (xy 120.394911 -250.228792) (xy 120.387092 -250.179429) (xy 119.142117 -250.179429)
			(xy 119.141993 -250.183595) (xy 119.133101 -250.234543) (xy 119.116078 -250.28338) (xy 119.104156 -250.306332)
			(xy 119.10314 -250.307856) (xy 119.102886 -250.308618) (xy 119.102886 -250.308872) (xy 119.101108 -250.312174)
			(xy 119.100854 -250.312428) (xy 119.1006 -250.312936) (xy 119.100092 -250.313698) (xy 119.09933 -250.314968)
			(xy 119.095012 -250.32335) (xy 119.090948 -250.330462) (xy 119.08663 -250.336304) (xy 119.084598 -250.338844)
			(xy 119.077994 -250.346718) (xy 119.076978 -250.348242) (xy 119.075708 -250.35002) (xy 119.06885 -250.37034)
			(xy 119.066056 -250.378214) (xy 119.065294 -250.380754) (xy 119.065419 -250.385566) (xy 119.067214 -250.395023)
			(xy 119.06885 -250.39955) (xy 119.106442 -250.47702) (xy 119.107458 -250.479052) (xy 119.107458 -250.479306)
			(xy 119.111014 -250.487434) (xy 119.115586 -250.492768) (xy 119.121682 -250.499118) (xy 119.130826 -250.505468)
			(xy 119.134894 -250.507546) (xy 119.143584 -250.51036) (xy 119.148098 -250.511056) (xy 119.148606 -250.511056)
			(xy 119.15521 -250.511564) (xy 119.64289 -250.511564) (xy 119.652727 -250.512103) (xy 119.670886 -250.519691)
			(xy 119.678196 -250.526296) (xy 119.725186 -250.573286) (xy 119.730862 -250.578484) (xy 119.744567 -250.585474)
			(xy 119.75211 -250.587002) (xy 119.752618 -250.587002) (xy 119.760746 -250.587764) (xy 119.761254 -250.587764)
			(xy 119.790972 -250.617482) (xy 119.790972 -250.634246) (xy 119.791226 -250.635516) (xy 119.791226 -251.126244)
			(xy 119.791988 -251.134372) (xy 119.791988 -251.13488) (xy 119.793582 -251.142402) (xy 119.800547 -251.156102)
			(xy 119.805704 -251.161804) (xy 119.902986 -251.259086) (xy 119.908662 -251.264284) (xy 119.922367 -251.271274)
			(xy 119.92991 -251.272802) (xy 119.930418 -251.272802) (xy 119.938546 -251.273564)
		)
		(stroke
			(width 0)
			(type solid)
		)
		(fill yes)
		(layer "B.Cu")
		(net "PVDDCR_CPU0_P1")
	)
	(gr_poly
		(pts
			(xy 138.466576 -266.21994) (xy 138.48031 -266.219454) (xy 138.506768 -266.212067) (xy 138.530304 -266.197901)
			(xy 138.549217 -266.177978) (xy 138.562142 -266.153739) (xy 138.568145 -266.126933) (xy 138.566793 -266.099496)
			(xy 138.562842 -266.086336) (xy 138.555292 -266.062007) (xy 138.54713 -266.011728) (xy 138.546586 -265.98626)
			(xy 138.547077 -265.961251) (xy 138.554901 -265.911848) (xy 138.570358 -265.864278) (xy 138.593066 -265.819711)
			(xy 138.622466 -265.779246) (xy 138.657834 -265.743878) (xy 138.698299 -265.714478) (xy 138.742866 -265.69177)
			(xy 138.790436 -265.676313) (xy 138.839839 -265.668489) (xy 138.889857 -265.668489) (xy 138.93926 -265.676313)
			(xy 138.98683 -265.69177) (xy 139.031397 -265.714478) (xy 139.071862 -265.743878) (xy 139.10723 -265.779246)
			(xy 139.13663 -265.819711) (xy 139.159338 -265.864278) (xy 139.174795 -265.911848) (xy 139.182619 -265.961251)
			(xy 139.18311 -265.98626) (xy 139.182591 -266.01173) (xy 139.174424 -266.062012) (xy 139.166854 -266.086336)
			(xy 139.162946 -266.09952) (xy 139.161546 -266.126971) (xy 139.167519 -266.153801) (xy 139.180431 -266.178067)
			(xy 139.199348 -266.198008) (xy 139.222899 -266.212182) (xy 139.249377 -266.219561) (xy 139.26312 -266.21994)
			(xy 139.406376 -266.21994) (xy 139.42011 -266.219454) (xy 139.446568 -266.212067) (xy 139.470104 -266.197901)
			(xy 139.489017 -266.177978) (xy 139.501942 -266.153739) (xy 139.507945 -266.126933) (xy 139.506593 -266.099496)
			(xy 139.502642 -266.086336) (xy 139.495092 -266.062007) (xy 139.48693 -266.011728) (xy 139.486386 -265.98626)
			(xy 139.486877 -265.961251) (xy 139.494701 -265.911848) (xy 139.510158 -265.864278) (xy 139.532866 -265.819711)
			(xy 139.562266 -265.779246) (xy 139.597634 -265.743878) (xy 139.638099 -265.714478) (xy 139.682666 -265.69177)
			(xy 139.730236 -265.676313) (xy 139.779639 -265.668489) (xy 139.829657 -265.668489) (xy 139.87906 -265.676313)
			(xy 139.92663 -265.69177) (xy 139.971197 -265.714478) (xy 140.011662 -265.743878) (xy 140.04703 -265.779246)
			(xy 140.07643 -265.819711) (xy 140.099138 -265.864278) (xy 140.114595 -265.911848) (xy 140.122419 -265.961251)
			(xy 140.12291 -265.98626) (xy 140.122391 -266.01173) (xy 140.114224 -266.062012) (xy 140.106654 -266.086336)
			(xy 140.102746 -266.09952) (xy 140.101346 -266.126971) (xy 140.107319 -266.153801) (xy 140.120231 -266.178067)
			(xy 140.139148 -266.198008) (xy 140.162699 -266.212182) (xy 140.189177 -266.219561) (xy 140.20292 -266.21994)
			(xy 140.34643 -266.21994) (xy 140.360159 -266.219448) (xy 140.386604 -266.212052) (xy 140.410126 -266.197883)
			(xy 140.429028 -266.177963) (xy 140.441945 -266.153731) (xy 140.447945 -266.126934) (xy 140.446595 -266.099508)
			(xy 140.442696 -266.086336) (xy 140.435147 -266.062007) (xy 140.426986 -266.011728) (xy 140.42644 -265.98626)
			(xy 140.426931 -265.961251) (xy 140.434755 -265.911848) (xy 140.450212 -265.864278) (xy 140.47292 -265.819711)
			(xy 140.50232 -265.779246) (xy 140.537688 -265.743878) (xy 140.578153 -265.714478) (xy 140.62272 -265.69177)
			(xy 140.67029 -265.676313) (xy 140.719693 -265.668489) (xy 140.769711 -265.668489) (xy 140.819114 -265.676313)
			(xy 140.866684 -265.69177) (xy 140.911251 -265.714478) (xy 140.951716 -265.743878) (xy 140.987084 -265.779246)
			(xy 141.016484 -265.819711) (xy 141.039192 -265.864278) (xy 141.054649 -265.911848) (xy 141.062473 -265.961251)
			(xy 141.062964 -265.98626) (xy 141.062444 -266.01173) (xy 141.054277 -266.062011) (xy 141.046708 -266.086336)
			(xy 141.042799 -266.099518) (xy 141.041397 -266.126965) (xy 141.04737 -266.153791) (xy 141.060284 -266.178051)
			(xy 141.079203 -266.197986) (xy 141.102755 -266.21215) (xy 141.129233 -266.219516) (xy 141.142974 -266.21994)
			(xy 141.286484 -266.21994) (xy 141.300217 -266.219453) (xy 141.326673 -266.212065) (xy 141.350207 -266.197898)
			(xy 141.369119 -266.177976) (xy 141.382042 -266.153738) (xy 141.388045 -266.126933) (xy 141.386693 -266.099498)
			(xy 141.38275 -266.086336) (xy 141.3752 -266.062007) (xy 141.367038 -266.011728) (xy 141.366494 -265.98626)
			(xy 141.366985 -265.961251) (xy 141.374809 -265.911848) (xy 141.390266 -265.864278) (xy 141.412974 -265.819711)
			(xy 141.442374 -265.779246) (xy 141.477742 -265.743878) (xy 141.518207 -265.714478) (xy 141.562774 -265.69177)
			(xy 141.610344 -265.676313) (xy 141.659747 -265.668489) (xy 141.709765 -265.668489) (xy 141.759168 -265.676313)
			(xy 141.806738 -265.69177) (xy 141.851305 -265.714478) (xy 141.89177 -265.743878) (xy 141.927138 -265.779246)
			(xy 141.956538 -265.819711) (xy 141.979246 -265.864278) (xy 141.994703 -265.911848) (xy 142.002527 -265.961251)
			(xy 142.003018 -265.98626) (xy 142.002499 -266.01173) (xy 141.994333 -266.062012) (xy 141.986762 -266.086336)
			(xy 141.982855 -266.09952) (xy 141.981454 -266.12697) (xy 141.987427 -266.1538) (xy 142.000339 -266.178064)
			(xy 142.019257 -266.198005) (xy 142.042808 -266.212177) (xy 142.069286 -266.219554) (xy 142.083028 -266.21994)
			(xy 142.226538 -266.21994) (xy 142.240266 -266.219447) (xy 142.266709 -266.21205) (xy 142.29023 -266.19788)
			(xy 142.30913 -266.177961) (xy 142.322046 -266.15373) (xy 142.328045 -266.126935) (xy 142.326696 -266.099509)
			(xy 142.322804 -266.086336) (xy 142.315254 -266.062007) (xy 142.307094 -266.011728) (xy 142.306548 -265.98626)
			(xy 142.307039 -265.961251) (xy 142.314863 -265.911848) (xy 142.33032 -265.864278) (xy 142.353028 -265.819711)
			(xy 142.382428 -265.779246) (xy 142.417796 -265.743878) (xy 142.458261 -265.714478) (xy 142.502828 -265.69177)
			(xy 142.550398 -265.676313) (xy 142.599801 -265.668489) (xy 142.649819 -265.668489) (xy 142.699222 -265.676313)
			(xy 142.746792 -265.69177) (xy 142.791359 -265.714478) (xy 142.831824 -265.743878) (xy 142.867192 -265.779246)
			(xy 142.896592 -265.819711) (xy 142.9193 -265.864278) (xy 142.934757 -265.911848) (xy 142.942581 -265.961251)
			(xy 142.943072 -265.98626) (xy 142.942552 -266.01173) (xy 142.934385 -266.062011) (xy 142.926816 -266.086336)
			(xy 142.922907 -266.099517) (xy 142.921505 -266.126964) (xy 142.927478 -266.15379) (xy 142.940392 -266.178049)
			(xy 142.959311 -266.197983) (xy 142.982864 -266.212145) (xy 143.009341 -266.21951) (xy 143.023082 -266.21994)
			(xy 144.685258 -266.21994) (xy 144.695164 -266.218924) (xy 144.702325 -266.217223) (xy 144.715357 -266.210396)
			(xy 144.720818 -266.205462) (xy 144.956022 -265.970258) (xy 144.961006 -265.964757) (xy 144.967843 -265.95159)
			(xy 144.969484 -265.94435) (xy 144.9705 -265.934698) (xy 144.9705 -256.926842) (xy 144.969935 -256.915174)
			(xy 144.959611 -256.894248) (xy 144.950688 -256.88671) (xy 144.931724 -256.871544) (xy 144.898183 -256.836435)
			(xy 144.870365 -256.796638) (xy 144.848916 -256.753077) (xy 144.834335 -256.706763) (xy 144.826959 -256.65877)
			(xy 144.82696 -256.610215) (xy 144.834338 -256.562223) (xy 144.848922 -256.515909) (xy 144.870372 -256.472349)
			(xy 144.898192 -256.432553) (xy 144.931735 -256.397446) (xy 144.950688 -256.382266) (xy 144.959556 -256.374683)
			(xy 144.969878 -256.353785) (xy 144.9705 -256.342134) (xy 144.9705 -255.30683) (xy 144.969932 -255.295163)
			(xy 144.959606 -255.274242) (xy 144.950688 -255.266698) (xy 144.931725 -255.251532) (xy 144.898186 -255.216424)
			(xy 144.870369 -255.176627) (xy 144.848922 -255.133067) (xy 144.834342 -255.086753) (xy 144.826968 -255.038762)
			(xy 144.82697 -254.990208) (xy 144.834349 -254.942218) (xy 144.848933 -254.895906) (xy 144.870384 -254.852347)
			(xy 144.898204 -254.812554) (xy 144.931747 -254.777448) (xy 144.950688 -254.762254) (xy 144.959553 -254.75467)
			(xy 144.969871 -254.733772) (xy 144.9705 -254.722122) (xy 144.9705 -253.686818) (xy 144.96993 -253.675152)
			(xy 144.9596 -253.654235) (xy 144.950688 -253.646686) (xy 144.931726 -253.63152) (xy 144.898188 -253.596412)
			(xy 144.870374 -253.556616) (xy 144.848928 -253.513056) (xy 144.83435 -253.466744) (xy 144.826977 -253.418754)
			(xy 144.82698 -253.370202) (xy 144.83436 -253.322213) (xy 144.848945 -253.275903) (xy 144.870396 -253.232346)
			(xy 144.898216 -253.192554) (xy 144.931759 -253.15745) (xy 144.950688 -253.142242) (xy 144.959551 -253.134657)
			(xy 144.969864 -253.113759) (xy 144.9705 -253.10211) (xy 144.9705 -252.066806) (xy 144.969927 -252.055142)
			(xy 144.959595 -252.034228) (xy 144.950688 -252.026674) (xy 144.931727 -252.011508) (xy 144.898191 -251.9764)
			(xy 144.870378 -251.936605) (xy 144.848934 -251.893046) (xy 144.834357 -251.846735) (xy 144.826985 -251.798746)
			(xy 144.82699 -251.750195) (xy 144.834371 -251.702208) (xy 144.848956 -251.6559) (xy 144.870408 -251.612345)
			(xy 144.898228 -251.572554) (xy 144.931771 -251.537453) (xy 144.950688 -251.52223) (xy 144.95955 -251.514645)
			(xy 144.969858 -251.493746) (xy 144.9705 -251.482098) (xy 144.9705 -251.336556) (xy 144.969933 -251.32166)
			(xy 144.961249 -251.293159) (xy 144.94472 -251.26837) (xy 144.921746 -251.249396) (xy 144.89428 -251.23785)
			(xy 144.864651 -251.234709) (xy 144.835374 -251.240241) (xy 144.82191 -251.24664) (xy 144.799066 -251.25797)
			(xy 144.750671 -251.274022) (xy 144.700338 -251.282172) (xy 144.674844 -251.282708) (xy 144.649827 -251.282246)
			(xy 144.600408 -251.274426) (xy 144.552821 -251.258969) (xy 144.508238 -251.236259) (xy 144.467758 -251.206853)
			(xy 144.432376 -251.171476) (xy 144.402964 -251.130999) (xy 144.380247 -251.08642) (xy 144.364785 -251.038835)
			(xy 144.356957 -250.989417) (xy 144.356957 -250.939383) (xy 144.364785 -250.889965) (xy 144.380247 -250.84238)
			(xy 144.402964 -250.797801) (xy 144.432376 -250.757324) (xy 144.467758 -250.721947) (xy 144.508238 -250.692541)
			(xy 144.552821 -250.669831) (xy 144.600408 -250.654374) (xy 144.649827 -250.646554) (xy 144.674844 -250.646184)
			(xy 144.70034 -250.646687) (xy 144.750679 -250.654828) (xy 144.79907 -250.670909) (xy 144.82191 -250.682252)
			(xy 144.835366 -250.688687) (xy 144.864655 -250.69426) (xy 144.894305 -250.691139) (xy 144.921791 -250.679589)
			(xy 144.944771 -250.660595) (xy 144.961288 -250.635775) (xy 144.969935 -250.607242) (xy 144.9705 -250.592336)
			(xy 144.9705 -250.446794) (xy 144.969924 -250.435131) (xy 144.95959 -250.414222) (xy 144.950688 -250.406662)
			(xy 144.93172 -250.391496) (xy 144.898171 -250.356386) (xy 144.870345 -250.316587) (xy 144.848889 -250.273022)
			(xy 144.834301 -250.226703) (xy 144.82692 -250.178705) (xy 144.826916 -250.130143) (xy 144.83429 -250.082145)
			(xy 144.848871 -250.035823) (xy 144.87032 -249.992255) (xy 144.89814 -249.952451) (xy 144.931684 -249.917336)
			(xy 144.950688 -249.902218) (xy 144.959548 -249.894632) (xy 144.969851 -249.873733) (xy 144.9705 -249.862086)
			(xy 144.9705 -248.826782) (xy 144.969922 -248.81512) (xy 144.959584 -248.794215) (xy 144.950688 -248.78665)
			(xy 144.931721 -248.771484) (xy 144.898174 -248.736374) (xy 144.87035 -248.696576) (xy 144.848896 -248.653011)
			(xy 144.834309 -248.606694) (xy 144.826929 -248.558697) (xy 144.826926 -248.510137) (xy 144.834301 -248.46214)
			(xy 144.848883 -248.41582) (xy 144.870333 -248.372254) (xy 144.898152 -248.332452) (xy 144.931696 -248.297339)
			(xy 144.950688 -248.282206) (xy 144.959545 -248.274619) (xy 144.969844 -248.25372) (xy 144.9705 -248.242074)
			(xy 144.9705 -247.20677) (xy 144.969919 -247.19511) (xy 144.959579 -247.174209) (xy 144.950688 -247.166638)
			(xy 144.931722 -247.151472) (xy 144.898177 -247.116363) (xy 144.870355 -247.076564) (xy 144.848902 -247.033001)
			(xy 144.834317 -246.986684) (xy 144.826938 -246.938689) (xy 144.826936 -246.89013) (xy 144.834312 -246.842135)
			(xy 144.848895 -246.795817) (xy 144.870345 -246.752252) (xy 144.898164 -246.712452) (xy 144.931708 -246.677341)
			(xy 144.950688 -246.662194) (xy 144.959544 -246.654606) (xy 144.969837 -246.633707) (xy 144.9705 -246.622062)
			(xy 144.9705 -245.586758) (xy 144.969917 -245.575099) (xy 144.959573 -245.554202) (xy 144.950688 -245.546626)
			(xy 144.931723 -245.53146) (xy 144.898179 -245.496351) (xy 144.870359 -245.456553) (xy 144.848908 -245.412991)
			(xy 144.834324 -245.366675) (xy 144.826947 -245.318681) (xy 144.826946 -245.270124) (xy 144.834323 -245.22213)
			(xy 144.848906 -245.175814) (xy 144.870357 -245.132251) (xy 144.898176 -245.092453) (xy 144.931719 -245.057343)
			(xy 144.950688 -245.042182) (xy 144.959558 -245.0346) (xy 144.969887 -245.013702) (xy 144.9705 -245.00205)
			(xy 144.9705 -243.966746) (xy 144.969935 -243.955077) (xy 144.959613 -243.93415) (xy 144.950688 -243.926614)
			(xy 144.931724 -243.911448) (xy 144.898182 -243.876339) (xy 144.870363 -243.836542) (xy 144.848914 -243.79298)
			(xy 144.834332 -243.746666) (xy 144.826956 -243.698673) (xy 144.826956 -243.650117) (xy 144.834334 -243.602125)
			(xy 144.848918 -243.55581) (xy 144.870368 -243.512249) (xy 144.898188 -243.472453) (xy 144.931731 -243.437345)
			(xy 144.950688 -243.42217) (xy 144.959556 -243.414587) (xy 144.969881 -243.393689) (xy 144.9705 -243.382038)
			(xy 144.9705 -242.346734) (xy 144.969933 -242.335067) (xy 144.959608 -242.314144) (xy 144.950688 -242.306602)
			(xy 144.931725 -242.291436) (xy 144.898185 -242.256328) (xy 144.870368 -242.216531) (xy 144.84892 -242.17297)
			(xy 144.83434 -242.126656) (xy 144.826965 -242.078665) (xy 144.826967 -242.030111) (xy 144.834345 -241.98212)
			(xy 144.848929 -241.935807) (xy 144.87038 -241.892248) (xy 144.8982 -241.852453) (xy 144.931743 -241.817347)
			(xy 144.950688 -241.802158) (xy 144.959554 -241.794574) (xy 144.969873 -241.773676) (xy 144.9705 -241.762026)
			(xy 144.9705 -240.726722) (xy 144.96993 -240.715056) (xy 144.959602 -240.694137) (xy 144.950688 -240.68659)
			(xy 144.931726 -240.671424) (xy 144.898187 -240.636316) (xy 144.870372 -240.59652) (xy 144.848926 -240.55296)
			(xy 144.834347 -240.506647) (xy 144.826974 -240.458657) (xy 144.826977 -240.410104) (xy 144.834356 -240.362115)
			(xy 144.848941 -240.315804) (xy 144.870392 -240.272247) (xy 144.898212 -240.232454) (xy 144.931755 -240.19735)
			(xy 144.950688 -240.182146) (xy 144.959552 -240.174562) (xy 144.969867 -240.153663) (xy 144.9705 -240.142014)
			(xy 144.9705 -239.10671) (xy 144.969928 -239.095045) (xy 144.959597 -239.074131) (xy 144.950688 -239.066578)
			(xy 144.931727 -239.051412) (xy 144.89819 -239.016304) (xy 144.870377 -238.976509) (xy 144.848932 -238.932949)
			(xy 144.834355 -238.886638) (xy 144.826982 -238.838649) (xy 144.826987 -238.790097) (xy 144.834367 -238.74211)
			(xy 144.848952 -238.695801) (xy 144.870404 -238.652245) (xy 144.898224 -238.612454) (xy 144.931767 -238.577352)
			(xy 144.950688 -238.562134) (xy 144.95955 -238.554549) (xy 144.96986 -238.53365) (xy 144.9705 -238.522002)
			(xy 144.9705 -237.486698) (xy 144.969925 -237.475035) (xy 144.959591 -237.454124) (xy 144.950688 -237.446566)
			(xy 144.93172 -237.4314) (xy 144.89817 -237.39629) (xy 144.870344 -237.356491) (xy 144.848887 -237.312925)
			(xy 144.834299 -237.266606) (xy 144.826917 -237.218608) (xy 144.826912 -237.170046) (xy 144.834286 -237.122046)
			(xy 144.848867 -237.075724) (xy 144.870316 -237.032156) (xy 144.898136 -236.992351) (xy 144.93168 -236.957235)
			(xy 144.950688 -236.942122) (xy 144.959548 -236.934536) (xy 144.969853 -236.913637) (xy 144.9705 -236.90199)
			(xy 144.9705 -235.866686) (xy 144.969923 -235.855024) (xy 144.959586 -235.834117) (xy 144.950688 -235.826554)
			(xy 144.931721 -235.811388) (xy 144.898173 -235.776279) (xy 144.870348 -235.73648) (xy 144.848893 -235.692915)
			(xy 144.834306 -235.646597) (xy 144.826925 -235.5986) (xy 144.826922 -235.550039) (xy 144.834297 -235.502041)
			(xy 144.848879 -235.455721) (xy 144.870328 -235.412154) (xy 144.898148 -235.372352) (xy 144.931692 -235.337238)
			(xy 144.950688 -235.32211) (xy 144.959546 -235.314523) (xy 144.969846 -235.293624) (xy 144.9705 -235.281978)
			(xy 144.9705 -234.246674) (xy 144.96992 -234.235013) (xy 144.95958 -234.214111) (xy 144.950688 -234.206542)
			(xy 144.931722 -234.191376) (xy 144.898176 -234.156267) (xy 144.870353 -234.116468) (xy 144.8489 -234.072905)
			(xy 144.834314 -234.026587) (xy 144.826935 -233.978592) (xy 144.826933 -233.930032) (xy 144.834309 -233.882036)
			(xy 144.848891 -233.835718) (xy 144.870341 -233.792153) (xy 144.89816 -233.752352) (xy 144.931704 -233.71724)
			(xy 144.950688 -233.702098) (xy 144.959544 -233.69451) (xy 144.969839 -233.673611) (xy 144.9705 -233.661966)
			(xy 144.9705 -232.626662) (xy 144.969918 -232.615002) (xy 144.959575 -232.594104) (xy 144.950688 -232.58653)
			(xy 144.931723 -232.571364) (xy 144.898178 -232.536255) (xy 144.870358 -232.496457) (xy 144.848906 -232.452894)
			(xy 144.834322 -232.406578) (xy 144.826944 -232.358584) (xy 144.826943 -232.310026) (xy 144.83432 -232.262031)
			(xy 144.848902 -232.215715) (xy 144.870353 -232.172151) (xy 144.898172 -232.132353) (xy 144.931716 -232.097242)
			(xy 144.950688 -232.082086) (xy 144.959559 -232.074504) (xy 144.969889 -232.053606) (xy 144.9705 -232.041954)
			(xy 144.9705 -231.006904) (xy 144.969927 -230.99524) (xy 144.959594 -230.974327) (xy 144.950688 -230.966772)
			(xy 144.931719 -230.951606) (xy 144.898169 -230.916496) (xy 144.870341 -230.876696) (xy 144.848884 -230.833131)
			(xy 144.834295 -230.786811) (xy 144.826912 -230.738812) (xy 144.826907 -230.690249) (xy 144.834281 -230.642249)
			(xy 144.848861 -230.595926) (xy 144.87031 -230.552356) (xy 144.89813 -230.512551) (xy 144.931674 -230.477434)
			(xy 144.950688 -230.462328) (xy 144.959549 -230.454742) (xy 144.969857 -230.433844) (xy 144.9705 -230.422196)
			(xy 144.9705 -229.386892) (xy 144.969924 -229.375229) (xy 144.959589 -229.354321) (xy 144.950688 -229.34676)
			(xy 144.93172 -229.331594) (xy 144.898171 -229.296485) (xy 144.870346 -229.256685) (xy 144.84889 -229.21312)
			(xy 144.834302 -229.166801) (xy 144.826921 -229.118804) (xy 144.826917 -229.070242) (xy 144.834292 -229.022244)
			(xy 144.848873 -228.975923) (xy 144.870322 -228.932355) (xy 144.898142 -228.892551) (xy 144.931686 -228.857437)
			(xy 144.950688 -228.842316) (xy 144.959547 -228.834729) (xy 144.969849 -228.813831) (xy 144.9705 -228.802184)
			(xy 144.9705 -227.76688) (xy 144.969922 -227.755218) (xy 144.959583 -227.734314) (xy 144.950688 -227.726748)
			(xy 144.931721 -227.711582) (xy 144.898174 -227.676473) (xy 144.870351 -227.636674) (xy 144.848897 -227.59311)
			(xy 144.83431 -227.546792) (xy 144.82693 -227.498796) (xy 144.826928 -227.450236) (xy 144.834303 -227.402239)
			(xy 144.848885 -227.35592) (xy 144.870335 -227.312354) (xy 144.898154 -227.272552) (xy 144.931698 -227.237439)
			(xy 144.950688 -227.222304) (xy 144.959545 -227.214717) (xy 144.969843 -227.193818) (xy 144.9705 -227.182172)
			(xy 144.9705 -226.223322) (xy 144.970158 -226.214629) (xy 144.964323 -226.198252) (xy 144.95907 -226.191318)
			(xy 144.955768 -226.187508) (xy 144.865852 -226.097592) (xy 144.86212 -226.094072) (xy 144.853544 -226.088447)
			(xy 144.848834 -226.086416) (xy 144.840198 -226.08286) (xy 143.51508 -226.08286) (xy 143.510532 -226.08298)
			(xy 143.501585 -226.084634) (xy 143.4973 -226.086162) (xy 143.47317 -226.095306) (xy 143.467836 -226.099624)
			(xy 143.466566 -226.10064) (xy 143.44507 -226.117516) (xy 143.397506 -226.144424) (xy 143.346052 -226.16283)
			(xy 143.292213 -226.172194) (xy 143.26489 -226.172776) (xy 143.264382 -226.172776) (xy 143.237056 -226.172214)
			(xy 143.183207 -226.162879) (xy 143.131749 -226.144468) (xy 143.084199 -226.117526) (xy 143.062706 -226.10064)
			(xy 143.061436 -226.099624) (xy 143.056102 -226.095306) (xy 143.031972 -226.086162) (xy 143.027685 -226.084637)
			(xy 143.01874 -226.082979) (xy 143.014192 -226.08286) (xy 142.57528 -226.08286) (xy 142.570732 -226.08298)
			(xy 142.561785 -226.084634) (xy 142.5575 -226.086162) (xy 142.53337 -226.095306) (xy 142.528036 -226.099624)
			(xy 142.526766 -226.10064) (xy 142.50527 -226.117516) (xy 142.457706 -226.144424) (xy 142.406252 -226.16283)
			(xy 142.352413 -226.172194) (xy 142.32509 -226.172776) (xy 142.324836 -226.172776) (xy 142.299823 -226.172314)
			(xy 142.250411 -226.164493) (xy 142.202831 -226.149038) (xy 142.158255 -226.126331) (xy 142.11778 -226.096929)
			(xy 142.082403 -226.061558) (xy 142.052995 -226.021088) (xy 142.030281 -225.976515) (xy 142.014819 -225.928938)
			(xy 142.00699 -225.879527) (xy 142.006574 -225.854514) (xy 142.006639 -225.844326) (xy 142.007911 -225.823991)
			(xy 142.009114 -225.813874) (xy 142.009114 -225.813366) (xy 142.009945 -225.80184) (xy 142.002391 -225.780026)
			(xy 141.994636 -225.771456) (xy 141.369034 -225.145854) (xy 141.358793 -225.136235) (xy 141.334281 -225.122527)
			(xy 141.30696 -225.116019) (xy 141.2789 -225.117206) (xy 141.252226 -225.125997) (xy 141.228958 -225.141725)
			(xy 141.21086 -225.163201) (xy 141.204696 -225.175826) (xy 141.19349 -225.199353) (xy 141.164573 -225.242702)
			(xy 141.128974 -225.280755) (xy 141.087645 -225.312493) (xy 141.041694 -225.337066) (xy 140.992351 -225.353816)
			(xy 140.940937 -225.362295) (xy 140.914882 -225.36277) (xy 140.889874 -225.362278) (xy 140.840473 -225.354451)
			(xy 140.792904 -225.338993) (xy 140.74834 -225.316285) (xy 140.707876 -225.286884) (xy 140.672509 -225.251517)
			(xy 140.64311 -225.211052) (xy 140.620403 -225.166486) (xy 140.604946 -225.118918) (xy 140.597121 -225.069516)
			(xy 140.59662 -225.044508) (xy 140.597051 -225.020569) (xy 140.604216 -224.973231) (xy 140.618386 -224.927499)
			(xy 140.639243 -224.884404) (xy 140.666315 -224.844915) (xy 140.698993 -224.809924) (xy 140.73654 -224.780219)
			(xy 140.778111 -224.756468) (xy 140.822769 -224.739208) (xy 140.846048 -224.733612) (xy 140.853922 -224.731834)
			(xy 140.866114 -224.72523) (xy 140.871194 -224.719896) (xy 140.872972 -224.718118) (xy 140.879162 -224.710629)
			(xy 140.885903 -224.692425) (xy 140.885411 -224.673018) (xy 140.877757 -224.655178) (xy 140.871194 -224.648014)
			(xy 140.842492 -224.619312) (xy 140.838763 -224.615789) (xy 140.83019 -224.610156) (xy 140.825474 -224.608136)
			(xy 140.816838 -224.60458) (xy 130.760216 -224.60458) (xy 130.751524 -224.604924) (xy 130.735154 -224.610768)
			(xy 130.728212 -224.61601) (xy 130.724402 -224.619312) (xy 130.677412 -224.666302) (xy 130.670813 -224.673554)
			(xy 130.663201 -224.691606) (xy 130.662928 -224.711194) (xy 130.670034 -224.72945) (xy 130.676396 -224.736914)
			(xy 130.677158 -224.73793) (xy 130.677412 -224.738184) (xy 130.68427 -224.745296) (xy 130.69443 -224.74936)
			(xy 130.719212 -224.760037) (xy 130.765066 -224.788476) (xy 130.805472 -224.824235) (xy 130.839273 -224.866291)
			(xy 130.865504 -224.913443) (xy 130.883413 -224.964341) (xy 130.892488 -225.017529) (xy 130.893058 -225.044508)
			(xy 130.892567 -225.069497) (xy 131.197332 -225.069497) (xy 131.197332 -225.019519) (xy 131.205151 -224.970156)
			(xy 131.220595 -224.922624) (xy 131.243285 -224.878092) (xy 131.272661 -224.837659) (xy 131.308001 -224.802319)
			(xy 131.348434 -224.772943) (xy 131.392966 -224.750253) (xy 131.440498 -224.734809) (xy 131.489861 -224.72699)
			(xy 131.539839 -224.72699) (xy 131.589202 -224.734809) (xy 131.636734 -224.750253) (xy 131.681266 -224.772943)
			(xy 131.721699 -224.802319) (xy 131.757039 -224.837659) (xy 131.786415 -224.878092) (xy 131.809105 -224.922624)
			(xy 131.824549 -224.970156) (xy 131.832368 -225.019519) (xy 131.832858 -225.044508) (xy 132.138415 -225.044508)
			(xy 132.14251 -224.99378) (xy 132.154689 -224.944366) (xy 132.174637 -224.897546) (xy 132.201838 -224.854532)
			(xy 132.235586 -224.816438) (xy 132.275008 -224.784251) (xy 132.319082 -224.758805) (xy 132.366668 -224.740758)
			(xy 132.416532 -224.730578) (xy 132.467384 -224.728529) (xy 132.517905 -224.734663) (xy 132.566789 -224.748823)
			(xy 132.612768 -224.77064) (xy 132.654652 -224.79955) (xy 132.691356 -224.834805) (xy 132.721929 -224.875491)
			(xy 132.74558 -224.920554) (xy 132.761696 -224.968828) (xy 132.76986 -225.019062) (xy 132.770372 -225.044508)
			(xy 132.769869 -225.069497) (xy 133.077186 -225.069497) (xy 133.077186 -225.019519) (xy 133.085005 -224.970156)
			(xy 133.100449 -224.922624) (xy 133.123139 -224.878092) (xy 133.152515 -224.837659) (xy 133.187855 -224.802319)
			(xy 133.228288 -224.772943) (xy 133.27282 -224.750253) (xy 133.320352 -224.734809) (xy 133.369715 -224.72699)
			(xy 133.419693 -224.72699) (xy 133.469056 -224.734809) (xy 133.516588 -224.750253) (xy 133.56112 -224.772943)
			(xy 133.601553 -224.802319) (xy 133.636893 -224.837659) (xy 133.666269 -224.878092) (xy 133.688959 -224.922624)
			(xy 133.704403 -224.970156) (xy 133.712222 -225.019519) (xy 133.712712 -225.044508) (xy 133.712222 -225.069497)
			(xy 134.01724 -225.069497) (xy 134.01724 -225.019519) (xy 134.025059 -224.970156) (xy 134.040503 -224.922624)
			(xy 134.063193 -224.878092) (xy 134.092569 -224.837659) (xy 134.127909 -224.802319) (xy 134.168342 -224.772943)
			(xy 134.212874 -224.750253) (xy 134.260406 -224.734809) (xy 134.309769 -224.72699) (xy 134.359747 -224.72699)
			(xy 134.40911 -224.734809) (xy 134.456642 -224.750253) (xy 134.501174 -224.772943) (xy 134.541607 -224.802319)
			(xy 134.576947 -224.837659) (xy 134.606323 -224.878092) (xy 134.629013 -224.922624) (xy 134.644457 -224.970156)
			(xy 134.652276 -225.019519) (xy 134.652766 -225.044508) (xy 134.652276 -225.069497) (xy 134.957294 -225.069497)
			(xy 134.957294 -225.019519) (xy 134.965113 -224.970156) (xy 134.980557 -224.922624) (xy 135.003247 -224.878092)
			(xy 135.032623 -224.837659) (xy 135.067963 -224.802319) (xy 135.108396 -224.772943) (xy 135.152928 -224.750253)
			(xy 135.20046 -224.734809) (xy 135.249823 -224.72699) (xy 135.299801 -224.72699) (xy 135.349164 -224.734809)
			(xy 135.396696 -224.750253) (xy 135.441228 -224.772943) (xy 135.481661 -224.802319) (xy 135.517001 -224.837659)
			(xy 135.546377 -224.878092) (xy 135.569067 -224.922624) (xy 135.584511 -224.970156) (xy 135.59233 -225.019519)
			(xy 135.59282 -225.044508) (xy 135.898631 -225.044508) (xy 135.902726 -224.99378) (xy 135.914905 -224.944366)
			(xy 135.934853 -224.897546) (xy 135.962054 -224.854532) (xy 135.995802 -224.816438) (xy 136.035224 -224.784251)
			(xy 136.079298 -224.758805) (xy 136.126884 -224.740758) (xy 136.176748 -224.730578) (xy 136.2276 -224.728529)
			(xy 136.278121 -224.734663) (xy 136.327005 -224.748823) (xy 136.372984 -224.77064) (xy 136.414868 -224.79955)
			(xy 136.451572 -224.834805) (xy 136.482145 -224.875491) (xy 136.505796 -224.920554) (xy 136.521912 -224.968828)
			(xy 136.530076 -225.019062) (xy 136.530588 -225.044508) (xy 136.530085 -225.069497) (xy 137.777202 -225.069497)
			(xy 137.777202 -225.019519) (xy 137.785021 -224.970156) (xy 137.800465 -224.922624) (xy 137.823155 -224.878092)
			(xy 137.852531 -224.837659) (xy 137.887871 -224.802319) (xy 137.928304 -224.772943) (xy 137.972836 -224.750253)
			(xy 138.020368 -224.734809) (xy 138.069731 -224.72699) (xy 138.119709 -224.72699) (xy 138.169072 -224.734809)
			(xy 138.216604 -224.750253) (xy 138.261136 -224.772943) (xy 138.301569 -224.802319) (xy 138.336909 -224.837659)
			(xy 138.366285 -224.878092) (xy 138.388975 -224.922624) (xy 138.404419 -224.970156) (xy 138.412238 -225.019519)
			(xy 138.412728 -225.044508) (xy 138.718539 -225.044508) (xy 138.722634 -224.99378) (xy 138.734813 -224.944366)
			(xy 138.754761 -224.897546) (xy 138.781962 -224.854532) (xy 138.81571 -224.816438) (xy 138.855132 -224.784251)
			(xy 138.899206 -224.758805) (xy 138.946792 -224.740758) (xy 138.996656 -224.730578) (xy 139.047508 -224.728529)
			(xy 139.098029 -224.734663) (xy 139.146913 -224.748823) (xy 139.192892 -224.77064) (xy 139.234776 -224.79955)
			(xy 139.27148 -224.834805) (xy 139.302053 -224.875491) (xy 139.325704 -224.920554) (xy 139.34182 -224.968828)
			(xy 139.349984 -225.019062) (xy 139.350496 -225.044508) (xy 139.349993 -225.069497) (xy 139.65731 -225.069497)
			(xy 139.65731 -225.019519) (xy 139.665129 -224.970156) (xy 139.680573 -224.922624) (xy 139.703263 -224.878092)
			(xy 139.732639 -224.837659) (xy 139.767979 -224.802319) (xy 139.808412 -224.772943) (xy 139.852944 -224.750253)
			(xy 139.900476 -224.734809) (xy 139.949839 -224.72699) (xy 139.999817 -224.72699) (xy 140.04918 -224.734809)
			(xy 140.096712 -224.750253) (xy 140.141244 -224.772943) (xy 140.181677 -224.802319) (xy 140.217017 -224.837659)
			(xy 140.246393 -224.878092) (xy 140.269083 -224.922624) (xy 140.284527 -224.970156) (xy 140.292346 -225.019519)
			(xy 140.292836 -225.044508) (xy 140.292346 -225.069497) (xy 140.284527 -225.11886) (xy 140.269083 -225.166392)
			(xy 140.246393 -225.210924) (xy 140.217017 -225.251357) (xy 140.181677 -225.286697) (xy 140.141244 -225.316073)
			(xy 140.096712 -225.338763) (xy 140.04918 -225.354207) (xy 139.999817 -225.362026) (xy 139.949839 -225.362026)
			(xy 139.900476 -225.354207) (xy 139.852944 -225.338763) (xy 139.808412 -225.316073) (xy 139.767979 -225.286697)
			(xy 139.732639 -225.251357) (xy 139.703263 -225.210924) (xy 139.680573 -225.166392) (xy 139.665129 -225.11886)
			(xy 139.65731 -225.069497) (xy 139.349993 -225.069497) (xy 139.349984 -225.069954) (xy 139.34182 -225.120188)
			(xy 139.325704 -225.168462) (xy 139.302053 -225.213525) (xy 139.27148 -225.254211) (xy 139.234776 -225.289466)
			(xy 139.192892 -225.318376) (xy 139.146913 -225.340193) (xy 139.098029 -225.354353) (xy 139.047508 -225.360487)
			(xy 138.996656 -225.358438) (xy 138.946792 -225.348258) (xy 138.899206 -225.330211) (xy 138.855132 -225.304765)
			(xy 138.81571 -225.272578) (xy 138.781962 -225.234484) (xy 138.754761 -225.19147) (xy 138.734813 -225.14465)
			(xy 138.722634 -225.095236) (xy 138.718539 -225.044508) (xy 138.412728 -225.044508) (xy 138.412238 -225.069497)
			(xy 138.404419 -225.11886) (xy 138.388975 -225.166392) (xy 138.366285 -225.210924) (xy 138.336909 -225.251357)
			(xy 138.301569 -225.286697) (xy 138.261136 -225.316073) (xy 138.216604 -225.338763) (xy 138.169072 -225.354207)
			(xy 138.119709 -225.362026) (xy 138.069731 -225.362026) (xy 138.020368 -225.354207) (xy 137.972836 -225.338763)
			(xy 137.928304 -225.316073) (xy 137.887871 -225.286697) (xy 137.852531 -225.251357) (xy 137.823155 -225.210924)
			(xy 137.800465 -225.166392) (xy 137.785021 -225.11886) (xy 137.777202 -225.069497) (xy 136.530085 -225.069497)
			(xy 136.530076 -225.069954) (xy 136.521912 -225.120188) (xy 136.505796 -225.168462) (xy 136.482145 -225.213525)
			(xy 136.451572 -225.254211) (xy 136.414868 -225.289466) (xy 136.372984 -225.318376) (xy 136.327005 -225.340193)
			(xy 136.278121 -225.354353) (xy 136.2276 -225.360487) (xy 136.176748 -225.358438) (xy 136.126884 -225.348258)
			(xy 136.079298 -225.330211) (xy 136.035224 -225.304765) (xy 135.995802 -225.272578) (xy 135.962054 -225.234484)
			(xy 135.934853 -225.19147) (xy 135.914905 -225.14465) (xy 135.902726 -225.095236) (xy 135.898631 -225.044508)
			(xy 135.59282 -225.044508) (xy 135.59233 -225.069497) (xy 135.584511 -225.11886) (xy 135.569067 -225.166392)
			(xy 135.546377 -225.210924) (xy 135.517001 -225.251357) (xy 135.481661 -225.286697) (xy 135.441228 -225.316073)
			(xy 135.396696 -225.338763) (xy 135.349164 -225.354207) (xy 135.299801 -225.362026) (xy 135.249823 -225.362026)
			(xy 135.20046 -225.354207) (xy 135.152928 -225.338763) (xy 135.108396 -225.316073) (xy 135.067963 -225.286697)
			(xy 135.032623 -225.251357) (xy 135.003247 -225.210924) (xy 134.980557 -225.166392) (xy 134.965113 -225.11886)
			(xy 134.957294 -225.069497) (xy 134.652276 -225.069497) (xy 134.644457 -225.11886) (xy 134.629013 -225.166392)
			(xy 134.606323 -225.210924) (xy 134.576947 -225.251357) (xy 134.541607 -225.286697) (xy 134.501174 -225.316073)
			(xy 134.456642 -225.338763) (xy 134.40911 -225.354207) (xy 134.359747 -225.362026) (xy 134.309769 -225.362026)
			(xy 134.260406 -225.354207) (xy 134.212874 -225.338763) (xy 134.168342 -225.316073) (xy 134.127909 -225.286697)
			(xy 134.092569 -225.251357) (xy 134.063193 -225.210924) (xy 134.040503 -225.166392) (xy 134.025059 -225.11886)
			(xy 134.01724 -225.069497) (xy 133.712222 -225.069497) (xy 133.704403 -225.11886) (xy 133.688959 -225.166392)
			(xy 133.666269 -225.210924) (xy 133.636893 -225.251357) (xy 133.601553 -225.286697) (xy 133.56112 -225.316073)
			(xy 133.516588 -225.338763) (xy 133.469056 -225.354207) (xy 133.419693 -225.362026) (xy 133.369715 -225.362026)
			(xy 133.320352 -225.354207) (xy 133.27282 -225.338763) (xy 133.228288 -225.316073) (xy 133.187855 -225.286697)
			(xy 133.152515 -225.251357) (xy 133.123139 -225.210924) (xy 133.100449 -225.166392) (xy 133.085005 -225.11886)
			(xy 133.077186 -225.069497) (xy 132.769869 -225.069497) (xy 132.76986 -225.069954) (xy 132.761696 -225.120188)
			(xy 132.74558 -225.168462) (xy 132.721929 -225.213525) (xy 132.691356 -225.254211) (xy 132.654652 -225.289466)
			(xy 132.612768 -225.318376) (xy 132.566789 -225.340193) (xy 132.517905 -225.354353) (xy 132.467384 -225.360487)
			(xy 132.416532 -225.358438) (xy 132.366668 -225.348258) (xy 132.319082 -225.330211) (xy 132.275008 -225.304765)
			(xy 132.235586 -225.272578) (xy 132.201838 -225.234484) (xy 132.174637 -225.19147) (xy 132.154689 -225.14465)
			(xy 132.14251 -225.095236) (xy 132.138415 -225.044508) (xy 131.832858 -225.044508) (xy 131.832368 -225.069497)
			(xy 131.824549 -225.11886) (xy 131.809105 -225.166392) (xy 131.786415 -225.210924) (xy 131.757039 -225.251357)
			(xy 131.721699 -225.286697) (xy 131.681266 -225.316073) (xy 131.636734 -225.338763) (xy 131.589202 -225.354207)
			(xy 131.539839 -225.362026) (xy 131.489861 -225.362026) (xy 131.440498 -225.354207) (xy 131.392966 -225.338763)
			(xy 131.348434 -225.316073) (xy 131.308001 -225.286697) (xy 131.272661 -225.251357) (xy 131.243285 -225.210924)
			(xy 131.220595 -225.166392) (xy 131.205151 -225.11886) (xy 131.197332 -225.069497) (xy 130.892567 -225.069497)
			(xy 130.892567 -225.069517) (xy 130.884741 -225.118918) (xy 130.869284 -225.166487) (xy 130.846576 -225.211052)
			(xy 130.817175 -225.251516) (xy 130.781807 -225.286883) (xy 130.741342 -225.316282) (xy 130.696776 -225.338989)
			(xy 130.649206 -225.354444) (xy 130.599805 -225.362268) (xy 130.574796 -225.36277) (xy 130.547999 -225.362226)
			(xy 130.495161 -225.353265) (xy 130.44457 -225.335582) (xy 130.397655 -225.309674) (xy 130.355742 -225.276275)
			(xy 130.320015 -225.236328) (xy 130.305302 -225.213926) (xy 130.296704 -225.201376) (xy 130.273622 -225.181586)
			(xy 130.245743 -225.169452) (xy 130.21553 -225.166046) (xy 130.18565 -225.171668) (xy 130.158741 -225.185822)
			(xy 130.147568 -225.196146) (xy 129.49682 -225.846894) (xy 129.493725 -225.850091) (xy 129.488611 -225.857372)
			(xy 129.48666 -225.861372) (xy 129.48285 -225.869754) (xy 129.482088 -225.878898) (xy 129.482088 -225.879152)
			(xy 129.482054 -225.879503) (xy 129.787124 -225.879503) (xy 129.787124 -225.829525) (xy 129.794943 -225.780162)
			(xy 129.810387 -225.73263) (xy 129.833077 -225.688098) (xy 129.862453 -225.647665) (xy 129.897793 -225.612325)
			(xy 129.938226 -225.582949) (xy 129.982758 -225.560259) (xy 130.03029 -225.544815) (xy 130.079653 -225.536996)
			(xy 130.129631 -225.536996) (xy 130.178994 -225.544815) (xy 130.226526 -225.560259) (xy 130.271058 -225.582949)
			(xy 130.311491 -225.612325) (xy 130.346831 -225.647665) (xy 130.376207 -225.688098) (xy 130.398897 -225.73263)
			(xy 130.414341 -225.780162) (xy 130.42216 -225.829525) (xy 130.42265 -225.854514) (xy 130.728461 -225.854514)
			(xy 130.732556 -225.803786) (xy 130.744735 -225.754372) (xy 130.764683 -225.707552) (xy 130.791884 -225.664538)
			(xy 130.825632 -225.626444) (xy 130.865054 -225.594257) (xy 130.909128 -225.568811) (xy 130.956714 -225.550764)
			(xy 131.006578 -225.540584) (xy 131.05743 -225.538535) (xy 131.107951 -225.544669) (xy 131.156835 -225.558829)
			(xy 131.202814 -225.580646) (xy 131.244698 -225.609556) (xy 131.281402 -225.644811) (xy 131.311975 -225.685497)
			(xy 131.335626 -225.73056) (xy 131.351742 -225.778834) (xy 131.359906 -225.829068) (xy 131.360418 -225.854514)
			(xy 131.359915 -225.879503) (xy 131.667232 -225.879503) (xy 131.667232 -225.829525) (xy 131.675051 -225.780162)
			(xy 131.690495 -225.73263) (xy 131.713185 -225.688098) (xy 131.742561 -225.647665) (xy 131.777901 -225.612325)
			(xy 131.818334 -225.582949) (xy 131.862866 -225.560259) (xy 131.910398 -225.544815) (xy 131.959761 -225.536996)
			(xy 132.009739 -225.536996) (xy 132.059102 -225.544815) (xy 132.106634 -225.560259) (xy 132.151166 -225.582949)
			(xy 132.191599 -225.612325) (xy 132.226939 -225.647665) (xy 132.256315 -225.688098) (xy 132.279005 -225.73263)
			(xy 132.294449 -225.780162) (xy 132.302268 -225.829525) (xy 132.302758 -225.854514) (xy 132.608569 -225.854514)
			(xy 132.612664 -225.803786) (xy 132.624843 -225.754372) (xy 132.644791 -225.707552) (xy 132.671992 -225.664538)
			(xy 132.70574 -225.626444) (xy 132.745162 -225.594257) (xy 132.789236 -225.568811) (xy 132.836822 -225.550764)
			(xy 132.886686 -225.540584) (xy 132.937538 -225.538535) (xy 132.988059 -225.544669) (xy 133.036943 -225.558829)
			(xy 133.082922 -225.580646) (xy 133.124806 -225.609556) (xy 133.16151 -225.644811) (xy 133.192083 -225.685497)
			(xy 133.215734 -225.73056) (xy 133.23185 -225.778834) (xy 133.240014 -225.829068) (xy 133.240526 -225.854514)
			(xy 133.240023 -225.879503) (xy 133.54734 -225.879503) (xy 133.54734 -225.829525) (xy 133.555159 -225.780162)
			(xy 133.570603 -225.73263) (xy 133.593293 -225.688098) (xy 133.622669 -225.647665) (xy 133.658009 -225.612325)
			(xy 133.698442 -225.582949) (xy 133.742974 -225.560259) (xy 133.790506 -225.544815) (xy 133.839869 -225.536996)
			(xy 133.889847 -225.536996) (xy 133.93921 -225.544815) (xy 133.986742 -225.560259) (xy 134.031274 -225.582949)
			(xy 134.071707 -225.612325) (xy 134.107047 -225.647665) (xy 134.136423 -225.688098) (xy 134.159113 -225.73263)
			(xy 134.174557 -225.780162) (xy 134.182376 -225.829525) (xy 134.182866 -225.854514) (xy 134.488423 -225.854514)
			(xy 134.492518 -225.803786) (xy 134.504697 -225.754372) (xy 134.524645 -225.707552) (xy 134.551846 -225.664538)
			(xy 134.585594 -225.626444) (xy 134.625016 -225.594257) (xy 134.66909 -225.568811) (xy 134.716676 -225.550764)
			(xy 134.76654 -225.540584) (xy 134.817392 -225.538535) (xy 134.867913 -225.544669) (xy 134.916797 -225.558829)
			(xy 134.962776 -225.580646) (xy 135.00466 -225.609556) (xy 135.041364 -225.644811) (xy 135.071937 -225.685497)
			(xy 135.095588 -225.73056) (xy 135.111704 -225.778834) (xy 135.119868 -225.829068) (xy 135.12038 -225.854514)
			(xy 135.428477 -225.854514) (xy 135.432572 -225.803786) (xy 135.444751 -225.754372) (xy 135.464699 -225.707552)
			(xy 135.4919 -225.664538) (xy 135.525648 -225.626444) (xy 135.56507 -225.594257) (xy 135.609144 -225.568811)
			(xy 135.65673 -225.550764) (xy 135.706594 -225.540584) (xy 135.757446 -225.538535) (xy 135.807967 -225.544669)
			(xy 135.856851 -225.558829) (xy 135.90283 -225.580646) (xy 135.944714 -225.609556) (xy 135.981418 -225.644811)
			(xy 136.011991 -225.685497) (xy 136.035642 -225.73056) (xy 136.051758 -225.778834) (xy 136.059922 -225.829068)
			(xy 136.060434 -225.854514) (xy 136.059931 -225.879503) (xy 136.367248 -225.879503) (xy 136.367248 -225.829525)
			(xy 136.375067 -225.780162) (xy 136.390511 -225.73263) (xy 136.413201 -225.688098) (xy 136.442577 -225.647665)
			(xy 136.477917 -225.612325) (xy 136.51835 -225.582949) (xy 136.562882 -225.560259) (xy 136.610414 -225.544815)
			(xy 136.659777 -225.536996) (xy 136.709755 -225.536996) (xy 136.759118 -225.544815) (xy 136.80665 -225.560259)
			(xy 136.851182 -225.582949) (xy 136.891615 -225.612325) (xy 136.926955 -225.647665) (xy 136.956331 -225.688098)
			(xy 136.979021 -225.73263) (xy 136.994465 -225.780162) (xy 137.002284 -225.829525) (xy 137.002774 -225.854514)
			(xy 137.308585 -225.854514) (xy 137.31268 -225.803786) (xy 137.324859 -225.754372) (xy 137.344807 -225.707552)
			(xy 137.372008 -225.664538) (xy 137.405756 -225.626444) (xy 137.445178 -225.594257) (xy 137.489252 -225.568811)
			(xy 137.536838 -225.550764) (xy 137.586702 -225.540584) (xy 137.637554 -225.538535) (xy 137.688075 -225.544669)
			(xy 137.736959 -225.558829) (xy 137.782938 -225.580646) (xy 137.824822 -225.609556) (xy 137.861526 -225.644811)
			(xy 137.892099 -225.685497) (xy 137.91575 -225.73056) (xy 137.931866 -225.778834) (xy 137.94003 -225.829068)
			(xy 137.940542 -225.854514) (xy 137.940039 -225.879503) (xy 138.247356 -225.879503) (xy 138.247356 -225.829525)
			(xy 138.255175 -225.780162) (xy 138.270619 -225.73263) (xy 138.293309 -225.688098) (xy 138.322685 -225.647665)
			(xy 138.358025 -225.612325) (xy 138.398458 -225.582949) (xy 138.44299 -225.560259) (xy 138.490522 -225.544815)
			(xy 138.539885 -225.536996) (xy 138.589863 -225.536996) (xy 138.639226 -225.544815) (xy 138.686758 -225.560259)
			(xy 138.73129 -225.582949) (xy 138.771723 -225.612325) (xy 138.807063 -225.647665) (xy 138.836439 -225.688098)
			(xy 138.859129 -225.73263) (xy 138.874573 -225.780162) (xy 138.882392 -225.829525) (xy 138.882882 -225.854514)
			(xy 139.188439 -225.854514) (xy 139.192534 -225.803786) (xy 139.204713 -225.754372) (xy 139.224661 -225.707552)
			(xy 139.251862 -225.664538) (xy 139.28561 -225.626444) (xy 139.325032 -225.594257) (xy 139.369106 -225.568811)
			(xy 139.416692 -225.550764) (xy 139.466556 -225.540584) (xy 139.517408 -225.538535) (xy 139.567929 -225.544669)
			(xy 139.616813 -225.558829) (xy 139.662792 -225.580646) (xy 139.704676 -225.609556) (xy 139.74138 -225.644811)
			(xy 139.771953 -225.685497) (xy 139.795604 -225.73056) (xy 139.81172 -225.778834) (xy 139.819884 -225.829068)
			(xy 139.820396 -225.854514) (xy 139.819893 -225.879503) (xy 140.12721 -225.879503) (xy 140.12721 -225.829525)
			(xy 140.135029 -225.780162) (xy 140.150473 -225.73263) (xy 140.173163 -225.688098) (xy 140.202539 -225.647665)
			(xy 140.237879 -225.612325) (xy 140.278312 -225.582949) (xy 140.322844 -225.560259) (xy 140.370376 -225.544815)
			(xy 140.419739 -225.536996) (xy 140.469717 -225.536996) (xy 140.51908 -225.544815) (xy 140.566612 -225.560259)
			(xy 140.611144 -225.582949) (xy 140.651577 -225.612325) (xy 140.686917 -225.647665) (xy 140.716293 -225.688098)
			(xy 140.738983 -225.73263) (xy 140.754427 -225.780162) (xy 140.762246 -225.829525) (xy 140.762736 -225.854514)
			(xy 141.068547 -225.854514) (xy 141.072642 -225.803786) (xy 141.084821 -225.754372) (xy 141.104769 -225.707552)
			(xy 141.13197 -225.664538) (xy 141.165718 -225.626444) (xy 141.20514 -225.594257) (xy 141.249214 -225.568811)
			(xy 141.2968 -225.550764) (xy 141.346664 -225.540584) (xy 141.397516 -225.538535) (xy 141.448037 -225.544669)
			(xy 141.496921 -225.558829) (xy 141.5429 -225.580646) (xy 141.584784 -225.609556) (xy 141.621488 -225.644811)
			(xy 141.652061 -225.685497) (xy 141.675712 -225.73056) (xy 141.691828 -225.778834) (xy 141.699992 -225.829068)
			(xy 141.700504 -225.854514) (xy 141.699992 -225.87996) (xy 141.691828 -225.930194) (xy 141.675712 -225.978468)
			(xy 141.652061 -226.023531) (xy 141.621488 -226.064217) (xy 141.584784 -226.099472) (xy 141.5429 -226.128382)
			(xy 141.496921 -226.150199) (xy 141.448037 -226.164359) (xy 141.397516 -226.170493) (xy 141.346664 -226.168444)
			(xy 141.2968 -226.158264) (xy 141.249214 -226.140217) (xy 141.20514 -226.114771) (xy 141.165718 -226.082584)
			(xy 141.13197 -226.04449) (xy 141.104769 -226.001476) (xy 141.084821 -225.954656) (xy 141.072642 -225.905242)
			(xy 141.068547 -225.854514) (xy 140.762736 -225.854514) (xy 140.762246 -225.879503) (xy 140.754427 -225.928866)
			(xy 140.738983 -225.976398) (xy 140.716293 -226.02093) (xy 140.686917 -226.061363) (xy 140.651577 -226.096703)
			(xy 140.611144 -226.126079) (xy 140.566612 -226.148769) (xy 140.51908 -226.164213) (xy 140.469717 -226.172032)
			(xy 140.419739 -226.172032) (xy 140.370376 -226.164213) (xy 140.322844 -226.148769) (xy 140.278312 -226.126079)
			(xy 140.237879 -226.096703) (xy 140.202539 -226.061363) (xy 140.173163 -226.02093) (xy 140.150473 -225.976398)
			(xy 140.135029 -225.928866) (xy 140.12721 -225.879503) (xy 139.819893 -225.879503) (xy 139.819884 -225.87996)
			(xy 139.81172 -225.930194) (xy 139.795604 -225.978468) (xy 139.771953 -226.023531) (xy 139.74138 -226.064217)
			(xy 139.704676 -226.099472) (xy 139.662792 -226.128382) (xy 139.616813 -226.150199) (xy 139.567929 -226.164359)
			(xy 139.517408 -226.170493) (xy 139.466556 -226.168444) (xy 139.416692 -226.158264) (xy 139.369106 -226.140217)
			(xy 139.325032 -226.114771) (xy 139.28561 -226.082584) (xy 139.251862 -226.04449) (xy 139.224661 -226.001476)
			(xy 139.204713 -225.954656) (xy 139.192534 -225.905242) (xy 139.188439 -225.854514) (xy 138.882882 -225.854514)
			(xy 138.882392 -225.879503) (xy 138.874573 -225.928866) (xy 138.859129 -225.976398) (xy 138.836439 -226.02093)
			(xy 138.807063 -226.061363) (xy 138.771723 -226.096703) (xy 138.73129 -226.126079) (xy 138.686758 -226.148769)
			(xy 138.639226 -226.164213) (xy 138.589863 -226.172032) (xy 138.539885 -226.172032) (xy 138.490522 -226.164213)
			(xy 138.44299 -226.148769) (xy 138.398458 -226.126079) (xy 138.358025 -226.096703) (xy 138.322685 -226.061363)
			(xy 138.293309 -226.02093) (xy 138.270619 -225.976398) (xy 138.255175 -225.928866) (xy 138.247356 -225.879503)
			(xy 137.940039 -225.879503) (xy 137.94003 -225.87996) (xy 137.931866 -225.930194) (xy 137.91575 -225.978468)
			(xy 137.892099 -226.023531) (xy 137.861526 -226.064217) (xy 137.824822 -226.099472) (xy 137.782938 -226.128382)
			(xy 137.736959 -226.150199) (xy 137.688075 -226.164359) (xy 137.637554 -226.170493) (xy 137.586702 -226.168444)
			(xy 137.536838 -226.158264) (xy 137.489252 -226.140217) (xy 137.445178 -226.114771) (xy 137.405756 -226.082584)
			(xy 137.372008 -226.04449) (xy 137.344807 -226.001476) (xy 137.324859 -225.954656) (xy 137.31268 -225.905242)
			(xy 137.308585 -225.854514) (xy 137.002774 -225.854514) (xy 137.002284 -225.879503) (xy 136.994465 -225.928866)
			(xy 136.979021 -225.976398) (xy 136.956331 -226.02093) (xy 136.926955 -226.061363) (xy 136.891615 -226.096703)
			(xy 136.851182 -226.126079) (xy 136.80665 -226.148769) (xy 136.759118 -226.164213) (xy 136.709755 -226.172032)
			(xy 136.659777 -226.172032) (xy 136.610414 -226.164213) (xy 136.562882 -226.148769) (xy 136.51835 -226.126079)
			(xy 136.477917 -226.096703) (xy 136.442577 -226.061363) (xy 136.413201 -226.02093) (xy 136.390511 -225.976398)
			(xy 136.375067 -225.928866) (xy 136.367248 -225.879503) (xy 136.059931 -225.879503) (xy 136.059922 -225.87996)
			(xy 136.051758 -225.930194) (xy 136.035642 -225.978468) (xy 136.011991 -226.023531) (xy 135.981418 -226.064217)
			(xy 135.944714 -226.099472) (xy 135.90283 -226.128382) (xy 135.856851 -226.150199) (xy 135.807967 -226.164359)
			(xy 135.757446 -226.170493) (xy 135.706594 -226.168444) (xy 135.65673 -226.158264) (xy 135.609144 -226.140217)
			(xy 135.56507 -226.114771) (xy 135.525648 -226.082584) (xy 135.4919 -226.04449) (xy 135.464699 -226.001476)
			(xy 135.444751 -225.954656) (xy 135.432572 -225.905242) (xy 135.428477 -225.854514) (xy 135.12038 -225.854514)
			(xy 135.119868 -225.87996) (xy 135.111704 -225.930194) (xy 135.095588 -225.978468) (xy 135.071937 -226.023531)
			(xy 135.041364 -226.064217) (xy 135.00466 -226.099472) (xy 134.962776 -226.128382) (xy 134.916797 -226.150199)
			(xy 134.867913 -226.164359) (xy 134.817392 -226.170493) (xy 134.76654 -226.168444) (xy 134.716676 -226.158264)
			(xy 134.66909 -226.140217) (xy 134.625016 -226.114771) (xy 134.585594 -226.082584) (xy 134.551846 -226.04449)
			(xy 134.524645 -226.001476) (xy 134.504697 -225.954656) (xy 134.492518 -225.905242) (xy 134.488423 -225.854514)
			(xy 134.182866 -225.854514) (xy 134.182376 -225.879503) (xy 134.174557 -225.928866) (xy 134.159113 -225.976398)
			(xy 134.136423 -226.02093) (xy 134.107047 -226.061363) (xy 134.071707 -226.096703) (xy 134.031274 -226.126079)
			(xy 133.986742 -226.148769) (xy 133.93921 -226.164213) (xy 133.889847 -226.172032) (xy 133.839869 -226.172032)
			(xy 133.790506 -226.164213) (xy 133.742974 -226.148769) (xy 133.698442 -226.126079) (xy 133.658009 -226.096703)
			(xy 133.622669 -226.061363) (xy 133.593293 -226.02093) (xy 133.570603 -225.976398) (xy 133.555159 -225.928866)
			(xy 133.54734 -225.879503) (xy 133.240023 -225.879503) (xy 133.240014 -225.87996) (xy 133.23185 -225.930194)
			(xy 133.215734 -225.978468) (xy 133.192083 -226.023531) (xy 133.16151 -226.064217) (xy 133.124806 -226.099472)
			(xy 133.082922 -226.128382) (xy 133.036943 -226.150199) (xy 132.988059 -226.164359) (xy 132.937538 -226.170493)
			(xy 132.886686 -226.168444) (xy 132.836822 -226.158264) (xy 132.789236 -226.140217) (xy 132.745162 -226.114771)
			(xy 132.70574 -226.082584) (xy 132.671992 -226.04449) (xy 132.644791 -226.001476) (xy 132.624843 -225.954656)
			(xy 132.612664 -225.905242) (xy 132.608569 -225.854514) (xy 132.302758 -225.854514) (xy 132.302268 -225.879503)
			(xy 132.294449 -225.928866) (xy 132.279005 -225.976398) (xy 132.256315 -226.02093) (xy 132.226939 -226.061363)
			(xy 132.191599 -226.096703) (xy 132.151166 -226.126079) (xy 132.106634 -226.148769) (xy 132.059102 -226.164213)
			(xy 132.009739 -226.172032) (xy 131.959761 -226.172032) (xy 131.910398 -226.164213) (xy 131.862866 -226.148769)
			(xy 131.818334 -226.126079) (xy 131.777901 -226.096703) (xy 131.742561 -226.061363) (xy 131.713185 -226.02093)
			(xy 131.690495 -225.976398) (xy 131.675051 -225.928866) (xy 131.667232 -225.879503) (xy 131.359915 -225.879503)
			(xy 131.359906 -225.87996) (xy 131.351742 -225.930194) (xy 131.335626 -225.978468) (xy 131.311975 -226.023531)
			(xy 131.281402 -226.064217) (xy 131.244698 -226.099472) (xy 131.202814 -226.128382) (xy 131.156835 -226.150199)
			(xy 131.107951 -226.164359) (xy 131.05743 -226.170493) (xy 131.006578 -226.168444) (xy 130.956714 -226.158264)
			(xy 130.909128 -226.140217) (xy 130.865054 -226.114771) (xy 130.825632 -226.082584) (xy 130.791884 -226.04449)
			(xy 130.764683 -226.001476) (xy 130.744735 -225.954656) (xy 130.732556 -225.905242) (xy 130.728461 -225.854514)
			(xy 130.42265 -225.854514) (xy 130.42216 -225.879503) (xy 130.414341 -225.928866) (xy 130.398897 -225.976398)
			(xy 130.376207 -226.02093) (xy 130.346831 -226.061363) (xy 130.311491 -226.096703) (xy 130.271058 -226.126079)
			(xy 130.226526 -226.148769) (xy 130.178994 -226.164213) (xy 130.129631 -226.172032) (xy 130.079653 -226.172032)
			(xy 130.03029 -226.164213) (xy 129.982758 -226.148769) (xy 129.938226 -226.126079) (xy 129.897793 -226.096703)
			(xy 129.862453 -226.061363) (xy 129.833077 -226.02093) (xy 129.810387 -225.976398) (xy 129.794943 -225.928866)
			(xy 129.787124 -225.879503) (xy 129.482054 -225.879503) (xy 129.479679 -225.904095) (xy 129.468013 -225.952827)
			(xy 129.448851 -225.999128) (xy 129.422668 -226.041853) (xy 129.390111 -226.079945) (xy 129.351985 -226.112462)
			(xy 129.309233 -226.138601) (xy 129.262912 -226.157715) (xy 129.214168 -226.16933) (xy 129.189226 -226.17176)
			(xy 129.180082 -226.172522) (xy 129.1717 -226.176332) (xy 129.167717 -226.178311) (xy 129.160435 -226.183416)
			(xy 129.157222 -226.186492) (xy 128.946148 -226.397566) (xy 128.94183 -226.402646) (xy 128.935623 -226.411681)
			(xy 128.930796 -226.433042) (xy 128.935244 -226.454485) (xy 128.941322 -226.463606) (xy 128.942592 -226.46513)
			(xy 128.942846 -226.465384) (xy 128.959245 -226.486731) (xy 128.985389 -226.533783) (xy 129.003263 -226.584555)
			(xy 129.012362 -226.637607) (xy 129.01295 -226.66452) (xy 129.318507 -226.66452) (xy 129.322602 -226.613792)
			(xy 129.334781 -226.564378) (xy 129.354729 -226.517558) (xy 129.38193 -226.474544) (xy 129.415678 -226.43645)
			(xy 129.4551 -226.404263) (xy 129.499174 -226.378817) (xy 129.54676 -226.36077) (xy 129.596624 -226.35059)
			(xy 129.647476 -226.348541) (xy 129.697997 -226.354675) (xy 129.746881 -226.368835) (xy 129.79286 -226.390652)
			(xy 129.834744 -226.419562) (xy 129.871448 -226.454817) (xy 129.902021 -226.495503) (xy 129.925672 -226.540566)
			(xy 129.941788 -226.58884) (xy 129.949952 -226.639074) (xy 129.950464 -226.66452) (xy 129.949961 -226.689509)
			(xy 130.257278 -226.689509) (xy 130.257278 -226.639531) (xy 130.265097 -226.590168) (xy 130.280541 -226.542636)
			(xy 130.303231 -226.498104) (xy 130.332607 -226.457671) (xy 130.367947 -226.422331) (xy 130.40838 -226.392955)
			(xy 130.452912 -226.370265) (xy 130.500444 -226.354821) (xy 130.549807 -226.347002) (xy 130.599785 -226.347002)
			(xy 130.649148 -226.354821) (xy 130.69668 -226.370265) (xy 130.741212 -226.392955) (xy 130.781645 -226.422331)
			(xy 130.816985 -226.457671) (xy 130.846361 -226.498104) (xy 130.869051 -226.542636) (xy 130.884495 -226.590168)
			(xy 130.892314 -226.639531) (xy 130.892804 -226.66452) (xy 131.198615 -226.66452) (xy 131.20271 -226.613792)
			(xy 131.214889 -226.564378) (xy 131.234837 -226.517558) (xy 131.262038 -226.474544) (xy 131.295786 -226.43645)
			(xy 131.335208 -226.404263) (xy 131.379282 -226.378817) (xy 131.426868 -226.36077) (xy 131.476732 -226.35059)
			(xy 131.527584 -226.348541) (xy 131.578105 -226.354675) (xy 131.626989 -226.368835) (xy 131.672968 -226.390652)
			(xy 131.714852 -226.419562) (xy 131.751556 -226.454817) (xy 131.782129 -226.495503) (xy 131.80578 -226.540566)
			(xy 131.821896 -226.58884) (xy 131.83006 -226.639074) (xy 131.830572 -226.66452) (xy 132.138415 -226.66452)
			(xy 132.14251 -226.613792) (xy 132.154689 -226.564378) (xy 132.174637 -226.517558) (xy 132.201838 -226.474544)
			(xy 132.235586 -226.43645) (xy 132.275008 -226.404263) (xy 132.319082 -226.378817) (xy 132.366668 -226.36077)
			(xy 132.416532 -226.35059) (xy 132.467384 -226.348541) (xy 132.517905 -226.354675) (xy 132.566789 -226.368835)
			(xy 132.612768 -226.390652) (xy 132.654652 -226.419562) (xy 132.691356 -226.454817) (xy 132.721929 -226.495503)
			(xy 132.74558 -226.540566) (xy 132.761696 -226.58884) (xy 132.76986 -226.639074) (xy 132.770372 -226.66452)
			(xy 132.769869 -226.689509) (xy 133.077186 -226.689509) (xy 133.077186 -226.639531) (xy 133.085005 -226.590168)
			(xy 133.100449 -226.542636) (xy 133.123139 -226.498104) (xy 133.152515 -226.457671) (xy 133.187855 -226.422331)
			(xy 133.228288 -226.392955) (xy 133.27282 -226.370265) (xy 133.320352 -226.354821) (xy 133.369715 -226.347002)
			(xy 133.419693 -226.347002) (xy 133.469056 -226.354821) (xy 133.516588 -226.370265) (xy 133.56112 -226.392955)
			(xy 133.601553 -226.422331) (xy 133.636893 -226.457671) (xy 133.666269 -226.498104) (xy 133.688959 -226.542636)
			(xy 133.704403 -226.590168) (xy 133.712222 -226.639531) (xy 133.712712 -226.66452) (xy 134.018523 -226.66452)
			(xy 134.022618 -226.613792) (xy 134.034797 -226.564378) (xy 134.054745 -226.517558) (xy 134.081946 -226.474544)
			(xy 134.115694 -226.43645) (xy 134.155116 -226.404263) (xy 134.19919 -226.378817) (xy 134.246776 -226.36077)
			(xy 134.29664 -226.35059) (xy 134.347492 -226.348541) (xy 134.398013 -226.354675) (xy 134.446897 -226.368835)
			(xy 134.492876 -226.390652) (xy 134.53476 -226.419562) (xy 134.571464 -226.454817) (xy 134.602037 -226.495503)
			(xy 134.625688 -226.540566) (xy 134.641804 -226.58884) (xy 134.649968 -226.639074) (xy 134.65048 -226.66452)
			(xy 134.649977 -226.689509) (xy 134.957294 -226.689509) (xy 134.957294 -226.639531) (xy 134.965113 -226.590168)
			(xy 134.980557 -226.542636) (xy 135.003247 -226.498104) (xy 135.032623 -226.457671) (xy 135.067963 -226.422331)
			(xy 135.108396 -226.392955) (xy 135.152928 -226.370265) (xy 135.20046 -226.354821) (xy 135.249823 -226.347002)
			(xy 135.299801 -226.347002) (xy 135.349164 -226.354821) (xy 135.396696 -226.370265) (xy 135.441228 -226.392955)
			(xy 135.481661 -226.422331) (xy 135.517001 -226.457671) (xy 135.546377 -226.498104) (xy 135.569067 -226.542636)
			(xy 135.584511 -226.590168) (xy 135.59233 -226.639531) (xy 135.59282 -226.66452) (xy 135.898631 -226.66452)
			(xy 135.902726 -226.613792) (xy 135.914905 -226.564378) (xy 135.934853 -226.517558) (xy 135.962054 -226.474544)
			(xy 135.995802 -226.43645) (xy 136.035224 -226.404263) (xy 136.079298 -226.378817) (xy 136.126884 -226.36077)
			(xy 136.176748 -226.35059) (xy 136.2276 -226.348541) (xy 136.278121 -226.354675) (xy 136.327005 -226.368835)
			(xy 136.372984 -226.390652) (xy 136.414868 -226.419562) (xy 136.451572 -226.454817) (xy 136.482145 -226.495503)
			(xy 136.505796 -226.540566) (xy 136.521912 -226.58884) (xy 136.530076 -226.639074) (xy 136.530588 -226.66452)
			(xy 136.530085 -226.689509) (xy 136.837148 -226.689509) (xy 136.837148 -226.639531) (xy 136.844967 -226.590168)
			(xy 136.860411 -226.542636) (xy 136.883101 -226.498104) (xy 136.912477 -226.457671) (xy 136.947817 -226.422331)
			(xy 136.98825 -226.392955) (xy 137.032782 -226.370265) (xy 137.080314 -226.354821) (xy 137.129677 -226.347002)
			(xy 137.179655 -226.347002) (xy 137.229018 -226.354821) (xy 137.27655 -226.370265) (xy 137.321082 -226.392955)
			(xy 137.361515 -226.422331) (xy 137.396855 -226.457671) (xy 137.426231 -226.498104) (xy 137.448921 -226.542636)
			(xy 137.464365 -226.590168) (xy 137.472184 -226.639531) (xy 137.472674 -226.66452) (xy 137.778485 -226.66452)
			(xy 137.78258 -226.613792) (xy 137.794759 -226.564378) (xy 137.814707 -226.517558) (xy 137.841908 -226.474544)
			(xy 137.875656 -226.43645) (xy 137.915078 -226.404263) (xy 137.959152 -226.378817) (xy 138.006738 -226.36077)
			(xy 138.056602 -226.35059) (xy 138.107454 -226.348541) (xy 138.157975 -226.354675) (xy 138.206859 -226.368835)
			(xy 138.252838 -226.390652) (xy 138.294722 -226.419562) (xy 138.331426 -226.454817) (xy 138.361999 -226.495503)
			(xy 138.38565 -226.540566) (xy 138.401766 -226.58884) (xy 138.40993 -226.639074) (xy 138.410442 -226.66452)
			(xy 138.718539 -226.66452) (xy 138.722634 -226.613792) (xy 138.734813 -226.564378) (xy 138.754761 -226.517558)
			(xy 138.781962 -226.474544) (xy 138.81571 -226.43645) (xy 138.855132 -226.404263) (xy 138.899206 -226.378817)
			(xy 138.946792 -226.36077) (xy 138.996656 -226.35059) (xy 139.047508 -226.348541) (xy 139.098029 -226.354675)
			(xy 139.146913 -226.368835) (xy 139.192892 -226.390652) (xy 139.234776 -226.419562) (xy 139.27148 -226.454817)
			(xy 139.302053 -226.495503) (xy 139.325704 -226.540566) (xy 139.34182 -226.58884) (xy 139.349984 -226.639074)
			(xy 139.350496 -226.66452) (xy 139.349993 -226.689509) (xy 139.65731 -226.689509) (xy 139.65731 -226.639531)
			(xy 139.665129 -226.590168) (xy 139.680573 -226.542636) (xy 139.703263 -226.498104) (xy 139.732639 -226.457671)
			(xy 139.767979 -226.422331) (xy 139.808412 -226.392955) (xy 139.852944 -226.370265) (xy 139.900476 -226.354821)
			(xy 139.949839 -226.347002) (xy 139.999817 -226.347002) (xy 140.04918 -226.354821) (xy 140.096712 -226.370265)
			(xy 140.141244 -226.392955) (xy 140.181677 -226.422331) (xy 140.217017 -226.457671) (xy 140.246393 -226.498104)
			(xy 140.269083 -226.542636) (xy 140.284527 -226.590168) (xy 140.292346 -226.639531) (xy 140.292836 -226.66452)
			(xy 140.598647 -226.66452) (xy 140.602742 -226.613792) (xy 140.614921 -226.564378) (xy 140.634869 -226.517558)
			(xy 140.66207 -226.474544) (xy 140.695818 -226.43645) (xy 140.73524 -226.404263) (xy 140.779314 -226.378817)
			(xy 140.8269 -226.36077) (xy 140.876764 -226.35059) (xy 140.927616 -226.348541) (xy 140.978137 -226.354675)
			(xy 141.027021 -226.368835) (xy 141.073 -226.390652) (xy 141.114884 -226.419562) (xy 141.151588 -226.454817)
			(xy 141.182161 -226.495503) (xy 141.205812 -226.540566) (xy 141.221928 -226.58884) (xy 141.230092 -226.639074)
			(xy 141.230604 -226.66452) (xy 141.230101 -226.689509) (xy 141.537164 -226.689509) (xy 141.537164 -226.639531)
			(xy 141.544983 -226.590168) (xy 141.560427 -226.542636) (xy 141.583117 -226.498104) (xy 141.612493 -226.457671)
			(xy 141.647833 -226.422331) (xy 141.688266 -226.392955) (xy 141.732798 -226.370265) (xy 141.78033 -226.354821)
			(xy 141.829693 -226.347002) (xy 141.879671 -226.347002) (xy 141.929034 -226.354821) (xy 141.976566 -226.370265)
			(xy 142.021098 -226.392955) (xy 142.061531 -226.422331) (xy 142.096871 -226.457671) (xy 142.126247 -226.498104)
			(xy 142.148937 -226.542636) (xy 142.164381 -226.590168) (xy 142.1722 -226.639531) (xy 142.17269 -226.66452)
			(xy 142.478501 -226.66452) (xy 142.482596 -226.613792) (xy 142.494775 -226.564378) (xy 142.514723 -226.517558)
			(xy 142.541924 -226.474544) (xy 142.575672 -226.43645) (xy 142.615094 -226.404263) (xy 142.659168 -226.378817)
			(xy 142.706754 -226.36077) (xy 142.756618 -226.35059) (xy 142.80747 -226.348541) (xy 142.857991 -226.354675)
			(xy 142.906875 -226.368835) (xy 142.952854 -226.390652) (xy 142.994738 -226.419562) (xy 143.031442 -226.454817)
			(xy 143.062015 -226.495503) (xy 143.085666 -226.540566) (xy 143.101782 -226.58884) (xy 143.109946 -226.639074)
			(xy 143.110458 -226.66452) (xy 143.109955 -226.689509) (xy 143.417272 -226.689509) (xy 143.417272 -226.639531)
			(xy 143.425091 -226.590168) (xy 143.440535 -226.542636) (xy 143.463225 -226.498104) (xy 143.492601 -226.457671)
			(xy 143.527941 -226.422331) (xy 143.568374 -226.392955) (xy 143.612906 -226.370265) (xy 143.660438 -226.354821)
			(xy 143.709801 -226.347002) (xy 143.759779 -226.347002) (xy 143.809142 -226.354821) (xy 143.856674 -226.370265)
			(xy 143.901206 -226.392955) (xy 143.941639 -226.422331) (xy 143.976979 -226.457671) (xy 144.006355 -226.498104)
			(xy 144.029045 -226.542636) (xy 144.044489 -226.590168) (xy 144.052308 -226.639531) (xy 144.052798 -226.66452)
			(xy 144.052308 -226.689509) (xy 144.044489 -226.738872) (xy 144.029045 -226.786404) (xy 144.006355 -226.830936)
			(xy 143.976979 -226.871369) (xy 143.941639 -226.906709) (xy 143.901206 -226.936085) (xy 143.856674 -226.958775)
			(xy 143.809142 -226.974219) (xy 143.759779 -226.982038) (xy 143.709801 -226.982038) (xy 143.660438 -226.974219)
			(xy 143.612906 -226.958775) (xy 143.568374 -226.936085) (xy 143.527941 -226.906709) (xy 143.492601 -226.871369)
			(xy 143.463225 -226.830936) (xy 143.440535 -226.786404) (xy 143.425091 -226.738872) (xy 143.417272 -226.689509)
			(xy 143.109955 -226.689509) (xy 143.109946 -226.689966) (xy 143.101782 -226.7402) (xy 143.085666 -226.788474)
			(xy 143.062015 -226.833537) (xy 143.031442 -226.874223) (xy 142.994738 -226.909478) (xy 142.952854 -226.938388)
			(xy 142.906875 -226.960205) (xy 142.857991 -226.974365) (xy 142.80747 -226.980499) (xy 142.756618 -226.97845)
			(xy 142.706754 -226.96827) (xy 142.659168 -226.950223) (xy 142.615094 -226.924777) (xy 142.575672 -226.89259)
			(xy 142.541924 -226.854496) (xy 142.514723 -226.811482) (xy 142.494775 -226.764662) (xy 142.482596 -226.715248)
			(xy 142.478501 -226.66452) (xy 142.17269 -226.66452) (xy 142.1722 -226.689509) (xy 142.164381 -226.738872)
			(xy 142.148937 -226.786404) (xy 142.126247 -226.830936) (xy 142.096871 -226.871369) (xy 142.061531 -226.906709)
			(xy 142.021098 -226.936085) (xy 141.976566 -226.958775) (xy 141.929034 -226.974219) (xy 141.879671 -226.982038)
			(xy 141.829693 -226.982038) (xy 141.78033 -226.974219) (xy 141.732798 -226.958775) (xy 141.688266 -226.936085)
			(xy 141.647833 -226.906709) (xy 141.612493 -226.871369) (xy 141.583117 -226.830936) (xy 141.560427 -226.786404)
			(xy 141.544983 -226.738872) (xy 141.537164 -226.689509) (xy 141.230101 -226.689509) (xy 141.230092 -226.689966)
			(xy 141.221928 -226.7402) (xy 141.205812 -226.788474) (xy 141.182161 -226.833537) (xy 141.151588 -226.874223)
			(xy 141.114884 -226.909478) (xy 141.073 -226.938388) (xy 141.027021 -226.960205) (xy 140.978137 -226.974365)
			(xy 140.927616 -226.980499) (xy 140.876764 -226.97845) (xy 140.8269 -226.96827) (xy 140.779314 -226.950223)
			(xy 140.73524 -226.924777) (xy 140.695818 -226.89259) (xy 140.66207 -226.854496) (xy 140.634869 -226.811482)
			(xy 140.614921 -226.764662) (xy 140.602742 -226.715248) (xy 140.598647 -226.66452) (xy 140.292836 -226.66452)
			(xy 140.292346 -226.689509) (xy 140.284527 -226.738872) (xy 140.269083 -226.786404) (xy 140.246393 -226.830936)
			(xy 140.217017 -226.871369) (xy 140.181677 -226.906709) (xy 140.141244 -226.936085) (xy 140.096712 -226.958775)
			(xy 140.04918 -226.974219) (xy 139.999817 -226.982038) (xy 139.949839 -226.982038) (xy 139.900476 -226.974219)
			(xy 139.852944 -226.958775) (xy 139.808412 -226.936085) (xy 139.767979 -226.906709) (xy 139.732639 -226.871369)
			(xy 139.703263 -226.830936) (xy 139.680573 -226.786404) (xy 139.665129 -226.738872) (xy 139.65731 -226.689509)
			(xy 139.349993 -226.689509) (xy 139.349984 -226.689966) (xy 139.34182 -226.7402) (xy 139.325704 -226.788474)
			(xy 139.302053 -226.833537) (xy 139.27148 -226.874223) (xy 139.234776 -226.909478) (xy 139.192892 -226.938388)
			(xy 139.146913 -226.960205) (xy 139.098029 -226.974365) (xy 139.047508 -226.980499) (xy 138.996656 -226.97845)
			(xy 138.946792 -226.96827) (xy 138.899206 -226.950223) (xy 138.855132 -226.924777) (xy 138.81571 -226.89259)
			(xy 138.781962 -226.854496) (xy 138.754761 -226.811482) (xy 138.734813 -226.764662) (xy 138.722634 -226.715248)
			(xy 138.718539 -226.66452) (xy 138.410442 -226.66452) (xy 138.40993 -226.689966) (xy 138.401766 -226.7402)
			(xy 138.38565 -226.788474) (xy 138.361999 -226.833537) (xy 138.331426 -226.874223) (xy 138.294722 -226.909478)
			(xy 138.252838 -226.938388) (xy 138.206859 -226.960205) (xy 138.157975 -226.974365) (xy 138.107454 -226.980499)
			(xy 138.056602 -226.97845) (xy 138.006738 -226.96827) (xy 137.959152 -226.950223) (xy 137.915078 -226.924777)
			(xy 137.875656 -226.89259) (xy 137.841908 -226.854496) (xy 137.814707 -226.811482) (xy 137.794759 -226.764662)
			(xy 137.78258 -226.715248) (xy 137.778485 -226.66452) (xy 137.472674 -226.66452) (xy 137.472184 -226.689509)
			(xy 137.464365 -226.738872) (xy 137.448921 -226.786404) (xy 137.426231 -226.830936) (xy 137.396855 -226.871369)
			(xy 137.361515 -226.906709) (xy 137.321082 -226.936085) (xy 137.27655 -226.958775) (xy 137.229018 -226.974219)
			(xy 137.179655 -226.982038) (xy 137.129677 -226.982038) (xy 137.080314 -226.974219) (xy 137.032782 -226.958775)
			(xy 136.98825 -226.936085) (xy 136.947817 -226.906709) (xy 136.912477 -226.871369) (xy 136.883101 -226.830936)
			(xy 136.860411 -226.786404) (xy 136.844967 -226.738872) (xy 136.837148 -226.689509) (xy 136.530085 -226.689509)
			(xy 136.530076 -226.689966) (xy 136.521912 -226.7402) (xy 136.505796 -226.788474) (xy 136.482145 -226.833537)
			(xy 136.451572 -226.874223) (xy 136.414868 -226.909478) (xy 136.372984 -226.938388) (xy 136.327005 -226.960205)
			(xy 136.278121 -226.974365) (xy 136.2276 -226.980499) (xy 136.176748 -226.97845) (xy 136.126884 -226.96827)
			(xy 136.079298 -226.950223) (xy 136.035224 -226.924777) (xy 135.995802 -226.89259) (xy 135.962054 -226.854496)
			(xy 135.934853 -226.811482) (xy 135.914905 -226.764662) (xy 135.902726 -226.715248) (xy 135.898631 -226.66452)
			(xy 135.59282 -226.66452) (xy 135.59233 -226.689509) (xy 135.584511 -226.738872) (xy 135.569067 -226.786404)
			(xy 135.546377 -226.830936) (xy 135.517001 -226.871369) (xy 135.481661 -226.906709) (xy 135.441228 -226.936085)
			(xy 135.396696 -226.958775) (xy 135.349164 -226.974219) (xy 135.299801 -226.982038) (xy 135.249823 -226.982038)
			(xy 135.20046 -226.974219) (xy 135.152928 -226.958775) (xy 135.108396 -226.936085) (xy 135.067963 -226.906709)
			(xy 135.032623 -226.871369) (xy 135.003247 -226.830936) (xy 134.980557 -226.786404) (xy 134.965113 -226.738872)
			(xy 134.957294 -226.689509) (xy 134.649977 -226.689509) (xy 134.649968 -226.689966) (xy 134.641804 -226.7402)
			(xy 134.625688 -226.788474) (xy 134.602037 -226.833537) (xy 134.571464 -226.874223) (xy 134.53476 -226.909478)
			(xy 134.492876 -226.938388) (xy 134.446897 -226.960205) (xy 134.398013 -226.974365) (xy 134.347492 -226.980499)
			(xy 134.29664 -226.97845) (xy 134.246776 -226.96827) (xy 134.19919 -226.950223) (xy 134.155116 -226.924777)
			(xy 134.115694 -226.89259) (xy 134.081946 -226.854496) (xy 134.054745 -226.811482) (xy 134.034797 -226.764662)
			(xy 134.022618 -226.715248) (xy 134.018523 -226.66452) (xy 133.712712 -226.66452) (xy 133.712222 -226.689509)
			(xy 133.704403 -226.738872) (xy 133.688959 -226.786404) (xy 133.666269 -226.830936) (xy 133.636893 -226.871369)
			(xy 133.601553 -226.906709) (xy 133.56112 -226.936085) (xy 133.516588 -226.958775) (xy 133.469056 -226.974219)
			(xy 133.419693 -226.982038) (xy 133.369715 -226.982038) (xy 133.320352 -226.974219) (xy 133.27282 -226.958775)
			(xy 133.228288 -226.936085) (xy 133.187855 -226.906709) (xy 133.152515 -226.871369) (xy 133.123139 -226.830936)
			(xy 133.100449 -226.786404) (xy 133.085005 -226.738872) (xy 133.077186 -226.689509) (xy 132.769869 -226.689509)
			(xy 132.76986 -226.689966) (xy 132.761696 -226.7402) (xy 132.74558 -226.788474) (xy 132.721929 -226.833537)
			(xy 132.691356 -226.874223) (xy 132.654652 -226.909478) (xy 132.612768 -226.938388) (xy 132.566789 -226.960205)
			(xy 132.517905 -226.974365) (xy 132.467384 -226.980499) (xy 132.416532 -226.97845) (xy 132.366668 -226.96827)
			(xy 132.319082 -226.950223) (xy 132.275008 -226.924777) (xy 132.235586 -226.89259) (xy 132.201838 -226.854496)
			(xy 132.174637 -226.811482) (xy 132.154689 -226.764662) (xy 132.14251 -226.715248) (xy 132.138415 -226.66452)
			(xy 131.830572 -226.66452) (xy 131.83006 -226.689966) (xy 131.821896 -226.7402) (xy 131.80578 -226.788474)
			(xy 131.782129 -226.833537) (xy 131.751556 -226.874223) (xy 131.714852 -226.909478) (xy 131.672968 -226.938388)
			(xy 131.626989 -226.960205) (xy 131.578105 -226.974365) (xy 131.527584 -226.980499) (xy 131.476732 -226.97845)
			(xy 131.426868 -226.96827) (xy 131.379282 -226.950223) (xy 131.335208 -226.924777) (xy 131.295786 -226.89259)
			(xy 131.262038 -226.854496) (xy 131.234837 -226.811482) (xy 131.214889 -226.764662) (xy 131.20271 -226.715248)
			(xy 131.198615 -226.66452) (xy 130.892804 -226.66452) (xy 130.892314 -226.689509) (xy 130.884495 -226.738872)
			(xy 130.869051 -226.786404) (xy 130.846361 -226.830936) (xy 130.816985 -226.871369) (xy 130.781645 -226.906709)
			(xy 130.741212 -226.936085) (xy 130.69668 -226.958775) (xy 130.649148 -226.974219) (xy 130.599785 -226.982038)
			(xy 130.549807 -226.982038) (xy 130.500444 -226.974219) (xy 130.452912 -226.958775) (xy 130.40838 -226.936085)
			(xy 130.367947 -226.906709) (xy 130.332607 -226.871369) (xy 130.303231 -226.830936) (xy 130.280541 -226.786404)
			(xy 130.265097 -226.738872) (xy 130.257278 -226.689509) (xy 129.949961 -226.689509) (xy 129.949952 -226.689966)
			(xy 129.941788 -226.7402) (xy 129.925672 -226.788474) (xy 129.902021 -226.833537) (xy 129.871448 -226.874223)
			(xy 129.834744 -226.909478) (xy 129.79286 -226.938388) (xy 129.746881 -226.960205) (xy 129.697997 -226.974365)
			(xy 129.647476 -226.980499) (xy 129.596624 -226.97845) (xy 129.54676 -226.96827) (xy 129.499174 -226.950223)
			(xy 129.4551 -226.924777) (xy 129.415678 -226.89259) (xy 129.38193 -226.854496) (xy 129.354729 -226.811482)
			(xy 129.334781 -226.764662) (xy 129.322602 -226.715248) (xy 129.318507 -226.66452) (xy 129.01295 -226.66452)
			(xy 129.012458 -226.689528) (xy 129.004631 -226.738927) (xy 128.989172 -226.786494) (xy 128.966463 -226.831057)
			(xy 128.937063 -226.871519) (xy 128.901694 -226.906883) (xy 128.86123 -226.93628) (xy 128.816664 -226.958985)
			(xy 128.769096 -226.974438) (xy 128.719696 -226.98226) (xy 128.694688 -226.982782) (xy 128.667771 -226.982222)
			(xy 128.614707 -226.973158) (xy 128.563931 -226.955275) (xy 128.516899 -226.929084) (xy 128.495552 -226.912678)
			(xy 128.495298 -226.912424) (xy 128.493774 -226.911154) (xy 128.484653 -226.905049) (xy 128.463197 -226.900529)
			(xy 128.441816 -226.905385) (xy 128.432814 -226.911662) (xy 128.427734 -226.91598) (xy 128.324356 -227.019358)
			(xy 128.314729 -227.029623) (xy 128.301019 -227.054188) (xy 128.294532 -227.081561) (xy 128.295759 -227.109666)
			(xy 128.304608 -227.136369) (xy 128.320407 -227.159645) (xy 128.341957 -227.177727) (xy 128.354582 -227.18395)
			(xy 128.378267 -227.195107) (xy 128.421933 -227.223987) (xy 128.460284 -227.259622) (xy 128.492288 -227.301053)
			(xy 128.51708 -227.347162) (xy 128.533994 -227.396706) (xy 128.542572 -227.44835) (xy 128.54305 -227.474526)
			(xy 128.848607 -227.474526) (xy 128.852702 -227.423798) (xy 128.864881 -227.374384) (xy 128.884829 -227.327564)
			(xy 128.91203 -227.28455) (xy 128.945778 -227.246456) (xy 128.9852 -227.214269) (xy 129.029274 -227.188823)
			(xy 129.07686 -227.170776) (xy 129.126724 -227.160596) (xy 129.177576 -227.158547) (xy 129.228097 -227.164681)
			(xy 129.276981 -227.178841) (xy 129.32296 -227.200658) (xy 129.364844 -227.229568) (xy 129.401548 -227.264823)
			(xy 129.432121 -227.305509) (xy 129.455772 -227.350572) (xy 129.471888 -227.398846) (xy 129.480052 -227.44908)
			(xy 129.480564 -227.474526) (xy 130.728461 -227.474526) (xy 130.732556 -227.423798) (xy 130.744735 -227.374384)
			(xy 130.764683 -227.327564) (xy 130.791884 -227.28455) (xy 130.825632 -227.246456) (xy 130.865054 -227.214269)
			(xy 130.909128 -227.188823) (xy 130.956714 -227.170776) (xy 131.006578 -227.160596) (xy 131.05743 -227.158547)
			(xy 131.107951 -227.164681) (xy 131.156835 -227.178841) (xy 131.202814 -227.200658) (xy 131.244698 -227.229568)
			(xy 131.281402 -227.264823) (xy 131.311975 -227.305509) (xy 131.335626 -227.350572) (xy 131.351742 -227.398846)
			(xy 131.359906 -227.44908) (xy 131.360418 -227.474526) (xy 131.359915 -227.499515) (xy 131.667232 -227.499515)
			(xy 131.667232 -227.449537) (xy 131.675051 -227.400174) (xy 131.690495 -227.352642) (xy 131.713185 -227.30811)
			(xy 131.742561 -227.267677) (xy 131.777901 -227.232337) (xy 131.818334 -227.202961) (xy 131.862866 -227.180271)
			(xy 131.910398 -227.164827) (xy 131.959761 -227.157008) (xy 132.009739 -227.157008) (xy 132.059102 -227.164827)
			(xy 132.106634 -227.180271) (xy 132.151166 -227.202961) (xy 132.191599 -227.232337) (xy 132.226939 -227.267677)
			(xy 132.256315 -227.30811) (xy 132.279005 -227.352642) (xy 132.294449 -227.400174) (xy 132.302268 -227.449537)
			(xy 132.302758 -227.474526) (xy 132.608569 -227.474526) (xy 132.612664 -227.423798) (xy 132.624843 -227.374384)
			(xy 132.644791 -227.327564) (xy 132.671992 -227.28455) (xy 132.70574 -227.246456) (xy 132.745162 -227.214269)
			(xy 132.789236 -227.188823) (xy 132.836822 -227.170776) (xy 132.886686 -227.160596) (xy 132.937538 -227.158547)
			(xy 132.988059 -227.164681) (xy 133.036943 -227.178841) (xy 133.082922 -227.200658) (xy 133.124806 -227.229568)
			(xy 133.16151 -227.264823) (xy 133.192083 -227.305509) (xy 133.215734 -227.350572) (xy 133.23185 -227.398846)
			(xy 133.240014 -227.44908) (xy 133.240526 -227.474526) (xy 133.240023 -227.499515) (xy 133.54734 -227.499515)
			(xy 133.54734 -227.449537) (xy 133.555159 -227.400174) (xy 133.570603 -227.352642) (xy 133.593293 -227.30811)
			(xy 133.622669 -227.267677) (xy 133.658009 -227.232337) (xy 133.698442 -227.202961) (xy 133.742974 -227.180271)
			(xy 133.790506 -227.164827) (xy 133.839869 -227.157008) (xy 133.889847 -227.157008) (xy 133.93921 -227.164827)
			(xy 133.986742 -227.180271) (xy 134.031274 -227.202961) (xy 134.071707 -227.232337) (xy 134.107047 -227.267677)
			(xy 134.136423 -227.30811) (xy 134.159113 -227.352642) (xy 134.174557 -227.400174) (xy 134.182376 -227.449537)
			(xy 134.182866 -227.474526) (xy 134.488423 -227.474526) (xy 134.492518 -227.423798) (xy 134.504697 -227.374384)
			(xy 134.524645 -227.327564) (xy 134.551846 -227.28455) (xy 134.585594 -227.246456) (xy 134.625016 -227.214269)
			(xy 134.66909 -227.188823) (xy 134.716676 -227.170776) (xy 134.76654 -227.160596) (xy 134.817392 -227.158547)
			(xy 134.867913 -227.164681) (xy 134.916797 -227.178841) (xy 134.962776 -227.200658) (xy 135.00466 -227.229568)
			(xy 135.041364 -227.264823) (xy 135.071937 -227.305509) (xy 135.095588 -227.350572) (xy 135.111704 -227.398846)
			(xy 135.119868 -227.44908) (xy 135.12038 -227.474526) (xy 135.428477 -227.474526) (xy 135.432572 -227.423798)
			(xy 135.444751 -227.374384) (xy 135.464699 -227.327564) (xy 135.4919 -227.28455) (xy 135.525648 -227.246456)
			(xy 135.56507 -227.214269) (xy 135.609144 -227.188823) (xy 135.65673 -227.170776) (xy 135.706594 -227.160596)
			(xy 135.757446 -227.158547) (xy 135.807967 -227.164681) (xy 135.856851 -227.178841) (xy 135.90283 -227.200658)
			(xy 135.944714 -227.229568) (xy 135.981418 -227.264823) (xy 136.011991 -227.305509) (xy 136.035642 -227.350572)
			(xy 136.051758 -227.398846) (xy 136.059922 -227.44908) (xy 136.060434 -227.474526) (xy 137.308585 -227.474526)
			(xy 137.31268 -227.423798) (xy 137.324859 -227.374384) (xy 137.344807 -227.327564) (xy 137.372008 -227.28455)
			(xy 137.405756 -227.246456) (xy 137.445178 -227.214269) (xy 137.489252 -227.188823) (xy 137.536838 -227.170776)
			(xy 137.586702 -227.160596) (xy 137.637554 -227.158547) (xy 137.688075 -227.164681) (xy 137.736959 -227.178841)
			(xy 137.782938 -227.200658) (xy 137.824822 -227.229568) (xy 137.861526 -227.264823) (xy 137.892099 -227.305509)
			(xy 137.91575 -227.350572) (xy 137.931866 -227.398846) (xy 137.94003 -227.44908) (xy 137.940542 -227.474526)
			(xy 137.940039 -227.499515) (xy 138.247356 -227.499515) (xy 138.247356 -227.449537) (xy 138.255175 -227.400174)
			(xy 138.270619 -227.352642) (xy 138.293309 -227.30811) (xy 138.322685 -227.267677) (xy 138.358025 -227.232337)
			(xy 138.398458 -227.202961) (xy 138.44299 -227.180271) (xy 138.490522 -227.164827) (xy 138.539885 -227.157008)
			(xy 138.589863 -227.157008) (xy 138.639226 -227.164827) (xy 138.686758 -227.180271) (xy 138.73129 -227.202961)
			(xy 138.771723 -227.232337) (xy 138.807063 -227.267677) (xy 138.836439 -227.30811) (xy 138.859129 -227.352642)
			(xy 138.874573 -227.400174) (xy 138.882392 -227.449537) (xy 138.882882 -227.474526) (xy 139.188439 -227.474526)
			(xy 139.192534 -227.423798) (xy 139.204713 -227.374384) (xy 139.224661 -227.327564) (xy 139.251862 -227.28455)
			(xy 139.28561 -227.246456) (xy 139.325032 -227.214269) (xy 139.369106 -227.188823) (xy 139.416692 -227.170776)
			(xy 139.466556 -227.160596) (xy 139.517408 -227.158547) (xy 139.567929 -227.164681) (xy 139.616813 -227.178841)
			(xy 139.662792 -227.200658) (xy 139.704676 -227.229568) (xy 139.74138 -227.264823) (xy 139.771953 -227.305509)
			(xy 139.795604 -227.350572) (xy 139.81172 -227.398846) (xy 139.819884 -227.44908) (xy 139.820396 -227.474526)
			(xy 139.819893 -227.499515) (xy 140.12721 -227.499515) (xy 140.12721 -227.449537) (xy 140.135029 -227.400174)
			(xy 140.150473 -227.352642) (xy 140.173163 -227.30811) (xy 140.202539 -227.267677) (xy 140.237879 -227.232337)
			(xy 140.278312 -227.202961) (xy 140.322844 -227.180271) (xy 140.370376 -227.164827) (xy 140.419739 -227.157008)
			(xy 140.469717 -227.157008) (xy 140.51908 -227.164827) (xy 140.566612 -227.180271) (xy 140.611144 -227.202961)
			(xy 140.651577 -227.232337) (xy 140.686917 -227.267677) (xy 140.716293 -227.30811) (xy 140.738983 -227.352642)
			(xy 140.754427 -227.400174) (xy 140.762246 -227.449537) (xy 140.762736 -227.474526) (xy 141.068547 -227.474526)
			(xy 141.072642 -227.423798) (xy 141.084821 -227.374384) (xy 141.104769 -227.327564) (xy 141.13197 -227.28455)
			(xy 141.165718 -227.246456) (xy 141.20514 -227.214269) (xy 141.249214 -227.188823) (xy 141.2968 -227.170776)
			(xy 141.346664 -227.160596) (xy 141.397516 -227.158547) (xy 141.448037 -227.164681) (xy 141.496921 -227.178841)
			(xy 141.5429 -227.200658) (xy 141.584784 -227.229568) (xy 141.621488 -227.264823) (xy 141.652061 -227.305509)
			(xy 141.675712 -227.350572) (xy 141.691828 -227.398846) (xy 141.699992 -227.44908) (xy 141.700504 -227.474526)
			(xy 142.008601 -227.474526) (xy 142.012696 -227.423798) (xy 142.024875 -227.374384) (xy 142.044823 -227.327564)
			(xy 142.072024 -227.28455) (xy 142.105772 -227.246456) (xy 142.145194 -227.214269) (xy 142.189268 -227.188823)
			(xy 142.236854 -227.170776) (xy 142.286718 -227.160596) (xy 142.33757 -227.158547) (xy 142.388091 -227.164681)
			(xy 142.436975 -227.178841) (xy 142.482954 -227.200658) (xy 142.524838 -227.229568) (xy 142.561542 -227.264823)
			(xy 142.592115 -227.305509) (xy 142.615766 -227.350572) (xy 142.631882 -227.398846) (xy 142.640046 -227.44908)
			(xy 142.640558 -227.474526) (xy 142.640046 -227.499972) (xy 142.631882 -227.550206) (xy 142.615766 -227.59848)
			(xy 142.592115 -227.643543) (xy 142.561542 -227.684229) (xy 142.524838 -227.719484) (xy 142.482954 -227.748394)
			(xy 142.436975 -227.770211) (xy 142.388091 -227.784371) (xy 142.33757 -227.790505) (xy 142.286718 -227.788456)
			(xy 142.236854 -227.778276) (xy 142.189268 -227.760229) (xy 142.145194 -227.734783) (xy 142.105772 -227.702596)
			(xy 142.072024 -227.664502) (xy 142.044823 -227.621488) (xy 142.024875 -227.574668) (xy 142.012696 -227.525254)
			(xy 142.008601 -227.474526) (xy 141.700504 -227.474526) (xy 141.699992 -227.499972) (xy 141.691828 -227.550206)
			(xy 141.675712 -227.59848) (xy 141.652061 -227.643543) (xy 141.621488 -227.684229) (xy 141.584784 -227.719484)
			(xy 141.5429 -227.748394) (xy 141.496921 -227.770211) (xy 141.448037 -227.784371) (xy 141.397516 -227.790505)
			(xy 141.346664 -227.788456) (xy 141.2968 -227.778276) (xy 141.249214 -227.760229) (xy 141.20514 -227.734783)
			(xy 141.165718 -227.702596) (xy 141.13197 -227.664502) (xy 141.104769 -227.621488) (xy 141.084821 -227.574668)
			(xy 141.072642 -227.525254) (xy 141.068547 -227.474526) (xy 140.762736 -227.474526) (xy 140.762246 -227.499515)
			(xy 140.754427 -227.548878) (xy 140.738983 -227.59641) (xy 140.716293 -227.640942) (xy 140.686917 -227.681375)
			(xy 140.651577 -227.716715) (xy 140.611144 -227.746091) (xy 140.566612 -227.768781) (xy 140.51908 -227.784225)
			(xy 140.469717 -227.792044) (xy 140.419739 -227.792044) (xy 140.370376 -227.784225) (xy 140.322844 -227.768781)
			(xy 140.278312 -227.746091) (xy 140.237879 -227.716715) (xy 140.202539 -227.681375) (xy 140.173163 -227.640942)
			(xy 140.150473 -227.59641) (xy 140.135029 -227.548878) (xy 140.12721 -227.499515) (xy 139.819893 -227.499515)
			(xy 139.819884 -227.499972) (xy 139.81172 -227.550206) (xy 139.795604 -227.59848) (xy 139.771953 -227.643543)
			(xy 139.74138 -227.684229) (xy 139.704676 -227.719484) (xy 139.662792 -227.748394) (xy 139.616813 -227.770211)
			(xy 139.567929 -227.784371) (xy 139.517408 -227.790505) (xy 139.466556 -227.788456) (xy 139.416692 -227.778276)
			(xy 139.369106 -227.760229) (xy 139.325032 -227.734783) (xy 139.28561 -227.702596) (xy 139.251862 -227.664502)
			(xy 139.224661 -227.621488) (xy 139.204713 -227.574668) (xy 139.192534 -227.525254) (xy 139.188439 -227.474526)
			(xy 138.882882 -227.474526) (xy 138.882392 -227.499515) (xy 138.874573 -227.548878) (xy 138.859129 -227.59641)
			(xy 138.836439 -227.640942) (xy 138.807063 -227.681375) (xy 138.771723 -227.716715) (xy 138.73129 -227.746091)
			(xy 138.686758 -227.768781) (xy 138.639226 -227.784225) (xy 138.589863 -227.792044) (xy 138.539885 -227.792044)
			(xy 138.490522 -227.784225) (xy 138.44299 -227.768781) (xy 138.398458 -227.746091) (xy 138.358025 -227.716715)
			(xy 138.322685 -227.681375) (xy 138.293309 -227.640942) (xy 138.270619 -227.59641) (xy 138.255175 -227.548878)
			(xy 138.247356 -227.499515) (xy 137.940039 -227.499515) (xy 137.94003 -227.499972) (xy 137.931866 -227.550206)
			(xy 137.91575 -227.59848) (xy 137.892099 -227.643543) (xy 137.861526 -227.684229) (xy 137.824822 -227.719484)
			(xy 137.782938 -227.748394) (xy 137.736959 -227.770211) (xy 137.688075 -227.784371) (xy 137.637554 -227.790505)
			(xy 137.586702 -227.788456) (xy 137.536838 -227.778276) (xy 137.489252 -227.760229) (xy 137.445178 -227.734783)
			(xy 137.405756 -227.702596) (xy 137.372008 -227.664502) (xy 137.344807 -227.621488) (xy 137.324859 -227.574668)
			(xy 137.31268 -227.525254) (xy 137.308585 -227.474526) (xy 136.060434 -227.474526) (xy 136.059922 -227.499972)
			(xy 136.051758 -227.550206) (xy 136.035642 -227.59848) (xy 136.011991 -227.643543) (xy 135.981418 -227.684229)
			(xy 135.944714 -227.719484) (xy 135.90283 -227.748394) (xy 135.856851 -227.770211) (xy 135.807967 -227.784371)
			(xy 135.757446 -227.790505) (xy 135.706594 -227.788456) (xy 135.65673 -227.778276) (xy 135.609144 -227.760229)
			(xy 135.56507 -227.734783) (xy 135.525648 -227.702596) (xy 135.4919 -227.664502) (xy 135.464699 -227.621488)
			(xy 135.444751 -227.574668) (xy 135.432572 -227.525254) (xy 135.428477 -227.474526) (xy 135.12038 -227.474526)
			(xy 135.119868 -227.499972) (xy 135.111704 -227.550206) (xy 135.095588 -227.59848) (xy 135.071937 -227.643543)
			(xy 135.041364 -227.684229) (xy 135.00466 -227.719484) (xy 134.962776 -227.748394) (xy 134.916797 -227.770211)
			(xy 134.867913 -227.784371) (xy 134.817392 -227.790505) (xy 134.76654 -227.788456) (xy 134.716676 -227.778276)
			(xy 134.66909 -227.760229) (xy 134.625016 -227.734783) (xy 134.585594 -227.702596) (xy 134.551846 -227.664502)
			(xy 134.524645 -227.621488) (xy 134.504697 -227.574668) (xy 134.492518 -227.525254) (xy 134.488423 -227.474526)
			(xy 134.182866 -227.474526) (xy 134.182376 -227.499515) (xy 134.174557 -227.548878) (xy 134.159113 -227.59641)
			(xy 134.136423 -227.640942) (xy 134.107047 -227.681375) (xy 134.071707 -227.716715) (xy 134.031274 -227.746091)
			(xy 133.986742 -227.768781) (xy 133.93921 -227.784225) (xy 133.889847 -227.792044) (xy 133.839869 -227.792044)
			(xy 133.790506 -227.784225) (xy 133.742974 -227.768781) (xy 133.698442 -227.746091) (xy 133.658009 -227.716715)
			(xy 133.622669 -227.681375) (xy 133.593293 -227.640942) (xy 133.570603 -227.59641) (xy 133.555159 -227.548878)
			(xy 133.54734 -227.499515) (xy 133.240023 -227.499515) (xy 133.240014 -227.499972) (xy 133.23185 -227.550206)
			(xy 133.215734 -227.59848) (xy 133.192083 -227.643543) (xy 133.16151 -227.684229) (xy 133.124806 -227.719484)
			(xy 133.082922 -227.748394) (xy 133.036943 -227.770211) (xy 132.988059 -227.784371) (xy 132.937538 -227.790505)
			(xy 132.886686 -227.788456) (xy 132.836822 -227.778276) (xy 132.789236 -227.760229) (xy 132.745162 -227.734783)
			(xy 132.70574 -227.702596) (xy 132.671992 -227.664502) (xy 132.644791 -227.621488) (xy 132.624843 -227.574668)
			(xy 132.612664 -227.525254) (xy 132.608569 -227.474526) (xy 132.302758 -227.474526) (xy 132.302268 -227.499515)
			(xy 132.294449 -227.548878) (xy 132.279005 -227.59641) (xy 132.256315 -227.640942) (xy 132.226939 -227.681375)
			(xy 132.191599 -227.716715) (xy 132.151166 -227.746091) (xy 132.106634 -227.768781) (xy 132.059102 -227.784225)
			(xy 132.009739 -227.792044) (xy 131.959761 -227.792044) (xy 131.910398 -227.784225) (xy 131.862866 -227.768781)
			(xy 131.818334 -227.746091) (xy 131.777901 -227.716715) (xy 131.742561 -227.681375) (xy 131.713185 -227.640942)
			(xy 131.690495 -227.59641) (xy 131.675051 -227.548878) (xy 131.667232 -227.499515) (xy 131.359915 -227.499515)
			(xy 131.359906 -227.499972) (xy 131.351742 -227.550206) (xy 131.335626 -227.59848) (xy 131.311975 -227.643543)
			(xy 131.281402 -227.684229) (xy 131.244698 -227.719484) (xy 131.202814 -227.748394) (xy 131.156835 -227.770211)
			(xy 131.107951 -227.784371) (xy 131.05743 -227.790505) (xy 131.006578 -227.788456) (xy 130.956714 -227.778276)
			(xy 130.909128 -227.760229) (xy 130.865054 -227.734783) (xy 130.825632 -227.702596) (xy 130.791884 -227.664502)
			(xy 130.764683 -227.621488) (xy 130.744735 -227.574668) (xy 130.732556 -227.525254) (xy 130.728461 -227.474526)
			(xy 129.480564 -227.474526) (xy 129.480052 -227.499972) (xy 129.471888 -227.550206) (xy 129.455772 -227.59848)
			(xy 129.432121 -227.643543) (xy 129.401548 -227.684229) (xy 129.364844 -227.719484) (xy 129.32296 -227.748394)
			(xy 129.276981 -227.770211) (xy 129.228097 -227.784371) (xy 129.177576 -227.790505) (xy 129.126724 -227.788456)
			(xy 129.07686 -227.778276) (xy 129.029274 -227.760229) (xy 128.9852 -227.734783) (xy 128.945778 -227.702596)
			(xy 128.91203 -227.664502) (xy 128.884829 -227.621488) (xy 128.864881 -227.574668) (xy 128.852702 -227.525254)
			(xy 128.848607 -227.474526) (xy 128.54305 -227.474526) (xy 128.542557 -227.499533) (xy 128.53473 -227.548932)
			(xy 128.519271 -227.596498) (xy 128.496561 -227.64106) (xy 128.467161 -227.681521) (xy 128.431792 -227.716885)
			(xy 128.391328 -227.746281) (xy 128.346763 -227.768985) (xy 128.299195 -227.784438) (xy 128.249796 -227.79226)
			(xy 128.224788 -227.792788) (xy 128.199018 -227.79229) (xy 128.148151 -227.783986) (xy 128.099285 -227.767597)
			(xy 128.053698 -227.743551) (xy 128.012578 -227.712477) (xy 127.977001 -227.675185) (xy 127.947896 -227.632649)
			(xy 127.926022 -227.58598) (xy 127.91195 -227.536398) (xy 127.908558 -227.510848) (xy 127.908558 -227.510594)
			(xy 127.908304 -227.508308) (xy 127.906521 -227.499671) (xy 127.897943 -227.484278) (xy 127.884634 -227.472728)
			(xy 127.876554 -227.469192) (xy 127.860044 -227.463096) (xy 127.859536 -227.463096) (xy 127.790702 -227.438966)
			(xy 127.781593 -227.436189) (xy 127.762577 -227.436875) (xy 127.745119 -227.444445) (xy 127.738124 -227.450904)
			(xy 127.566166 -227.622862) (xy 127.56261 -227.629212) (xy 127.547734 -227.654622) (xy 127.510126 -227.699919)
			(xy 127.464831 -227.737528) (xy 127.43942 -227.752402) (xy 127.43307 -227.755958) (xy 127.107696 -228.081332)
			(xy 127.102296 -228.087217) (xy 127.095056 -228.101444) (xy 127.093472 -228.109272) (xy 127.093472 -228.109526)
			(xy 127.093218 -228.111812) (xy 127.097536 -228.138482) (xy 127.098298 -228.140006) (xy 127.100838 -228.14534)
			(xy 127.110921 -228.1671) (xy 127.12517 -228.212891) (xy 127.132399 -228.2603) (xy 127.132842 -228.284278)
			(xy 127.132842 -228.284532) (xy 127.438399 -228.284532) (xy 127.442494 -228.233804) (xy 127.454673 -228.18439)
			(xy 127.474621 -228.13757) (xy 127.501822 -228.094556) (xy 127.53557 -228.056462) (xy 127.574992 -228.024275)
			(xy 127.619066 -227.998829) (xy 127.666652 -227.980782) (xy 127.716516 -227.970602) (xy 127.767368 -227.968553)
			(xy 127.817889 -227.974687) (xy 127.866773 -227.988847) (xy 127.912752 -228.010664) (xy 127.954636 -228.039574)
			(xy 127.99134 -228.074829) (xy 128.021913 -228.115515) (xy 128.045564 -228.160578) (xy 128.06168 -228.208852)
			(xy 128.069844 -228.259086) (xy 128.070356 -228.284532) (xy 128.069853 -228.309521) (xy 128.37717 -228.309521)
			(xy 128.37717 -228.259543) (xy 128.384989 -228.21018) (xy 128.400433 -228.162648) (xy 128.423123 -228.118116)
			(xy 128.452499 -228.077683) (xy 128.487839 -228.042343) (xy 128.528272 -228.012967) (xy 128.572804 -227.990277)
			(xy 128.620336 -227.974833) (xy 128.669699 -227.967014) (xy 128.719677 -227.967014) (xy 128.76904 -227.974833)
			(xy 128.816572 -227.990277) (xy 128.861104 -228.012967) (xy 128.901537 -228.042343) (xy 128.936877 -228.077683)
			(xy 128.966253 -228.118116) (xy 128.988943 -228.162648) (xy 129.004387 -228.21018) (xy 129.012206 -228.259543)
			(xy 129.012696 -228.284532) (xy 129.318507 -228.284532) (xy 129.322602 -228.233804) (xy 129.334781 -228.18439)
			(xy 129.354729 -228.13757) (xy 129.38193 -228.094556) (xy 129.415678 -228.056462) (xy 129.4551 -228.024275)
			(xy 129.499174 -227.998829) (xy 129.54676 -227.980782) (xy 129.596624 -227.970602) (xy 129.647476 -227.968553)
			(xy 129.697997 -227.974687) (xy 129.746881 -227.988847) (xy 129.79286 -228.010664) (xy 129.834744 -228.039574)
			(xy 129.871448 -228.074829) (xy 129.902021 -228.115515) (xy 129.925672 -228.160578) (xy 129.941788 -228.208852)
			(xy 129.949952 -228.259086) (xy 129.950464 -228.284532) (xy 129.949961 -228.309521) (xy 130.257278 -228.309521)
			(xy 130.257278 -228.259543) (xy 130.265097 -228.21018) (xy 130.280541 -228.162648) (xy 130.303231 -228.118116)
			(xy 130.332607 -228.077683) (xy 130.367947 -228.042343) (xy 130.40838 -228.012967) (xy 130.452912 -227.990277)
			(xy 130.500444 -227.974833) (xy 130.549807 -227.967014) (xy 130.599785 -227.967014) (xy 130.649148 -227.974833)
			(xy 130.69668 -227.990277) (xy 130.741212 -228.012967) (xy 130.781645 -228.042343) (xy 130.816985 -228.077683)
			(xy 130.846361 -228.118116) (xy 130.869051 -228.162648) (xy 130.884495 -228.21018) (xy 130.892314 -228.259543)
			(xy 130.892804 -228.284532) (xy 131.198615 -228.284532) (xy 131.20271 -228.233804) (xy 131.214889 -228.18439)
			(xy 131.234837 -228.13757) (xy 131.262038 -228.094556) (xy 131.295786 -228.056462) (xy 131.335208 -228.024275)
			(xy 131.379282 -227.998829) (xy 131.426868 -227.980782) (xy 131.476732 -227.970602) (xy 131.527584 -227.968553)
			(xy 131.578105 -227.974687) (xy 131.626989 -227.988847) (xy 131.672968 -228.010664) (xy 131.714852 -228.039574)
			(xy 131.751556 -228.074829) (xy 131.782129 -228.115515) (xy 131.80578 -228.160578) (xy 131.821896 -228.208852)
			(xy 131.83006 -228.259086) (xy 131.830572 -228.284532) (xy 132.138415 -228.284532) (xy 132.14251 -228.233804)
			(xy 132.154689 -228.18439) (xy 132.174637 -228.13757) (xy 132.201838 -228.094556) (xy 132.235586 -228.056462)
			(xy 132.275008 -228.024275) (xy 132.319082 -227.998829) (xy 132.366668 -227.980782) (xy 132.416532 -227.970602)
			(xy 132.467384 -227.968553) (xy 132.517905 -227.974687) (xy 132.566789 -227.988847) (xy 132.612768 -228.010664)
			(xy 132.654652 -228.039574) (xy 132.691356 -228.074829) (xy 132.721929 -228.115515) (xy 132.74558 -228.160578)
			(xy 132.761696 -228.208852) (xy 132.76986 -228.259086) (xy 132.770372 -228.284532) (xy 132.769869 -228.309521)
			(xy 133.077186 -228.309521) (xy 133.077186 -228.259543) (xy 133.085005 -228.21018) (xy 133.100449 -228.162648)
			(xy 133.123139 -228.118116) (xy 133.152515 -228.077683) (xy 133.187855 -228.042343) (xy 133.228288 -228.012967)
			(xy 133.27282 -227.990277) (xy 133.320352 -227.974833) (xy 133.369715 -227.967014) (xy 133.419693 -227.967014)
			(xy 133.469056 -227.974833) (xy 133.516588 -227.990277) (xy 133.56112 -228.012967) (xy 133.601553 -228.042343)
			(xy 133.636893 -228.077683) (xy 133.666269 -228.118116) (xy 133.688959 -228.162648) (xy 133.704403 -228.21018)
			(xy 133.712222 -228.259543) (xy 133.712712 -228.284532) (xy 134.018523 -228.284532) (xy 134.022618 -228.233804)
			(xy 134.034797 -228.18439) (xy 134.054745 -228.13757) (xy 134.081946 -228.094556) (xy 134.115694 -228.056462)
			(xy 134.155116 -228.024275) (xy 134.19919 -227.998829) (xy 134.246776 -227.980782) (xy 134.29664 -227.970602)
			(xy 134.347492 -227.968553) (xy 134.398013 -227.974687) (xy 134.446897 -227.988847) (xy 134.492876 -228.010664)
			(xy 134.53476 -228.039574) (xy 134.571464 -228.074829) (xy 134.602037 -228.115515) (xy 134.625688 -228.160578)
			(xy 134.641804 -228.208852) (xy 134.649968 -228.259086) (xy 134.65048 -228.284532) (xy 134.649977 -228.309521)
			(xy 134.957294 -228.309521) (xy 134.957294 -228.259543) (xy 134.965113 -228.21018) (xy 134.980557 -228.162648)
			(xy 135.003247 -228.118116) (xy 135.032623 -228.077683) (xy 135.067963 -228.042343) (xy 135.108396 -228.012967)
			(xy 135.152928 -227.990277) (xy 135.20046 -227.974833) (xy 135.249823 -227.967014) (xy 135.299801 -227.967014)
			(xy 135.349164 -227.974833) (xy 135.396696 -227.990277) (xy 135.441228 -228.012967) (xy 135.481661 -228.042343)
			(xy 135.517001 -228.077683) (xy 135.546377 -228.118116) (xy 135.569067 -228.162648) (xy 135.584511 -228.21018)
			(xy 135.59233 -228.259543) (xy 135.59282 -228.284532) (xy 135.898631 -228.284532) (xy 135.902726 -228.233804)
			(xy 135.914905 -228.18439) (xy 135.934853 -228.13757) (xy 135.962054 -228.094556) (xy 135.995802 -228.056462)
			(xy 136.035224 -228.024275) (xy 136.079298 -227.998829) (xy 136.126884 -227.980782) (xy 136.176748 -227.970602)
			(xy 136.2276 -227.968553) (xy 136.278121 -227.974687) (xy 136.327005 -227.988847) (xy 136.372984 -228.010664)
			(xy 136.414868 -228.039574) (xy 136.451572 -228.074829) (xy 136.482145 -228.115515) (xy 136.505796 -228.160578)
			(xy 136.521912 -228.208852) (xy 136.530076 -228.259086) (xy 136.530588 -228.284532) (xy 136.530085 -228.309521)
			(xy 136.837148 -228.309521) (xy 136.837148 -228.259543) (xy 136.844967 -228.21018) (xy 136.860411 -228.162648)
			(xy 136.883101 -228.118116) (xy 136.912477 -228.077683) (xy 136.947817 -228.042343) (xy 136.98825 -228.012967)
			(xy 137.032782 -227.990277) (xy 137.080314 -227.974833) (xy 137.129677 -227.967014) (xy 137.179655 -227.967014)
			(xy 137.229018 -227.974833) (xy 137.27655 -227.990277) (xy 137.321082 -228.012967) (xy 137.361515 -228.042343)
			(xy 137.396855 -228.077683) (xy 137.426231 -228.118116) (xy 137.448921 -228.162648) (xy 137.464365 -228.21018)
			(xy 137.472184 -228.259543) (xy 137.472674 -228.284532) (xy 137.778485 -228.284532) (xy 137.78258 -228.233804)
			(xy 137.794759 -228.18439) (xy 137.814707 -228.13757) (xy 137.841908 -228.094556) (xy 137.875656 -228.056462)
			(xy 137.915078 -228.024275) (xy 137.959152 -227.998829) (xy 138.006738 -227.980782) (xy 138.056602 -227.970602)
			(xy 138.107454 -227.968553) (xy 138.157975 -227.974687) (xy 138.206859 -227.988847) (xy 138.252838 -228.010664)
			(xy 138.294722 -228.039574) (xy 138.331426 -228.074829) (xy 138.361999 -228.115515) (xy 138.38565 -228.160578)
			(xy 138.401766 -228.208852) (xy 138.40993 -228.259086) (xy 138.410442 -228.284532) (xy 138.718539 -228.284532)
			(xy 138.722634 -228.233804) (xy 138.734813 -228.18439) (xy 138.754761 -228.13757) (xy 138.781962 -228.094556)
			(xy 138.81571 -228.056462) (xy 138.855132 -228.024275) (xy 138.899206 -227.998829) (xy 138.946792 -227.980782)
			(xy 138.996656 -227.970602) (xy 139.047508 -227.968553) (xy 139.098029 -227.974687) (xy 139.146913 -227.988847)
			(xy 139.192892 -228.010664) (xy 139.234776 -228.039574) (xy 139.27148 -228.074829) (xy 139.302053 -228.115515)
			(xy 139.325704 -228.160578) (xy 139.34182 -228.208852) (xy 139.349984 -228.259086) (xy 139.350496 -228.284532)
			(xy 139.349993 -228.309521) (xy 139.65731 -228.309521) (xy 139.65731 -228.259543) (xy 139.665129 -228.21018)
			(xy 139.680573 -228.162648) (xy 139.703263 -228.118116) (xy 139.732639 -228.077683) (xy 139.767979 -228.042343)
			(xy 139.808412 -228.012967) (xy 139.852944 -227.990277) (xy 139.900476 -227.974833) (xy 139.949839 -227.967014)
			(xy 139.999817 -227.967014) (xy 140.04918 -227.974833) (xy 140.096712 -227.990277) (xy 140.141244 -228.012967)
			(xy 140.181677 -228.042343) (xy 140.217017 -228.077683) (xy 140.246393 -228.118116) (xy 140.269083 -228.162648)
			(xy 140.284527 -228.21018) (xy 140.292346 -228.259543) (xy 140.292836 -228.284532) (xy 140.598647 -228.284532)
			(xy 140.602742 -228.233804) (xy 140.614921 -228.18439) (xy 140.634869 -228.13757) (xy 140.66207 -228.094556)
			(xy 140.695818 -228.056462) (xy 140.73524 -228.024275) (xy 140.779314 -227.998829) (xy 140.8269 -227.980782)
			(xy 140.876764 -227.970602) (xy 140.927616 -227.968553) (xy 140.978137 -227.974687) (xy 141.027021 -227.988847)
			(xy 141.073 -228.010664) (xy 141.114884 -228.039574) (xy 141.151588 -228.074829) (xy 141.182161 -228.115515)
			(xy 141.205812 -228.160578) (xy 141.221928 -228.208852) (xy 141.230092 -228.259086) (xy 141.230604 -228.284532)
			(xy 141.230101 -228.309521) (xy 141.537164 -228.309521) (xy 141.537164 -228.259543) (xy 141.544983 -228.21018)
			(xy 141.560427 -228.162648) (xy 141.583117 -228.118116) (xy 141.612493 -228.077683) (xy 141.647833 -228.042343)
			(xy 141.688266 -228.012967) (xy 141.732798 -227.990277) (xy 141.78033 -227.974833) (xy 141.829693 -227.967014)
			(xy 141.879671 -227.967014) (xy 141.929034 -227.974833) (xy 141.976566 -227.990277) (xy 142.021098 -228.012967)
			(xy 142.061531 -228.042343) (xy 142.096871 -228.077683) (xy 142.126247 -228.118116) (xy 142.148937 -228.162648)
			(xy 142.164381 -228.21018) (xy 142.1722 -228.259543) (xy 142.17269 -228.284532) (xy 142.478501 -228.284532)
			(xy 142.482596 -228.233804) (xy 142.494775 -228.18439) (xy 142.514723 -228.13757) (xy 142.541924 -228.094556)
			(xy 142.575672 -228.056462) (xy 142.615094 -228.024275) (xy 142.659168 -227.998829) (xy 142.706754 -227.980782)
			(xy 142.756618 -227.970602) (xy 142.80747 -227.968553) (xy 142.857991 -227.974687) (xy 142.906875 -227.988847)
			(xy 142.952854 -228.010664) (xy 142.994738 -228.039574) (xy 143.031442 -228.074829) (xy 143.062015 -228.115515)
			(xy 143.085666 -228.160578) (xy 143.101782 -228.208852) (xy 143.109946 -228.259086) (xy 143.110458 -228.284532)
			(xy 143.109955 -228.309521) (xy 143.417272 -228.309521) (xy 143.417272 -228.259543) (xy 143.425091 -228.21018)
			(xy 143.440535 -228.162648) (xy 143.463225 -228.118116) (xy 143.492601 -228.077683) (xy 143.527941 -228.042343)
			(xy 143.568374 -228.012967) (xy 143.612906 -227.990277) (xy 143.660438 -227.974833) (xy 143.709801 -227.967014)
			(xy 143.759779 -227.967014) (xy 143.809142 -227.974833) (xy 143.856674 -227.990277) (xy 143.901206 -228.012967)
			(xy 143.941639 -228.042343) (xy 143.976979 -228.077683) (xy 144.006355 -228.118116) (xy 144.029045 -228.162648)
			(xy 144.044489 -228.21018) (xy 144.052308 -228.259543) (xy 144.052798 -228.284532) (xy 144.052308 -228.309521)
			(xy 144.044489 -228.358884) (xy 144.029045 -228.406416) (xy 144.006355 -228.450948) (xy 143.976979 -228.491381)
			(xy 143.941639 -228.526721) (xy 143.901206 -228.556097) (xy 143.856674 -228.578787) (xy 143.809142 -228.594231)
			(xy 143.759779 -228.60205) (xy 143.709801 -228.60205) (xy 143.660438 -228.594231) (xy 143.612906 -228.578787)
			(xy 143.568374 -228.556097) (xy 143.527941 -228.526721) (xy 143.492601 -228.491381) (xy 143.463225 -228.450948)
			(xy 143.440535 -228.406416) (xy 143.425091 -228.358884) (xy 143.417272 -228.309521) (xy 143.109955 -228.309521)
			(xy 143.109946 -228.309978) (xy 143.101782 -228.360212) (xy 143.085666 -228.408486) (xy 143.062015 -228.453549)
			(xy 143.031442 -228.494235) (xy 142.994738 -228.52949) (xy 142.952854 -228.5584) (xy 142.906875 -228.580217)
			(xy 142.857991 -228.594377) (xy 142.80747 -228.600511) (xy 142.756618 -228.598462) (xy 142.706754 -228.588282)
			(xy 142.659168 -228.570235) (xy 142.615094 -228.544789) (xy 142.575672 -228.512602) (xy 142.541924 -228.474508)
			(xy 142.514723 -228.431494) (xy 142.494775 -228.384674) (xy 142.482596 -228.33526) (xy 142.478501 -228.284532)
			(xy 142.17269 -228.284532) (xy 142.1722 -228.309521) (xy 142.164381 -228.358884) (xy 142.148937 -228.406416)
			(xy 142.126247 -228.450948) (xy 142.096871 -228.491381) (xy 142.061531 -228.526721) (xy 142.021098 -228.556097)
			(xy 141.976566 -228.578787) (xy 141.929034 -228.594231) (xy 141.879671 -228.60205) (xy 141.829693 -228.60205)
			(xy 141.78033 -228.594231) (xy 141.732798 -228.578787) (xy 141.688266 -228.556097) (xy 141.647833 -228.526721)
			(xy 141.612493 -228.491381) (xy 141.583117 -228.450948) (xy 141.560427 -228.406416) (xy 141.544983 -228.358884)
			(xy 141.537164 -228.309521) (xy 141.230101 -228.309521) (xy 141.230092 -228.309978) (xy 141.221928 -228.360212)
			(xy 141.205812 -228.408486) (xy 141.182161 -228.453549) (xy 141.151588 -228.494235) (xy 141.114884 -228.52949)
			(xy 141.073 -228.5584) (xy 141.027021 -228.580217) (xy 140.978137 -228.594377) (xy 140.927616 -228.600511)
			(xy 140.876764 -228.598462) (xy 140.8269 -228.588282) (xy 140.779314 -228.570235) (xy 140.73524 -228.544789)
			(xy 140.695818 -228.512602) (xy 140.66207 -228.474508) (xy 140.634869 -228.431494) (xy 140.614921 -228.384674)
			(xy 140.602742 -228.33526) (xy 140.598647 -228.284532) (xy 140.292836 -228.284532) (xy 140.292346 -228.309521)
			(xy 140.284527 -228.358884) (xy 140.269083 -228.406416) (xy 140.246393 -228.450948) (xy 140.217017 -228.491381)
			(xy 140.181677 -228.526721) (xy 140.141244 -228.556097) (xy 140.096712 -228.578787) (xy 140.04918 -228.594231)
			(xy 139.999817 -228.60205) (xy 139.949839 -228.60205) (xy 139.900476 -228.594231) (xy 139.852944 -228.578787)
			(xy 139.808412 -228.556097) (xy 139.767979 -228.526721) (xy 139.732639 -228.491381) (xy 139.703263 -228.450948)
			(xy 139.680573 -228.406416) (xy 139.665129 -228.358884) (xy 139.65731 -228.309521) (xy 139.349993 -228.309521)
			(xy 139.349984 -228.309978) (xy 139.34182 -228.360212) (xy 139.325704 -228.408486) (xy 139.302053 -228.453549)
			(xy 139.27148 -228.494235) (xy 139.234776 -228.52949) (xy 139.192892 -228.5584) (xy 139.146913 -228.580217)
			(xy 139.098029 -228.594377) (xy 139.047508 -228.600511) (xy 138.996656 -228.598462) (xy 138.946792 -228.588282)
			(xy 138.899206 -228.570235) (xy 138.855132 -228.544789) (xy 138.81571 -228.512602) (xy 138.781962 -228.474508)
			(xy 138.754761 -228.431494) (xy 138.734813 -228.384674) (xy 138.722634 -228.33526) (xy 138.718539 -228.284532)
			(xy 138.410442 -228.284532) (xy 138.40993 -228.309978) (xy 138.401766 -228.360212) (xy 138.38565 -228.408486)
			(xy 138.361999 -228.453549) (xy 138.331426 -228.494235) (xy 138.294722 -228.52949) (xy 138.252838 -228.5584)
			(xy 138.206859 -228.580217) (xy 138.157975 -228.594377) (xy 138.107454 -228.600511) (xy 138.056602 -228.598462)
			(xy 138.006738 -228.588282) (xy 137.959152 -228.570235) (xy 137.915078 -228.544789) (xy 137.875656 -228.512602)
			(xy 137.841908 -228.474508) (xy 137.814707 -228.431494) (xy 137.794759 -228.384674) (xy 137.78258 -228.33526)
			(xy 137.778485 -228.284532) (xy 137.472674 -228.284532) (xy 137.472184 -228.309521) (xy 137.464365 -228.358884)
			(xy 137.448921 -228.406416) (xy 137.426231 -228.450948) (xy 137.396855 -228.491381) (xy 137.361515 -228.526721)
			(xy 137.321082 -228.556097) (xy 137.27655 -228.578787) (xy 137.229018 -228.594231) (xy 137.179655 -228.60205)
			(xy 137.129677 -228.60205) (xy 137.080314 -228.594231) (xy 137.032782 -228.578787) (xy 136.98825 -228.556097)
			(xy 136.947817 -228.526721) (xy 136.912477 -228.491381) (xy 136.883101 -228.450948) (xy 136.860411 -228.406416)
			(xy 136.844967 -228.358884) (xy 136.837148 -228.309521) (xy 136.530085 -228.309521) (xy 136.530076 -228.309978)
			(xy 136.521912 -228.360212) (xy 136.505796 -228.408486) (xy 136.482145 -228.453549) (xy 136.451572 -228.494235)
			(xy 136.414868 -228.52949) (xy 136.372984 -228.5584) (xy 136.327005 -228.580217) (xy 136.278121 -228.594377)
			(xy 136.2276 -228.600511) (xy 136.176748 -228.598462) (xy 136.126884 -228.588282) (xy 136.079298 -228.570235)
			(xy 136.035224 -228.544789) (xy 135.995802 -228.512602) (xy 135.962054 -228.474508) (xy 135.934853 -228.431494)
			(xy 135.914905 -228.384674) (xy 135.902726 -228.33526) (xy 135.898631 -228.284532) (xy 135.59282 -228.284532)
			(xy 135.59233 -228.309521) (xy 135.584511 -228.358884) (xy 135.569067 -228.406416) (xy 135.546377 -228.450948)
			(xy 135.517001 -228.491381) (xy 135.481661 -228.526721) (xy 135.441228 -228.556097) (xy 135.396696 -228.578787)
			(xy 135.349164 -228.594231) (xy 135.299801 -228.60205) (xy 135.249823 -228.60205) (xy 135.20046 -228.594231)
			(xy 135.152928 -228.578787) (xy 135.108396 -228.556097) (xy 135.067963 -228.526721) (xy 135.032623 -228.491381)
			(xy 135.003247 -228.450948) (xy 134.980557 -228.406416) (xy 134.965113 -228.358884) (xy 134.957294 -228.309521)
			(xy 134.649977 -228.309521) (xy 134.649968 -228.309978) (xy 134.641804 -228.360212) (xy 134.625688 -228.408486)
			(xy 134.602037 -228.453549) (xy 134.571464 -228.494235) (xy 134.53476 -228.52949) (xy 134.492876 -228.5584)
			(xy 134.446897 -228.580217) (xy 134.398013 -228.594377) (xy 134.347492 -228.600511) (xy 134.29664 -228.598462)
			(xy 134.246776 -228.588282) (xy 134.19919 -228.570235) (xy 134.155116 -228.544789) (xy 134.115694 -228.512602)
			(xy 134.081946 -228.474508) (xy 134.054745 -228.431494) (xy 134.034797 -228.384674) (xy 134.022618 -228.33526)
			(xy 134.018523 -228.284532) (xy 133.712712 -228.284532) (xy 133.712222 -228.309521) (xy 133.704403 -228.358884)
			(xy 133.688959 -228.406416) (xy 133.666269 -228.450948) (xy 133.636893 -228.491381) (xy 133.601553 -228.526721)
			(xy 133.56112 -228.556097) (xy 133.516588 -228.578787) (xy 133.469056 -228.594231) (xy 133.419693 -228.60205)
			(xy 133.369715 -228.60205) (xy 133.320352 -228.594231) (xy 133.27282 -228.578787) (xy 133.228288 -228.556097)
			(xy 133.187855 -228.526721) (xy 133.152515 -228.491381) (xy 133.123139 -228.450948) (xy 133.100449 -228.406416)
			(xy 133.085005 -228.358884) (xy 133.077186 -228.309521) (xy 132.769869 -228.309521) (xy 132.76986 -228.309978)
			(xy 132.761696 -228.360212) (xy 132.74558 -228.408486) (xy 132.721929 -228.453549) (xy 132.691356 -228.494235)
			(xy 132.654652 -228.52949) (xy 132.612768 -228.5584) (xy 132.566789 -228.580217) (xy 132.517905 -228.594377)
			(xy 132.467384 -228.600511) (xy 132.416532 -228.598462) (xy 132.366668 -228.588282) (xy 132.319082 -228.570235)
			(xy 132.275008 -228.544789) (xy 132.235586 -228.512602) (xy 132.201838 -228.474508) (xy 132.174637 -228.431494)
			(xy 132.154689 -228.384674) (xy 132.14251 -228.33526) (xy 132.138415 -228.284532) (xy 131.830572 -228.284532)
			(xy 131.83006 -228.309978) (xy 131.821896 -228.360212) (xy 131.80578 -228.408486) (xy 131.782129 -228.453549)
			(xy 131.751556 -228.494235) (xy 131.714852 -228.52949) (xy 131.672968 -228.5584) (xy 131.626989 -228.580217)
			(xy 131.578105 -228.594377) (xy 131.527584 -228.600511) (xy 131.476732 -228.598462) (xy 131.426868 -228.588282)
			(xy 131.379282 -228.570235) (xy 131.335208 -228.544789) (xy 131.295786 -228.512602) (xy 131.262038 -228.474508)
			(xy 131.234837 -228.431494) (xy 131.214889 -228.384674) (xy 131.20271 -228.33526) (xy 131.198615 -228.284532)
			(xy 130.892804 -228.284532) (xy 130.892314 -228.309521) (xy 130.884495 -228.358884) (xy 130.869051 -228.406416)
			(xy 130.846361 -228.450948) (xy 130.816985 -228.491381) (xy 130.781645 -228.526721) (xy 130.741212 -228.556097)
			(xy 130.69668 -228.578787) (xy 130.649148 -228.594231) (xy 130.599785 -228.60205) (xy 130.549807 -228.60205)
			(xy 130.500444 -228.594231) (xy 130.452912 -228.578787) (xy 130.40838 -228.556097) (xy 130.367947 -228.526721)
			(xy 130.332607 -228.491381) (xy 130.303231 -228.450948) (xy 130.280541 -228.406416) (xy 130.265097 -228.358884)
			(xy 130.257278 -228.309521) (xy 129.949961 -228.309521) (xy 129.949952 -228.309978) (xy 129.941788 -228.360212)
			(xy 129.925672 -228.408486) (xy 129.902021 -228.453549) (xy 129.871448 -228.494235) (xy 129.834744 -228.52949)
			(xy 129.79286 -228.5584) (xy 129.746881 -228.580217) (xy 129.697997 -228.594377) (xy 129.647476 -228.600511)
			(xy 129.596624 -228.598462) (xy 129.54676 -228.588282) (xy 129.499174 -228.570235) (xy 129.4551 -228.544789)
			(xy 129.415678 -228.512602) (xy 129.38193 -228.474508) (xy 129.354729 -228.431494) (xy 129.334781 -228.384674)
			(xy 129.322602 -228.33526) (xy 129.318507 -228.284532) (xy 129.012696 -228.284532) (xy 129.012206 -228.309521)
			(xy 129.004387 -228.358884) (xy 128.988943 -228.406416) (xy 128.966253 -228.450948) (xy 128.936877 -228.491381)
			(xy 128.901537 -228.526721) (xy 128.861104 -228.556097) (xy 128.816572 -228.578787) (xy 128.76904 -228.594231)
			(xy 128.719677 -228.60205) (xy 128.669699 -228.60205) (xy 128.620336 -228.594231) (xy 128.572804 -228.578787)
			(xy 128.528272 -228.556097) (xy 128.487839 -228.526721) (xy 128.452499 -228.491381) (xy 128.423123 -228.450948)
			(xy 128.400433 -228.406416) (xy 128.384989 -228.358884) (xy 128.37717 -228.309521) (xy 128.069853 -228.309521)
			(xy 128.069844 -228.309978) (xy 128.06168 -228.360212) (xy 128.045564 -228.408486) (xy 128.021913 -228.453549)
			(xy 127.99134 -228.494235) (xy 127.954636 -228.52949) (xy 127.912752 -228.5584) (xy 127.866773 -228.580217)
			(xy 127.817889 -228.594377) (xy 127.767368 -228.600511) (xy 127.716516 -228.598462) (xy 127.666652 -228.588282)
			(xy 127.619066 -228.570235) (xy 127.574992 -228.544789) (xy 127.53557 -228.512602) (xy 127.501822 -228.474508)
			(xy 127.474621 -228.431494) (xy 127.454673 -228.384674) (xy 127.442494 -228.33526) (xy 127.438399 -228.284532)
			(xy 127.132842 -228.284532) (xy 127.132349 -228.309521) (xy 127.124527 -228.358882) (xy 127.109081 -228.406412)
			(xy 127.08639 -228.450941) (xy 127.057013 -228.491373) (xy 127.021674 -228.526712) (xy 126.981243 -228.556089)
			(xy 126.936714 -228.57878) (xy 126.889184 -228.594227) (xy 126.839823 -228.602049) (xy 126.814834 -228.60254)
			(xy 126.8024 -228.602442) (xy 126.777607 -228.600532) (xy 126.765304 -228.59873) (xy 126.763526 -228.598476)
			(xy 126.75616 -228.597968) (xy 126.747781 -228.598395) (xy 126.731968 -228.60397) (xy 126.725172 -228.60889)
			(xy 126.701042 -228.62921) (xy 126.700534 -228.629718) (xy 126.666244 -228.659182) (xy 126.658713 -228.666249)
			(xy 126.649527 -228.684725) (xy 126.648464 -228.694996) (xy 126.648464 -228.99243) (xy 126.648972 -228.995986)
			(xy 126.650496 -229.006908) (xy 126.651004 -229.00894) (xy 126.651512 -229.010464) (xy 126.656771 -229.031082)
			(xy 126.662373 -229.073262) (xy 126.662688 -229.094538) (xy 127.908553 -229.094538) (xy 127.912648 -229.04381)
			(xy 127.924827 -228.994396) (xy 127.944775 -228.947576) (xy 127.971976 -228.904562) (xy 128.005724 -228.866468)
			(xy 128.045146 -228.834281) (xy 128.08922 -228.808835) (xy 128.136806 -228.790788) (xy 128.18667 -228.780608)
			(xy 128.237522 -228.778559) (xy 128.288043 -228.784693) (xy 128.336927 -228.798853) (xy 128.382906 -228.82067)
			(xy 128.42479 -228.84958) (xy 128.461494 -228.884835) (xy 128.492067 -228.925521) (xy 128.515718 -228.970584)
			(xy 128.531834 -229.018858) (xy 128.539998 -229.069092) (xy 128.54051 -229.094538) (xy 128.848607 -229.094538)
			(xy 128.852702 -229.04381) (xy 128.864881 -228.994396) (xy 128.884829 -228.947576) (xy 128.91203 -228.904562)
			(xy 128.945778 -228.866468) (xy 128.9852 -228.834281) (xy 129.029274 -228.808835) (xy 129.07686 -228.790788)
			(xy 129.126724 -228.780608) (xy 129.177576 -228.778559) (xy 129.228097 -228.784693) (xy 129.276981 -228.798853)
			(xy 129.32296 -228.82067) (xy 129.364844 -228.84958) (xy 129.401548 -228.884835) (xy 129.432121 -228.925521)
			(xy 129.455772 -228.970584) (xy 129.471888 -229.018858) (xy 129.480052 -229.069092) (xy 129.480564 -229.094538)
			(xy 129.480061 -229.119527) (xy 129.787124 -229.119527) (xy 129.787124 -229.069549) (xy 129.794943 -229.020186)
			(xy 129.810387 -228.972654) (xy 129.833077 -228.928122) (xy 129.862453 -228.887689) (xy 129.897793 -228.852349)
			(xy 129.938226 -228.822973) (xy 129.982758 -228.800283) (xy 130.03029 -228.784839) (xy 130.079653 -228.77702)
			(xy 130.129631 -228.77702) (xy 130.178994 -228.784839) (xy 130.226526 -228.800283) (xy 130.271058 -228.822973)
			(xy 130.311491 -228.852349) (xy 130.346831 -228.887689) (xy 130.376207 -228.928122) (xy 130.398897 -228.972654)
			(xy 130.414341 -229.020186) (xy 130.42216 -229.069549) (xy 130.42265 -229.094538) (xy 130.728461 -229.094538)
			(xy 130.732556 -229.04381) (xy 130.744735 -228.994396) (xy 130.764683 -228.947576) (xy 130.791884 -228.904562)
			(xy 130.825632 -228.866468) (xy 130.865054 -228.834281) (xy 130.909128 -228.808835) (xy 130.956714 -228.790788)
			(xy 131.006578 -228.780608) (xy 131.05743 -228.778559) (xy 131.107951 -228.784693) (xy 131.156835 -228.798853)
			(xy 131.202814 -228.82067) (xy 131.244698 -228.84958) (xy 131.281402 -228.884835) (xy 131.311975 -228.925521)
			(xy 131.335626 -228.970584) (xy 131.351742 -229.018858) (xy 131.359906 -229.069092) (xy 131.360418 -229.094538)
			(xy 131.359915 -229.119527) (xy 131.667232 -229.119527) (xy 131.667232 -229.069549) (xy 131.675051 -229.020186)
			(xy 131.690495 -228.972654) (xy 131.713185 -228.928122) (xy 131.742561 -228.887689) (xy 131.777901 -228.852349)
			(xy 131.818334 -228.822973) (xy 131.862866 -228.800283) (xy 131.910398 -228.784839) (xy 131.959761 -228.77702)
			(xy 132.009739 -228.77702) (xy 132.059102 -228.784839) (xy 132.106634 -228.800283) (xy 132.151166 -228.822973)
			(xy 132.191599 -228.852349) (xy 132.226939 -228.887689) (xy 132.256315 -228.928122) (xy 132.279005 -228.972654)
			(xy 132.294449 -229.020186) (xy 132.302268 -229.069549) (xy 132.302758 -229.094538) (xy 132.608569 -229.094538)
			(xy 132.612664 -229.04381) (xy 132.624843 -228.994396) (xy 132.644791 -228.947576) (xy 132.671992 -228.904562)
			(xy 132.70574 -228.866468) (xy 132.745162 -228.834281) (xy 132.789236 -228.808835) (xy 132.836822 -228.790788)
			(xy 132.886686 -228.780608) (xy 132.937538 -228.778559) (xy 132.988059 -228.784693) (xy 133.036943 -228.798853)
			(xy 133.082922 -228.82067) (xy 133.124806 -228.84958) (xy 133.16151 -228.884835) (xy 133.192083 -228.925521)
			(xy 133.215734 -228.970584) (xy 133.23185 -229.018858) (xy 133.240014 -229.069092) (xy 133.240526 -229.094538)
			(xy 133.240023 -229.119527) (xy 133.54734 -229.119527) (xy 133.54734 -229.069549) (xy 133.555159 -229.020186)
			(xy 133.570603 -228.972654) (xy 133.593293 -228.928122) (xy 133.622669 -228.887689) (xy 133.658009 -228.852349)
			(xy 133.698442 -228.822973) (xy 133.742974 -228.800283) (xy 133.790506 -228.784839) (xy 133.839869 -228.77702)
			(xy 133.889847 -228.77702) (xy 133.93921 -228.784839) (xy 133.986742 -228.800283) (xy 134.031274 -228.822973)
			(xy 134.071707 -228.852349) (xy 134.107047 -228.887689) (xy 134.136423 -228.928122) (xy 134.159113 -228.972654)
			(xy 134.174557 -229.020186) (xy 134.182376 -229.069549) (xy 134.182866 -229.094538) (xy 134.488423 -229.094538)
			(xy 134.492518 -229.04381) (xy 134.504697 -228.994396) (xy 134.524645 -228.947576) (xy 134.551846 -228.904562)
			(xy 134.585594 -228.866468) (xy 134.625016 -228.834281) (xy 134.66909 -228.808835) (xy 134.716676 -228.790788)
			(xy 134.76654 -228.780608) (xy 134.817392 -228.778559) (xy 134.867913 -228.784693) (xy 134.916797 -228.798853)
			(xy 134.962776 -228.82067) (xy 135.00466 -228.84958) (xy 135.041364 -228.884835) (xy 135.071937 -228.925521)
			(xy 135.095588 -228.970584) (xy 135.111704 -229.018858) (xy 135.119868 -229.069092) (xy 135.12038 -229.094538)
			(xy 135.428477 -229.094538) (xy 135.432572 -229.04381) (xy 135.444751 -228.994396) (xy 135.464699 -228.947576)
			(xy 135.4919 -228.904562) (xy 135.525648 -228.866468) (xy 135.56507 -228.834281) (xy 135.609144 -228.808835)
			(xy 135.65673 -228.790788) (xy 135.706594 -228.780608) (xy 135.757446 -228.778559) (xy 135.807967 -228.784693)
			(xy 135.856851 -228.798853) (xy 135.90283 -228.82067) (xy 135.944714 -228.84958) (xy 135.981418 -228.884835)
			(xy 136.011991 -228.925521) (xy 136.035642 -228.970584) (xy 136.051758 -229.018858) (xy 136.059922 -229.069092)
			(xy 136.060434 -229.094538) (xy 136.059931 -229.119527) (xy 136.367248 -229.119527) (xy 136.367248 -229.069549)
			(xy 136.375067 -229.020186) (xy 136.390511 -228.972654) (xy 136.413201 -228.928122) (xy 136.442577 -228.887689)
			(xy 136.477917 -228.852349) (xy 136.51835 -228.822973) (xy 136.562882 -228.800283) (xy 136.610414 -228.784839)
			(xy 136.659777 -228.77702) (xy 136.709755 -228.77702) (xy 136.759118 -228.784839) (xy 136.80665 -228.800283)
			(xy 136.851182 -228.822973) (xy 136.891615 -228.852349) (xy 136.926955 -228.887689) (xy 136.956331 -228.928122)
			(xy 136.979021 -228.972654) (xy 136.994465 -229.020186) (xy 137.002284 -229.069549) (xy 137.002774 -229.094538)
			(xy 137.308585 -229.094538) (xy 137.31268 -229.04381) (xy 137.324859 -228.994396) (xy 137.344807 -228.947576)
			(xy 137.372008 -228.904562) (xy 137.405756 -228.866468) (xy 137.445178 -228.834281) (xy 137.489252 -228.808835)
			(xy 137.536838 -228.790788) (xy 137.586702 -228.780608) (xy 137.637554 -228.778559) (xy 137.688075 -228.784693)
			(xy 137.736959 -228.798853) (xy 137.782938 -228.82067) (xy 137.824822 -228.84958) (xy 137.861526 -228.884835)
			(xy 137.892099 -228.925521) (xy 137.91575 -228.970584) (xy 137.931866 -229.018858) (xy 137.94003 -229.069092)
			(xy 137.940542 -229.094538) (xy 137.940039 -229.119527) (xy 138.247356 -229.119527) (xy 138.247356 -229.069549)
			(xy 138.255175 -229.020186) (xy 138.270619 -228.972654) (xy 138.293309 -228.928122) (xy 138.322685 -228.887689)
			(xy 138.358025 -228.852349) (xy 138.398458 -228.822973) (xy 138.44299 -228.800283) (xy 138.490522 -228.784839)
			(xy 138.539885 -228.77702) (xy 138.589863 -228.77702) (xy 138.639226 -228.784839) (xy 138.686758 -228.800283)
			(xy 138.73129 -228.822973) (xy 138.771723 -228.852349) (xy 138.807063 -228.887689) (xy 138.836439 -228.928122)
			(xy 138.859129 -228.972654) (xy 138.874573 -229.020186) (xy 138.882392 -229.069549) (xy 138.882882 -229.094538)
			(xy 139.188439 -229.094538) (xy 139.192534 -229.04381) (xy 139.204713 -228.994396) (xy 139.224661 -228.947576)
			(xy 139.251862 -228.904562) (xy 139.28561 -228.866468) (xy 139.325032 -228.834281) (xy 139.369106 -228.808835)
			(xy 139.416692 -228.790788) (xy 139.466556 -228.780608) (xy 139.517408 -228.778559) (xy 139.567929 -228.784693)
			(xy 139.616813 -228.798853) (xy 139.662792 -228.82067) (xy 139.704676 -228.84958) (xy 139.74138 -228.884835)
			(xy 139.771953 -228.925521) (xy 139.795604 -228.970584) (xy 139.81172 -229.018858) (xy 139.819884 -229.069092)
			(xy 139.820396 -229.094538) (xy 139.819893 -229.119527) (xy 140.12721 -229.119527) (xy 140.12721 -229.069549)
			(xy 140.135029 -229.020186) (xy 140.150473 -228.972654) (xy 140.173163 -228.928122) (xy 140.202539 -228.887689)
			(xy 140.237879 -228.852349) (xy 140.278312 -228.822973) (xy 140.322844 -228.800283) (xy 140.370376 -228.784839)
			(xy 140.419739 -228.77702) (xy 140.469717 -228.77702) (xy 140.51908 -228.784839) (xy 140.566612 -228.800283)
			(xy 140.611144 -228.822973) (xy 140.651577 -228.852349) (xy 140.686917 -228.887689) (xy 140.716293 -228.928122)
			(xy 140.738983 -228.972654) (xy 140.754427 -229.020186) (xy 140.762246 -229.069549) (xy 140.762736 -229.094538)
			(xy 141.068547 -229.094538) (xy 141.072642 -229.04381) (xy 141.084821 -228.994396) (xy 141.104769 -228.947576)
			(xy 141.13197 -228.904562) (xy 141.165718 -228.866468) (xy 141.20514 -228.834281) (xy 141.249214 -228.808835)
			(xy 141.2968 -228.790788) (xy 141.346664 -228.780608) (xy 141.397516 -228.778559) (xy 141.448037 -228.784693)
			(xy 141.496921 -228.798853) (xy 141.5429 -228.82067) (xy 141.584784 -228.84958) (xy 141.621488 -228.884835)
			(xy 141.652061 -228.925521) (xy 141.675712 -228.970584) (xy 141.691828 -229.018858) (xy 141.699992 -229.069092)
			(xy 141.700504 -229.094538) (xy 142.008601 -229.094538) (xy 142.012696 -229.04381) (xy 142.024875 -228.994396)
			(xy 142.044823 -228.947576) (xy 142.072024 -228.904562) (xy 142.105772 -228.866468) (xy 142.145194 -228.834281)
			(xy 142.189268 -228.808835) (xy 142.236854 -228.790788) (xy 142.286718 -228.780608) (xy 142.33757 -228.778559)
			(xy 142.388091 -228.784693) (xy 142.436975 -228.798853) (xy 142.482954 -228.82067) (xy 142.524838 -228.84958)
			(xy 142.561542 -228.884835) (xy 142.592115 -228.925521) (xy 142.615766 -228.970584) (xy 142.631882 -229.018858)
			(xy 142.640046 -229.069092) (xy 142.640558 -229.094538) (xy 142.640055 -229.119527) (xy 142.947118 -229.119527)
			(xy 142.947118 -229.069549) (xy 142.954937 -229.020186) (xy 142.970381 -228.972654) (xy 142.993071 -228.928122)
			(xy 143.022447 -228.887689) (xy 143.057787 -228.852349) (xy 143.09822 -228.822973) (xy 143.142752 -228.800283)
			(xy 143.190284 -228.784839) (xy 143.239647 -228.77702) (xy 143.289625 -228.77702) (xy 143.338988 -228.784839)
			(xy 143.38652 -228.800283) (xy 143.431052 -228.822973) (xy 143.471485 -228.852349) (xy 143.506825 -228.887689)
			(xy 143.536201 -228.928122) (xy 143.558891 -228.972654) (xy 143.574335 -229.020186) (xy 143.582154 -229.069549)
			(xy 143.582644 -229.094538) (xy 143.582154 -229.119527) (xy 143.574335 -229.16889) (xy 143.558891 -229.216422)
			(xy 143.536201 -229.260954) (xy 143.506825 -229.301387) (xy 143.471485 -229.336727) (xy 143.431052 -229.366103)
			(xy 143.38652 -229.388793) (xy 143.338988 -229.404237) (xy 143.289625 -229.412056) (xy 143.239647 -229.412056)
			(xy 143.190284 -229.404237) (xy 143.142752 -229.388793) (xy 143.09822 -229.366103) (xy 143.057787 -229.336727)
			(xy 143.022447 -229.301387) (xy 142.993071 -229.260954) (xy 142.970381 -229.216422) (xy 142.954937 -229.16889)
			(xy 142.947118 -229.119527) (xy 142.640055 -229.119527) (xy 142.640046 -229.119984) (xy 142.631882 -229.170218)
			(xy 142.615766 -229.218492) (xy 142.592115 -229.263555) (xy 142.561542 -229.304241) (xy 142.524838 -229.339496)
			(xy 142.482954 -229.368406) (xy 142.436975 -229.390223) (xy 142.388091 -229.404383) (xy 142.33757 -229.410517)
			(xy 142.286718 -229.408468) (xy 142.236854 -229.398288) (xy 142.189268 -229.380241) (xy 142.145194 -229.354795)
			(xy 142.105772 -229.322608) (xy 142.072024 -229.284514) (xy 142.044823 -229.2415) (xy 142.024875 -229.19468)
			(xy 142.012696 -229.145266) (xy 142.008601 -229.094538) (xy 141.700504 -229.094538) (xy 141.699992 -229.119984)
			(xy 141.691828 -229.170218) (xy 141.675712 -229.218492) (xy 141.652061 -229.263555) (xy 141.621488 -229.304241)
			(xy 141.584784 -229.339496) (xy 141.5429 -229.368406) (xy 141.496921 -229.390223) (xy 141.448037 -229.404383)
			(xy 141.397516 -229.410517) (xy 141.346664 -229.408468) (xy 141.2968 -229.398288) (xy 141.249214 -229.380241)
			(xy 141.20514 -229.354795) (xy 141.165718 -229.322608) (xy 141.13197 -229.284514) (xy 141.104769 -229.2415)
			(xy 141.084821 -229.19468) (xy 141.072642 -229.145266) (xy 141.068547 -229.094538) (xy 140.762736 -229.094538)
			(xy 140.762246 -229.119527) (xy 140.754427 -229.16889) (xy 140.738983 -229.216422) (xy 140.716293 -229.260954)
			(xy 140.686917 -229.301387) (xy 140.651577 -229.336727) (xy 140.611144 -229.366103) (xy 140.566612 -229.388793)
			(xy 140.51908 -229.404237) (xy 140.469717 -229.412056) (xy 140.419739 -229.412056) (xy 140.370376 -229.404237)
			(xy 140.322844 -229.388793) (xy 140.278312 -229.366103) (xy 140.237879 -229.336727) (xy 140.202539 -229.301387)
			(xy 140.173163 -229.260954) (xy 140.150473 -229.216422) (xy 140.135029 -229.16889) (xy 140.12721 -229.119527)
			(xy 139.819893 -229.119527) (xy 139.819884 -229.119984) (xy 139.81172 -229.170218) (xy 139.795604 -229.218492)
			(xy 139.771953 -229.263555) (xy 139.74138 -229.304241) (xy 139.704676 -229.339496) (xy 139.662792 -229.368406)
			(xy 139.616813 -229.390223) (xy 139.567929 -229.404383) (xy 139.517408 -229.410517) (xy 139.466556 -229.408468)
			(xy 139.416692 -229.398288) (xy 139.369106 -229.380241) (xy 139.325032 -229.354795) (xy 139.28561 -229.322608)
			(xy 139.251862 -229.284514) (xy 139.224661 -229.2415) (xy 139.204713 -229.19468) (xy 139.192534 -229.145266)
			(xy 139.188439 -229.094538) (xy 138.882882 -229.094538) (xy 138.882392 -229.119527) (xy 138.874573 -229.16889)
			(xy 138.859129 -229.216422) (xy 138.836439 -229.260954) (xy 138.807063 -229.301387) (xy 138.771723 -229.336727)
			(xy 138.73129 -229.366103) (xy 138.686758 -229.388793) (xy 138.639226 -229.404237) (xy 138.589863 -229.412056)
			(xy 138.539885 -229.412056) (xy 138.490522 -229.404237) (xy 138.44299 -229.388793) (xy 138.398458 -229.366103)
			(xy 138.358025 -229.336727) (xy 138.322685 -229.301387) (xy 138.293309 -229.260954) (xy 138.270619 -229.216422)
			(xy 138.255175 -229.16889) (xy 138.247356 -229.119527) (xy 137.940039 -229.119527) (xy 137.94003 -229.119984)
			(xy 137.931866 -229.170218) (xy 137.91575 -229.218492) (xy 137.892099 -229.263555) (xy 137.861526 -229.304241)
			(xy 137.824822 -229.339496) (xy 137.782938 -229.368406) (xy 137.736959 -229.390223) (xy 137.688075 -229.404383)
			(xy 137.637554 -229.410517) (xy 137.586702 -229.408468) (xy 137.536838 -229.398288) (xy 137.489252 -229.380241)
			(xy 137.445178 -229.354795) (xy 137.405756 -229.322608) (xy 137.372008 -229.284514) (xy 137.344807 -229.2415)
			(xy 137.324859 -229.19468) (xy 137.31268 -229.145266) (xy 137.308585 -229.094538) (xy 137.002774 -229.094538)
			(xy 137.002284 -229.119527) (xy 136.994465 -229.16889) (xy 136.979021 -229.216422) (xy 136.956331 -229.260954)
			(xy 136.926955 -229.301387) (xy 136.891615 -229.336727) (xy 136.851182 -229.366103) (xy 136.80665 -229.388793)
			(xy 136.759118 -229.404237) (xy 136.709755 -229.412056) (xy 136.659777 -229.412056) (xy 136.610414 -229.404237)
			(xy 136.562882 -229.388793) (xy 136.51835 -229.366103) (xy 136.477917 -229.336727) (xy 136.442577 -229.301387)
			(xy 136.413201 -229.260954) (xy 136.390511 -229.216422) (xy 136.375067 -229.16889) (xy 136.367248 -229.119527)
			(xy 136.059931 -229.119527) (xy 136.059922 -229.119984) (xy 136.051758 -229.170218) (xy 136.035642 -229.218492)
			(xy 136.011991 -229.263555) (xy 135.981418 -229.304241) (xy 135.944714 -229.339496) (xy 135.90283 -229.368406)
			(xy 135.856851 -229.390223) (xy 135.807967 -229.404383) (xy 135.757446 -229.410517) (xy 135.706594 -229.408468)
			(xy 135.65673 -229.398288) (xy 135.609144 -229.380241) (xy 135.56507 -229.354795) (xy 135.525648 -229.322608)
			(xy 135.4919 -229.284514) (xy 135.464699 -229.2415) (xy 135.444751 -229.19468) (xy 135.432572 -229.145266)
			(xy 135.428477 -229.094538) (xy 135.12038 -229.094538) (xy 135.119868 -229.119984) (xy 135.111704 -229.170218)
			(xy 135.095588 -229.218492) (xy 135.071937 -229.263555) (xy 135.041364 -229.304241) (xy 135.00466 -229.339496)
			(xy 134.962776 -229.368406) (xy 134.916797 -229.390223) (xy 134.867913 -229.404383) (xy 134.817392 -229.410517)
			(xy 134.76654 -229.408468) (xy 134.716676 -229.398288) (xy 134.66909 -229.380241) (xy 134.625016 -229.354795)
			(xy 134.585594 -229.322608) (xy 134.551846 -229.284514) (xy 134.524645 -229.2415) (xy 134.504697 -229.19468)
			(xy 134.492518 -229.145266) (xy 134.488423 -229.094538) (xy 134.182866 -229.094538) (xy 134.182376 -229.119527)
			(xy 134.174557 -229.16889) (xy 134.159113 -229.216422) (xy 134.136423 -229.260954) (xy 134.107047 -229.301387)
			(xy 134.071707 -229.336727) (xy 134.031274 -229.366103) (xy 133.986742 -229.388793) (xy 133.93921 -229.404237)
			(xy 133.889847 -229.412056) (xy 133.839869 -229.412056) (xy 133.790506 -229.404237) (xy 133.742974 -229.388793)
			(xy 133.698442 -229.366103) (xy 133.658009 -229.336727) (xy 133.622669 -229.301387) (xy 133.593293 -229.260954)
			(xy 133.570603 -229.216422) (xy 133.555159 -229.16889) (xy 133.54734 -229.119527) (xy 133.240023 -229.119527)
			(xy 133.240014 -229.119984) (xy 133.23185 -229.170218) (xy 133.215734 -229.218492) (xy 133.192083 -229.263555)
			(xy 133.16151 -229.304241) (xy 133.124806 -229.339496) (xy 133.082922 -229.368406) (xy 133.036943 -229.390223)
			(xy 132.988059 -229.404383) (xy 132.937538 -229.410517) (xy 132.886686 -229.408468) (xy 132.836822 -229.398288)
			(xy 132.789236 -229.380241) (xy 132.745162 -229.354795) (xy 132.70574 -229.322608) (xy 132.671992 -229.284514)
			(xy 132.644791 -229.2415) (xy 132.624843 -229.19468) (xy 132.612664 -229.145266) (xy 132.608569 -229.094538)
			(xy 132.302758 -229.094538) (xy 132.302268 -229.119527) (xy 132.294449 -229.16889) (xy 132.279005 -229.216422)
			(xy 132.256315 -229.260954) (xy 132.226939 -229.301387) (xy 132.191599 -229.336727) (xy 132.151166 -229.366103)
			(xy 132.106634 -229.388793) (xy 132.059102 -229.404237) (xy 132.009739 -229.412056) (xy 131.959761 -229.412056)
			(xy 131.910398 -229.404237) (xy 131.862866 -229.388793) (xy 131.818334 -229.366103) (xy 131.777901 -229.336727)
			(xy 131.742561 -229.301387) (xy 131.713185 -229.260954) (xy 131.690495 -229.216422) (xy 131.675051 -229.16889)
			(xy 131.667232 -229.119527) (xy 131.359915 -229.119527) (xy 131.359906 -229.119984) (xy 131.351742 -229.170218)
			(xy 131.335626 -229.218492) (xy 131.311975 -229.263555) (xy 131.281402 -229.304241) (xy 131.244698 -229.339496)
			(xy 131.202814 -229.368406) (xy 131.156835 -229.390223) (xy 131.107951 -229.404383) (xy 131.05743 -229.410517)
			(xy 131.006578 -229.408468) (xy 130.956714 -229.398288) (xy 130.909128 -229.380241) (xy 130.865054 -229.354795)
			(xy 130.825632 -229.322608) (xy 130.791884 -229.284514) (xy 130.764683 -229.2415) (xy 130.744735 -229.19468)
			(xy 130.732556 -229.145266) (xy 130.728461 -229.094538) (xy 130.42265 -229.094538) (xy 130.42216 -229.119527)
			(xy 130.414341 -229.16889) (xy 130.398897 -229.216422) (xy 130.376207 -229.260954) (xy 130.346831 -229.301387)
			(xy 130.311491 -229.336727) (xy 130.271058 -229.366103) (xy 130.226526 -229.388793) (xy 130.178994 -229.404237)
			(xy 130.129631 -229.412056) (xy 130.079653 -229.412056) (xy 130.03029 -229.404237) (xy 129.982758 -229.388793)
			(xy 129.938226 -229.366103) (xy 129.897793 -229.336727) (xy 129.862453 -229.301387) (xy 129.833077 -229.260954)
			(xy 129.810387 -229.216422) (xy 129.794943 -229.16889) (xy 129.787124 -229.119527) (xy 129.480061 -229.119527)
			(xy 129.480052 -229.119984) (xy 129.471888 -229.170218) (xy 129.455772 -229.218492) (xy 129.432121 -229.263555)
			(xy 129.401548 -229.304241) (xy 129.364844 -229.339496) (xy 129.32296 -229.368406) (xy 129.276981 -229.390223)
			(xy 129.228097 -229.404383) (xy 129.177576 -229.410517) (xy 129.126724 -229.408468) (xy 129.07686 -229.398288)
			(xy 129.029274 -229.380241) (xy 128.9852 -229.354795) (xy 128.945778 -229.322608) (xy 128.91203 -229.284514)
			(xy 128.884829 -229.2415) (xy 128.864881 -229.19468) (xy 128.852702 -229.145266) (xy 128.848607 -229.094538)
			(xy 128.54051 -229.094538) (xy 128.539998 -229.119984) (xy 128.531834 -229.170218) (xy 128.515718 -229.218492)
			(xy 128.492067 -229.263555) (xy 128.461494 -229.304241) (xy 128.42479 -229.339496) (xy 128.382906 -229.368406)
			(xy 128.336927 -229.390223) (xy 128.288043 -229.404383) (xy 128.237522 -229.410517) (xy 128.18667 -229.408468)
			(xy 128.136806 -229.398288) (xy 128.08922 -229.380241) (xy 128.045146 -229.354795) (xy 128.005724 -229.322608)
			(xy 127.971976 -229.284514) (xy 127.944775 -229.2415) (xy 127.924827 -229.19468) (xy 127.912648 -229.145266)
			(xy 127.908553 -229.094538) (xy 126.662688 -229.094538) (xy 126.662434 -229.108254) (xy 126.661376 -229.127056)
			(xy 126.655396 -229.164239) (xy 126.650496 -229.182422) (xy 126.648464 -229.18928) (xy 126.648464 -229.491032)
			(xy 126.648464 -229.493826) (xy 126.649364 -229.503251) (xy 126.657201 -229.520471) (xy 126.663704 -229.527354)
			(xy 126.665736 -229.529132) (xy 126.700534 -229.559104) (xy 126.701042 -229.559612) (xy 126.725172 -229.579932)
			(xy 126.731962 -229.584864) (xy 126.747778 -229.590441) (xy 126.75616 -229.590854) (xy 126.763526 -229.590346)
			(xy 126.765304 -229.590092) (xy 126.777607 -229.588295) (xy 126.802401 -229.586388) (xy 126.814834 -229.586282)
			(xy 126.839822 -229.586775) (xy 126.889183 -229.594598) (xy 126.936712 -229.610045) (xy 126.98124 -229.632738)
			(xy 127.02167 -229.662116) (xy 127.057006 -229.697456) (xy 127.08638 -229.737889) (xy 127.109068 -229.78242)
			(xy 127.12451 -229.82995) (xy 127.132328 -229.879312) (xy 127.132328 -229.90429) (xy 127.438399 -229.90429)
			(xy 127.442494 -229.853562) (xy 127.454673 -229.804148) (xy 127.474621 -229.757328) (xy 127.501822 -229.714314)
			(xy 127.53557 -229.67622) (xy 127.574992 -229.644033) (xy 127.619066 -229.618587) (xy 127.666652 -229.60054)
			(xy 127.716516 -229.59036) (xy 127.767368 -229.588311) (xy 127.817889 -229.594445) (xy 127.866773 -229.608605)
			(xy 127.912752 -229.630422) (xy 127.954636 -229.659332) (xy 127.99134 -229.694587) (xy 128.021913 -229.735273)
			(xy 128.045564 -229.780336) (xy 128.06168 -229.82861) (xy 128.069844 -229.878844) (xy 128.070356 -229.90429)
			(xy 128.069853 -229.929279) (xy 128.37717 -229.929279) (xy 128.37717 -229.879301) (xy 128.384989 -229.829938)
			(xy 128.400433 -229.782406) (xy 128.423123 -229.737874) (xy 128.452499 -229.697441) (xy 128.487839 -229.662101)
			(xy 128.528272 -229.632725) (xy 128.572804 -229.610035) (xy 128.620336 -229.594591) (xy 128.669699 -229.586772)
			(xy 128.719677 -229.586772) (xy 128.76904 -229.594591) (xy 128.816572 -229.610035) (xy 128.861104 -229.632725)
			(xy 128.901537 -229.662101) (xy 128.936877 -229.697441) (xy 128.966253 -229.737874) (xy 128.988943 -229.782406)
			(xy 129.004387 -229.829938) (xy 129.012206 -229.879301) (xy 129.012696 -229.90429) (xy 129.318507 -229.90429)
			(xy 129.322602 -229.853562) (xy 129.334781 -229.804148) (xy 129.354729 -229.757328) (xy 129.38193 -229.714314)
			(xy 129.415678 -229.67622) (xy 129.4551 -229.644033) (xy 129.499174 -229.618587) (xy 129.54676 -229.60054)
			(xy 129.596624 -229.59036) (xy 129.647476 -229.588311) (xy 129.697997 -229.594445) (xy 129.746881 -229.608605)
			(xy 129.79286 -229.630422) (xy 129.834744 -229.659332) (xy 129.871448 -229.694587) (xy 129.902021 -229.735273)
			(xy 129.925672 -229.780336) (xy 129.941788 -229.82861) (xy 129.949952 -229.878844) (xy 129.950464 -229.90429)
			(xy 131.198615 -229.90429) (xy 131.20271 -229.853562) (xy 131.214889 -229.804148) (xy 131.234837 -229.757328)
			(xy 131.262038 -229.714314) (xy 131.295786 -229.67622) (xy 131.335208 -229.644033) (xy 131.379282 -229.618587)
			(xy 131.426868 -229.60054) (xy 131.476732 -229.59036) (xy 131.527584 -229.588311) (xy 131.578105 -229.594445)
			(xy 131.626989 -229.608605) (xy 131.672968 -229.630422) (xy 131.714852 -229.659332) (xy 131.751556 -229.694587)
			(xy 131.782129 -229.735273) (xy 131.80578 -229.780336) (xy 131.821896 -229.82861) (xy 131.83006 -229.878844)
			(xy 131.830572 -229.90429) (xy 132.138415 -229.90429) (xy 132.14251 -229.853562) (xy 132.154689 -229.804148)
			(xy 132.174637 -229.757328) (xy 132.201838 -229.714314) (xy 132.235586 -229.67622) (xy 132.275008 -229.644033)
			(xy 132.319082 -229.618587) (xy 132.366668 -229.60054) (xy 132.416532 -229.59036) (xy 132.467384 -229.588311)
			(xy 132.517905 -229.594445) (xy 132.566789 -229.608605) (xy 132.612768 -229.630422) (xy 132.654652 -229.659332)
			(xy 132.691356 -229.694587) (xy 132.721929 -229.735273) (xy 132.74558 -229.780336) (xy 132.761696 -229.82861)
			(xy 132.76986 -229.878844) (xy 132.770372 -229.90429) (xy 132.769869 -229.929279) (xy 133.077186 -229.929279)
			(xy 133.077186 -229.879301) (xy 133.085005 -229.829938) (xy 133.100449 -229.782406) (xy 133.123139 -229.737874)
			(xy 133.152515 -229.697441) (xy 133.187855 -229.662101) (xy 133.228288 -229.632725) (xy 133.27282 -229.610035)
			(xy 133.320352 -229.594591) (xy 133.369715 -229.586772) (xy 133.419693 -229.586772) (xy 133.469056 -229.594591)
			(xy 133.516588 -229.610035) (xy 133.56112 -229.632725) (xy 133.601553 -229.662101) (xy 133.636893 -229.697441)
			(xy 133.666269 -229.737874) (xy 133.688959 -229.782406) (xy 133.704403 -229.829938) (xy 133.712222 -229.879301)
			(xy 133.712712 -229.90429) (xy 134.018523 -229.90429) (xy 134.022618 -229.853562) (xy 134.034797 -229.804148)
			(xy 134.054745 -229.757328) (xy 134.081946 -229.714314) (xy 134.115694 -229.67622) (xy 134.155116 -229.644033)
			(xy 134.19919 -229.618587) (xy 134.246776 -229.60054) (xy 134.29664 -229.59036) (xy 134.347492 -229.588311)
			(xy 134.398013 -229.594445) (xy 134.446897 -229.608605) (xy 134.492876 -229.630422) (xy 134.53476 -229.659332)
			(xy 134.571464 -229.694587) (xy 134.602037 -229.735273) (xy 134.625688 -229.780336) (xy 134.641804 -229.82861)
			(xy 134.649968 -229.878844) (xy 134.65048 -229.90429) (xy 134.649977 -229.929279) (xy 134.957294 -229.929279)
			(xy 134.957294 -229.879301) (xy 134.965113 -229.829938) (xy 134.980557 -229.782406) (xy 135.003247 -229.737874)
			(xy 135.032623 -229.697441) (xy 135.067963 -229.662101) (xy 135.108396 -229.632725) (xy 135.152928 -229.610035)
			(xy 135.20046 -229.594591) (xy 135.249823 -229.586772) (xy 135.299801 -229.586772) (xy 135.349164 -229.594591)
			(xy 135.396696 -229.610035) (xy 135.441228 -229.632725) (xy 135.481661 -229.662101) (xy 135.517001 -229.697441)
			(xy 135.546377 -229.737874) (xy 135.569067 -229.782406) (xy 135.584511 -229.829938) (xy 135.59233 -229.879301)
			(xy 135.59282 -229.90429) (xy 135.898631 -229.90429) (xy 135.902726 -229.853562) (xy 135.914905 -229.804148)
			(xy 135.934853 -229.757328) (xy 135.962054 -229.714314) (xy 135.995802 -229.67622) (xy 136.035224 -229.644033)
			(xy 136.079298 -229.618587) (xy 136.126884 -229.60054) (xy 136.176748 -229.59036) (xy 136.2276 -229.588311)
			(xy 136.278121 -229.594445) (xy 136.327005 -229.608605) (xy 136.372984 -229.630422) (xy 136.414868 -229.659332)
			(xy 136.451572 -229.694587) (xy 136.482145 -229.735273) (xy 136.505796 -229.780336) (xy 136.521912 -229.82861)
			(xy 136.530076 -229.878844) (xy 136.530588 -229.90429) (xy 137.778485 -229.90429) (xy 137.78258 -229.853562)
			(xy 137.794759 -229.804148) (xy 137.814707 -229.757328) (xy 137.841908 -229.714314) (xy 137.875656 -229.67622)
			(xy 137.915078 -229.644033) (xy 137.959152 -229.618587) (xy 138.006738 -229.60054) (xy 138.056602 -229.59036)
			(xy 138.107454 -229.588311) (xy 138.157975 -229.594445) (xy 138.206859 -229.608605) (xy 138.252838 -229.630422)
			(xy 138.294722 -229.659332) (xy 138.331426 -229.694587) (xy 138.361999 -229.735273) (xy 138.38565 -229.780336)
			(xy 138.401766 -229.82861) (xy 138.40993 -229.878844) (xy 138.410442 -229.90429) (xy 138.718539 -229.90429)
			(xy 138.722634 -229.853562) (xy 138.734813 -229.804148) (xy 138.754761 -229.757328) (xy 138.781962 -229.714314)
			(xy 138.81571 -229.67622) (xy 138.855132 -229.644033) (xy 138.899206 -229.618587) (xy 138.946792 -229.60054)
			(xy 138.996656 -229.59036) (xy 139.047508 -229.588311) (xy 139.098029 -229.594445) (xy 139.146913 -229.608605)
			(xy 139.192892 -229.630422) (xy 139.234776 -229.659332) (xy 139.27148 -229.694587) (xy 139.302053 -229.735273)
			(xy 139.325704 -229.780336) (xy 139.34182 -229.82861) (xy 139.349984 -229.878844) (xy 139.350496 -229.90429)
			(xy 139.349993 -229.929279) (xy 139.65731 -229.929279) (xy 139.65731 -229.879301) (xy 139.665129 -229.829938)
			(xy 139.680573 -229.782406) (xy 139.703263 -229.737874) (xy 139.732639 -229.697441) (xy 139.767979 -229.662101)
			(xy 139.808412 -229.632725) (xy 139.852944 -229.610035) (xy 139.900476 -229.594591) (xy 139.949839 -229.586772)
			(xy 139.999817 -229.586772) (xy 140.04918 -229.594591) (xy 140.096712 -229.610035) (xy 140.141244 -229.632725)
			(xy 140.181677 -229.662101) (xy 140.217017 -229.697441) (xy 140.246393 -229.737874) (xy 140.269083 -229.782406)
			(xy 140.284527 -229.829938) (xy 140.292346 -229.879301) (xy 140.292836 -229.90429) (xy 140.598647 -229.90429)
			(xy 140.602742 -229.853562) (xy 140.614921 -229.804148) (xy 140.634869 -229.757328) (xy 140.66207 -229.714314)
			(xy 140.695818 -229.67622) (xy 140.73524 -229.644033) (xy 140.779314 -229.618587) (xy 140.8269 -229.60054)
			(xy 140.876764 -229.59036) (xy 140.927616 -229.588311) (xy 140.978137 -229.594445) (xy 141.027021 -229.608605)
			(xy 141.073 -229.630422) (xy 141.114884 -229.659332) (xy 141.151588 -229.694587) (xy 141.182161 -229.735273)
			(xy 141.205812 -229.780336) (xy 141.221928 -229.82861) (xy 141.230092 -229.878844) (xy 141.230604 -229.90429)
			(xy 141.230101 -229.929279) (xy 141.537164 -229.929279) (xy 141.537164 -229.879301) (xy 141.544983 -229.829938)
			(xy 141.560427 -229.782406) (xy 141.583117 -229.737874) (xy 141.612493 -229.697441) (xy 141.647833 -229.662101)
			(xy 141.688266 -229.632725) (xy 141.732798 -229.610035) (xy 141.78033 -229.594591) (xy 141.829693 -229.586772)
			(xy 141.879671 -229.586772) (xy 141.929034 -229.594591) (xy 141.976566 -229.610035) (xy 142.021098 -229.632725)
			(xy 142.061531 -229.662101) (xy 142.096871 -229.697441) (xy 142.126247 -229.737874) (xy 142.148937 -229.782406)
			(xy 142.164381 -229.829938) (xy 142.1722 -229.879301) (xy 142.17269 -229.90429) (xy 142.478501 -229.90429)
			(xy 142.482596 -229.853562) (xy 142.494775 -229.804148) (xy 142.514723 -229.757328) (xy 142.541924 -229.714314)
			(xy 142.575672 -229.67622) (xy 142.615094 -229.644033) (xy 142.659168 -229.618587) (xy 142.706754 -229.60054)
			(xy 142.756618 -229.59036) (xy 142.80747 -229.588311) (xy 142.857991 -229.594445) (xy 142.906875 -229.608605)
			(xy 142.952854 -229.630422) (xy 142.994738 -229.659332) (xy 143.031442 -229.694587) (xy 143.062015 -229.735273)
			(xy 143.085666 -229.780336) (xy 143.101782 -229.82861) (xy 143.109946 -229.878844) (xy 143.110458 -229.90429)
			(xy 143.109946 -229.929736) (xy 143.101782 -229.97997) (xy 143.085666 -230.028244) (xy 143.062015 -230.073307)
			(xy 143.031442 -230.113993) (xy 142.994738 -230.149248) (xy 142.952854 -230.178158) (xy 142.906875 -230.199975)
			(xy 142.857991 -230.214135) (xy 142.80747 -230.220269) (xy 142.756618 -230.21822) (xy 142.706754 -230.20804)
			(xy 142.659168 -230.189993) (xy 142.615094 -230.164547) (xy 142.575672 -230.13236) (xy 142.541924 -230.094266)
			(xy 142.514723 -230.051252) (xy 142.494775 -230.004432) (xy 142.482596 -229.955018) (xy 142.478501 -229.90429)
			(xy 142.17269 -229.90429) (xy 142.1722 -229.929279) (xy 142.164381 -229.978642) (xy 142.148937 -230.026174)
			(xy 142.126247 -230.070706) (xy 142.096871 -230.111139) (xy 142.061531 -230.146479) (xy 142.021098 -230.175855)
			(xy 141.976566 -230.198545) (xy 141.929034 -230.213989) (xy 141.879671 -230.221808) (xy 141.829693 -230.221808)
			(xy 141.78033 -230.213989) (xy 141.732798 -230.198545) (xy 141.688266 -230.175855) (xy 141.647833 -230.146479)
			(xy 141.612493 -230.111139) (xy 141.583117 -230.070706) (xy 141.560427 -230.026174) (xy 141.544983 -229.978642)
			(xy 141.537164 -229.929279) (xy 141.230101 -229.929279) (xy 141.230092 -229.929736) (xy 141.221928 -229.97997)
			(xy 141.205812 -230.028244) (xy 141.182161 -230.073307) (xy 141.151588 -230.113993) (xy 141.114884 -230.149248)
			(xy 141.073 -230.178158) (xy 141.027021 -230.199975) (xy 140.978137 -230.214135) (xy 140.927616 -230.220269)
			(xy 140.876764 -230.21822) (xy 140.8269 -230.20804) (xy 140.779314 -230.189993) (xy 140.73524 -230.164547)
			(xy 140.695818 -230.13236) (xy 140.66207 -230.094266) (xy 140.634869 -230.051252) (xy 140.614921 -230.004432)
			(xy 140.602742 -229.955018) (xy 140.598647 -229.90429) (xy 140.292836 -229.90429) (xy 140.292346 -229.929279)
			(xy 140.284527 -229.978642) (xy 140.269083 -230.026174) (xy 140.246393 -230.070706) (xy 140.217017 -230.111139)
			(xy 140.181677 -230.146479) (xy 140.141244 -230.175855) (xy 140.096712 -230.198545) (xy 140.04918 -230.213989)
			(xy 139.999817 -230.221808) (xy 139.949839 -230.221808) (xy 139.900476 -230.213989) (xy 139.852944 -230.198545)
			(xy 139.808412 -230.175855) (xy 139.767979 -230.146479) (xy 139.732639 -230.111139) (xy 139.703263 -230.070706)
			(xy 139.680573 -230.026174) (xy 139.665129 -229.978642) (xy 139.65731 -229.929279) (xy 139.349993 -229.929279)
			(xy 139.349984 -229.929736) (xy 139.34182 -229.97997) (xy 139.325704 -230.028244) (xy 139.302053 -230.073307)
			(xy 139.27148 -230.113993) (xy 139.234776 -230.149248) (xy 139.192892 -230.178158) (xy 139.146913 -230.199975)
			(xy 139.098029 -230.214135) (xy 139.047508 -230.220269) (xy 138.996656 -230.21822) (xy 138.946792 -230.20804)
			(xy 138.899206 -230.189993) (xy 138.855132 -230.164547) (xy 138.81571 -230.13236) (xy 138.781962 -230.094266)
			(xy 138.754761 -230.051252) (xy 138.734813 -230.004432) (xy 138.722634 -229.955018) (xy 138.718539 -229.90429)
			(xy 138.410442 -229.90429) (xy 138.40993 -229.929736) (xy 138.401766 -229.97997) (xy 138.38565 -230.028244)
			(xy 138.361999 -230.073307) (xy 138.331426 -230.113993) (xy 138.294722 -230.149248) (xy 138.252838 -230.178158)
			(xy 138.206859 -230.199975) (xy 138.157975 -230.214135) (xy 138.107454 -230.220269) (xy 138.056602 -230.21822)
			(xy 138.006738 -230.20804) (xy 137.959152 -230.189993) (xy 137.915078 -230.164547) (xy 137.875656 -230.13236)
			(xy 137.841908 -230.094266) (xy 137.814707 -230.051252) (xy 137.794759 -230.004432) (xy 137.78258 -229.955018)
			(xy 137.778485 -229.90429) (xy 136.530588 -229.90429) (xy 136.530076 -229.929736) (xy 136.521912 -229.97997)
			(xy 136.505796 -230.028244) (xy 136.482145 -230.073307) (xy 136.451572 -230.113993) (xy 136.414868 -230.149248)
			(xy 136.372984 -230.178158) (xy 136.327005 -230.199975) (xy 136.278121 -230.214135) (xy 136.2276 -230.220269)
			(xy 136.176748 -230.21822) (xy 136.126884 -230.20804) (xy 136.079298 -230.189993) (xy 136.035224 -230.164547)
			(xy 135.995802 -230.13236) (xy 135.962054 -230.094266) (xy 135.934853 -230.051252) (xy 135.914905 -230.004432)
			(xy 135.902726 -229.955018) (xy 135.898631 -229.90429) (xy 135.59282 -229.90429) (xy 135.59233 -229.929279)
			(xy 135.584511 -229.978642) (xy 135.569067 -230.026174) (xy 135.546377 -230.070706) (xy 135.517001 -230.111139)
			(xy 135.481661 -230.146479) (xy 135.441228 -230.175855) (xy 135.396696 -230.198545) (xy 135.349164 -230.213989)
			(xy 135.299801 -230.221808) (xy 135.249823 -230.221808) (xy 135.20046 -230.213989) (xy 135.152928 -230.198545)
			(xy 135.108396 -230.175855) (xy 135.067963 -230.146479) (xy 135.032623 -230.111139) (xy 135.003247 -230.070706)
			(xy 134.980557 -230.026174) (xy 134.965113 -229.978642) (xy 134.957294 -229.929279) (xy 134.649977 -229.929279)
			(xy 134.649968 -229.929736) (xy 134.641804 -229.97997) (xy 134.625688 -230.028244) (xy 134.602037 -230.073307)
			(xy 134.571464 -230.113993) (xy 134.53476 -230.149248) (xy 134.492876 -230.178158) (xy 134.446897 -230.199975)
			(xy 134.398013 -230.214135) (xy 134.347492 -230.220269) (xy 134.29664 -230.21822) (xy 134.246776 -230.20804)
			(xy 134.19919 -230.189993) (xy 134.155116 -230.164547) (xy 134.115694 -230.13236) (xy 134.081946 -230.094266)
			(xy 134.054745 -230.051252) (xy 134.034797 -230.004432) (xy 134.022618 -229.955018) (xy 134.018523 -229.90429)
			(xy 133.712712 -229.90429) (xy 133.712222 -229.929279) (xy 133.704403 -229.978642) (xy 133.688959 -230.026174)
			(xy 133.666269 -230.070706) (xy 133.636893 -230.111139) (xy 133.601553 -230.146479) (xy 133.56112 -230.175855)
			(xy 133.516588 -230.198545) (xy 133.469056 -230.213989) (xy 133.419693 -230.221808) (xy 133.369715 -230.221808)
			(xy 133.320352 -230.213989) (xy 133.27282 -230.198545) (xy 133.228288 -230.175855) (xy 133.187855 -230.146479)
			(xy 133.152515 -230.111139) (xy 133.123139 -230.070706) (xy 133.100449 -230.026174) (xy 133.085005 -229.978642)
			(xy 133.077186 -229.929279) (xy 132.769869 -229.929279) (xy 132.76986 -229.929736) (xy 132.761696 -229.97997)
			(xy 132.74558 -230.028244) (xy 132.721929 -230.073307) (xy 132.691356 -230.113993) (xy 132.654652 -230.149248)
			(xy 132.612768 -230.178158) (xy 132.566789 -230.199975) (xy 132.517905 -230.214135) (xy 132.467384 -230.220269)
			(xy 132.416532 -230.21822) (xy 132.366668 -230.20804) (xy 132.319082 -230.189993) (xy 132.275008 -230.164547)
			(xy 132.235586 -230.13236) (xy 132.201838 -230.094266) (xy 132.174637 -230.051252) (xy 132.154689 -230.004432)
			(xy 132.14251 -229.955018) (xy 132.138415 -229.90429) (xy 131.830572 -229.90429) (xy 131.83006 -229.929736)
			(xy 131.821896 -229.97997) (xy 131.80578 -230.028244) (xy 131.782129 -230.073307) (xy 131.751556 -230.113993)
			(xy 131.714852 -230.149248) (xy 131.672968 -230.178158) (xy 131.626989 -230.199975) (xy 131.578105 -230.214135)
			(xy 131.527584 -230.220269) (xy 131.476732 -230.21822) (xy 131.426868 -230.20804) (xy 131.379282 -230.189993)
			(xy 131.335208 -230.164547) (xy 131.295786 -230.13236) (xy 131.262038 -230.094266) (xy 131.234837 -230.051252)
			(xy 131.214889 -230.004432) (xy 131.20271 -229.955018) (xy 131.198615 -229.90429) (xy 129.950464 -229.90429)
			(xy 129.949952 -229.929736) (xy 129.941788 -229.97997) (xy 129.925672 -230.028244) (xy 129.902021 -230.073307)
			(xy 129.871448 -230.113993) (xy 129.834744 -230.149248) (xy 129.79286 -230.178158) (xy 129.746881 -230.199975)
			(xy 129.697997 -230.214135) (xy 129.647476 -230.220269) (xy 129.596624 -230.21822) (xy 129.54676 -230.20804)
			(xy 129.499174 -230.189993) (xy 129.4551 -230.164547) (xy 129.415678 -230.13236) (xy 129.38193 -230.094266)
			(xy 129.354729 -230.051252) (xy 129.334781 -230.004432) (xy 129.322602 -229.955018) (xy 129.318507 -229.90429)
			(xy 129.012696 -229.90429) (xy 129.012206 -229.929279) (xy 129.004387 -229.978642) (xy 128.988943 -230.026174)
			(xy 128.966253 -230.070706) (xy 128.936877 -230.111139) (xy 128.901537 -230.146479) (xy 128.861104 -230.175855)
			(xy 128.816572 -230.198545) (xy 128.76904 -230.213989) (xy 128.719677 -230.221808) (xy 128.669699 -230.221808)
			(xy 128.620336 -230.213989) (xy 128.572804 -230.198545) (xy 128.528272 -230.175855) (xy 128.487839 -230.146479)
			(xy 128.452499 -230.111139) (xy 128.423123 -230.070706) (xy 128.400433 -230.026174) (xy 128.384989 -229.978642)
			(xy 128.37717 -229.929279) (xy 128.069853 -229.929279) (xy 128.069844 -229.929736) (xy 128.06168 -229.97997)
			(xy 128.045564 -230.028244) (xy 128.021913 -230.073307) (xy 127.99134 -230.113993) (xy 127.954636 -230.149248)
			(xy 127.912752 -230.178158) (xy 127.866773 -230.199975) (xy 127.817889 -230.214135) (xy 127.767368 -230.220269)
			(xy 127.716516 -230.21822) (xy 127.666652 -230.20804) (xy 127.619066 -230.189993) (xy 127.574992 -230.164547)
			(xy 127.53557 -230.13236) (xy 127.501822 -230.094266) (xy 127.474621 -230.051252) (xy 127.454673 -230.004432)
			(xy 127.442494 -229.955018) (xy 127.438399 -229.90429) (xy 127.132328 -229.90429) (xy 127.132328 -229.929288)
			(xy 127.12451 -229.97865) (xy 127.109068 -230.02618) (xy 127.08638 -230.070711) (xy 127.057006 -230.111144)
			(xy 127.02167 -230.146484) (xy 126.98124 -230.175862) (xy 126.936712 -230.198555) (xy 126.889183 -230.214002)
			(xy 126.839822 -230.221825) (xy 126.814834 -230.222298) (xy 126.802206 -230.22215) (xy 126.777031 -230.220112)
			(xy 126.764542 -230.218234) (xy 126.75362 -230.216456) (xy 126.74346 -230.21925) (xy 126.738264 -230.220878)
			(xy 126.728657 -230.226002) (xy 126.72441 -230.22941) (xy 126.663958 -230.280718) (xy 126.657456 -230.28762)
			(xy 126.649519 -230.304822) (xy 126.648464 -230.314246) (xy 126.648464 -230.608886) (xy 126.648972 -230.615998)
			(xy 126.650496 -230.62692) (xy 126.656204 -230.648376) (xy 126.662321 -230.692351) (xy 126.662688 -230.71455)
			(xy 126.66237 -230.736816) (xy 126.661992 -230.739539) (xy 126.967216 -230.739539) (xy 126.967216 -230.689561)
			(xy 126.975035 -230.640198) (xy 126.990479 -230.592666) (xy 127.013169 -230.548134) (xy 127.042545 -230.507701)
			(xy 127.077885 -230.472361) (xy 127.118318 -230.442985) (xy 127.16285 -230.420295) (xy 127.210382 -230.404851)
			(xy 127.259745 -230.397032) (xy 127.309723 -230.397032) (xy 127.359086 -230.404851) (xy 127.406618 -230.420295)
			(xy 127.45115 -230.442985) (xy 127.491583 -230.472361) (xy 127.526923 -230.507701) (xy 127.556299 -230.548134)
			(xy 127.578989 -230.592666) (xy 127.594433 -230.640198) (xy 127.602252 -230.689561) (xy 127.602742 -230.71455)
			(xy 127.908553 -230.71455) (xy 127.912648 -230.663822) (xy 127.924827 -230.614408) (xy 127.944775 -230.567588)
			(xy 127.971976 -230.524574) (xy 128.005724 -230.48648) (xy 128.045146 -230.454293) (xy 128.08922 -230.428847)
			(xy 128.136806 -230.4108) (xy 128.18667 -230.40062) (xy 128.237522 -230.398571) (xy 128.288043 -230.404705)
			(xy 128.336927 -230.418865) (xy 128.382906 -230.440682) (xy 128.42479 -230.469592) (xy 128.461494 -230.504847)
			(xy 128.492067 -230.545533) (xy 128.515718 -230.590596) (xy 128.531834 -230.63887) (xy 128.539998 -230.689104)
			(xy 128.54051 -230.71455) (xy 128.848607 -230.71455) (xy 128.852702 -230.663822) (xy 128.864881 -230.614408)
			(xy 128.884829 -230.567588) (xy 128.91203 -230.524574) (xy 128.945778 -230.48648) (xy 128.9852 -230.454293)
			(xy 129.029274 -230.428847) (xy 129.07686 -230.4108) (xy 129.126724 -230.40062) (xy 129.177576 -230.398571)
			(xy 129.228097 -230.404705) (xy 129.276981 -230.418865) (xy 129.32296 -230.440682) (xy 129.364844 -230.469592)
			(xy 129.401548 -230.504847) (xy 129.432121 -230.545533) (xy 129.455772 -230.590596) (xy 129.471888 -230.63887)
			(xy 129.480052 -230.689104) (xy 129.480564 -230.71455) (xy 129.480061 -230.739539) (xy 129.787124 -230.739539)
			(xy 129.787124 -230.689561) (xy 129.794943 -230.640198) (xy 129.810387 -230.592666) (xy 129.833077 -230.548134)
			(xy 129.862453 -230.507701) (xy 129.897793 -230.472361) (xy 129.938226 -230.442985) (xy 129.982758 -230.420295)
			(xy 130.03029 -230.404851) (xy 130.079653 -230.397032) (xy 130.129631 -230.397032) (xy 130.178994 -230.404851)
			(xy 130.226526 -230.420295) (xy 130.271058 -230.442985) (xy 130.311491 -230.472361) (xy 130.346831 -230.507701)
			(xy 130.376207 -230.548134) (xy 130.398897 -230.592666) (xy 130.414341 -230.640198) (xy 130.42216 -230.689561)
			(xy 130.42265 -230.71455) (xy 130.728461 -230.71455) (xy 130.732556 -230.663822) (xy 130.744735 -230.614408)
			(xy 130.764683 -230.567588) (xy 130.791884 -230.524574) (xy 130.825632 -230.48648) (xy 130.865054 -230.454293)
			(xy 130.909128 -230.428847) (xy 130.956714 -230.4108) (xy 131.006578 -230.40062) (xy 131.05743 -230.398571)
			(xy 131.107951 -230.404705) (xy 131.156835 -230.418865) (xy 131.202814 -230.440682) (xy 131.244698 -230.469592)
			(xy 131.281402 -230.504847) (xy 131.311975 -230.545533) (xy 131.335626 -230.590596) (xy 131.351742 -230.63887)
			(xy 131.359906 -230.689104) (xy 131.360418 -230.71455) (xy 131.359915 -230.739539) (xy 131.667232 -230.739539)
			(xy 131.667232 -230.689561) (xy 131.675051 -230.640198) (xy 131.690495 -230.592666) (xy 131.713185 -230.548134)
			(xy 131.742561 -230.507701) (xy 131.777901 -230.472361) (xy 131.818334 -230.442985) (xy 131.862866 -230.420295)
			(xy 131.910398 -230.404851) (xy 131.959761 -230.397032) (xy 132.009739 -230.397032) (xy 132.059102 -230.404851)
			(xy 132.106634 -230.420295) (xy 132.151166 -230.442985) (xy 132.191599 -230.472361) (xy 132.226939 -230.507701)
			(xy 132.256315 -230.548134) (xy 132.279005 -230.592666) (xy 132.294449 -230.640198) (xy 132.302268 -230.689561)
			(xy 132.302758 -230.71455) (xy 132.608569 -230.71455) (xy 132.612664 -230.663822) (xy 132.624843 -230.614408)
			(xy 132.644791 -230.567588) (xy 132.671992 -230.524574) (xy 132.70574 -230.48648) (xy 132.745162 -230.454293)
			(xy 132.789236 -230.428847) (xy 132.836822 -230.4108) (xy 132.886686 -230.40062) (xy 132.937538 -230.398571)
			(xy 132.988059 -230.404705) (xy 133.036943 -230.418865) (xy 133.082922 -230.440682) (xy 133.124806 -230.469592)
			(xy 133.16151 -230.504847) (xy 133.192083 -230.545533) (xy 133.215734 -230.590596) (xy 133.23185 -230.63887)
			(xy 133.240014 -230.689104) (xy 133.240526 -230.71455) (xy 133.240028 -230.739285) (xy 133.54734 -230.739285)
			(xy 133.54734 -230.689307) (xy 133.555159 -230.639944) (xy 133.570603 -230.592412) (xy 133.593293 -230.54788)
			(xy 133.622669 -230.507447) (xy 133.658009 -230.472107) (xy 133.698442 -230.442731) (xy 133.742974 -230.420041)
			(xy 133.790506 -230.404597) (xy 133.839869 -230.396778) (xy 133.889847 -230.396778) (xy 133.93921 -230.404597)
			(xy 133.986742 -230.420041) (xy 134.031274 -230.442731) (xy 134.071707 -230.472107) (xy 134.107047 -230.507447)
			(xy 134.136423 -230.54788) (xy 134.159113 -230.592412) (xy 134.174557 -230.639944) (xy 134.182376 -230.689307)
			(xy 134.182866 -230.714296) (xy 134.182861 -230.71455) (xy 134.488423 -230.71455) (xy 134.492518 -230.663822)
			(xy 134.504697 -230.614408) (xy 134.524645 -230.567588) (xy 134.551846 -230.524574) (xy 134.585594 -230.48648)
			(xy 134.625016 -230.454293) (xy 134.66909 -230.428847) (xy 134.716676 -230.4108) (xy 134.76654 -230.40062)
			(xy 134.817392 -230.398571) (xy 134.867913 -230.404705) (xy 134.916797 -230.418865) (xy 134.962776 -230.440682)
			(xy 135.00466 -230.469592) (xy 135.041364 -230.504847) (xy 135.071937 -230.545533) (xy 135.095588 -230.590596)
			(xy 135.111704 -230.63887) (xy 135.119868 -230.689104) (xy 135.12038 -230.71455) (xy 135.428477 -230.71455)
			(xy 135.432572 -230.663822) (xy 135.444751 -230.614408) (xy 135.464699 -230.567588) (xy 135.4919 -230.524574)
			(xy 135.525648 -230.48648) (xy 135.56507 -230.454293) (xy 135.609144 -230.428847) (xy 135.65673 -230.4108)
			(xy 135.706594 -230.40062) (xy 135.757446 -230.398571) (xy 135.807967 -230.404705) (xy 135.856851 -230.418865)
			(xy 135.90283 -230.440682) (xy 135.944714 -230.469592) (xy 135.981418 -230.504847) (xy 136.011991 -230.545533)
			(xy 136.035642 -230.590596) (xy 136.051758 -230.63887) (xy 136.059922 -230.689104) (xy 136.060434 -230.71455)
			(xy 136.059931 -230.739539) (xy 136.367248 -230.739539) (xy 136.367248 -230.689561) (xy 136.375067 -230.640198)
			(xy 136.390511 -230.592666) (xy 136.413201 -230.548134) (xy 136.442577 -230.507701) (xy 136.477917 -230.472361)
			(xy 136.51835 -230.442985) (xy 136.562882 -230.420295) (xy 136.610414 -230.404851) (xy 136.659777 -230.397032)
			(xy 136.709755 -230.397032) (xy 136.759118 -230.404851) (xy 136.80665 -230.420295) (xy 136.851182 -230.442985)
			(xy 136.891615 -230.472361) (xy 136.926955 -230.507701) (xy 136.956331 -230.548134) (xy 136.979021 -230.592666)
			(xy 136.994465 -230.640198) (xy 137.002284 -230.689561) (xy 137.002774 -230.71455) (xy 137.308585 -230.71455)
			(xy 137.31268 -230.663822) (xy 137.324859 -230.614408) (xy 137.344807 -230.567588) (xy 137.372008 -230.524574)
			(xy 137.405756 -230.48648) (xy 137.445178 -230.454293) (xy 137.489252 -230.428847) (xy 137.536838 -230.4108)
			(xy 137.586702 -230.40062) (xy 137.637554 -230.398571) (xy 137.688075 -230.404705) (xy 137.736959 -230.418865)
			(xy 137.782938 -230.440682) (xy 137.824822 -230.469592) (xy 137.861526 -230.504847) (xy 137.892099 -230.545533)
			(xy 137.91575 -230.590596) (xy 137.931866 -230.63887) (xy 137.94003 -230.689104) (xy 137.940542 -230.71455)
			(xy 137.940044 -230.739285) (xy 138.247356 -230.739285) (xy 138.247356 -230.689307) (xy 138.255175 -230.639944)
			(xy 138.270619 -230.592412) (xy 138.293309 -230.54788) (xy 138.322685 -230.507447) (xy 138.358025 -230.472107)
			(xy 138.398458 -230.442731) (xy 138.44299 -230.420041) (xy 138.490522 -230.404597) (xy 138.539885 -230.396778)
			(xy 138.589863 -230.396778) (xy 138.639226 -230.404597) (xy 138.686758 -230.420041) (xy 138.73129 -230.442731)
			(xy 138.771723 -230.472107) (xy 138.807063 -230.507447) (xy 138.836439 -230.54788) (xy 138.859129 -230.592412)
			(xy 138.874573 -230.639944) (xy 138.882392 -230.689307) (xy 138.882882 -230.714296) (xy 138.882877 -230.71455)
			(xy 139.188439 -230.71455) (xy 139.192534 -230.663822) (xy 139.204713 -230.614408) (xy 139.224661 -230.567588)
			(xy 139.251862 -230.524574) (xy 139.28561 -230.48648) (xy 139.325032 -230.454293) (xy 139.369106 -230.428847)
			(xy 139.416692 -230.4108) (xy 139.466556 -230.40062) (xy 139.517408 -230.398571) (xy 139.567929 -230.404705)
			(xy 139.616813 -230.418865) (xy 139.662792 -230.440682) (xy 139.704676 -230.469592) (xy 139.74138 -230.504847)
			(xy 139.771953 -230.545533) (xy 139.795604 -230.590596) (xy 139.81172 -230.63887) (xy 139.819884 -230.689104)
			(xy 139.820396 -230.71455) (xy 139.819893 -230.739539) (xy 140.12721 -230.739539) (xy 140.12721 -230.689561)
			(xy 140.135029 -230.640198) (xy 140.150473 -230.592666) (xy 140.173163 -230.548134) (xy 140.202539 -230.507701)
			(xy 140.237879 -230.472361) (xy 140.278312 -230.442985) (xy 140.322844 -230.420295) (xy 140.370376 -230.404851)
			(xy 140.419739 -230.397032) (xy 140.469717 -230.397032) (xy 140.51908 -230.404851) (xy 140.566612 -230.420295)
			(xy 140.611144 -230.442985) (xy 140.651577 -230.472361) (xy 140.686917 -230.507701) (xy 140.716293 -230.548134)
			(xy 140.738983 -230.592666) (xy 140.754427 -230.640198) (xy 140.762246 -230.689561) (xy 140.762736 -230.71455)
			(xy 141.068547 -230.71455) (xy 141.072642 -230.663822) (xy 141.084821 -230.614408) (xy 141.104769 -230.567588)
			(xy 141.13197 -230.524574) (xy 141.165718 -230.48648) (xy 141.20514 -230.454293) (xy 141.249214 -230.428847)
			(xy 141.2968 -230.4108) (xy 141.346664 -230.40062) (xy 141.397516 -230.398571) (xy 141.448037 -230.404705)
			(xy 141.496921 -230.418865) (xy 141.5429 -230.440682) (xy 141.584784 -230.469592) (xy 141.621488 -230.504847)
			(xy 141.652061 -230.545533) (xy 141.675712 -230.590596) (xy 141.691828 -230.63887) (xy 141.699992 -230.689104)
			(xy 141.700504 -230.71455) (xy 142.008601 -230.71455) (xy 142.012696 -230.663822) (xy 142.024875 -230.614408)
			(xy 142.044823 -230.567588) (xy 142.072024 -230.524574) (xy 142.105772 -230.48648) (xy 142.145194 -230.454293)
			(xy 142.189268 -230.428847) (xy 142.236854 -230.4108) (xy 142.286718 -230.40062) (xy 142.33757 -230.398571)
			(xy 142.388091 -230.404705) (xy 142.436975 -230.418865) (xy 142.482954 -230.440682) (xy 142.524838 -230.469592)
			(xy 142.561542 -230.504847) (xy 142.592115 -230.545533) (xy 142.615766 -230.590596) (xy 142.631882 -230.63887)
			(xy 142.640046 -230.689104) (xy 142.640558 -230.71455) (xy 142.640055 -230.739539) (xy 142.947118 -230.739539)
			(xy 142.947118 -230.689561) (xy 142.954937 -230.640198) (xy 142.970381 -230.592666) (xy 142.993071 -230.548134)
			(xy 143.022447 -230.507701) (xy 143.057787 -230.472361) (xy 143.09822 -230.442985) (xy 143.142752 -230.420295)
			(xy 143.190284 -230.404851) (xy 143.239647 -230.397032) (xy 143.289625 -230.397032) (xy 143.338988 -230.404851)
			(xy 143.38652 -230.420295) (xy 143.431052 -230.442985) (xy 143.471485 -230.472361) (xy 143.506825 -230.507701)
			(xy 143.536201 -230.548134) (xy 143.558891 -230.592666) (xy 143.574335 -230.640198) (xy 143.582154 -230.689561)
			(xy 143.582644 -230.71455) (xy 143.582154 -230.739539) (xy 143.574335 -230.788902) (xy 143.558891 -230.836434)
			(xy 143.536201 -230.880966) (xy 143.506825 -230.921399) (xy 143.471485 -230.956739) (xy 143.431052 -230.986115)
			(xy 143.38652 -231.008805) (xy 143.338988 -231.024249) (xy 143.289625 -231.032068) (xy 143.239647 -231.032068)
			(xy 143.190284 -231.024249) (xy 143.142752 -231.008805) (xy 143.09822 -230.986115) (xy 143.057787 -230.956739)
			(xy 143.022447 -230.921399) (xy 142.993071 -230.880966) (xy 142.970381 -230.836434) (xy 142.954937 -230.788902)
			(xy 142.947118 -230.739539) (xy 142.640055 -230.739539) (xy 142.640046 -230.739996) (xy 142.631882 -230.79023)
			(xy 142.615766 -230.838504) (xy 142.592115 -230.883567) (xy 142.561542 -230.924253) (xy 142.524838 -230.959508)
			(xy 142.482954 -230.988418) (xy 142.436975 -231.010235) (xy 142.388091 -231.024395) (xy 142.33757 -231.030529)
			(xy 142.286718 -231.02848) (xy 142.236854 -231.0183) (xy 142.189268 -231.000253) (xy 142.145194 -230.974807)
			(xy 142.105772 -230.94262) (xy 142.072024 -230.904526) (xy 142.044823 -230.861512) (xy 142.024875 -230.814692)
			(xy 142.012696 -230.765278) (xy 142.008601 -230.71455) (xy 141.700504 -230.71455) (xy 141.699992 -230.739996)
			(xy 141.691828 -230.79023) (xy 141.675712 -230.838504) (xy 141.652061 -230.883567) (xy 141.621488 -230.924253)
			(xy 141.584784 -230.959508) (xy 141.5429 -230.988418) (xy 141.496921 -231.010235) (xy 141.448037 -231.024395)
			(xy 141.397516 -231.030529) (xy 141.346664 -231.02848) (xy 141.2968 -231.0183) (xy 141.249214 -231.000253)
			(xy 141.20514 -230.974807) (xy 141.165718 -230.94262) (xy 141.13197 -230.904526) (xy 141.104769 -230.861512)
			(xy 141.084821 -230.814692) (xy 141.072642 -230.765278) (xy 141.068547 -230.71455) (xy 140.762736 -230.71455)
			(xy 140.762246 -230.739539) (xy 140.754427 -230.788902) (xy 140.738983 -230.836434) (xy 140.716293 -230.880966)
			(xy 140.686917 -230.921399) (xy 140.651577 -230.956739) (xy 140.611144 -230.986115) (xy 140.566612 -231.008805)
			(xy 140.51908 -231.024249) (xy 140.469717 -231.032068) (xy 140.419739 -231.032068) (xy 140.370376 -231.024249)
			(xy 140.322844 -231.008805) (xy 140.278312 -230.986115) (xy 140.237879 -230.956739) (xy 140.202539 -230.921399)
			(xy 140.173163 -230.880966) (xy 140.150473 -230.836434) (xy 140.135029 -230.788902) (xy 140.12721 -230.739539)
			(xy 139.819893 -230.739539) (xy 139.819884 -230.739996) (xy 139.81172 -230.79023) (xy 139.795604 -230.838504)
			(xy 139.771953 -230.883567) (xy 139.74138 -230.924253) (xy 139.704676 -230.959508) (xy 139.662792 -230.988418)
			(xy 139.616813 -231.010235) (xy 139.567929 -231.024395) (xy 139.517408 -231.030529) (xy 139.466556 -231.02848)
			(xy 139.416692 -231.0183) (xy 139.369106 -231.000253) (xy 139.325032 -230.974807) (xy 139.28561 -230.94262)
			(xy 139.251862 -230.904526) (xy 139.224661 -230.861512) (xy 139.204713 -230.814692) (xy 139.192534 -230.765278)
			(xy 139.188439 -230.71455) (xy 138.882877 -230.71455) (xy 138.882392 -230.739285) (xy 138.874573 -230.788648)
			(xy 138.859129 -230.83618) (xy 138.836439 -230.880712) (xy 138.807063 -230.921145) (xy 138.771723 -230.956485)
			(xy 138.73129 -230.985861) (xy 138.686758 -231.008551) (xy 138.639226 -231.023995) (xy 138.589863 -231.031814)
			(xy 138.539885 -231.031814) (xy 138.490522 -231.023995) (xy 138.44299 -231.008551) (xy 138.398458 -230.985861)
			(xy 138.358025 -230.956485) (xy 138.322685 -230.921145) (xy 138.293309 -230.880712) (xy 138.270619 -230.83618)
			(xy 138.255175 -230.788648) (xy 138.247356 -230.739285) (xy 137.940044 -230.739285) (xy 137.94003 -230.739996)
			(xy 137.931866 -230.79023) (xy 137.91575 -230.838504) (xy 137.892099 -230.883567) (xy 137.861526 -230.924253)
			(xy 137.824822 -230.959508) (xy 137.782938 -230.988418) (xy 137.736959 -231.010235) (xy 137.688075 -231.024395)
			(xy 137.637554 -231.030529) (xy 137.586702 -231.02848) (xy 137.536838 -231.0183) (xy 137.489252 -231.000253)
			(xy 137.445178 -230.974807) (xy 137.405756 -230.94262) (xy 137.372008 -230.904526) (xy 137.344807 -230.861512)
			(xy 137.324859 -230.814692) (xy 137.31268 -230.765278) (xy 137.308585 -230.71455) (xy 137.002774 -230.71455)
			(xy 137.002284 -230.739539) (xy 136.994465 -230.788902) (xy 136.979021 -230.836434) (xy 136.956331 -230.880966)
			(xy 136.926955 -230.921399) (xy 136.891615 -230.956739) (xy 136.851182 -230.986115) (xy 136.80665 -231.008805)
			(xy 136.759118 -231.024249) (xy 136.709755 -231.032068) (xy 136.659777 -231.032068) (xy 136.610414 -231.024249)
			(xy 136.562882 -231.008805) (xy 136.51835 -230.986115) (xy 136.477917 -230.956739) (xy 136.442577 -230.921399)
			(xy 136.413201 -230.880966) (xy 136.390511 -230.836434) (xy 136.375067 -230.788902) (xy 136.367248 -230.739539)
			(xy 136.059931 -230.739539) (xy 136.059922 -230.739996) (xy 136.051758 -230.79023) (xy 136.035642 -230.838504)
			(xy 136.011991 -230.883567) (xy 135.981418 -230.924253) (xy 135.944714 -230.959508) (xy 135.90283 -230.988418)
			(xy 135.856851 -231.010235) (xy 135.807967 -231.024395) (xy 135.757446 -231.030529) (xy 135.706594 -231.02848)
			(xy 135.65673 -231.0183) (xy 135.609144 -231.000253) (xy 135.56507 -230.974807) (xy 135.525648 -230.94262)
			(xy 135.4919 -230.904526) (xy 135.464699 -230.861512) (xy 135.444751 -230.814692) (xy 135.432572 -230.765278)
			(xy 135.428477 -230.71455) (xy 135.12038 -230.71455) (xy 135.119868 -230.739996) (xy 135.111704 -230.79023)
			(xy 135.095588 -230.838504) (xy 135.071937 -230.883567) (xy 135.041364 -230.924253) (xy 135.00466 -230.959508)
			(xy 134.962776 -230.988418) (xy 134.916797 -231.010235) (xy 134.867913 -231.024395) (xy 134.817392 -231.030529)
			(xy 134.76654 -231.02848) (xy 134.716676 -231.0183) (xy 134.66909 -231.000253) (xy 134.625016 -230.974807)
			(xy 134.585594 -230.94262) (xy 134.551846 -230.904526) (xy 134.524645 -230.861512) (xy 134.504697 -230.814692)
			(xy 134.492518 -230.765278) (xy 134.488423 -230.71455) (xy 134.182861 -230.71455) (xy 134.182376 -230.739285)
			(xy 134.174557 -230.788648) (xy 134.159113 -230.83618) (xy 134.136423 -230.880712) (xy 134.107047 -230.921145)
			(xy 134.071707 -230.956485) (xy 134.031274 -230.985861) (xy 133.986742 -231.008551) (xy 133.93921 -231.023995)
			(xy 133.889847 -231.031814) (xy 133.839869 -231.031814) (xy 133.790506 -231.023995) (xy 133.742974 -231.008551)
			(xy 133.698442 -230.985861) (xy 133.658009 -230.956485) (xy 133.622669 -230.921145) (xy 133.593293 -230.880712)
			(xy 133.570603 -230.83618) (xy 133.555159 -230.788648) (xy 133.54734 -230.739285) (xy 133.240028 -230.739285)
			(xy 133.240014 -230.739996) (xy 133.23185 -230.79023) (xy 133.215734 -230.838504) (xy 133.192083 -230.883567)
			(xy 133.16151 -230.924253) (xy 133.124806 -230.959508) (xy 133.082922 -230.988418) (xy 133.036943 -231.010235)
			(xy 132.988059 -231.024395) (xy 132.937538 -231.030529) (xy 132.886686 -231.02848) (xy 132.836822 -231.0183)
			(xy 132.789236 -231.000253) (xy 132.745162 -230.974807) (xy 132.70574 -230.94262) (xy 132.671992 -230.904526)
			(xy 132.644791 -230.861512) (xy 132.624843 -230.814692) (xy 132.612664 -230.765278) (xy 132.608569 -230.71455)
			(xy 132.302758 -230.71455) (xy 132.302268 -230.739539) (xy 132.294449 -230.788902) (xy 132.279005 -230.836434)
			(xy 132.256315 -230.880966) (xy 132.226939 -230.921399) (xy 132.191599 -230.956739) (xy 132.151166 -230.986115)
			(xy 132.106634 -231.008805) (xy 132.059102 -231.024249) (xy 132.009739 -231.032068) (xy 131.959761 -231.032068)
			(xy 131.910398 -231.024249) (xy 131.862866 -231.008805) (xy 131.818334 -230.986115) (xy 131.777901 -230.956739)
			(xy 131.742561 -230.921399) (xy 131.713185 -230.880966) (xy 131.690495 -230.836434) (xy 131.675051 -230.788902)
			(xy 131.667232 -230.739539) (xy 131.359915 -230.739539) (xy 131.359906 -230.739996) (xy 131.351742 -230.79023)
			(xy 131.335626 -230.838504) (xy 131.311975 -230.883567) (xy 131.281402 -230.924253) (xy 131.244698 -230.959508)
			(xy 131.202814 -230.988418) (xy 131.156835 -231.010235) (xy 131.107951 -231.024395) (xy 131.05743 -231.030529)
			(xy 131.006578 -231.02848) (xy 130.956714 -231.0183) (xy 130.909128 -231.000253) (xy 130.865054 -230.974807)
			(xy 130.825632 -230.94262) (xy 130.791884 -230.904526) (xy 130.764683 -230.861512) (xy 130.744735 -230.814692)
			(xy 130.732556 -230.765278) (xy 130.728461 -230.71455) (xy 130.42265 -230.71455) (xy 130.42216 -230.739539)
			(xy 130.414341 -230.788902) (xy 130.398897 -230.836434) (xy 130.376207 -230.880966) (xy 130.346831 -230.921399)
			(xy 130.311491 -230.956739) (xy 130.271058 -230.986115) (xy 130.226526 -231.008805) (xy 130.178994 -231.024249)
			(xy 130.129631 -231.032068) (xy 130.079653 -231.032068) (xy 130.03029 -231.024249) (xy 129.982758 -231.008805)
			(xy 129.938226 -230.986115) (xy 129.897793 -230.956739) (xy 129.862453 -230.921399) (xy 129.833077 -230.880966)
			(xy 129.810387 -230.836434) (xy 129.794943 -230.788902) (xy 129.787124 -230.739539) (xy 129.480061 -230.739539)
			(xy 129.480052 -230.739996) (xy 129.471888 -230.79023) (xy 129.455772 -230.838504) (xy 129.432121 -230.883567)
			(xy 129.401548 -230.924253) (xy 129.364844 -230.959508) (xy 129.32296 -230.988418) (xy 129.276981 -231.010235)
			(xy 129.228097 -231.024395) (xy 129.177576 -231.030529) (xy 129.126724 -231.02848) (xy 129.07686 -231.0183)
			(xy 129.029274 -231.000253) (xy 128.9852 -230.974807) (xy 128.945778 -230.94262) (xy 128.91203 -230.904526)
			(xy 128.884829 -230.861512) (xy 128.864881 -230.814692) (xy 128.852702 -230.765278) (xy 128.848607 -230.71455)
			(xy 128.54051 -230.71455) (xy 128.539998 -230.739996) (xy 128.531834 -230.79023) (xy 128.515718 -230.838504)
			(xy 128.492067 -230.883567) (xy 128.461494 -230.924253) (xy 128.42479 -230.959508) (xy 128.382906 -230.988418)
			(xy 128.336927 -231.010235) (xy 128.288043 -231.024395) (xy 128.237522 -231.030529) (xy 128.18667 -231.02848)
			(xy 128.136806 -231.0183) (xy 128.08922 -231.000253) (xy 128.045146 -230.974807) (xy 128.005724 -230.94262)
			(xy 127.971976 -230.904526) (xy 127.944775 -230.861512) (xy 127.924827 -230.814692) (xy 127.912648 -230.765278)
			(xy 127.908553 -230.71455) (xy 127.602742 -230.71455) (xy 127.602252 -230.739539) (xy 127.594433 -230.788902)
			(xy 127.578989 -230.836434) (xy 127.556299 -230.880966) (xy 127.526923 -230.921399) (xy 127.491583 -230.956739)
			(xy 127.45115 -230.986115) (xy 127.406618 -231.008805) (xy 127.359086 -231.024249) (xy 127.309723 -231.032068)
			(xy 127.259745 -231.032068) (xy 127.210382 -231.024249) (xy 127.16285 -231.008805) (xy 127.118318 -230.986115)
			(xy 127.077885 -230.956739) (xy 127.042545 -230.921399) (xy 127.013169 -230.880966) (xy 126.990479 -230.836434)
			(xy 126.975035 -230.788902) (xy 126.967216 -230.739539) (xy 126.661992 -230.739539) (xy 126.65625 -230.780922)
			(xy 126.650496 -230.802434) (xy 126.648464 -230.809292) (xy 126.648464 -231.111298) (xy 126.648464 -231.114346)
			(xy 126.649412 -231.123798) (xy 126.65737 -231.141031) (xy 126.663958 -231.147874) (xy 126.72441 -231.199182)
			(xy 126.728648 -231.202604) (xy 126.738255 -231.207734) (xy 126.74346 -231.209342) (xy 126.75362 -231.212136)
			(xy 126.764542 -231.210358) (xy 126.777028 -231.208458) (xy 126.802205 -231.206421) (xy 126.814834 -231.206294)
			(xy 126.839821 -231.206787) (xy 126.88918 -231.214609) (xy 126.936707 -231.230056) (xy 126.981233 -231.252748)
			(xy 127.021662 -231.282125) (xy 127.056997 -231.317464) (xy 127.08637 -231.357896) (xy 127.109057 -231.402424)
			(xy 127.124499 -231.449953) (xy 127.132316 -231.499313) (xy 127.132316 -231.524302) (xy 127.438399 -231.524302)
			(xy 127.442494 -231.473574) (xy 127.454673 -231.42416) (xy 127.474621 -231.37734) (xy 127.501822 -231.334326)
			(xy 127.53557 -231.296232) (xy 127.574992 -231.264045) (xy 127.619066 -231.238599) (xy 127.666652 -231.220552)
			(xy 127.716516 -231.210372) (xy 127.767368 -231.208323) (xy 127.817889 -231.214457) (xy 127.866773 -231.228617)
			(xy 127.912752 -231.250434) (xy 127.954636 -231.279344) (xy 127.99134 -231.314599) (xy 128.021913 -231.355285)
			(xy 128.045564 -231.400348) (xy 128.06168 -231.448622) (xy 128.069844 -231.498856) (xy 128.070356 -231.524302)
			(xy 128.069853 -231.549291) (xy 128.37717 -231.549291) (xy 128.37717 -231.499313) (xy 128.384989 -231.44995)
			(xy 128.400433 -231.402418) (xy 128.423123 -231.357886) (xy 128.452499 -231.317453) (xy 128.487839 -231.282113)
			(xy 128.528272 -231.252737) (xy 128.572804 -231.230047) (xy 128.620336 -231.214603) (xy 128.669699 -231.206784)
			(xy 128.719677 -231.206784) (xy 128.76904 -231.214603) (xy 128.816572 -231.230047) (xy 128.861104 -231.252737)
			(xy 128.901537 -231.282113) (xy 128.936877 -231.317453) (xy 128.966253 -231.357886) (xy 128.988943 -231.402418)
			(xy 129.004387 -231.44995) (xy 129.012206 -231.499313) (xy 129.012696 -231.524302) (xy 129.318507 -231.524302)
			(xy 129.322602 -231.473574) (xy 129.334781 -231.42416) (xy 129.354729 -231.37734) (xy 129.38193 -231.334326)
			(xy 129.415678 -231.296232) (xy 129.4551 -231.264045) (xy 129.499174 -231.238599) (xy 129.54676 -231.220552)
			(xy 129.596624 -231.210372) (xy 129.647476 -231.208323) (xy 129.697997 -231.214457) (xy 129.746881 -231.228617)
			(xy 129.79286 -231.250434) (xy 129.834744 -231.279344) (xy 129.871448 -231.314599) (xy 129.902021 -231.355285)
			(xy 129.925672 -231.400348) (xy 129.941788 -231.448622) (xy 129.949952 -231.498856) (xy 129.950464 -231.524302)
			(xy 129.949961 -231.549291) (xy 130.257278 -231.549291) (xy 130.257278 -231.499313) (xy 130.265097 -231.44995)
			(xy 130.280541 -231.402418) (xy 130.303231 -231.357886) (xy 130.332607 -231.317453) (xy 130.367947 -231.282113)
			(xy 130.40838 -231.252737) (xy 130.452912 -231.230047) (xy 130.500444 -231.214603) (xy 130.549807 -231.206784)
			(xy 130.599785 -231.206784) (xy 130.649148 -231.214603) (xy 130.69668 -231.230047) (xy 130.741212 -231.252737)
			(xy 130.781645 -231.282113) (xy 130.816985 -231.317453) (xy 130.846361 -231.357886) (xy 130.869051 -231.402418)
			(xy 130.884495 -231.44995) (xy 130.892314 -231.499313) (xy 130.892804 -231.524302) (xy 131.198615 -231.524302)
			(xy 131.20271 -231.473574) (xy 131.214889 -231.42416) (xy 131.234837 -231.37734) (xy 131.262038 -231.334326)
			(xy 131.295786 -231.296232) (xy 131.335208 -231.264045) (xy 131.379282 -231.238599) (xy 131.426868 -231.220552)
			(xy 131.476732 -231.210372) (xy 131.527584 -231.208323) (xy 131.578105 -231.214457) (xy 131.626989 -231.228617)
			(xy 131.672968 -231.250434) (xy 131.714852 -231.279344) (xy 131.751556 -231.314599) (xy 131.782129 -231.355285)
			(xy 131.80578 -231.400348) (xy 131.821896 -231.448622) (xy 131.83006 -231.498856) (xy 131.830572 -231.524302)
			(xy 132.138415 -231.524302) (xy 132.14251 -231.473574) (xy 132.154689 -231.42416) (xy 132.174637 -231.37734)
			(xy 132.201838 -231.334326) (xy 132.235586 -231.296232) (xy 132.275008 -231.264045) (xy 132.319082 -231.238599)
			(xy 132.366668 -231.220552) (xy 132.416532 -231.210372) (xy 132.467384 -231.208323) (xy 132.517905 -231.214457)
			(xy 132.566789 -231.228617) (xy 132.612768 -231.250434) (xy 132.654652 -231.279344) (xy 132.691356 -231.314599)
			(xy 132.721929 -231.355285) (xy 132.74558 -231.400348) (xy 132.761696 -231.448622) (xy 132.76986 -231.498856)
			(xy 132.770372 -231.524302) (xy 132.769869 -231.549291) (xy 133.077186 -231.549291) (xy 133.077186 -231.499313)
			(xy 133.085005 -231.44995) (xy 133.100449 -231.402418) (xy 133.123139 -231.357886) (xy 133.152515 -231.317453)
			(xy 133.187855 -231.282113) (xy 133.228288 -231.252737) (xy 133.27282 -231.230047) (xy 133.320352 -231.214603)
			(xy 133.369715 -231.206784) (xy 133.419693 -231.206784) (xy 133.469056 -231.214603) (xy 133.516588 -231.230047)
			(xy 133.56112 -231.252737) (xy 133.601553 -231.282113) (xy 133.636893 -231.317453) (xy 133.666269 -231.357886)
			(xy 133.688959 -231.402418) (xy 133.704403 -231.44995) (xy 133.712222 -231.499313) (xy 133.712712 -231.524302)
			(xy 134.018523 -231.524302) (xy 134.022618 -231.473574) (xy 134.034797 -231.42416) (xy 134.054745 -231.37734)
			(xy 134.081946 -231.334326) (xy 134.115694 -231.296232) (xy 134.155116 -231.264045) (xy 134.19919 -231.238599)
			(xy 134.246776 -231.220552) (xy 134.29664 -231.210372) (xy 134.347492 -231.208323) (xy 134.398013 -231.214457)
			(xy 134.446897 -231.228617) (xy 134.492876 -231.250434) (xy 134.53476 -231.279344) (xy 134.571464 -231.314599)
			(xy 134.602037 -231.355285) (xy 134.625688 -231.400348) (xy 134.641804 -231.448622) (xy 134.649968 -231.498856)
			(xy 134.65048 -231.524302) (xy 134.649977 -231.549291) (xy 134.957294 -231.549291) (xy 134.957294 -231.499313)
			(xy 134.965113 -231.44995) (xy 134.980557 -231.402418) (xy 135.003247 -231.357886) (xy 135.032623 -231.317453)
			(xy 135.067963 -231.282113) (xy 135.108396 -231.252737) (xy 135.152928 -231.230047) (xy 135.20046 -231.214603)
			(xy 135.249823 -231.206784) (xy 135.299801 -231.206784) (xy 135.349164 -231.214603) (xy 135.396696 -231.230047)
			(xy 135.441228 -231.252737) (xy 135.481661 -231.282113) (xy 135.517001 -231.317453) (xy 135.546377 -231.357886)
			(xy 135.569067 -231.402418) (xy 135.584511 -231.44995) (xy 135.59233 -231.499313) (xy 135.59282 -231.524302)
			(xy 135.898631 -231.524302) (xy 135.902726 -231.473574) (xy 135.914905 -231.42416) (xy 135.934853 -231.37734)
			(xy 135.962054 -231.334326) (xy 135.995802 -231.296232) (xy 136.035224 -231.264045) (xy 136.079298 -231.238599)
			(xy 136.126884 -231.220552) (xy 136.176748 -231.210372) (xy 136.2276 -231.208323) (xy 136.278121 -231.214457)
			(xy 136.327005 -231.228617) (xy 136.372984 -231.250434) (xy 136.414868 -231.279344) (xy 136.451572 -231.314599)
			(xy 136.482145 -231.355285) (xy 136.505796 -231.400348) (xy 136.521912 -231.448622) (xy 136.530076 -231.498856)
			(xy 136.530588 -231.524302) (xy 136.530085 -231.549291) (xy 136.837148 -231.549291) (xy 136.837148 -231.499313)
			(xy 136.844967 -231.44995) (xy 136.860411 -231.402418) (xy 136.883101 -231.357886) (xy 136.912477 -231.317453)
			(xy 136.947817 -231.282113) (xy 136.98825 -231.252737) (xy 137.032782 -231.230047) (xy 137.080314 -231.214603)
			(xy 137.129677 -231.206784) (xy 137.179655 -231.206784) (xy 137.229018 -231.214603) (xy 137.27655 -231.230047)
			(xy 137.321082 -231.252737) (xy 137.361515 -231.282113) (xy 137.396855 -231.317453) (xy 137.426231 -231.357886)
			(xy 137.448921 -231.402418) (xy 137.464365 -231.44995) (xy 137.472184 -231.499313) (xy 137.472674 -231.524302)
			(xy 137.778485 -231.524302) (xy 137.78258 -231.473574) (xy 137.794759 -231.42416) (xy 137.814707 -231.37734)
			(xy 137.841908 -231.334326) (xy 137.875656 -231.296232) (xy 137.915078 -231.264045) (xy 137.959152 -231.238599)
			(xy 138.006738 -231.220552) (xy 138.056602 -231.210372) (xy 138.107454 -231.208323) (xy 138.157975 -231.214457)
			(xy 138.206859 -231.228617) (xy 138.252838 -231.250434) (xy 138.294722 -231.279344) (xy 138.331426 -231.314599)
			(xy 138.361999 -231.355285) (xy 138.38565 -231.400348) (xy 138.401766 -231.448622) (xy 138.40993 -231.498856)
			(xy 138.410442 -231.524302) (xy 138.718539 -231.524302) (xy 138.722634 -231.473574) (xy 138.734813 -231.42416)
			(xy 138.754761 -231.37734) (xy 138.781962 -231.334326) (xy 138.81571 -231.296232) (xy 138.855132 -231.264045)
			(xy 138.899206 -231.238599) (xy 138.946792 -231.220552) (xy 138.996656 -231.210372) (xy 139.047508 -231.208323)
			(xy 139.098029 -231.214457) (xy 139.146913 -231.228617) (xy 139.192892 -231.250434) (xy 139.234776 -231.279344)
			(xy 139.27148 -231.314599) (xy 139.302053 -231.355285) (xy 139.325704 -231.400348) (xy 139.34182 -231.448622)
			(xy 139.349984 -231.498856) (xy 139.350496 -231.524302) (xy 139.349993 -231.549291) (xy 139.65731 -231.549291)
			(xy 139.65731 -231.499313) (xy 139.665129 -231.44995) (xy 139.680573 -231.402418) (xy 139.703263 -231.357886)
			(xy 139.732639 -231.317453) (xy 139.767979 -231.282113) (xy 139.808412 -231.252737) (xy 139.852944 -231.230047)
			(xy 139.900476 -231.214603) (xy 139.949839 -231.206784) (xy 139.999817 -231.206784) (xy 140.04918 -231.214603)
			(xy 140.096712 -231.230047) (xy 140.141244 -231.252737) (xy 140.181677 -231.282113) (xy 140.217017 -231.317453)
			(xy 140.246393 -231.357886) (xy 140.269083 -231.402418) (xy 140.284527 -231.44995) (xy 140.292346 -231.499313)
			(xy 140.292836 -231.524302) (xy 140.598647 -231.524302) (xy 140.602742 -231.473574) (xy 140.614921 -231.42416)
			(xy 140.634869 -231.37734) (xy 140.66207 -231.334326) (xy 140.695818 -231.296232) (xy 140.73524 -231.264045)
			(xy 140.779314 -231.238599) (xy 140.8269 -231.220552) (xy 140.876764 -231.210372) (xy 140.927616 -231.208323)
			(xy 140.978137 -231.214457) (xy 141.027021 -231.228617) (xy 141.073 -231.250434) (xy 141.114884 -231.279344)
			(xy 141.151588 -231.314599) (xy 141.182161 -231.355285) (xy 141.205812 -231.400348) (xy 141.221928 -231.448622)
			(xy 141.230092 -231.498856) (xy 141.230604 -231.524302) (xy 141.230101 -231.549291) (xy 141.537164 -231.549291)
			(xy 141.537164 -231.499313) (xy 141.544983 -231.44995) (xy 141.560427 -231.402418) (xy 141.583117 -231.357886)
			(xy 141.612493 -231.317453) (xy 141.647833 -231.282113) (xy 141.688266 -231.252737) (xy 141.732798 -231.230047)
			(xy 141.78033 -231.214603) (xy 141.829693 -231.206784) (xy 141.879671 -231.206784) (xy 141.929034 -231.214603)
			(xy 141.976566 -231.230047) (xy 142.021098 -231.252737) (xy 142.061531 -231.282113) (xy 142.096871 -231.317453)
			(xy 142.126247 -231.357886) (xy 142.148937 -231.402418) (xy 142.164381 -231.44995) (xy 142.1722 -231.499313)
			(xy 142.17269 -231.524302) (xy 142.478501 -231.524302) (xy 142.482596 -231.473574) (xy 142.494775 -231.42416)
			(xy 142.514723 -231.37734) (xy 142.541924 -231.334326) (xy 142.575672 -231.296232) (xy 142.615094 -231.264045)
			(xy 142.659168 -231.238599) (xy 142.706754 -231.220552) (xy 142.756618 -231.210372) (xy 142.80747 -231.208323)
			(xy 142.857991 -231.214457) (xy 142.906875 -231.228617) (xy 142.952854 -231.250434) (xy 142.994738 -231.279344)
			(xy 143.031442 -231.314599) (xy 143.062015 -231.355285) (xy 143.085666 -231.400348) (xy 143.101782 -231.448622)
			(xy 143.109946 -231.498856) (xy 143.110458 -231.524302) (xy 143.109955 -231.549291) (xy 143.417272 -231.549291)
			(xy 143.417272 -231.499313) (xy 143.425091 -231.44995) (xy 143.440535 -231.402418) (xy 143.463225 -231.357886)
			(xy 143.492601 -231.317453) (xy 143.527941 -231.282113) (xy 143.568374 -231.252737) (xy 143.612906 -231.230047)
			(xy 143.660438 -231.214603) (xy 143.709801 -231.206784) (xy 143.759779 -231.206784) (xy 143.809142 -231.214603)
			(xy 143.856674 -231.230047) (xy 143.901206 -231.252737) (xy 143.941639 -231.282113) (xy 143.976979 -231.317453)
			(xy 144.006355 -231.357886) (xy 144.029045 -231.402418) (xy 144.044489 -231.44995) (xy 144.052308 -231.499313)
			(xy 144.052798 -231.524302) (xy 144.052308 -231.549291) (xy 144.044489 -231.598654) (xy 144.029045 -231.646186)
			(xy 144.006355 -231.690718) (xy 143.976979 -231.731151) (xy 143.941639 -231.766491) (xy 143.901206 -231.795867)
			(xy 143.856674 -231.818557) (xy 143.809142 -231.834001) (xy 143.759779 -231.84182) (xy 143.709801 -231.84182)
			(xy 143.660438 -231.834001) (xy 143.612906 -231.818557) (xy 143.568374 -231.795867) (xy 143.527941 -231.766491)
			(xy 143.492601 -231.731151) (xy 143.463225 -231.690718) (xy 143.440535 -231.646186) (xy 143.425091 -231.598654)
			(xy 143.417272 -231.549291) (xy 143.109955 -231.549291) (xy 143.109946 -231.549748) (xy 143.101782 -231.599982)
			(xy 143.085666 -231.648256) (xy 143.062015 -231.693319) (xy 143.031442 -231.734005) (xy 142.994738 -231.76926)
			(xy 142.952854 -231.79817) (xy 142.906875 -231.819987) (xy 142.857991 -231.834147) (xy 142.80747 -231.840281)
			(xy 142.756618 -231.838232) (xy 142.706754 -231.828052) (xy 142.659168 -231.810005) (xy 142.615094 -231.784559)
			(xy 142.575672 -231.752372) (xy 142.541924 -231.714278) (xy 142.514723 -231.671264) (xy 142.494775 -231.624444)
			(xy 142.482596 -231.57503) (xy 142.478501 -231.524302) (xy 142.17269 -231.524302) (xy 142.1722 -231.549291)
			(xy 142.164381 -231.598654) (xy 142.148937 -231.646186) (xy 142.126247 -231.690718) (xy 142.096871 -231.731151)
			(xy 142.061531 -231.766491) (xy 142.021098 -231.795867) (xy 141.976566 -231.818557) (xy 141.929034 -231.834001)
			(xy 141.879671 -231.84182) (xy 141.829693 -231.84182) (xy 141.78033 -231.834001) (xy 141.732798 -231.818557)
			(xy 141.688266 -231.795867) (xy 141.647833 -231.766491) (xy 141.612493 -231.731151) (xy 141.583117 -231.690718)
			(xy 141.560427 -231.646186) (xy 141.544983 -231.598654) (xy 141.537164 -231.549291) (xy 141.230101 -231.549291)
			(xy 141.230092 -231.549748) (xy 141.221928 -231.599982) (xy 141.205812 -231.648256) (xy 141.182161 -231.693319)
			(xy 141.151588 -231.734005) (xy 141.114884 -231.76926) (xy 141.073 -231.79817) (xy 141.027021 -231.819987)
			(xy 140.978137 -231.834147) (xy 140.927616 -231.840281) (xy 140.876764 -231.838232) (xy 140.8269 -231.828052)
			(xy 140.779314 -231.810005) (xy 140.73524 -231.784559) (xy 140.695818 -231.752372) (xy 140.66207 -231.714278)
			(xy 140.634869 -231.671264) (xy 140.614921 -231.624444) (xy 140.602742 -231.57503) (xy 140.598647 -231.524302)
			(xy 140.292836 -231.524302) (xy 140.292346 -231.549291) (xy 140.284527 -231.598654) (xy 140.269083 -231.646186)
			(xy 140.246393 -231.690718) (xy 140.217017 -231.731151) (xy 140.181677 -231.766491) (xy 140.141244 -231.795867)
			(xy 140.096712 -231.818557) (xy 140.04918 -231.834001) (xy 139.999817 -231.84182) (xy 139.949839 -231.84182)
			(xy 139.900476 -231.834001) (xy 139.852944 -231.818557) (xy 139.808412 -231.795867) (xy 139.767979 -231.766491)
			(xy 139.732639 -231.731151) (xy 139.703263 -231.690718) (xy 139.680573 -231.646186) (xy 139.665129 -231.598654)
			(xy 139.65731 -231.549291) (xy 139.349993 -231.549291) (xy 139.349984 -231.549748) (xy 139.34182 -231.599982)
			(xy 139.325704 -231.648256) (xy 139.302053 -231.693319) (xy 139.27148 -231.734005) (xy 139.234776 -231.76926)
			(xy 139.192892 -231.79817) (xy 139.146913 -231.819987) (xy 139.098029 -231.834147) (xy 139.047508 -231.840281)
			(xy 138.996656 -231.838232) (xy 138.946792 -231.828052) (xy 138.899206 -231.810005) (xy 138.855132 -231.784559)
			(xy 138.81571 -231.752372) (xy 138.781962 -231.714278) (xy 138.754761 -231.671264) (xy 138.734813 -231.624444)
			(xy 138.722634 -231.57503) (xy 138.718539 -231.524302) (xy 138.410442 -231.524302) (xy 138.40993 -231.549748)
			(xy 138.401766 -231.599982) (xy 138.38565 -231.648256) (xy 138.361999 -231.693319) (xy 138.331426 -231.734005)
			(xy 138.294722 -231.76926) (xy 138.252838 -231.79817) (xy 138.206859 -231.819987) (xy 138.157975 -231.834147)
			(xy 138.107454 -231.840281) (xy 138.056602 -231.838232) (xy 138.006738 -231.828052) (xy 137.959152 -231.810005)
			(xy 137.915078 -231.784559) (xy 137.875656 -231.752372) (xy 137.841908 -231.714278) (xy 137.814707 -231.671264)
			(xy 137.794759 -231.624444) (xy 137.78258 -231.57503) (xy 137.778485 -231.524302) (xy 137.472674 -231.524302)
			(xy 137.472184 -231.549291) (xy 137.464365 -231.598654) (xy 137.448921 -231.646186) (xy 137.426231 -231.690718)
			(xy 137.396855 -231.731151) (xy 137.361515 -231.766491) (xy 137.321082 -231.795867) (xy 137.27655 -231.818557)
			(xy 137.229018 -231.834001) (xy 137.179655 -231.84182) (xy 137.129677 -231.84182) (xy 137.080314 -231.834001)
			(xy 137.032782 -231.818557) (xy 136.98825 -231.795867) (xy 136.947817 -231.766491) (xy 136.912477 -231.731151)
			(xy 136.883101 -231.690718) (xy 136.860411 -231.646186) (xy 136.844967 -231.598654) (xy 136.837148 -231.549291)
			(xy 136.530085 -231.549291) (xy 136.530076 -231.549748) (xy 136.521912 -231.599982) (xy 136.505796 -231.648256)
			(xy 136.482145 -231.693319) (xy 136.451572 -231.734005) (xy 136.414868 -231.76926) (xy 136.372984 -231.79817)
			(xy 136.327005 -231.819987) (xy 136.278121 -231.834147) (xy 136.2276 -231.840281) (xy 136.176748 -231.838232)
			(xy 136.126884 -231.828052) (xy 136.079298 -231.810005) (xy 136.035224 -231.784559) (xy 135.995802 -231.752372)
			(xy 135.962054 -231.714278) (xy 135.934853 -231.671264) (xy 135.914905 -231.624444) (xy 135.902726 -231.57503)
			(xy 135.898631 -231.524302) (xy 135.59282 -231.524302) (xy 135.59233 -231.549291) (xy 135.584511 -231.598654)
			(xy 135.569067 -231.646186) (xy 135.546377 -231.690718) (xy 135.517001 -231.731151) (xy 135.481661 -231.766491)
			(xy 135.441228 -231.795867) (xy 135.396696 -231.818557) (xy 135.349164 -231.834001) (xy 135.299801 -231.84182)
			(xy 135.249823 -231.84182) (xy 135.20046 -231.834001) (xy 135.152928 -231.818557) (xy 135.108396 -231.795867)
			(xy 135.067963 -231.766491) (xy 135.032623 -231.731151) (xy 135.003247 -231.690718) (xy 134.980557 -231.646186)
			(xy 134.965113 -231.598654) (xy 134.957294 -231.549291) (xy 134.649977 -231.549291) (xy 134.649968 -231.549748)
			(xy 134.641804 -231.599982) (xy 134.625688 -231.648256) (xy 134.602037 -231.693319) (xy 134.571464 -231.734005)
			(xy 134.53476 -231.76926) (xy 134.492876 -231.79817) (xy 134.446897 -231.819987) (xy 134.398013 -231.834147)
			(xy 134.347492 -231.840281) (xy 134.29664 -231.838232) (xy 134.246776 -231.828052) (xy 134.19919 -231.810005)
			(xy 134.155116 -231.784559) (xy 134.115694 -231.752372) (xy 134.081946 -231.714278) (xy 134.054745 -231.671264)
			(xy 134.034797 -231.624444) (xy 134.022618 -231.57503) (xy 134.018523 -231.524302) (xy 133.712712 -231.524302)
			(xy 133.712222 -231.549291) (xy 133.704403 -231.598654) (xy 133.688959 -231.646186) (xy 133.666269 -231.690718)
			(xy 133.636893 -231.731151) (xy 133.601553 -231.766491) (xy 133.56112 -231.795867) (xy 133.516588 -231.818557)
			(xy 133.469056 -231.834001) (xy 133.419693 -231.84182) (xy 133.369715 -231.84182) (xy 133.320352 -231.834001)
			(xy 133.27282 -231.818557) (xy 133.228288 -231.795867) (xy 133.187855 -231.766491) (xy 133.152515 -231.731151)
			(xy 133.123139 -231.690718) (xy 133.100449 -231.646186) (xy 133.085005 -231.598654) (xy 133.077186 -231.549291)
			(xy 132.769869 -231.549291) (xy 132.76986 -231.549748) (xy 132.761696 -231.599982) (xy 132.74558 -231.648256)
			(xy 132.721929 -231.693319) (xy 132.691356 -231.734005) (xy 132.654652 -231.76926) (xy 132.612768 -231.79817)
			(xy 132.566789 -231.819987) (xy 132.517905 -231.834147) (xy 132.467384 -231.840281) (xy 132.416532 -231.838232)
			(xy 132.366668 -231.828052) (xy 132.319082 -231.810005) (xy 132.275008 -231.784559) (xy 132.235586 -231.752372)
			(xy 132.201838 -231.714278) (xy 132.174637 -231.671264) (xy 132.154689 -231.624444) (xy 132.14251 -231.57503)
			(xy 132.138415 -231.524302) (xy 131.830572 -231.524302) (xy 131.83006 -231.549748) (xy 131.821896 -231.599982)
			(xy 131.80578 -231.648256) (xy 131.782129 -231.693319) (xy 131.751556 -231.734005) (xy 131.714852 -231.76926)
			(xy 131.672968 -231.79817) (xy 131.626989 -231.819987) (xy 131.578105 -231.834147) (xy 131.527584 -231.840281)
			(xy 131.476732 -231.838232) (xy 131.426868 -231.828052) (xy 131.379282 -231.810005) (xy 131.335208 -231.784559)
			(xy 131.295786 -231.752372) (xy 131.262038 -231.714278) (xy 131.234837 -231.671264) (xy 131.214889 -231.624444)
			(xy 131.20271 -231.57503) (xy 131.198615 -231.524302) (xy 130.892804 -231.524302) (xy 130.892314 -231.549291)
			(xy 130.884495 -231.598654) (xy 130.869051 -231.646186) (xy 130.846361 -231.690718) (xy 130.816985 -231.731151)
			(xy 130.781645 -231.766491) (xy 130.741212 -231.795867) (xy 130.69668 -231.818557) (xy 130.649148 -231.834001)
			(xy 130.599785 -231.84182) (xy 130.549807 -231.84182) (xy 130.500444 -231.834001) (xy 130.452912 -231.818557)
			(xy 130.40838 -231.795867) (xy 130.367947 -231.766491) (xy 130.332607 -231.731151) (xy 130.303231 -231.690718)
			(xy 130.280541 -231.646186) (xy 130.265097 -231.598654) (xy 130.257278 -231.549291) (xy 129.949961 -231.549291)
			(xy 129.949952 -231.549748) (xy 129.941788 -231.599982) (xy 129.925672 -231.648256) (xy 129.902021 -231.693319)
			(xy 129.871448 -231.734005) (xy 129.834744 -231.76926) (xy 129.79286 -231.79817) (xy 129.746881 -231.819987)
			(xy 129.697997 -231.834147) (xy 129.647476 -231.840281) (xy 129.596624 -231.838232) (xy 129.54676 -231.828052)
			(xy 129.499174 -231.810005) (xy 129.4551 -231.784559) (xy 129.415678 -231.752372) (xy 129.38193 -231.714278)
			(xy 129.354729 -231.671264) (xy 129.334781 -231.624444) (xy 129.322602 -231.57503) (xy 129.318507 -231.524302)
			(xy 129.012696 -231.524302) (xy 129.012206 -231.549291) (xy 129.004387 -231.598654) (xy 128.988943 -231.646186)
			(xy 128.966253 -231.690718) (xy 128.936877 -231.731151) (xy 128.901537 -231.766491) (xy 128.861104 -231.795867)
			(xy 128.816572 -231.818557) (xy 128.76904 -231.834001) (xy 128.719677 -231.84182) (xy 128.669699 -231.84182)
			(xy 128.620336 -231.834001) (xy 128.572804 -231.818557) (xy 128.528272 -231.795867) (xy 128.487839 -231.766491)
			(xy 128.452499 -231.731151) (xy 128.423123 -231.690718) (xy 128.400433 -231.646186) (xy 128.384989 -231.598654)
			(xy 128.37717 -231.549291) (xy 128.069853 -231.549291) (xy 128.069844 -231.549748) (xy 128.06168 -231.599982)
			(xy 128.045564 -231.648256) (xy 128.021913 -231.693319) (xy 127.99134 -231.734005) (xy 127.954636 -231.76926)
			(xy 127.912752 -231.79817) (xy 127.866773 -231.819987) (xy 127.817889 -231.834147) (xy 127.767368 -231.840281)
			(xy 127.716516 -231.838232) (xy 127.666652 -231.828052) (xy 127.619066 -231.810005) (xy 127.574992 -231.784559)
			(xy 127.53557 -231.752372) (xy 127.501822 -231.714278) (xy 127.474621 -231.671264) (xy 127.454673 -231.624444)
			(xy 127.442494 -231.57503) (xy 127.438399 -231.524302) (xy 127.132316 -231.524302) (xy 127.132316 -231.549287)
			(xy 127.124499 -231.598647) (xy 127.109057 -231.646176) (xy 127.08637 -231.690704) (xy 127.056997 -231.731136)
			(xy 127.021662 -231.766475) (xy 126.981233 -231.795852) (xy 126.936707 -231.818544) (xy 126.88918 -231.833991)
			(xy 126.839821 -231.841813) (xy 126.814834 -231.84231) (xy 126.8024 -231.842209) (xy 126.777607 -231.8403)
			(xy 126.765304 -231.8385) (xy 126.763526 -231.838246) (xy 126.75616 -231.837738) (xy 126.74778 -231.838164)
			(xy 126.731966 -231.843737) (xy 126.725172 -231.84866) (xy 126.706122 -231.864662) (xy 126.705614 -231.86517)
			(xy 126.666244 -231.898952) (xy 126.658708 -231.906017) (xy 126.649511 -231.924492) (xy 126.648464 -231.934766)
			(xy 126.648464 -232.2322) (xy 126.648972 -232.235756) (xy 126.650496 -232.246678) (xy 126.651004 -232.24871)
			(xy 126.651512 -232.250234) (xy 126.656773 -232.270852) (xy 126.662379 -232.313032) (xy 126.662688 -232.334308)
			(xy 127.908553 -232.334308) (xy 127.912648 -232.28358) (xy 127.924827 -232.234166) (xy 127.944775 -232.187346)
			(xy 127.971976 -232.144332) (xy 128.005724 -232.106238) (xy 128.045146 -232.074051) (xy 128.08922 -232.048605)
			(xy 128.136806 -232.030558) (xy 128.18667 -232.020378) (xy 128.237522 -232.018329) (xy 128.288043 -232.024463)
			(xy 128.336927 -232.038623) (xy 128.382906 -232.06044) (xy 128.42479 -232.08935) (xy 128.461494 -232.124605)
			(xy 128.492067 -232.165291) (xy 128.515718 -232.210354) (xy 128.531834 -232.258628) (xy 128.539998 -232.308862)
			(xy 128.54051 -232.334308) (xy 128.848607 -232.334308) (xy 128.852702 -232.28358) (xy 128.864881 -232.234166)
			(xy 128.884829 -232.187346) (xy 128.91203 -232.144332) (xy 128.945778 -232.106238) (xy 128.9852 -232.074051)
			(xy 129.029274 -232.048605) (xy 129.07686 -232.030558) (xy 129.126724 -232.020378) (xy 129.177576 -232.018329)
			(xy 129.228097 -232.024463) (xy 129.276981 -232.038623) (xy 129.32296 -232.06044) (xy 129.364844 -232.08935)
			(xy 129.401548 -232.124605) (xy 129.432121 -232.165291) (xy 129.455772 -232.210354) (xy 129.471888 -232.258628)
			(xy 129.480052 -232.308862) (xy 129.480564 -232.334308) (xy 130.728461 -232.334308) (xy 130.732556 -232.28358)
			(xy 130.744735 -232.234166) (xy 130.764683 -232.187346) (xy 130.791884 -232.144332) (xy 130.825632 -232.106238)
			(xy 130.865054 -232.074051) (xy 130.909128 -232.048605) (xy 130.956714 -232.030558) (xy 131.006578 -232.020378)
			(xy 131.05743 -232.018329) (xy 131.107951 -232.024463) (xy 131.156835 -232.038623) (xy 131.202814 -232.06044)
			(xy 131.244698 -232.08935) (xy 131.281402 -232.124605) (xy 131.311975 -232.165291) (xy 131.335626 -232.210354)
			(xy 131.351742 -232.258628) (xy 131.359906 -232.308862) (xy 131.360418 -232.334308) (xy 131.359915 -232.359297)
			(xy 131.667232 -232.359297) (xy 131.667232 -232.309319) (xy 131.675051 -232.259956) (xy 131.690495 -232.212424)
			(xy 131.713185 -232.167892) (xy 131.742561 -232.127459) (xy 131.777901 -232.092119) (xy 131.818334 -232.062743)
			(xy 131.862866 -232.040053) (xy 131.910398 -232.024609) (xy 131.959761 -232.01679) (xy 132.009739 -232.01679)
			(xy 132.059102 -232.024609) (xy 132.106634 -232.040053) (xy 132.151166 -232.062743) (xy 132.191599 -232.092119)
			(xy 132.226939 -232.127459) (xy 132.256315 -232.167892) (xy 132.279005 -232.212424) (xy 132.294449 -232.259956)
			(xy 132.302268 -232.309319) (xy 132.302758 -232.334308) (xy 132.608569 -232.334308) (xy 132.612664 -232.28358)
			(xy 132.624843 -232.234166) (xy 132.644791 -232.187346) (xy 132.671992 -232.144332) (xy 132.70574 -232.106238)
			(xy 132.745162 -232.074051) (xy 132.789236 -232.048605) (xy 132.836822 -232.030558) (xy 132.886686 -232.020378)
			(xy 132.937538 -232.018329) (xy 132.988059 -232.024463) (xy 133.036943 -232.038623) (xy 133.082922 -232.06044)
			(xy 133.124806 -232.08935) (xy 133.16151 -232.124605) (xy 133.192083 -232.165291) (xy 133.215734 -232.210354)
			(xy 133.23185 -232.258628) (xy 133.240014 -232.308862) (xy 133.240526 -232.334308) (xy 133.240023 -232.359297)
			(xy 133.54734 -232.359297) (xy 133.54734 -232.309319) (xy 133.555159 -232.259956) (xy 133.570603 -232.212424)
			(xy 133.593293 -232.167892) (xy 133.622669 -232.127459) (xy 133.658009 -232.092119) (xy 133.698442 -232.062743)
			(xy 133.742974 -232.040053) (xy 133.790506 -232.024609) (xy 133.839869 -232.01679) (xy 133.889847 -232.01679)
			(xy 133.93921 -232.024609) (xy 133.986742 -232.040053) (xy 134.031274 -232.062743) (xy 134.071707 -232.092119)
			(xy 134.107047 -232.127459) (xy 134.136423 -232.167892) (xy 134.159113 -232.212424) (xy 134.174557 -232.259956)
			(xy 134.182376 -232.309319) (xy 134.182866 -232.334308) (xy 134.488423 -232.334308) (xy 134.492518 -232.28358)
			(xy 134.504697 -232.234166) (xy 134.524645 -232.187346) (xy 134.551846 -232.144332) (xy 134.585594 -232.106238)
			(xy 134.625016 -232.074051) (xy 134.66909 -232.048605) (xy 134.716676 -232.030558) (xy 134.76654 -232.020378)
			(xy 134.817392 -232.018329) (xy 134.867913 -232.024463) (xy 134.916797 -232.038623) (xy 134.962776 -232.06044)
			(xy 135.00466 -232.08935) (xy 135.041364 -232.124605) (xy 135.071937 -232.165291) (xy 135.095588 -232.210354)
			(xy 135.111704 -232.258628) (xy 135.119868 -232.308862) (xy 135.12038 -232.334308) (xy 135.428477 -232.334308)
			(xy 135.432572 -232.28358) (xy 135.444751 -232.234166) (xy 135.464699 -232.187346) (xy 135.4919 -232.144332)
			(xy 135.525648 -232.106238) (xy 135.56507 -232.074051) (xy 135.609144 -232.048605) (xy 135.65673 -232.030558)
			(xy 135.706594 -232.020378) (xy 135.757446 -232.018329) (xy 135.807967 -232.024463) (xy 135.856851 -232.038623)
			(xy 135.90283 -232.06044) (xy 135.944714 -232.08935) (xy 135.981418 -232.124605) (xy 136.011991 -232.165291)
			(xy 136.035642 -232.210354) (xy 136.051758 -232.258628) (xy 136.059922 -232.308862) (xy 136.060434 -232.334308)
			(xy 137.308585 -232.334308) (xy 137.31268 -232.28358) (xy 137.324859 -232.234166) (xy 137.344807 -232.187346)
			(xy 137.372008 -232.144332) (xy 137.405756 -232.106238) (xy 137.445178 -232.074051) (xy 137.489252 -232.048605)
			(xy 137.536838 -232.030558) (xy 137.586702 -232.020378) (xy 137.637554 -232.018329) (xy 137.688075 -232.024463)
			(xy 137.736959 -232.038623) (xy 137.782938 -232.06044) (xy 137.824822 -232.08935) (xy 137.861526 -232.124605)
			(xy 137.892099 -232.165291) (xy 137.91575 -232.210354) (xy 137.931866 -232.258628) (xy 137.94003 -232.308862)
			(xy 137.940542 -232.334308) (xy 137.940039 -232.359297) (xy 138.247356 -232.359297) (xy 138.247356 -232.309319)
			(xy 138.255175 -232.259956) (xy 138.270619 -232.212424) (xy 138.293309 -232.167892) (xy 138.322685 -232.127459)
			(xy 138.358025 -232.092119) (xy 138.398458 -232.062743) (xy 138.44299 -232.040053) (xy 138.490522 -232.024609)
			(xy 138.539885 -232.01679) (xy 138.589863 -232.01679) (xy 138.639226 -232.024609) (xy 138.686758 -232.040053)
			(xy 138.73129 -232.062743) (xy 138.771723 -232.092119) (xy 138.807063 -232.127459) (xy 138.836439 -232.167892)
			(xy 138.859129 -232.212424) (xy 138.874573 -232.259956) (xy 138.882392 -232.309319) (xy 138.882882 -232.334308)
			(xy 139.188439 -232.334308) (xy 139.192534 -232.28358) (xy 139.204713 -232.234166) (xy 139.224661 -232.187346)
			(xy 139.251862 -232.144332) (xy 139.28561 -232.106238) (xy 139.325032 -232.074051) (xy 139.369106 -232.048605)
			(xy 139.416692 -232.030558) (xy 139.466556 -232.020378) (xy 139.517408 -232.018329) (xy 139.567929 -232.024463)
			(xy 139.616813 -232.038623) (xy 139.662792 -232.06044) (xy 139.704676 -232.08935) (xy 139.74138 -232.124605)
			(xy 139.771953 -232.165291) (xy 139.795604 -232.210354) (xy 139.81172 -232.258628) (xy 139.819884 -232.308862)
			(xy 139.820396 -232.334308) (xy 139.819893 -232.359297) (xy 140.12721 -232.359297) (xy 140.12721 -232.309319)
			(xy 140.135029 -232.259956) (xy 140.150473 -232.212424) (xy 140.173163 -232.167892) (xy 140.202539 -232.127459)
			(xy 140.237879 -232.092119) (xy 140.278312 -232.062743) (xy 140.322844 -232.040053) (xy 140.370376 -232.024609)
			(xy 140.419739 -232.01679) (xy 140.469717 -232.01679) (xy 140.51908 -232.024609) (xy 140.566612 -232.040053)
			(xy 140.611144 -232.062743) (xy 140.651577 -232.092119) (xy 140.686917 -232.127459) (xy 140.716293 -232.167892)
			(xy 140.738983 -232.212424) (xy 140.754427 -232.259956) (xy 140.762246 -232.309319) (xy 140.762736 -232.334308)
			(xy 141.068547 -232.334308) (xy 141.072642 -232.28358) (xy 141.084821 -232.234166) (xy 141.104769 -232.187346)
			(xy 141.13197 -232.144332) (xy 141.165718 -232.106238) (xy 141.20514 -232.074051) (xy 141.249214 -232.048605)
			(xy 141.2968 -232.030558) (xy 141.346664 -232.020378) (xy 141.397516 -232.018329) (xy 141.448037 -232.024463)
			(xy 141.496921 -232.038623) (xy 141.5429 -232.06044) (xy 141.584784 -232.08935) (xy 141.621488 -232.124605)
			(xy 141.652061 -232.165291) (xy 141.675712 -232.210354) (xy 141.691828 -232.258628) (xy 141.699992 -232.308862)
			(xy 141.700504 -232.334308) (xy 142.008601 -232.334308) (xy 142.012696 -232.28358) (xy 142.024875 -232.234166)
			(xy 142.044823 -232.187346) (xy 142.072024 -232.144332) (xy 142.105772 -232.106238) (xy 142.145194 -232.074051)
			(xy 142.189268 -232.048605) (xy 142.236854 -232.030558) (xy 142.286718 -232.020378) (xy 142.33757 -232.018329)
			(xy 142.388091 -232.024463) (xy 142.436975 -232.038623) (xy 142.482954 -232.06044) (xy 142.524838 -232.08935)
			(xy 142.561542 -232.124605) (xy 142.592115 -232.165291) (xy 142.615766 -232.210354) (xy 142.631882 -232.258628)
			(xy 142.640046 -232.308862) (xy 142.640558 -232.334308) (xy 142.640046 -232.359754) (xy 142.631882 -232.409988)
			(xy 142.615766 -232.458262) (xy 142.592115 -232.503325) (xy 142.561542 -232.544011) (xy 142.524838 -232.579266)
			(xy 142.482954 -232.608176) (xy 142.436975 -232.629993) (xy 142.388091 -232.644153) (xy 142.33757 -232.650287)
			(xy 142.286718 -232.648238) (xy 142.236854 -232.638058) (xy 142.189268 -232.620011) (xy 142.145194 -232.594565)
			(xy 142.105772 -232.562378) (xy 142.072024 -232.524284) (xy 142.044823 -232.48127) (xy 142.024875 -232.43445)
			(xy 142.012696 -232.385036) (xy 142.008601 -232.334308) (xy 141.700504 -232.334308) (xy 141.699992 -232.359754)
			(xy 141.691828 -232.409988) (xy 141.675712 -232.458262) (xy 141.652061 -232.503325) (xy 141.621488 -232.544011)
			(xy 141.584784 -232.579266) (xy 141.5429 -232.608176) (xy 141.496921 -232.629993) (xy 141.448037 -232.644153)
			(xy 141.397516 -232.650287) (xy 141.346664 -232.648238) (xy 141.2968 -232.638058) (xy 141.249214 -232.620011)
			(xy 141.20514 -232.594565) (xy 141.165718 -232.562378) (xy 141.13197 -232.524284) (xy 141.104769 -232.48127)
			(xy 141.084821 -232.43445) (xy 141.072642 -232.385036) (xy 141.068547 -232.334308) (xy 140.762736 -232.334308)
			(xy 140.762246 -232.359297) (xy 140.754427 -232.40866) (xy 140.738983 -232.456192) (xy 140.716293 -232.500724)
			(xy 140.686917 -232.541157) (xy 140.651577 -232.576497) (xy 140.611144 -232.605873) (xy 140.566612 -232.628563)
			(xy 140.51908 -232.644007) (xy 140.469717 -232.651826) (xy 140.419739 -232.651826) (xy 140.370376 -232.644007)
			(xy 140.322844 -232.628563) (xy 140.278312 -232.605873) (xy 140.237879 -232.576497) (xy 140.202539 -232.541157)
			(xy 140.173163 -232.500724) (xy 140.150473 -232.456192) (xy 140.135029 -232.40866) (xy 140.12721 -232.359297)
			(xy 139.819893 -232.359297) (xy 139.819884 -232.359754) (xy 139.81172 -232.409988) (xy 139.795604 -232.458262)
			(xy 139.771953 -232.503325) (xy 139.74138 -232.544011) (xy 139.704676 -232.579266) (xy 139.662792 -232.608176)
			(xy 139.616813 -232.629993) (xy 139.567929 -232.644153) (xy 139.517408 -232.650287) (xy 139.466556 -232.648238)
			(xy 139.416692 -232.638058) (xy 139.369106 -232.620011) (xy 139.325032 -232.594565) (xy 139.28561 -232.562378)
			(xy 139.251862 -232.524284) (xy 139.224661 -232.48127) (xy 139.204713 -232.43445) (xy 139.192534 -232.385036)
			(xy 139.188439 -232.334308) (xy 138.882882 -232.334308) (xy 138.882392 -232.359297) (xy 138.874573 -232.40866)
			(xy 138.859129 -232.456192) (xy 138.836439 -232.500724) (xy 138.807063 -232.541157) (xy 138.771723 -232.576497)
			(xy 138.73129 -232.605873) (xy 138.686758 -232.628563) (xy 138.639226 -232.644007) (xy 138.589863 -232.651826)
			(xy 138.539885 -232.651826) (xy 138.490522 -232.644007) (xy 138.44299 -232.628563) (xy 138.398458 -232.605873)
			(xy 138.358025 -232.576497) (xy 138.322685 -232.541157) (xy 138.293309 -232.500724) (xy 138.270619 -232.456192)
			(xy 138.255175 -232.40866) (xy 138.247356 -232.359297) (xy 137.940039 -232.359297) (xy 137.94003 -232.359754)
			(xy 137.931866 -232.409988) (xy 137.91575 -232.458262) (xy 137.892099 -232.503325) (xy 137.861526 -232.544011)
			(xy 137.824822 -232.579266) (xy 137.782938 -232.608176) (xy 137.736959 -232.629993) (xy 137.688075 -232.644153)
			(xy 137.637554 -232.650287) (xy 137.586702 -232.648238) (xy 137.536838 -232.638058) (xy 137.489252 -232.620011)
			(xy 137.445178 -232.594565) (xy 137.405756 -232.562378) (xy 137.372008 -232.524284) (xy 137.344807 -232.48127)
			(xy 137.324859 -232.43445) (xy 137.31268 -232.385036) (xy 137.308585 -232.334308) (xy 136.060434 -232.334308)
			(xy 136.059922 -232.359754) (xy 136.051758 -232.409988) (xy 136.035642 -232.458262) (xy 136.011991 -232.503325)
			(xy 135.981418 -232.544011) (xy 135.944714 -232.579266) (xy 135.90283 -232.608176) (xy 135.856851 -232.629993)
			(xy 135.807967 -232.644153) (xy 135.757446 -232.650287) (xy 135.706594 -232.648238) (xy 135.65673 -232.638058)
			(xy 135.609144 -232.620011) (xy 135.56507 -232.594565) (xy 135.525648 -232.562378) (xy 135.4919 -232.524284)
			(xy 135.464699 -232.48127) (xy 135.444751 -232.43445) (xy 135.432572 -232.385036) (xy 135.428477 -232.334308)
			(xy 135.12038 -232.334308) (xy 135.119868 -232.359754) (xy 135.111704 -232.409988) (xy 135.095588 -232.458262)
			(xy 135.071937 -232.503325) (xy 135.041364 -232.544011) (xy 135.00466 -232.579266) (xy 134.962776 -232.608176)
			(xy 134.916797 -232.629993) (xy 134.867913 -232.644153) (xy 134.817392 -232.650287) (xy 134.76654 -232.648238)
			(xy 134.716676 -232.638058) (xy 134.66909 -232.620011) (xy 134.625016 -232.594565) (xy 134.585594 -232.562378)
			(xy 134.551846 -232.524284) (xy 134.524645 -232.48127) (xy 134.504697 -232.43445) (xy 134.492518 -232.385036)
			(xy 134.488423 -232.334308) (xy 134.182866 -232.334308) (xy 134.182376 -232.359297) (xy 134.174557 -232.40866)
			(xy 134.159113 -232.456192) (xy 134.136423 -232.500724) (xy 134.107047 -232.541157) (xy 134.071707 -232.576497)
			(xy 134.031274 -232.605873) (xy 133.986742 -232.628563) (xy 133.93921 -232.644007) (xy 133.889847 -232.651826)
			(xy 133.839869 -232.651826) (xy 133.790506 -232.644007) (xy 133.742974 -232.628563) (xy 133.698442 -232.605873)
			(xy 133.658009 -232.576497) (xy 133.622669 -232.541157) (xy 133.593293 -232.500724) (xy 133.570603 -232.456192)
			(xy 133.555159 -232.40866) (xy 133.54734 -232.359297) (xy 133.240023 -232.359297) (xy 133.240014 -232.359754)
			(xy 133.23185 -232.409988) (xy 133.215734 -232.458262) (xy 133.192083 -232.503325) (xy 133.16151 -232.544011)
			(xy 133.124806 -232.579266) (xy 133.082922 -232.608176) (xy 133.036943 -232.629993) (xy 132.988059 -232.644153)
			(xy 132.937538 -232.650287) (xy 132.886686 -232.648238) (xy 132.836822 -232.638058) (xy 132.789236 -232.620011)
			(xy 132.745162 -232.594565) (xy 132.70574 -232.562378) (xy 132.671992 -232.524284) (xy 132.644791 -232.48127)
			(xy 132.624843 -232.43445) (xy 132.612664 -232.385036) (xy 132.608569 -232.334308) (xy 132.302758 -232.334308)
			(xy 132.302268 -232.359297) (xy 132.294449 -232.40866) (xy 132.279005 -232.456192) (xy 132.256315 -232.500724)
			(xy 132.226939 -232.541157) (xy 132.191599 -232.576497) (xy 132.151166 -232.605873) (xy 132.106634 -232.628563)
			(xy 132.059102 -232.644007) (xy 132.009739 -232.651826) (xy 131.959761 -232.651826) (xy 131.910398 -232.644007)
			(xy 131.862866 -232.628563) (xy 131.818334 -232.605873) (xy 131.777901 -232.576497) (xy 131.742561 -232.541157)
			(xy 131.713185 -232.500724) (xy 131.690495 -232.456192) (xy 131.675051 -232.40866) (xy 131.667232 -232.359297)
			(xy 131.359915 -232.359297) (xy 131.359906 -232.359754) (xy 131.351742 -232.409988) (xy 131.335626 -232.458262)
			(xy 131.311975 -232.503325) (xy 131.281402 -232.544011) (xy 131.244698 -232.579266) (xy 131.202814 -232.608176)
			(xy 131.156835 -232.629993) (xy 131.107951 -232.644153) (xy 131.05743 -232.650287) (xy 131.006578 -232.648238)
			(xy 130.956714 -232.638058) (xy 130.909128 -232.620011) (xy 130.865054 -232.594565) (xy 130.825632 -232.562378)
			(xy 130.791884 -232.524284) (xy 130.764683 -232.48127) (xy 130.744735 -232.43445) (xy 130.732556 -232.385036)
			(xy 130.728461 -232.334308) (xy 129.480564 -232.334308) (xy 129.480052 -232.359754) (xy 129.471888 -232.409988)
			(xy 129.455772 -232.458262) (xy 129.432121 -232.503325) (xy 129.401548 -232.544011) (xy 129.364844 -232.579266)
			(xy 129.32296 -232.608176) (xy 129.276981 -232.629993) (xy 129.228097 -232.644153) (xy 129.177576 -232.650287)
			(xy 129.126724 -232.648238) (xy 129.07686 -232.638058) (xy 129.029274 -232.620011) (xy 128.9852 -232.594565)
			(xy 128.945778 -232.562378) (xy 128.91203 -232.524284) (xy 128.884829 -232.48127) (xy 128.864881 -232.43445)
			(xy 128.852702 -232.385036) (xy 128.848607 -232.334308) (xy 128.54051 -232.334308) (xy 128.539998 -232.359754)
			(xy 128.531834 -232.409988) (xy 128.515718 -232.458262) (xy 128.492067 -232.503325) (xy 128.461494 -232.544011)
			(xy 128.42479 -232.579266) (xy 128.382906 -232.608176) (xy 128.336927 -232.629993) (xy 128.288043 -232.644153)
			(xy 128.237522 -232.650287) (xy 128.18667 -232.648238) (xy 128.136806 -232.638058) (xy 128.08922 -232.620011)
			(xy 128.045146 -232.594565) (xy 128.005724 -232.562378) (xy 127.971976 -232.524284) (xy 127.944775 -232.48127)
			(xy 127.924827 -232.43445) (xy 127.912648 -232.385036) (xy 127.908553 -232.334308) (xy 126.662688 -232.334308)
			(xy 126.662434 -232.348024) (xy 126.661371 -232.366826) (xy 126.655385 -232.404006) (xy 126.650496 -232.422192)
			(xy 126.648464 -232.42905) (xy 126.648464 -232.731056) (xy 126.648464 -232.73385) (xy 126.649368 -232.743273)
			(xy 126.657211 -232.760487) (xy 126.663704 -232.767378) (xy 126.665736 -232.769156) (xy 126.705614 -232.803446)
			(xy 126.706122 -232.803954) (xy 126.725172 -232.819956) (xy 126.731962 -232.824887) (xy 126.747779 -232.83046)
			(xy 126.75616 -232.830878) (xy 126.763526 -232.83037) (xy 126.765304 -232.830116) (xy 126.777607 -232.828319)
			(xy 126.802401 -232.826411) (xy 126.814834 -232.826306) (xy 126.83982 -232.826799) (xy 126.889177 -232.834621)
			(xy 126.936703 -232.850068) (xy 126.981227 -232.872758) (xy 127.021654 -232.902134) (xy 127.056988 -232.937472)
			(xy 127.08636 -232.977902) (xy 127.109045 -233.022429) (xy 127.124487 -233.069956) (xy 127.132304 -233.119314)
			(xy 127.132304 -233.144314) (xy 127.438399 -233.144314) (xy 127.442494 -233.093586) (xy 127.454673 -233.044172)
			(xy 127.474621 -232.997352) (xy 127.501822 -232.954338) (xy 127.53557 -232.916244) (xy 127.574992 -232.884057)
			(xy 127.619066 -232.858611) (xy 127.666652 -232.840564) (xy 127.716516 -232.830384) (xy 127.767368 -232.828335)
			(xy 127.817889 -232.834469) (xy 127.866773 -232.848629) (xy 127.912752 -232.870446) (xy 127.954636 -232.899356)
			(xy 127.99134 -232.934611) (xy 128.021913 -232.975297) (xy 128.045564 -233.02036) (xy 128.06168 -233.068634)
			(xy 128.069844 -233.118868) (xy 128.070356 -233.144314) (xy 128.069853 -233.169303) (xy 128.37717 -233.169303)
			(xy 128.37717 -233.119325) (xy 128.384989 -233.069962) (xy 128.400433 -233.02243) (xy 128.423123 -232.977898)
			(xy 128.452499 -232.937465) (xy 128.487839 -232.902125) (xy 128.528272 -232.872749) (xy 128.572804 -232.850059)
			(xy 128.620336 -232.834615) (xy 128.669699 -232.826796) (xy 128.719677 -232.826796) (xy 128.76904 -232.834615)
			(xy 128.816572 -232.850059) (xy 128.861104 -232.872749) (xy 128.901537 -232.902125) (xy 128.936877 -232.937465)
			(xy 128.966253 -232.977898) (xy 128.988943 -233.02243) (xy 129.004387 -233.069962) (xy 129.012206 -233.119325)
			(xy 129.012696 -233.144314) (xy 129.318507 -233.144314) (xy 129.322602 -233.093586) (xy 129.334781 -233.044172)
			(xy 129.354729 -232.997352) (xy 129.38193 -232.954338) (xy 129.415678 -232.916244) (xy 129.4551 -232.884057)
			(xy 129.499174 -232.858611) (xy 129.54676 -232.840564) (xy 129.596624 -232.830384) (xy 129.647476 -232.828335)
			(xy 129.697997 -232.834469) (xy 129.746881 -232.848629) (xy 129.79286 -232.870446) (xy 129.834744 -232.899356)
			(xy 129.871448 -232.934611) (xy 129.902021 -232.975297) (xy 129.925672 -233.02036) (xy 129.941788 -233.068634)
			(xy 129.949952 -233.118868) (xy 129.950464 -233.144314) (xy 129.949961 -233.169303) (xy 130.257278 -233.169303)
			(xy 130.257278 -233.119325) (xy 130.265097 -233.069962) (xy 130.280541 -233.02243) (xy 130.303231 -232.977898)
			(xy 130.332607 -232.937465) (xy 130.367947 -232.902125) (xy 130.40838 -232.872749) (xy 130.452912 -232.850059)
			(xy 130.500444 -232.834615) (xy 130.549807 -232.826796) (xy 130.599785 -232.826796) (xy 130.649148 -232.834615)
			(xy 130.69668 -232.850059) (xy 130.741212 -232.872749) (xy 130.781645 -232.902125) (xy 130.816985 -232.937465)
			(xy 130.846361 -232.977898) (xy 130.869051 -233.02243) (xy 130.884495 -233.069962) (xy 130.892314 -233.119325)
			(xy 130.892804 -233.144314) (xy 131.198615 -233.144314) (xy 131.20271 -233.093586) (xy 131.214889 -233.044172)
			(xy 131.234837 -232.997352) (xy 131.262038 -232.954338) (xy 131.295786 -232.916244) (xy 131.335208 -232.884057)
			(xy 131.379282 -232.858611) (xy 131.426868 -232.840564) (xy 131.476732 -232.830384) (xy 131.527584 -232.828335)
			(xy 131.578105 -232.834469) (xy 131.626989 -232.848629) (xy 131.672968 -232.870446) (xy 131.714852 -232.899356)
			(xy 131.751556 -232.934611) (xy 131.782129 -232.975297) (xy 131.80578 -233.02036) (xy 131.821896 -233.068634)
			(xy 131.83006 -233.118868) (xy 131.830572 -233.144314) (xy 132.138415 -233.144314) (xy 132.14251 -233.093586)
			(xy 132.154689 -233.044172) (xy 132.174637 -232.997352) (xy 132.201838 -232.954338) (xy 132.235586 -232.916244)
			(xy 132.275008 -232.884057) (xy 132.319082 -232.858611) (xy 132.366668 -232.840564) (xy 132.416532 -232.830384)
			(xy 132.467384 -232.828335) (xy 132.517905 -232.834469) (xy 132.566789 -232.848629) (xy 132.612768 -232.870446)
			(xy 132.654652 -232.899356) (xy 132.691356 -232.934611) (xy 132.721929 -232.975297) (xy 132.74558 -233.02036)
			(xy 132.761696 -233.068634) (xy 132.76986 -233.118868) (xy 132.770372 -233.144314) (xy 132.769869 -233.169303)
			(xy 133.077186 -233.169303) (xy 133.077186 -233.119325) (xy 133.085005 -233.069962) (xy 133.100449 -233.02243)
			(xy 133.123139 -232.977898) (xy 133.152515 -232.937465) (xy 133.187855 -232.902125) (xy 133.228288 -232.872749)
			(xy 133.27282 -232.850059) (xy 133.320352 -232.834615) (xy 133.369715 -232.826796) (xy 133.419693 -232.826796)
			(xy 133.469056 -232.834615) (xy 133.516588 -232.850059) (xy 133.56112 -232.872749) (xy 133.601553 -232.902125)
			(xy 133.636893 -232.937465) (xy 133.666269 -232.977898) (xy 133.688959 -233.02243) (xy 133.704403 -233.069962)
			(xy 133.712222 -233.119325) (xy 133.712712 -233.144314) (xy 134.018523 -233.144314) (xy 134.022618 -233.093586)
			(xy 134.034797 -233.044172) (xy 134.054745 -232.997352) (xy 134.081946 -232.954338) (xy 134.115694 -232.916244)
			(xy 134.155116 -232.884057) (xy 134.19919 -232.858611) (xy 134.246776 -232.840564) (xy 134.29664 -232.830384)
			(xy 134.347492 -232.828335) (xy 134.398013 -232.834469) (xy 134.446897 -232.848629) (xy 134.492876 -232.870446)
			(xy 134.53476 -232.899356) (xy 134.571464 -232.934611) (xy 134.602037 -232.975297) (xy 134.625688 -233.02036)
			(xy 134.641804 -233.068634) (xy 134.649968 -233.118868) (xy 134.65048 -233.144314) (xy 134.649977 -233.169303)
			(xy 134.957294 -233.169303) (xy 134.957294 -233.119325) (xy 134.965113 -233.069962) (xy 134.980557 -233.02243)
			(xy 135.003247 -232.977898) (xy 135.032623 -232.937465) (xy 135.067963 -232.902125) (xy 135.108396 -232.872749)
			(xy 135.152928 -232.850059) (xy 135.20046 -232.834615) (xy 135.249823 -232.826796) (xy 135.299801 -232.826796)
			(xy 135.349164 -232.834615) (xy 135.396696 -232.850059) (xy 135.441228 -232.872749) (xy 135.481661 -232.902125)
			(xy 135.517001 -232.937465) (xy 135.546377 -232.977898) (xy 135.569067 -233.02243) (xy 135.584511 -233.069962)
			(xy 135.59233 -233.119325) (xy 135.59282 -233.144314) (xy 135.898631 -233.144314) (xy 135.902726 -233.093586)
			(xy 135.914905 -233.044172) (xy 135.934853 -232.997352) (xy 135.962054 -232.954338) (xy 135.995802 -232.916244)
			(xy 136.035224 -232.884057) (xy 136.079298 -232.858611) (xy 136.126884 -232.840564) (xy 136.176748 -232.830384)
			(xy 136.2276 -232.828335) (xy 136.278121 -232.834469) (xy 136.327005 -232.848629) (xy 136.372984 -232.870446)
			(xy 136.414868 -232.899356) (xy 136.451572 -232.934611) (xy 136.482145 -232.975297) (xy 136.505796 -233.02036)
			(xy 136.521912 -233.068634) (xy 136.530076 -233.118868) (xy 136.530588 -233.144314) (xy 136.530085 -233.169303)
			(xy 136.837148 -233.169303) (xy 136.837148 -233.119325) (xy 136.844967 -233.069962) (xy 136.860411 -233.02243)
			(xy 136.883101 -232.977898) (xy 136.912477 -232.937465) (xy 136.947817 -232.902125) (xy 136.98825 -232.872749)
			(xy 137.032782 -232.850059) (xy 137.080314 -232.834615) (xy 137.129677 -232.826796) (xy 137.179655 -232.826796)
			(xy 137.229018 -232.834615) (xy 137.27655 -232.850059) (xy 137.321082 -232.872749) (xy 137.361515 -232.902125)
			(xy 137.396855 -232.937465) (xy 137.426231 -232.977898) (xy 137.448921 -233.02243) (xy 137.464365 -233.069962)
			(xy 137.472184 -233.119325) (xy 137.472674 -233.144314) (xy 137.778485 -233.144314) (xy 137.78258 -233.093586)
			(xy 137.794759 -233.044172) (xy 137.814707 -232.997352) (xy 137.841908 -232.954338) (xy 137.875656 -232.916244)
			(xy 137.915078 -232.884057) (xy 137.959152 -232.858611) (xy 138.006738 -232.840564) (xy 138.056602 -232.830384)
			(xy 138.107454 -232.828335) (xy 138.157975 -232.834469) (xy 138.206859 -232.848629) (xy 138.252838 -232.870446)
			(xy 138.294722 -232.899356) (xy 138.331426 -232.934611) (xy 138.361999 -232.975297) (xy 138.38565 -233.02036)
			(xy 138.401766 -233.068634) (xy 138.40993 -233.118868) (xy 138.410442 -233.144314) (xy 138.718539 -233.144314)
			(xy 138.722634 -233.093586) (xy 138.734813 -233.044172) (xy 138.754761 -232.997352) (xy 138.781962 -232.954338)
			(xy 138.81571 -232.916244) (xy 138.855132 -232.884057) (xy 138.899206 -232.858611) (xy 138.946792 -232.840564)
			(xy 138.996656 -232.830384) (xy 139.047508 -232.828335) (xy 139.098029 -232.834469) (xy 139.146913 -232.848629)
			(xy 139.192892 -232.870446) (xy 139.234776 -232.899356) (xy 139.27148 -232.934611) (xy 139.302053 -232.975297)
			(xy 139.325704 -233.02036) (xy 139.34182 -233.068634) (xy 139.349984 -233.118868) (xy 139.350496 -233.144314)
			(xy 139.349993 -233.169303) (xy 139.65731 -233.169303) (xy 139.65731 -233.119325) (xy 139.665129 -233.069962)
			(xy 139.680573 -233.02243) (xy 139.703263 -232.977898) (xy 139.732639 -232.937465) (xy 139.767979 -232.902125)
			(xy 139.808412 -232.872749) (xy 139.852944 -232.850059) (xy 139.900476 -232.834615) (xy 139.949839 -232.826796)
			(xy 139.999817 -232.826796) (xy 140.04918 -232.834615) (xy 140.096712 -232.850059) (xy 140.141244 -232.872749)
			(xy 140.181677 -232.902125) (xy 140.217017 -232.937465) (xy 140.246393 -232.977898) (xy 140.269083 -233.02243)
			(xy 140.284527 -233.069962) (xy 140.292346 -233.119325) (xy 140.292836 -233.144314) (xy 140.598647 -233.144314)
			(xy 140.602742 -233.093586) (xy 140.614921 -233.044172) (xy 140.634869 -232.997352) (xy 140.66207 -232.954338)
			(xy 140.695818 -232.916244) (xy 140.73524 -232.884057) (xy 140.779314 -232.858611) (xy 140.8269 -232.840564)
			(xy 140.876764 -232.830384) (xy 140.927616 -232.828335) (xy 140.978137 -232.834469) (xy 141.027021 -232.848629)
			(xy 141.073 -232.870446) (xy 141.114884 -232.899356) (xy 141.151588 -232.934611) (xy 141.182161 -232.975297)
			(xy 141.205812 -233.02036) (xy 141.221928 -233.068634) (xy 141.230092 -233.118868) (xy 141.230604 -233.144314)
			(xy 141.230101 -233.169303) (xy 141.537164 -233.169303) (xy 141.537164 -233.119325) (xy 141.544983 -233.069962)
			(xy 141.560427 -233.02243) (xy 141.583117 -232.977898) (xy 141.612493 -232.937465) (xy 141.647833 -232.902125)
			(xy 141.688266 -232.872749) (xy 141.732798 -232.850059) (xy 141.78033 -232.834615) (xy 141.829693 -232.826796)
			(xy 141.879671 -232.826796) (xy 141.929034 -232.834615) (xy 141.976566 -232.850059) (xy 142.021098 -232.872749)
			(xy 142.061531 -232.902125) (xy 142.096871 -232.937465) (xy 142.126247 -232.977898) (xy 142.148937 -233.02243)
			(xy 142.164381 -233.069962) (xy 142.1722 -233.119325) (xy 142.17269 -233.144314) (xy 142.478501 -233.144314)
			(xy 142.482596 -233.093586) (xy 142.494775 -233.044172) (xy 142.514723 -232.997352) (xy 142.541924 -232.954338)
			(xy 142.575672 -232.916244) (xy 142.615094 -232.884057) (xy 142.659168 -232.858611) (xy 142.706754 -232.840564)
			(xy 142.756618 -232.830384) (xy 142.80747 -232.828335) (xy 142.857991 -232.834469) (xy 142.906875 -232.848629)
			(xy 142.952854 -232.870446) (xy 142.994738 -232.899356) (xy 143.031442 -232.934611) (xy 143.062015 -232.975297)
			(xy 143.085666 -233.02036) (xy 143.101782 -233.068634) (xy 143.109946 -233.118868) (xy 143.110458 -233.144314)
			(xy 143.109955 -233.169303) (xy 143.417272 -233.169303) (xy 143.417272 -233.119325) (xy 143.425091 -233.069962)
			(xy 143.440535 -233.02243) (xy 143.463225 -232.977898) (xy 143.492601 -232.937465) (xy 143.527941 -232.902125)
			(xy 143.568374 -232.872749) (xy 143.612906 -232.850059) (xy 143.660438 -232.834615) (xy 143.709801 -232.826796)
			(xy 143.759779 -232.826796) (xy 143.809142 -232.834615) (xy 143.856674 -232.850059) (xy 143.901206 -232.872749)
			(xy 143.941639 -232.902125) (xy 143.976979 -232.937465) (xy 144.006355 -232.977898) (xy 144.029045 -233.02243)
			(xy 144.044489 -233.069962) (xy 144.052308 -233.119325) (xy 144.052798 -233.144314) (xy 144.052308 -233.169303)
			(xy 144.044489 -233.218666) (xy 144.029045 -233.266198) (xy 144.006355 -233.31073) (xy 143.976979 -233.351163)
			(xy 143.941639 -233.386503) (xy 143.901206 -233.415879) (xy 143.856674 -233.438569) (xy 143.809142 -233.454013)
			(xy 143.759779 -233.461832) (xy 143.709801 -233.461832) (xy 143.660438 -233.454013) (xy 143.612906 -233.438569)
			(xy 143.568374 -233.415879) (xy 143.527941 -233.386503) (xy 143.492601 -233.351163) (xy 143.463225 -233.31073)
			(xy 143.440535 -233.266198) (xy 143.425091 -233.218666) (xy 143.417272 -233.169303) (xy 143.109955 -233.169303)
			(xy 143.109946 -233.16976) (xy 143.101782 -233.219994) (xy 143.085666 -233.268268) (xy 143.062015 -233.313331)
			(xy 143.031442 -233.354017) (xy 142.994738 -233.389272) (xy 142.952854 -233.418182) (xy 142.906875 -233.439999)
			(xy 142.857991 -233.454159) (xy 142.80747 -233.460293) (xy 142.756618 -233.458244) (xy 142.706754 -233.448064)
			(xy 142.659168 -233.430017) (xy 142.615094 -233.404571) (xy 142.575672 -233.372384) (xy 142.541924 -233.33429)
			(xy 142.514723 -233.291276) (xy 142.494775 -233.244456) (xy 142.482596 -233.195042) (xy 142.478501 -233.144314)
			(xy 142.17269 -233.144314) (xy 142.1722 -233.169303) (xy 142.164381 -233.218666) (xy 142.148937 -233.266198)
			(xy 142.126247 -233.31073) (xy 142.096871 -233.351163) (xy 142.061531 -233.386503) (xy 142.021098 -233.415879)
			(xy 141.976566 -233.438569) (xy 141.929034 -233.454013) (xy 141.879671 -233.461832) (xy 141.829693 -233.461832)
			(xy 141.78033 -233.454013) (xy 141.732798 -233.438569) (xy 141.688266 -233.415879) (xy 141.647833 -233.386503)
			(xy 141.612493 -233.351163) (xy 141.583117 -233.31073) (xy 141.560427 -233.266198) (xy 141.544983 -233.218666)
			(xy 141.537164 -233.169303) (xy 141.230101 -233.169303) (xy 141.230092 -233.16976) (xy 141.221928 -233.219994)
			(xy 141.205812 -233.268268) (xy 141.182161 -233.313331) (xy 141.151588 -233.354017) (xy 141.114884 -233.389272)
			(xy 141.073 -233.418182) (xy 141.027021 -233.439999) (xy 140.978137 -233.454159) (xy 140.927616 -233.460293)
			(xy 140.876764 -233.458244) (xy 140.8269 -233.448064) (xy 140.779314 -233.430017) (xy 140.73524 -233.404571)
			(xy 140.695818 -233.372384) (xy 140.66207 -233.33429) (xy 140.634869 -233.291276) (xy 140.614921 -233.244456)
			(xy 140.602742 -233.195042) (xy 140.598647 -233.144314) (xy 140.292836 -233.144314) (xy 140.292346 -233.169303)
			(xy 140.284527 -233.218666) (xy 140.269083 -233.266198) (xy 140.246393 -233.31073) (xy 140.217017 -233.351163)
			(xy 140.181677 -233.386503) (xy 140.141244 -233.415879) (xy 140.096712 -233.438569) (xy 140.04918 -233.454013)
			(xy 139.999817 -233.461832) (xy 139.949839 -233.461832) (xy 139.900476 -233.454013) (xy 139.852944 -233.438569)
			(xy 139.808412 -233.415879) (xy 139.767979 -233.386503) (xy 139.732639 -233.351163) (xy 139.703263 -233.31073)
			(xy 139.680573 -233.266198) (xy 139.665129 -233.218666) (xy 139.65731 -233.169303) (xy 139.349993 -233.169303)
			(xy 139.349984 -233.16976) (xy 139.34182 -233.219994) (xy 139.325704 -233.268268) (xy 139.302053 -233.313331)
			(xy 139.27148 -233.354017) (xy 139.234776 -233.389272) (xy 139.192892 -233.418182) (xy 139.146913 -233.439999)
			(xy 139.098029 -233.454159) (xy 139.047508 -233.460293) (xy 138.996656 -233.458244) (xy 138.946792 -233.448064)
			(xy 138.899206 -233.430017) (xy 138.855132 -233.404571) (xy 138.81571 -233.372384) (xy 138.781962 -233.33429)
			(xy 138.754761 -233.291276) (xy 138.734813 -233.244456) (xy 138.722634 -233.195042) (xy 138.718539 -233.144314)
			(xy 138.410442 -233.144314) (xy 138.40993 -233.16976) (xy 138.401766 -233.219994) (xy 138.38565 -233.268268)
			(xy 138.361999 -233.313331) (xy 138.331426 -233.354017) (xy 138.294722 -233.389272) (xy 138.252838 -233.418182)
			(xy 138.206859 -233.439999) (xy 138.157975 -233.454159) (xy 138.107454 -233.460293) (xy 138.056602 -233.458244)
			(xy 138.006738 -233.448064) (xy 137.959152 -233.430017) (xy 137.915078 -233.404571) (xy 137.875656 -233.372384)
			(xy 137.841908 -233.33429) (xy 137.814707 -233.291276) (xy 137.794759 -233.244456) (xy 137.78258 -233.195042)
			(xy 137.778485 -233.144314) (xy 137.472674 -233.144314) (xy 137.472184 -233.169303) (xy 137.464365 -233.218666)
			(xy 137.448921 -233.266198) (xy 137.426231 -233.31073) (xy 137.396855 -233.351163) (xy 137.361515 -233.386503)
			(xy 137.321082 -233.415879) (xy 137.27655 -233.438569) (xy 137.229018 -233.454013) (xy 137.179655 -233.461832)
			(xy 137.129677 -233.461832) (xy 137.080314 -233.454013) (xy 137.032782 -233.438569) (xy 136.98825 -233.415879)
			(xy 136.947817 -233.386503) (xy 136.912477 -233.351163) (xy 136.883101 -233.31073) (xy 136.860411 -233.266198)
			(xy 136.844967 -233.218666) (xy 136.837148 -233.169303) (xy 136.530085 -233.169303) (xy 136.530076 -233.16976)
			(xy 136.521912 -233.219994) (xy 136.505796 -233.268268) (xy 136.482145 -233.313331) (xy 136.451572 -233.354017)
			(xy 136.414868 -233.389272) (xy 136.372984 -233.418182) (xy 136.327005 -233.439999) (xy 136.278121 -233.454159)
			(xy 136.2276 -233.460293) (xy 136.176748 -233.458244) (xy 136.126884 -233.448064) (xy 136.079298 -233.430017)
			(xy 136.035224 -233.404571) (xy 135.995802 -233.372384) (xy 135.962054 -233.33429) (xy 135.934853 -233.291276)
			(xy 135.914905 -233.244456) (xy 135.902726 -233.195042) (xy 135.898631 -233.144314) (xy 135.59282 -233.144314)
			(xy 135.59233 -233.169303) (xy 135.584511 -233.218666) (xy 135.569067 -233.266198) (xy 135.546377 -233.31073)
			(xy 135.517001 -233.351163) (xy 135.481661 -233.386503) (xy 135.441228 -233.415879) (xy 135.396696 -233.438569)
			(xy 135.349164 -233.454013) (xy 135.299801 -233.461832) (xy 135.249823 -233.461832) (xy 135.20046 -233.454013)
			(xy 135.152928 -233.438569) (xy 135.108396 -233.415879) (xy 135.067963 -233.386503) (xy 135.032623 -233.351163)
			(xy 135.003247 -233.31073) (xy 134.980557 -233.266198) (xy 134.965113 -233.218666) (xy 134.957294 -233.169303)
			(xy 134.649977 -233.169303) (xy 134.649968 -233.16976) (xy 134.641804 -233.219994) (xy 134.625688 -233.268268)
			(xy 134.602037 -233.313331) (xy 134.571464 -233.354017) (xy 134.53476 -233.389272) (xy 134.492876 -233.418182)
			(xy 134.446897 -233.439999) (xy 134.398013 -233.454159) (xy 134.347492 -233.460293) (xy 134.29664 -233.458244)
			(xy 134.246776 -233.448064) (xy 134.19919 -233.430017) (xy 134.155116 -233.404571) (xy 134.115694 -233.372384)
			(xy 134.081946 -233.33429) (xy 134.054745 -233.291276) (xy 134.034797 -233.244456) (xy 134.022618 -233.195042)
			(xy 134.018523 -233.144314) (xy 133.712712 -233.144314) (xy 133.712222 -233.169303) (xy 133.704403 -233.218666)
			(xy 133.688959 -233.266198) (xy 133.666269 -233.31073) (xy 133.636893 -233.351163) (xy 133.601553 -233.386503)
			(xy 133.56112 -233.415879) (xy 133.516588 -233.438569) (xy 133.469056 -233.454013) (xy 133.419693 -233.461832)
			(xy 133.369715 -233.461832) (xy 133.320352 -233.454013) (xy 133.27282 -233.438569) (xy 133.228288 -233.415879)
			(xy 133.187855 -233.386503) (xy 133.152515 -233.351163) (xy 133.123139 -233.31073) (xy 133.100449 -233.266198)
			(xy 133.085005 -233.218666) (xy 133.077186 -233.169303) (xy 132.769869 -233.169303) (xy 132.76986 -233.16976)
			(xy 132.761696 -233.219994) (xy 132.74558 -233.268268) (xy 132.721929 -233.313331) (xy 132.691356 -233.354017)
			(xy 132.654652 -233.389272) (xy 132.612768 -233.418182) (xy 132.566789 -233.439999) (xy 132.517905 -233.454159)
			(xy 132.467384 -233.460293) (xy 132.416532 -233.458244) (xy 132.366668 -233.448064) (xy 132.319082 -233.430017)
			(xy 132.275008 -233.404571) (xy 132.235586 -233.372384) (xy 132.201838 -233.33429) (xy 132.174637 -233.291276)
			(xy 132.154689 -233.244456) (xy 132.14251 -233.195042) (xy 132.138415 -233.144314) (xy 131.830572 -233.144314)
			(xy 131.83006 -233.16976) (xy 131.821896 -233.219994) (xy 131.80578 -233.268268) (xy 131.782129 -233.313331)
			(xy 131.751556 -233.354017) (xy 131.714852 -233.389272) (xy 131.672968 -233.418182) (xy 131.626989 -233.439999)
			(xy 131.578105 -233.454159) (xy 131.527584 -233.460293) (xy 131.476732 -233.458244) (xy 131.426868 -233.448064)
			(xy 131.379282 -233.430017) (xy 131.335208 -233.404571) (xy 131.295786 -233.372384) (xy 131.262038 -233.33429)
			(xy 131.234837 -233.291276) (xy 131.214889 -233.244456) (xy 131.20271 -233.195042) (xy 131.198615 -233.144314)
			(xy 130.892804 -233.144314) (xy 130.892314 -233.169303) (xy 130.884495 -233.218666) (xy 130.869051 -233.266198)
			(xy 130.846361 -233.31073) (xy 130.816985 -233.351163) (xy 130.781645 -233.386503) (xy 130.741212 -233.415879)
			(xy 130.69668 -233.438569) (xy 130.649148 -233.454013) (xy 130.599785 -233.461832) (xy 130.549807 -233.461832)
			(xy 130.500444 -233.454013) (xy 130.452912 -233.438569) (xy 130.40838 -233.415879) (xy 130.367947 -233.386503)
			(xy 130.332607 -233.351163) (xy 130.303231 -233.31073) (xy 130.280541 -233.266198) (xy 130.265097 -233.218666)
			(xy 130.257278 -233.169303) (xy 129.949961 -233.169303) (xy 129.949952 -233.16976) (xy 129.941788 -233.219994)
			(xy 129.925672 -233.268268) (xy 129.902021 -233.313331) (xy 129.871448 -233.354017) (xy 129.834744 -233.389272)
			(xy 129.79286 -233.418182) (xy 129.746881 -233.439999) (xy 129.697997 -233.454159) (xy 129.647476 -233.460293)
			(xy 129.596624 -233.458244) (xy 129.54676 -233.448064) (xy 129.499174 -233.430017) (xy 129.4551 -233.404571)
			(xy 129.415678 -233.372384) (xy 129.38193 -233.33429) (xy 129.354729 -233.291276) (xy 129.334781 -233.244456)
			(xy 129.322602 -233.195042) (xy 129.318507 -233.144314) (xy 129.012696 -233.144314) (xy 129.012206 -233.169303)
			(xy 129.004387 -233.218666) (xy 128.988943 -233.266198) (xy 128.966253 -233.31073) (xy 128.936877 -233.351163)
			(xy 128.901537 -233.386503) (xy 128.861104 -233.415879) (xy 128.816572 -233.438569) (xy 128.76904 -233.454013)
			(xy 128.719677 -233.461832) (xy 128.669699 -233.461832) (xy 128.620336 -233.454013) (xy 128.572804 -233.438569)
			(xy 128.528272 -233.415879) (xy 128.487839 -233.386503) (xy 128.452499 -233.351163) (xy 128.423123 -233.31073)
			(xy 128.400433 -233.266198) (xy 128.384989 -233.218666) (xy 128.37717 -233.169303) (xy 128.069853 -233.169303)
			(xy 128.069844 -233.16976) (xy 128.06168 -233.219994) (xy 128.045564 -233.268268) (xy 128.021913 -233.313331)
			(xy 127.99134 -233.354017) (xy 127.954636 -233.389272) (xy 127.912752 -233.418182) (xy 127.866773 -233.439999)
			(xy 127.817889 -233.454159) (xy 127.767368 -233.460293) (xy 127.716516 -233.458244) (xy 127.666652 -233.448064)
			(xy 127.619066 -233.430017) (xy 127.574992 -233.404571) (xy 127.53557 -233.372384) (xy 127.501822 -233.33429)
			(xy 127.474621 -233.291276) (xy 127.454673 -233.244456) (xy 127.442494 -233.195042) (xy 127.438399 -233.144314)
			(xy 127.132304 -233.144314) (xy 127.132304 -233.169286) (xy 127.124487 -233.218644) (xy 127.109045 -233.266171)
			(xy 127.08636 -233.310698) (xy 127.056988 -233.351128) (xy 127.021654 -233.386466) (xy 126.981227 -233.415842)
			(xy 126.936703 -233.438532) (xy 126.889177 -233.453979) (xy 126.83982 -233.461801) (xy 126.814834 -233.462322)
			(xy 126.802206 -233.462174) (xy 126.777031 -233.460137) (xy 126.764542 -233.458258) (xy 126.75362 -233.45648)
			(xy 126.74346 -233.459274) (xy 126.738264 -233.460903) (xy 126.728659 -233.466028) (xy 126.72441 -233.469434)
			(xy 126.663958 -233.520742) (xy 126.657446 -233.52764) (xy 126.649483 -233.54484) (xy 126.648464 -233.55427)
			(xy 126.648464 -233.848656) (xy 126.648972 -233.855768) (xy 126.650496 -233.86669) (xy 126.656206 -233.888146)
			(xy 126.662327 -233.93212) (xy 126.662688 -233.95432) (xy 126.662372 -233.976586) (xy 126.661994 -233.979309)
			(xy 126.967216 -233.979309) (xy 126.967216 -233.929331) (xy 126.975035 -233.879968) (xy 126.990479 -233.832436)
			(xy 127.013169 -233.787904) (xy 127.042545 -233.747471) (xy 127.077885 -233.712131) (xy 127.118318 -233.682755)
			(xy 127.16285 -233.660065) (xy 127.210382 -233.644621) (xy 127.259745 -233.636802) (xy 127.309723 -233.636802)
			(xy 127.359086 -233.644621) (xy 127.406618 -233.660065) (xy 127.45115 -233.682755) (xy 127.491583 -233.712131)
			(xy 127.526923 -233.747471) (xy 127.556299 -233.787904) (xy 127.578989 -233.832436) (xy 127.594433 -233.879968)
			(xy 127.602252 -233.929331) (xy 127.602742 -233.95432) (xy 127.908553 -233.95432) (xy 127.912648 -233.903592)
			(xy 127.924827 -233.854178) (xy 127.944775 -233.807358) (xy 127.971976 -233.764344) (xy 128.005724 -233.72625)
			(xy 128.045146 -233.694063) (xy 128.08922 -233.668617) (xy 128.136806 -233.65057) (xy 128.18667 -233.64039)
			(xy 128.237522 -233.638341) (xy 128.288043 -233.644475) (xy 128.336927 -233.658635) (xy 128.382906 -233.680452)
			(xy 128.42479 -233.709362) (xy 128.461494 -233.744617) (xy 128.492067 -233.785303) (xy 128.515718 -233.830366)
			(xy 128.531834 -233.87864) (xy 128.539998 -233.928874) (xy 128.54051 -233.95432) (xy 128.848607 -233.95432)
			(xy 128.852702 -233.903592) (xy 128.864881 -233.854178) (xy 128.884829 -233.807358) (xy 128.91203 -233.764344)
			(xy 128.945778 -233.72625) (xy 128.9852 -233.694063) (xy 129.029274 -233.668617) (xy 129.07686 -233.65057)
			(xy 129.126724 -233.64039) (xy 129.177576 -233.638341) (xy 129.228097 -233.644475) (xy 129.276981 -233.658635)
			(xy 129.32296 -233.680452) (xy 129.364844 -233.709362) (xy 129.401548 -233.744617) (xy 129.432121 -233.785303)
			(xy 129.455772 -233.830366) (xy 129.471888 -233.87864) (xy 129.480052 -233.928874) (xy 129.480564 -233.95432)
			(xy 129.480061 -233.979309) (xy 129.787124 -233.979309) (xy 129.787124 -233.929331) (xy 129.794943 -233.879968)
			(xy 129.810387 -233.832436) (xy 129.833077 -233.787904) (xy 129.862453 -233.747471) (xy 129.897793 -233.712131)
			(xy 129.938226 -233.682755) (xy 129.982758 -233.660065) (xy 130.03029 -233.644621) (xy 130.079653 -233.636802)
			(xy 130.129631 -233.636802) (xy 130.178994 -233.644621) (xy 130.226526 -233.660065) (xy 130.271058 -233.682755)
			(xy 130.311491 -233.712131) (xy 130.346831 -233.747471) (xy 130.376207 -233.787904) (xy 130.398897 -233.832436)
			(xy 130.414341 -233.879968) (xy 130.42216 -233.929331) (xy 130.42265 -233.95432) (xy 130.728461 -233.95432)
			(xy 130.732556 -233.903592) (xy 130.744735 -233.854178) (xy 130.764683 -233.807358) (xy 130.791884 -233.764344)
			(xy 130.825632 -233.72625) (xy 130.865054 -233.694063) (xy 130.909128 -233.668617) (xy 130.956714 -233.65057)
			(xy 131.006578 -233.64039) (xy 131.05743 -233.638341) (xy 131.107951 -233.644475) (xy 131.156835 -233.658635)
			(xy 131.202814 -233.680452) (xy 131.244698 -233.709362) (xy 131.281402 -233.744617) (xy 131.311975 -233.785303)
			(xy 131.335626 -233.830366) (xy 131.351742 -233.87864) (xy 131.359906 -233.928874) (xy 131.360418 -233.95432)
			(xy 131.359915 -233.979309) (xy 131.667232 -233.979309) (xy 131.667232 -233.929331) (xy 131.675051 -233.879968)
			(xy 131.690495 -233.832436) (xy 131.713185 -233.787904) (xy 131.742561 -233.747471) (xy 131.777901 -233.712131)
			(xy 131.818334 -233.682755) (xy 131.862866 -233.660065) (xy 131.910398 -233.644621) (xy 131.959761 -233.636802)
			(xy 132.009739 -233.636802) (xy 132.059102 -233.644621) (xy 132.106634 -233.660065) (xy 132.151166 -233.682755)
			(xy 132.191599 -233.712131) (xy 132.226939 -233.747471) (xy 132.256315 -233.787904) (xy 132.279005 -233.832436)
			(xy 132.294449 -233.879968) (xy 132.302268 -233.929331) (xy 132.302758 -233.95432) (xy 132.608569 -233.95432)
			(xy 132.612664 -233.903592) (xy 132.624843 -233.854178) (xy 132.644791 -233.807358) (xy 132.671992 -233.764344)
			(xy 132.70574 -233.72625) (xy 132.745162 -233.694063) (xy 132.789236 -233.668617) (xy 132.836822 -233.65057)
			(xy 132.886686 -233.64039) (xy 132.937538 -233.638341) (xy 132.988059 -233.644475) (xy 133.036943 -233.658635)
			(xy 133.082922 -233.680452) (xy 133.124806 -233.709362) (xy 133.16151 -233.744617) (xy 133.192083 -233.785303)
			(xy 133.215734 -233.830366) (xy 133.23185 -233.87864) (xy 133.240014 -233.928874) (xy 133.240526 -233.95432)
			(xy 133.240023 -233.979309) (xy 133.54734 -233.979309) (xy 133.54734 -233.929331) (xy 133.555159 -233.879968)
			(xy 133.570603 -233.832436) (xy 133.593293 -233.787904) (xy 133.622669 -233.747471) (xy 133.658009 -233.712131)
			(xy 133.698442 -233.682755) (xy 133.742974 -233.660065) (xy 133.790506 -233.644621) (xy 133.839869 -233.636802)
			(xy 133.889847 -233.636802) (xy 133.93921 -233.644621) (xy 133.986742 -233.660065) (xy 134.031274 -233.682755)
			(xy 134.071707 -233.712131) (xy 134.107047 -233.747471) (xy 134.136423 -233.787904) (xy 134.159113 -233.832436)
			(xy 134.174557 -233.879968) (xy 134.182376 -233.929331) (xy 134.182866 -233.95432) (xy 134.488423 -233.95432)
			(xy 134.492518 -233.903592) (xy 134.504697 -233.854178) (xy 134.524645 -233.807358) (xy 134.551846 -233.764344)
			(xy 134.585594 -233.72625) (xy 134.625016 -233.694063) (xy 134.66909 -233.668617) (xy 134.716676 -233.65057)
			(xy 134.76654 -233.64039) (xy 134.817392 -233.638341) (xy 134.867913 -233.644475) (xy 134.916797 -233.658635)
			(xy 134.962776 -233.680452) (xy 135.00466 -233.709362) (xy 135.041364 -233.744617) (xy 135.071937 -233.785303)
			(xy 135.095588 -233.830366) (xy 135.111704 -233.87864) (xy 135.119868 -233.928874) (xy 135.12038 -233.95432)
			(xy 135.428477 -233.95432) (xy 135.432572 -233.903592) (xy 135.444751 -233.854178) (xy 135.464699 -233.807358)
			(xy 135.4919 -233.764344) (xy 135.525648 -233.72625) (xy 135.56507 -233.694063) (xy 135.609144 -233.668617)
			(xy 135.65673 -233.65057) (xy 135.706594 -233.64039) (xy 135.757446 -233.638341) (xy 135.807967 -233.644475)
			(xy 135.856851 -233.658635) (xy 135.90283 -233.680452) (xy 135.944714 -233.709362) (xy 135.981418 -233.744617)
			(xy 136.011991 -233.785303) (xy 136.035642 -233.830366) (xy 136.051758 -233.87864) (xy 136.059922 -233.928874)
			(xy 136.060434 -233.95432) (xy 136.059931 -233.979309) (xy 136.367248 -233.979309) (xy 136.367248 -233.929331)
			(xy 136.375067 -233.879968) (xy 136.390511 -233.832436) (xy 136.413201 -233.787904) (xy 136.442577 -233.747471)
			(xy 136.477917 -233.712131) (xy 136.51835 -233.682755) (xy 136.562882 -233.660065) (xy 136.610414 -233.644621)
			(xy 136.659777 -233.636802) (xy 136.709755 -233.636802) (xy 136.759118 -233.644621) (xy 136.80665 -233.660065)
			(xy 136.851182 -233.682755) (xy 136.891615 -233.712131) (xy 136.926955 -233.747471) (xy 136.956331 -233.787904)
			(xy 136.979021 -233.832436) (xy 136.994465 -233.879968) (xy 137.002284 -233.929331) (xy 137.002774 -233.95432)
			(xy 137.308585 -233.95432) (xy 137.31268 -233.903592) (xy 137.324859 -233.854178) (xy 137.344807 -233.807358)
			(xy 137.372008 -233.764344) (xy 137.405756 -233.72625) (xy 137.445178 -233.694063) (xy 137.489252 -233.668617)
			(xy 137.536838 -233.65057) (xy 137.586702 -233.64039) (xy 137.637554 -233.638341) (xy 137.688075 -233.644475)
			(xy 137.736959 -233.658635) (xy 137.782938 -233.680452) (xy 137.824822 -233.709362) (xy 137.861526 -233.744617)
			(xy 137.892099 -233.785303) (xy 137.91575 -233.830366) (xy 137.931866 -233.87864) (xy 137.94003 -233.928874)
			(xy 137.940542 -233.95432) (xy 137.940039 -233.979309) (xy 138.247356 -233.979309) (xy 138.247356 -233.929331)
			(xy 138.255175 -233.879968) (xy 138.270619 -233.832436) (xy 138.293309 -233.787904) (xy 138.322685 -233.747471)
			(xy 138.358025 -233.712131) (xy 138.398458 -233.682755) (xy 138.44299 -233.660065) (xy 138.490522 -233.644621)
			(xy 138.539885 -233.636802) (xy 138.589863 -233.636802) (xy 138.639226 -233.644621) (xy 138.686758 -233.660065)
			(xy 138.73129 -233.682755) (xy 138.771723 -233.712131) (xy 138.807063 -233.747471) (xy 138.836439 -233.787904)
			(xy 138.859129 -233.832436) (xy 138.874573 -233.879968) (xy 138.882392 -233.929331) (xy 138.882882 -233.95432)
			(xy 139.188439 -233.95432) (xy 139.192534 -233.903592) (xy 139.204713 -233.854178) (xy 139.224661 -233.807358)
			(xy 139.251862 -233.764344) (xy 139.28561 -233.72625) (xy 139.325032 -233.694063) (xy 139.369106 -233.668617)
			(xy 139.416692 -233.65057) (xy 139.466556 -233.64039) (xy 139.517408 -233.638341) (xy 139.567929 -233.644475)
			(xy 139.616813 -233.658635) (xy 139.662792 -233.680452) (xy 139.704676 -233.709362) (xy 139.74138 -233.744617)
			(xy 139.771953 -233.785303) (xy 139.795604 -233.830366) (xy 139.81172 -233.87864) (xy 139.819884 -233.928874)
			(xy 139.820396 -233.95432) (xy 139.819893 -233.979309) (xy 140.12721 -233.979309) (xy 140.12721 -233.929331)
			(xy 140.135029 -233.879968) (xy 140.150473 -233.832436) (xy 140.173163 -233.787904) (xy 140.202539 -233.747471)
			(xy 140.237879 -233.712131) (xy 140.278312 -233.682755) (xy 140.322844 -233.660065) (xy 140.370376 -233.644621)
			(xy 140.419739 -233.636802) (xy 140.469717 -233.636802) (xy 140.51908 -233.644621) (xy 140.566612 -233.660065)
			(xy 140.611144 -233.682755) (xy 140.651577 -233.712131) (xy 140.686917 -233.747471) (xy 140.716293 -233.787904)
			(xy 140.738983 -233.832436) (xy 140.754427 -233.879968) (xy 140.762246 -233.929331) (xy 140.762736 -233.95432)
			(xy 141.068547 -233.95432) (xy 141.072642 -233.903592) (xy 141.084821 -233.854178) (xy 141.104769 -233.807358)
			(xy 141.13197 -233.764344) (xy 141.165718 -233.72625) (xy 141.20514 -233.694063) (xy 141.249214 -233.668617)
			(xy 141.2968 -233.65057) (xy 141.346664 -233.64039) (xy 141.397516 -233.638341) (xy 141.448037 -233.644475)
			(xy 141.496921 -233.658635) (xy 141.5429 -233.680452) (xy 141.584784 -233.709362) (xy 141.621488 -233.744617)
			(xy 141.652061 -233.785303) (xy 141.675712 -233.830366) (xy 141.691828 -233.87864) (xy 141.699992 -233.928874)
			(xy 141.700504 -233.95432) (xy 142.008601 -233.95432) (xy 142.012696 -233.903592) (xy 142.024875 -233.854178)
			(xy 142.044823 -233.807358) (xy 142.072024 -233.764344) (xy 142.105772 -233.72625) (xy 142.145194 -233.694063)
			(xy 142.189268 -233.668617) (xy 142.236854 -233.65057) (xy 142.286718 -233.64039) (xy 142.33757 -233.638341)
			(xy 142.388091 -233.644475) (xy 142.436975 -233.658635) (xy 142.482954 -233.680452) (xy 142.524838 -233.709362)
			(xy 142.561542 -233.744617) (xy 142.592115 -233.785303) (xy 142.615766 -233.830366) (xy 142.631882 -233.87864)
			(xy 142.640046 -233.928874) (xy 142.640558 -233.95432) (xy 142.640055 -233.979309) (xy 142.947118 -233.979309)
			(xy 142.947118 -233.929331) (xy 142.954937 -233.879968) (xy 142.970381 -233.832436) (xy 142.993071 -233.787904)
			(xy 143.022447 -233.747471) (xy 143.057787 -233.712131) (xy 143.09822 -233.682755) (xy 143.142752 -233.660065)
			(xy 143.190284 -233.644621) (xy 143.239647 -233.636802) (xy 143.289625 -233.636802) (xy 143.338988 -233.644621)
			(xy 143.38652 -233.660065) (xy 143.431052 -233.682755) (xy 143.471485 -233.712131) (xy 143.506825 -233.747471)
			(xy 143.536201 -233.787904) (xy 143.558891 -233.832436) (xy 143.574335 -233.879968) (xy 143.582154 -233.929331)
			(xy 143.582644 -233.95432) (xy 143.582154 -233.979309) (xy 143.574335 -234.028672) (xy 143.558891 -234.076204)
			(xy 143.536201 -234.120736) (xy 143.506825 -234.161169) (xy 143.471485 -234.196509) (xy 143.431052 -234.225885)
			(xy 143.38652 -234.248575) (xy 143.338988 -234.264019) (xy 143.289625 -234.271838) (xy 143.239647 -234.271838)
			(xy 143.190284 -234.264019) (xy 143.142752 -234.248575) (xy 143.09822 -234.225885) (xy 143.057787 -234.196509)
			(xy 143.022447 -234.161169) (xy 142.993071 -234.120736) (xy 142.970381 -234.076204) (xy 142.954937 -234.028672)
			(xy 142.947118 -233.979309) (xy 142.640055 -233.979309) (xy 142.640046 -233.979766) (xy 142.631882 -234.03)
			(xy 142.615766 -234.078274) (xy 142.592115 -234.123337) (xy 142.561542 -234.164023) (xy 142.524838 -234.199278)
			(xy 142.482954 -234.228188) (xy 142.436975 -234.250005) (xy 142.388091 -234.264165) (xy 142.33757 -234.270299)
			(xy 142.286718 -234.26825) (xy 142.236854 -234.25807) (xy 142.189268 -234.240023) (xy 142.145194 -234.214577)
			(xy 142.105772 -234.18239) (xy 142.072024 -234.144296) (xy 142.044823 -234.101282) (xy 142.024875 -234.054462)
			(xy 142.012696 -234.005048) (xy 142.008601 -233.95432) (xy 141.700504 -233.95432) (xy 141.699992 -233.979766)
			(xy 141.691828 -234.03) (xy 141.675712 -234.078274) (xy 141.652061 -234.123337) (xy 141.621488 -234.164023)
			(xy 141.584784 -234.199278) (xy 141.5429 -234.228188) (xy 141.496921 -234.250005) (xy 141.448037 -234.264165)
			(xy 141.397516 -234.270299) (xy 141.346664 -234.26825) (xy 141.2968 -234.25807) (xy 141.249214 -234.240023)
			(xy 141.20514 -234.214577) (xy 141.165718 -234.18239) (xy 141.13197 -234.144296) (xy 141.104769 -234.101282)
			(xy 141.084821 -234.054462) (xy 141.072642 -234.005048) (xy 141.068547 -233.95432) (xy 140.762736 -233.95432)
			(xy 140.762246 -233.979309) (xy 140.754427 -234.028672) (xy 140.738983 -234.076204) (xy 140.716293 -234.120736)
			(xy 140.686917 -234.161169) (xy 140.651577 -234.196509) (xy 140.611144 -234.225885) (xy 140.566612 -234.248575)
			(xy 140.51908 -234.264019) (xy 140.469717 -234.271838) (xy 140.419739 -234.271838) (xy 140.370376 -234.264019)
			(xy 140.322844 -234.248575) (xy 140.278312 -234.225885) (xy 140.237879 -234.196509) (xy 140.202539 -234.161169)
			(xy 140.173163 -234.120736) (xy 140.150473 -234.076204) (xy 140.135029 -234.028672) (xy 140.12721 -233.979309)
			(xy 139.819893 -233.979309) (xy 139.819884 -233.979766) (xy 139.81172 -234.03) (xy 139.795604 -234.078274)
			(xy 139.771953 -234.123337) (xy 139.74138 -234.164023) (xy 139.704676 -234.199278) (xy 139.662792 -234.228188)
			(xy 139.616813 -234.250005) (xy 139.567929 -234.264165) (xy 139.517408 -234.270299) (xy 139.466556 -234.26825)
			(xy 139.416692 -234.25807) (xy 139.369106 -234.240023) (xy 139.325032 -234.214577) (xy 139.28561 -234.18239)
			(xy 139.251862 -234.144296) (xy 139.224661 -234.101282) (xy 139.204713 -234.054462) (xy 139.192534 -234.005048)
			(xy 139.188439 -233.95432) (xy 138.882882 -233.95432) (xy 138.882392 -233.979309) (xy 138.874573 -234.028672)
			(xy 138.859129 -234.076204) (xy 138.836439 -234.120736) (xy 138.807063 -234.161169) (xy 138.771723 -234.196509)
			(xy 138.73129 -234.225885) (xy 138.686758 -234.248575) (xy 138.639226 -234.264019) (xy 138.589863 -234.271838)
			(xy 138.539885 -234.271838) (xy 138.490522 -234.264019) (xy 138.44299 -234.248575) (xy 138.398458 -234.225885)
			(xy 138.358025 -234.196509) (xy 138.322685 -234.161169) (xy 138.293309 -234.120736) (xy 138.270619 -234.076204)
			(xy 138.255175 -234.028672) (xy 138.247356 -233.979309) (xy 137.940039 -233.979309) (xy 137.94003 -233.979766)
			(xy 137.931866 -234.03) (xy 137.91575 -234.078274) (xy 137.892099 -234.123337) (xy 137.861526 -234.164023)
			(xy 137.824822 -234.199278) (xy 137.782938 -234.228188) (xy 137.736959 -234.250005) (xy 137.688075 -234.264165)
			(xy 137.637554 -234.270299) (xy 137.586702 -234.26825) (xy 137.536838 -234.25807) (xy 137.489252 -234.240023)
			(xy 137.445178 -234.214577) (xy 137.405756 -234.18239) (xy 137.372008 -234.144296) (xy 137.344807 -234.101282)
			(xy 137.324859 -234.054462) (xy 137.31268 -234.005048) (xy 137.308585 -233.95432) (xy 137.002774 -233.95432)
			(xy 137.002284 -233.979309) (xy 136.994465 -234.028672) (xy 136.979021 -234.076204) (xy 136.956331 -234.120736)
			(xy 136.926955 -234.161169) (xy 136.891615 -234.196509) (xy 136.851182 -234.225885) (xy 136.80665 -234.248575)
			(xy 136.759118 -234.264019) (xy 136.709755 -234.271838) (xy 136.659777 -234.271838) (xy 136.610414 -234.264019)
			(xy 136.562882 -234.248575) (xy 136.51835 -234.225885) (xy 136.477917 -234.196509) (xy 136.442577 -234.161169)
			(xy 136.413201 -234.120736) (xy 136.390511 -234.076204) (xy 136.375067 -234.028672) (xy 136.367248 -233.979309)
			(xy 136.059931 -233.979309) (xy 136.059922 -233.979766) (xy 136.051758 -234.03) (xy 136.035642 -234.078274)
			(xy 136.011991 -234.123337) (xy 135.981418 -234.164023) (xy 135.944714 -234.199278) (xy 135.90283 -234.228188)
			(xy 135.856851 -234.250005) (xy 135.807967 -234.264165) (xy 135.757446 -234.270299) (xy 135.706594 -234.26825)
			(xy 135.65673 -234.25807) (xy 135.609144 -234.240023) (xy 135.56507 -234.214577) (xy 135.525648 -234.18239)
			(xy 135.4919 -234.144296) (xy 135.464699 -234.101282) (xy 135.444751 -234.054462) (xy 135.432572 -234.005048)
			(xy 135.428477 -233.95432) (xy 135.12038 -233.95432) (xy 135.119868 -233.979766) (xy 135.111704 -234.03)
			(xy 135.095588 -234.078274) (xy 135.071937 -234.123337) (xy 135.041364 -234.164023) (xy 135.00466 -234.199278)
			(xy 134.962776 -234.228188) (xy 134.916797 -234.250005) (xy 134.867913 -234.264165) (xy 134.817392 -234.270299)
			(xy 134.76654 -234.26825) (xy 134.716676 -234.25807) (xy 134.66909 -234.240023) (xy 134.625016 -234.214577)
			(xy 134.585594 -234.18239) (xy 134.551846 -234.144296) (xy 134.524645 -234.101282) (xy 134.504697 -234.054462)
			(xy 134.492518 -234.005048) (xy 134.488423 -233.95432) (xy 134.182866 -233.95432) (xy 134.182376 -233.979309)
			(xy 134.174557 -234.028672) (xy 134.159113 -234.076204) (xy 134.136423 -234.120736) (xy 134.107047 -234.161169)
			(xy 134.071707 -234.196509) (xy 134.031274 -234.225885) (xy 133.986742 -234.248575) (xy 133.93921 -234.264019)
			(xy 133.889847 -234.271838) (xy 133.839869 -234.271838) (xy 133.790506 -234.264019) (xy 133.742974 -234.248575)
			(xy 133.698442 -234.225885) (xy 133.658009 -234.196509) (xy 133.622669 -234.161169) (xy 133.593293 -234.120736)
			(xy 133.570603 -234.076204) (xy 133.555159 -234.028672) (xy 133.54734 -233.979309) (xy 133.240023 -233.979309)
			(xy 133.240014 -233.979766) (xy 133.23185 -234.03) (xy 133.215734 -234.078274) (xy 133.192083 -234.123337)
			(xy 133.16151 -234.164023) (xy 133.124806 -234.199278) (xy 133.082922 -234.228188) (xy 133.036943 -234.250005)
			(xy 132.988059 -234.264165) (xy 132.937538 -234.270299) (xy 132.886686 -234.26825) (xy 132.836822 -234.25807)
			(xy 132.789236 -234.240023) (xy 132.745162 -234.214577) (xy 132.70574 -234.18239) (xy 132.671992 -234.144296)
			(xy 132.644791 -234.101282) (xy 132.624843 -234.054462) (xy 132.612664 -234.005048) (xy 132.608569 -233.95432)
			(xy 132.302758 -233.95432) (xy 132.302268 -233.979309) (xy 132.294449 -234.028672) (xy 132.279005 -234.076204)
			(xy 132.256315 -234.120736) (xy 132.226939 -234.161169) (xy 132.191599 -234.196509) (xy 132.151166 -234.225885)
			(xy 132.106634 -234.248575) (xy 132.059102 -234.264019) (xy 132.009739 -234.271838) (xy 131.959761 -234.271838)
			(xy 131.910398 -234.264019) (xy 131.862866 -234.248575) (xy 131.818334 -234.225885) (xy 131.777901 -234.196509)
			(xy 131.742561 -234.161169) (xy 131.713185 -234.120736) (xy 131.690495 -234.076204) (xy 131.675051 -234.028672)
			(xy 131.667232 -233.979309) (xy 131.359915 -233.979309) (xy 131.359906 -233.979766) (xy 131.351742 -234.03)
			(xy 131.335626 -234.078274) (xy 131.311975 -234.123337) (xy 131.281402 -234.164023) (xy 131.244698 -234.199278)
			(xy 131.202814 -234.228188) (xy 131.156835 -234.250005) (xy 131.107951 -234.264165) (xy 131.05743 -234.270299)
			(xy 131.006578 -234.26825) (xy 130.956714 -234.25807) (xy 130.909128 -234.240023) (xy 130.865054 -234.214577)
			(xy 130.825632 -234.18239) (xy 130.791884 -234.144296) (xy 130.764683 -234.101282) (xy 130.744735 -234.054462)
			(xy 130.732556 -234.005048) (xy 130.728461 -233.95432) (xy 130.42265 -233.95432) (xy 130.42216 -233.979309)
			(xy 130.414341 -234.028672) (xy 130.398897 -234.076204) (xy 130.376207 -234.120736) (xy 130.346831 -234.161169)
			(xy 130.311491 -234.196509) (xy 130.271058 -234.225885) (xy 130.226526 -234.248575) (xy 130.178994 -234.264019)
			(xy 130.129631 -234.271838) (xy 130.079653 -234.271838) (xy 130.03029 -234.264019) (xy 129.982758 -234.248575)
			(xy 129.938226 -234.225885) (xy 129.897793 -234.196509) (xy 129.862453 -234.161169) (xy 129.833077 -234.120736)
			(xy 129.810387 -234.076204) (xy 129.794943 -234.028672) (xy 129.787124 -233.979309) (xy 129.480061 -233.979309)
			(xy 129.480052 -233.979766) (xy 129.471888 -234.03) (xy 129.455772 -234.078274) (xy 129.432121 -234.123337)
			(xy 129.401548 -234.164023) (xy 129.364844 -234.199278) (xy 129.32296 -234.228188) (xy 129.276981 -234.250005)
			(xy 129.228097 -234.264165) (xy 129.177576 -234.270299) (xy 129.126724 -234.26825) (xy 129.07686 -234.25807)
			(xy 129.029274 -234.240023) (xy 128.9852 -234.214577) (xy 128.945778 -234.18239) (xy 128.91203 -234.144296)
			(xy 128.884829 -234.101282) (xy 128.864881 -234.054462) (xy 128.852702 -234.005048) (xy 128.848607 -233.95432)
			(xy 128.54051 -233.95432) (xy 128.539998 -233.979766) (xy 128.531834 -234.03) (xy 128.515718 -234.078274)
			(xy 128.492067 -234.123337) (xy 128.461494 -234.164023) (xy 128.42479 -234.199278) (xy 128.382906 -234.228188)
			(xy 128.336927 -234.250005) (xy 128.288043 -234.264165) (xy 128.237522 -234.270299) (xy 128.18667 -234.26825)
			(xy 128.136806 -234.25807) (xy 128.08922 -234.240023) (xy 128.045146 -234.214577) (xy 128.005724 -234.18239)
			(xy 127.971976 -234.144296) (xy 127.944775 -234.101282) (xy 127.924827 -234.054462) (xy 127.912648 -234.005048)
			(xy 127.908553 -233.95432) (xy 127.602742 -233.95432) (xy 127.602252 -233.979309) (xy 127.594433 -234.028672)
			(xy 127.578989 -234.076204) (xy 127.556299 -234.120736) (xy 127.526923 -234.161169) (xy 127.491583 -234.196509)
			(xy 127.45115 -234.225885) (xy 127.406618 -234.248575) (xy 127.359086 -234.264019) (xy 127.309723 -234.271838)
			(xy 127.259745 -234.271838) (xy 127.210382 -234.264019) (xy 127.16285 -234.248575) (xy 127.118318 -234.225885)
			(xy 127.077885 -234.196509) (xy 127.042545 -234.161169) (xy 127.013169 -234.120736) (xy 126.990479 -234.076204)
			(xy 126.975035 -234.028672) (xy 126.967216 -233.979309) (xy 126.661994 -233.979309) (xy 126.656256 -234.020694)
			(xy 126.650496 -234.042204) (xy 126.648464 -234.049062) (xy 126.648464 -234.351322) (xy 126.648464 -234.35437)
			(xy 126.649416 -234.36382) (xy 126.65738 -234.381047) (xy 126.663958 -234.387898) (xy 126.72441 -234.439206)
			(xy 126.728649 -234.442627) (xy 126.738257 -234.447755) (xy 126.74346 -234.449366) (xy 126.75362 -234.45216)
			(xy 126.764542 -234.450382) (xy 126.777028 -234.448482) (xy 126.802205 -234.446445) (xy 126.814834 -234.446318)
			(xy 126.839819 -234.446811) (xy 126.889174 -234.454633) (xy 126.936698 -234.470079) (xy 126.981221 -234.492768)
			(xy 127.021646 -234.522143) (xy 127.056979 -234.55748) (xy 127.08635 -234.597908) (xy 127.109034 -234.642433)
			(xy 127.124475 -234.689959) (xy 127.132292 -234.739315) (xy 127.132292 -234.764326) (xy 127.438399 -234.764326)
			(xy 127.442494 -234.713598) (xy 127.454673 -234.664184) (xy 127.474621 -234.617364) (xy 127.501822 -234.57435)
			(xy 127.53557 -234.536256) (xy 127.574992 -234.504069) (xy 127.619066 -234.478623) (xy 127.666652 -234.460576)
			(xy 127.716516 -234.450396) (xy 127.767368 -234.448347) (xy 127.817889 -234.454481) (xy 127.866773 -234.468641)
			(xy 127.912752 -234.490458) (xy 127.954636 -234.519368) (xy 127.99134 -234.554623) (xy 128.021913 -234.595309)
			(xy 128.045564 -234.640372) (xy 128.06168 -234.688646) (xy 128.069844 -234.73888) (xy 128.070356 -234.764326)
			(xy 128.069853 -234.789315) (xy 128.37717 -234.789315) (xy 128.37717 -234.739337) (xy 128.384989 -234.689974)
			(xy 128.400433 -234.642442) (xy 128.423123 -234.59791) (xy 128.452499 -234.557477) (xy 128.487839 -234.522137)
			(xy 128.528272 -234.492761) (xy 128.572804 -234.470071) (xy 128.620336 -234.454627) (xy 128.669699 -234.446808)
			(xy 128.719677 -234.446808) (xy 128.76904 -234.454627) (xy 128.816572 -234.470071) (xy 128.861104 -234.492761)
			(xy 128.901537 -234.522137) (xy 128.936877 -234.557477) (xy 128.966253 -234.59791) (xy 128.988943 -234.642442)
			(xy 129.004387 -234.689974) (xy 129.012206 -234.739337) (xy 129.012696 -234.764326) (xy 129.318507 -234.764326)
			(xy 129.322602 -234.713598) (xy 129.334781 -234.664184) (xy 129.354729 -234.617364) (xy 129.38193 -234.57435)
			(xy 129.415678 -234.536256) (xy 129.4551 -234.504069) (xy 129.499174 -234.478623) (xy 129.54676 -234.460576)
			(xy 129.596624 -234.450396) (xy 129.647476 -234.448347) (xy 129.697997 -234.454481) (xy 129.746881 -234.468641)
			(xy 129.79286 -234.490458) (xy 129.834744 -234.519368) (xy 129.871448 -234.554623) (xy 129.902021 -234.595309)
			(xy 129.925672 -234.640372) (xy 129.941788 -234.688646) (xy 129.949952 -234.73888) (xy 129.950464 -234.764326)
			(xy 131.198615 -234.764326) (xy 131.20271 -234.713598) (xy 131.214889 -234.664184) (xy 131.234837 -234.617364)
			(xy 131.262038 -234.57435) (xy 131.295786 -234.536256) (xy 131.335208 -234.504069) (xy 131.379282 -234.478623)
			(xy 131.426868 -234.460576) (xy 131.476732 -234.450396) (xy 131.527584 -234.448347) (xy 131.578105 -234.454481)
			(xy 131.626989 -234.468641) (xy 131.672968 -234.490458) (xy 131.714852 -234.519368) (xy 131.751556 -234.554623)
			(xy 131.782129 -234.595309) (xy 131.80578 -234.640372) (xy 131.821896 -234.688646) (xy 131.83006 -234.73888)
			(xy 131.830572 -234.764326) (xy 132.138415 -234.764326) (xy 132.14251 -234.713598) (xy 132.154689 -234.664184)
			(xy 132.174637 -234.617364) (xy 132.201838 -234.57435) (xy 132.235586 -234.536256) (xy 132.275008 -234.504069)
			(xy 132.319082 -234.478623) (xy 132.366668 -234.460576) (xy 132.416532 -234.450396) (xy 132.467384 -234.448347)
			(xy 132.517905 -234.454481) (xy 132.566789 -234.468641) (xy 132.612768 -234.490458) (xy 132.654652 -234.519368)
			(xy 132.691356 -234.554623) (xy 132.721929 -234.595309) (xy 132.74558 -234.640372) (xy 132.761696 -234.688646)
			(xy 132.76986 -234.73888) (xy 132.770372 -234.764326) (xy 132.769869 -234.789315) (xy 133.077186 -234.789315)
			(xy 133.077186 -234.739337) (xy 133.085005 -234.689974) (xy 133.100449 -234.642442) (xy 133.123139 -234.59791)
			(xy 133.152515 -234.557477) (xy 133.187855 -234.522137) (xy 133.228288 -234.492761) (xy 133.27282 -234.470071)
			(xy 133.320352 -234.454627) (xy 133.369715 -234.446808) (xy 133.419693 -234.446808) (xy 133.469056 -234.454627)
			(xy 133.516588 -234.470071) (xy 133.56112 -234.492761) (xy 133.601553 -234.522137) (xy 133.636893 -234.557477)
			(xy 133.666269 -234.59791) (xy 133.688959 -234.642442) (xy 133.704403 -234.689974) (xy 133.712222 -234.739337)
			(xy 133.712712 -234.764326) (xy 134.018523 -234.764326) (xy 134.022618 -234.713598) (xy 134.034797 -234.664184)
			(xy 134.054745 -234.617364) (xy 134.081946 -234.57435) (xy 134.115694 -234.536256) (xy 134.155116 -234.504069)
			(xy 134.19919 -234.478623) (xy 134.246776 -234.460576) (xy 134.29664 -234.450396) (xy 134.347492 -234.448347)
			(xy 134.398013 -234.454481) (xy 134.446897 -234.468641) (xy 134.492876 -234.490458) (xy 134.53476 -234.519368)
			(xy 134.571464 -234.554623) (xy 134.602037 -234.595309) (xy 134.625688 -234.640372) (xy 134.641804 -234.688646)
			(xy 134.649968 -234.73888) (xy 134.65048 -234.764326) (xy 134.649977 -234.789315) (xy 134.957294 -234.789315)
			(xy 134.957294 -234.739337) (xy 134.965113 -234.689974) (xy 134.980557 -234.642442) (xy 135.003247 -234.59791)
			(xy 135.032623 -234.557477) (xy 135.067963 -234.522137) (xy 135.108396 -234.492761) (xy 135.152928 -234.470071)
			(xy 135.20046 -234.454627) (xy 135.249823 -234.446808) (xy 135.299801 -234.446808) (xy 135.349164 -234.454627)
			(xy 135.396696 -234.470071) (xy 135.441228 -234.492761) (xy 135.481661 -234.522137) (xy 135.517001 -234.557477)
			(xy 135.546377 -234.59791) (xy 135.569067 -234.642442) (xy 135.584511 -234.689974) (xy 135.59233 -234.739337)
			(xy 135.59282 -234.764326) (xy 135.898631 -234.764326) (xy 135.902726 -234.713598) (xy 135.914905 -234.664184)
			(xy 135.934853 -234.617364) (xy 135.962054 -234.57435) (xy 135.995802 -234.536256) (xy 136.035224 -234.504069)
			(xy 136.079298 -234.478623) (xy 136.126884 -234.460576) (xy 136.176748 -234.450396) (xy 136.2276 -234.448347)
			(xy 136.278121 -234.454481) (xy 136.327005 -234.468641) (xy 136.372984 -234.490458) (xy 136.414868 -234.519368)
			(xy 136.451572 -234.554623) (xy 136.482145 -234.595309) (xy 136.505796 -234.640372) (xy 136.521912 -234.688646)
			(xy 136.530076 -234.73888) (xy 136.530588 -234.764326) (xy 137.778485 -234.764326) (xy 137.78258 -234.713598)
			(xy 137.794759 -234.664184) (xy 137.814707 -234.617364) (xy 137.841908 -234.57435) (xy 137.875656 -234.536256)
			(xy 137.915078 -234.504069) (xy 137.959152 -234.478623) (xy 138.006738 -234.460576) (xy 138.056602 -234.450396)
			(xy 138.107454 -234.448347) (xy 138.157975 -234.454481) (xy 138.206859 -234.468641) (xy 138.252838 -234.490458)
			(xy 138.294722 -234.519368) (xy 138.331426 -234.554623) (xy 138.361999 -234.595309) (xy 138.38565 -234.640372)
			(xy 138.401766 -234.688646) (xy 138.40993 -234.73888) (xy 138.410442 -234.764326) (xy 138.718539 -234.764326)
			(xy 138.722634 -234.713598) (xy 138.734813 -234.664184) (xy 138.754761 -234.617364) (xy 138.781962 -234.57435)
			(xy 138.81571 -234.536256) (xy 138.855132 -234.504069) (xy 138.899206 -234.478623) (xy 138.946792 -234.460576)
			(xy 138.996656 -234.450396) (xy 139.047508 -234.448347) (xy 139.098029 -234.454481) (xy 139.146913 -234.468641)
			(xy 139.192892 -234.490458) (xy 139.234776 -234.519368) (xy 139.27148 -234.554623) (xy 139.302053 -234.595309)
			(xy 139.325704 -234.640372) (xy 139.34182 -234.688646) (xy 139.349984 -234.73888) (xy 139.350496 -234.764326)
			(xy 139.349993 -234.789315) (xy 139.65731 -234.789315) (xy 139.65731 -234.739337) (xy 139.665129 -234.689974)
			(xy 139.680573 -234.642442) (xy 139.703263 -234.59791) (xy 139.732639 -234.557477) (xy 139.767979 -234.522137)
			(xy 139.808412 -234.492761) (xy 139.852944 -234.470071) (xy 139.900476 -234.454627) (xy 139.949839 -234.446808)
			(xy 139.999817 -234.446808) (xy 140.04918 -234.454627) (xy 140.096712 -234.470071) (xy 140.141244 -234.492761)
			(xy 140.181677 -234.522137) (xy 140.217017 -234.557477) (xy 140.246393 -234.59791) (xy 140.269083 -234.642442)
			(xy 140.284527 -234.689974) (xy 140.292346 -234.739337) (xy 140.292836 -234.764326) (xy 140.598647 -234.764326)
			(xy 140.602742 -234.713598) (xy 140.614921 -234.664184) (xy 140.634869 -234.617364) (xy 140.66207 -234.57435)
			(xy 140.695818 -234.536256) (xy 140.73524 -234.504069) (xy 140.779314 -234.478623) (xy 140.8269 -234.460576)
			(xy 140.876764 -234.450396) (xy 140.927616 -234.448347) (xy 140.978137 -234.454481) (xy 141.027021 -234.468641)
			(xy 141.073 -234.490458) (xy 141.114884 -234.519368) (xy 141.151588 -234.554623) (xy 141.182161 -234.595309)
			(xy 141.205812 -234.640372) (xy 141.221928 -234.688646) (xy 141.230092 -234.73888) (xy 141.230604 -234.764326)
			(xy 141.230101 -234.789315) (xy 141.537164 -234.789315) (xy 141.537164 -234.739337) (xy 141.544983 -234.689974)
			(xy 141.560427 -234.642442) (xy 141.583117 -234.59791) (xy 141.612493 -234.557477) (xy 141.647833 -234.522137)
			(xy 141.688266 -234.492761) (xy 141.732798 -234.470071) (xy 141.78033 -234.454627) (xy 141.829693 -234.446808)
			(xy 141.879671 -234.446808) (xy 141.929034 -234.454627) (xy 141.976566 -234.470071) (xy 142.021098 -234.492761)
			(xy 142.061531 -234.522137) (xy 142.096871 -234.557477) (xy 142.126247 -234.59791) (xy 142.148937 -234.642442)
			(xy 142.164381 -234.689974) (xy 142.1722 -234.739337) (xy 142.17269 -234.764326) (xy 142.478501 -234.764326)
			(xy 142.482596 -234.713598) (xy 142.494775 -234.664184) (xy 142.514723 -234.617364) (xy 142.541924 -234.57435)
			(xy 142.575672 -234.536256) (xy 142.615094 -234.504069) (xy 142.659168 -234.478623) (xy 142.706754 -234.460576)
			(xy 142.756618 -234.450396) (xy 142.80747 -234.448347) (xy 142.857991 -234.454481) (xy 142.906875 -234.468641)
			(xy 142.952854 -234.490458) (xy 142.994738 -234.519368) (xy 143.031442 -234.554623) (xy 143.062015 -234.595309)
			(xy 143.085666 -234.640372) (xy 143.101782 -234.688646) (xy 143.109946 -234.73888) (xy 143.110458 -234.764326)
			(xy 143.109946 -234.789772) (xy 143.101782 -234.840006) (xy 143.085666 -234.88828) (xy 143.062015 -234.933343)
			(xy 143.031442 -234.974029) (xy 142.994738 -235.009284) (xy 142.952854 -235.038194) (xy 142.906875 -235.060011)
			(xy 142.857991 -235.074171) (xy 142.80747 -235.080305) (xy 142.756618 -235.078256) (xy 142.706754 -235.068076)
			(xy 142.659168 -235.050029) (xy 142.615094 -235.024583) (xy 142.575672 -234.992396) (xy 142.541924 -234.954302)
			(xy 142.514723 -234.911288) (xy 142.494775 -234.864468) (xy 142.482596 -234.815054) (xy 142.478501 -234.764326)
			(xy 142.17269 -234.764326) (xy 142.1722 -234.789315) (xy 142.164381 -234.838678) (xy 142.148937 -234.88621)
			(xy 142.126247 -234.930742) (xy 142.096871 -234.971175) (xy 142.061531 -235.006515) (xy 142.021098 -235.035891)
			(xy 141.976566 -235.058581) (xy 141.929034 -235.074025) (xy 141.879671 -235.081844) (xy 141.829693 -235.081844)
			(xy 141.78033 -235.074025) (xy 141.732798 -235.058581) (xy 141.688266 -235.035891) (xy 141.647833 -235.006515)
			(xy 141.612493 -234.971175) (xy 141.583117 -234.930742) (xy 141.560427 -234.88621) (xy 141.544983 -234.838678)
			(xy 141.537164 -234.789315) (xy 141.230101 -234.789315) (xy 141.230092 -234.789772) (xy 141.221928 -234.840006)
			(xy 141.205812 -234.88828) (xy 141.182161 -234.933343) (xy 141.151588 -234.974029) (xy 141.114884 -235.009284)
			(xy 141.073 -235.038194) (xy 141.027021 -235.060011) (xy 140.978137 -235.074171) (xy 140.927616 -235.080305)
			(xy 140.876764 -235.078256) (xy 140.8269 -235.068076) (xy 140.779314 -235.050029) (xy 140.73524 -235.024583)
			(xy 140.695818 -234.992396) (xy 140.66207 -234.954302) (xy 140.634869 -234.911288) (xy 140.614921 -234.864468)
			(xy 140.602742 -234.815054) (xy 140.598647 -234.764326) (xy 140.292836 -234.764326) (xy 140.292346 -234.789315)
			(xy 140.284527 -234.838678) (xy 140.269083 -234.88621) (xy 140.246393 -234.930742) (xy 140.217017 -234.971175)
			(xy 140.181677 -235.006515) (xy 140.141244 -235.035891) (xy 140.096712 -235.058581) (xy 140.04918 -235.074025)
			(xy 139.999817 -235.081844) (xy 139.949839 -235.081844) (xy 139.900476 -235.074025) (xy 139.852944 -235.058581)
			(xy 139.808412 -235.035891) (xy 139.767979 -235.006515) (xy 139.732639 -234.971175) (xy 139.703263 -234.930742)
			(xy 139.680573 -234.88621) (xy 139.665129 -234.838678) (xy 139.65731 -234.789315) (xy 139.349993 -234.789315)
			(xy 139.349984 -234.789772) (xy 139.34182 -234.840006) (xy 139.325704 -234.88828) (xy 139.302053 -234.933343)
			(xy 139.27148 -234.974029) (xy 139.234776 -235.009284) (xy 139.192892 -235.038194) (xy 139.146913 -235.060011)
			(xy 139.098029 -235.074171) (xy 139.047508 -235.080305) (xy 138.996656 -235.078256) (xy 138.946792 -235.068076)
			(xy 138.899206 -235.050029) (xy 138.855132 -235.024583) (xy 138.81571 -234.992396) (xy 138.781962 -234.954302)
			(xy 138.754761 -234.911288) (xy 138.734813 -234.864468) (xy 138.722634 -234.815054) (xy 138.718539 -234.764326)
			(xy 138.410442 -234.764326) (xy 138.40993 -234.789772) (xy 138.401766 -234.840006) (xy 138.38565 -234.88828)
			(xy 138.361999 -234.933343) (xy 138.331426 -234.974029) (xy 138.294722 -235.009284) (xy 138.252838 -235.038194)
			(xy 138.206859 -235.060011) (xy 138.157975 -235.074171) (xy 138.107454 -235.080305) (xy 138.056602 -235.078256)
			(xy 138.006738 -235.068076) (xy 137.959152 -235.050029) (xy 137.915078 -235.024583) (xy 137.875656 -234.992396)
			(xy 137.841908 -234.954302) (xy 137.814707 -234.911288) (xy 137.794759 -234.864468) (xy 137.78258 -234.815054)
			(xy 137.778485 -234.764326) (xy 136.530588 -234.764326) (xy 136.530076 -234.789772) (xy 136.521912 -234.840006)
			(xy 136.505796 -234.88828) (xy 136.482145 -234.933343) (xy 136.451572 -234.974029) (xy 136.414868 -235.009284)
			(xy 136.372984 -235.038194) (xy 136.327005 -235.060011) (xy 136.278121 -235.074171) (xy 136.2276 -235.080305)
			(xy 136.176748 -235.078256) (xy 136.126884 -235.068076) (xy 136.079298 -235.050029) (xy 136.035224 -235.024583)
			(xy 135.995802 -234.992396) (xy 135.962054 -234.954302) (xy 135.934853 -234.911288) (xy 135.914905 -234.864468)
			(xy 135.902726 -234.815054) (xy 135.898631 -234.764326) (xy 135.59282 -234.764326) (xy 135.59233 -234.789315)
			(xy 135.584511 -234.838678) (xy 135.569067 -234.88621) (xy 135.546377 -234.930742) (xy 135.517001 -234.971175)
			(xy 135.481661 -235.006515) (xy 135.441228 -235.035891) (xy 135.396696 -235.058581) (xy 135.349164 -235.074025)
			(xy 135.299801 -235.081844) (xy 135.249823 -235.081844) (xy 135.20046 -235.074025) (xy 135.152928 -235.058581)
			(xy 135.108396 -235.035891) (xy 135.067963 -235.006515) (xy 135.032623 -234.971175) (xy 135.003247 -234.930742)
			(xy 134.980557 -234.88621) (xy 134.965113 -234.838678) (xy 134.957294 -234.789315) (xy 134.649977 -234.789315)
			(xy 134.649968 -234.789772) (xy 134.641804 -234.840006) (xy 134.625688 -234.88828) (xy 134.602037 -234.933343)
			(xy 134.571464 -234.974029) (xy 134.53476 -235.009284) (xy 134.492876 -235.038194) (xy 134.446897 -235.060011)
			(xy 134.398013 -235.074171) (xy 134.347492 -235.080305) (xy 134.29664 -235.078256) (xy 134.246776 -235.068076)
			(xy 134.19919 -235.050029) (xy 134.155116 -235.024583) (xy 134.115694 -234.992396) (xy 134.081946 -234.954302)
			(xy 134.054745 -234.911288) (xy 134.034797 -234.864468) (xy 134.022618 -234.815054) (xy 134.018523 -234.764326)
			(xy 133.712712 -234.764326) (xy 133.712222 -234.789315) (xy 133.704403 -234.838678) (xy 133.688959 -234.88621)
			(xy 133.666269 -234.930742) (xy 133.636893 -234.971175) (xy 133.601553 -235.006515) (xy 133.56112 -235.035891)
			(xy 133.516588 -235.058581) (xy 133.469056 -235.074025) (xy 133.419693 -235.081844) (xy 133.369715 -235.081844)
			(xy 133.320352 -235.074025) (xy 133.27282 -235.058581) (xy 133.228288 -235.035891) (xy 133.187855 -235.006515)
			(xy 133.152515 -234.971175) (xy 133.123139 -234.930742) (xy 133.100449 -234.88621) (xy 133.085005 -234.838678)
			(xy 133.077186 -234.789315) (xy 132.769869 -234.789315) (xy 132.76986 -234.789772) (xy 132.761696 -234.840006)
			(xy 132.74558 -234.88828) (xy 132.721929 -234.933343) (xy 132.691356 -234.974029) (xy 132.654652 -235.009284)
			(xy 132.612768 -235.038194) (xy 132.566789 -235.060011) (xy 132.517905 -235.074171) (xy 132.467384 -235.080305)
			(xy 132.416532 -235.078256) (xy 132.366668 -235.068076) (xy 132.319082 -235.050029) (xy 132.275008 -235.024583)
			(xy 132.235586 -234.992396) (xy 132.201838 -234.954302) (xy 132.174637 -234.911288) (xy 132.154689 -234.864468)
			(xy 132.14251 -234.815054) (xy 132.138415 -234.764326) (xy 131.830572 -234.764326) (xy 131.83006 -234.789772)
			(xy 131.821896 -234.840006) (xy 131.80578 -234.88828) (xy 131.782129 -234.933343) (xy 131.751556 -234.974029)
			(xy 131.714852 -235.009284) (xy 131.672968 -235.038194) (xy 131.626989 -235.060011) (xy 131.578105 -235.074171)
			(xy 131.527584 -235.080305) (xy 131.476732 -235.078256) (xy 131.426868 -235.068076) (xy 131.379282 -235.050029)
			(xy 131.335208 -235.024583) (xy 131.295786 -234.992396) (xy 131.262038 -234.954302) (xy 131.234837 -234.911288)
			(xy 131.214889 -234.864468) (xy 131.20271 -234.815054) (xy 131.198615 -234.764326) (xy 129.950464 -234.764326)
			(xy 129.949952 -234.789772) (xy 129.941788 -234.840006) (xy 129.925672 -234.88828) (xy 129.902021 -234.933343)
			(xy 129.871448 -234.974029) (xy 129.834744 -235.009284) (xy 129.79286 -235.038194) (xy 129.746881 -235.060011)
			(xy 129.697997 -235.074171) (xy 129.647476 -235.080305) (xy 129.596624 -235.078256) (xy 129.54676 -235.068076)
			(xy 129.499174 -235.050029) (xy 129.4551 -235.024583) (xy 129.415678 -234.992396) (xy 129.38193 -234.954302)
			(xy 129.354729 -234.911288) (xy 129.334781 -234.864468) (xy 129.322602 -234.815054) (xy 129.318507 -234.764326)
			(xy 129.012696 -234.764326) (xy 129.012206 -234.789315) (xy 129.004387 -234.838678) (xy 128.988943 -234.88621)
			(xy 128.966253 -234.930742) (xy 128.936877 -234.971175) (xy 128.901537 -235.006515) (xy 128.861104 -235.035891)
			(xy 128.816572 -235.058581) (xy 128.76904 -235.074025) (xy 128.719677 -235.081844) (xy 128.669699 -235.081844)
			(xy 128.620336 -235.074025) (xy 128.572804 -235.058581) (xy 128.528272 -235.035891) (xy 128.487839 -235.006515)
			(xy 128.452499 -234.971175) (xy 128.423123 -234.930742) (xy 128.400433 -234.88621) (xy 128.384989 -234.838678)
			(xy 128.37717 -234.789315) (xy 128.069853 -234.789315) (xy 128.069844 -234.789772) (xy 128.06168 -234.840006)
			(xy 128.045564 -234.88828) (xy 128.021913 -234.933343) (xy 127.99134 -234.974029) (xy 127.954636 -235.009284)
			(xy 127.912752 -235.038194) (xy 127.866773 -235.060011) (xy 127.817889 -235.074171) (xy 127.767368 -235.080305)
			(xy 127.716516 -235.078256) (xy 127.666652 -235.068076) (xy 127.619066 -235.050029) (xy 127.574992 -235.024583)
			(xy 127.53557 -234.992396) (xy 127.501822 -234.954302) (xy 127.474621 -234.911288) (xy 127.454673 -234.864468)
			(xy 127.442494 -234.815054) (xy 127.438399 -234.764326) (xy 127.132292 -234.764326) (xy 127.132292 -234.789285)
			(xy 127.124475 -234.838641) (xy 127.109034 -234.886167) (xy 127.08635 -234.930692) (xy 127.056979 -234.97112)
			(xy 127.021646 -235.006457) (xy 126.981221 -235.035832) (xy 126.936698 -235.058521) (xy 126.889174 -235.073967)
			(xy 126.839819 -235.081789) (xy 126.814834 -235.082334) (xy 126.8024 -235.082236) (xy 126.777607 -235.080326)
			(xy 126.765304 -235.078524) (xy 126.763526 -235.07827) (xy 126.75616 -235.077762) (xy 126.747781 -235.078189)
			(xy 126.731968 -235.083764) (xy 126.725172 -235.088684) (xy 126.706122 -235.104686) (xy 126.705614 -235.105194)
			(xy 126.666244 -235.138976) (xy 126.658712 -235.146042) (xy 126.649524 -235.164518) (xy 126.648464 -235.17479)
			(xy 126.648464 -235.472224) (xy 126.648972 -235.47578) (xy 126.650496 -235.486702) (xy 126.651004 -235.488734)
			(xy 126.651512 -235.490258) (xy 126.656772 -235.510876) (xy 126.662374 -235.553056) (xy 126.662688 -235.574332)
			(xy 127.908553 -235.574332) (xy 127.912648 -235.523604) (xy 127.924827 -235.47419) (xy 127.944775 -235.42737)
			(xy 127.971976 -235.384356) (xy 128.005724 -235.346262) (xy 128.045146 -235.314075) (xy 128.08922 -235.288629)
			(xy 128.136806 -235.270582) (xy 128.18667 -235.260402) (xy 128.237522 -235.258353) (xy 128.288043 -235.264487)
			(xy 128.336927 -235.278647) (xy 128.382906 -235.300464) (xy 128.42479 -235.329374) (xy 128.461494 -235.364629)
			(xy 128.492067 -235.405315) (xy 128.515718 -235.450378) (xy 128.531834 -235.498652) (xy 128.539998 -235.548886)
			(xy 128.54051 -235.574332) (xy 128.848607 -235.574332) (xy 128.852702 -235.523604) (xy 128.864881 -235.47419)
			(xy 128.884829 -235.42737) (xy 128.91203 -235.384356) (xy 128.945778 -235.346262) (xy 128.9852 -235.314075)
			(xy 129.029274 -235.288629) (xy 129.07686 -235.270582) (xy 129.126724 -235.260402) (xy 129.177576 -235.258353)
			(xy 129.228097 -235.264487) (xy 129.276981 -235.278647) (xy 129.32296 -235.300464) (xy 129.364844 -235.329374)
			(xy 129.401548 -235.364629) (xy 129.432121 -235.405315) (xy 129.455772 -235.450378) (xy 129.471888 -235.498652)
			(xy 129.480052 -235.548886) (xy 129.480564 -235.574332) (xy 129.480061 -235.599321) (xy 129.787124 -235.599321)
			(xy 129.787124 -235.549343) (xy 129.794943 -235.49998) (xy 129.810387 -235.452448) (xy 129.833077 -235.407916)
			(xy 129.862453 -235.367483) (xy 129.897793 -235.332143) (xy 129.938226 -235.302767) (xy 129.982758 -235.280077)
			(xy 130.03029 -235.264633) (xy 130.079653 -235.256814) (xy 130.129631 -235.256814) (xy 130.178994 -235.264633)
			(xy 130.226526 -235.280077) (xy 130.271058 -235.302767) (xy 130.311491 -235.332143) (xy 130.346831 -235.367483)
			(xy 130.376207 -235.407916) (xy 130.398897 -235.452448) (xy 130.414341 -235.49998) (xy 130.42216 -235.549343)
			(xy 130.42265 -235.574332) (xy 130.728461 -235.574332) (xy 130.732556 -235.523604) (xy 130.744735 -235.47419)
			(xy 130.764683 -235.42737) (xy 130.791884 -235.384356) (xy 130.825632 -235.346262) (xy 130.865054 -235.314075)
			(xy 130.909128 -235.288629) (xy 130.956714 -235.270582) (xy 131.006578 -235.260402) (xy 131.05743 -235.258353)
			(xy 131.107951 -235.264487) (xy 131.156835 -235.278647) (xy 131.202814 -235.300464) (xy 131.244698 -235.329374)
			(xy 131.281402 -235.364629) (xy 131.311975 -235.405315) (xy 131.335626 -235.450378) (xy 131.351742 -235.498652)
			(xy 131.359906 -235.548886) (xy 131.360418 -235.574332) (xy 131.359915 -235.599321) (xy 131.667232 -235.599321)
			(xy 131.667232 -235.549343) (xy 131.675051 -235.49998) (xy 131.690495 -235.452448) (xy 131.713185 -235.407916)
			(xy 131.742561 -235.367483) (xy 131.777901 -235.332143) (xy 131.818334 -235.302767) (xy 131.862866 -235.280077)
			(xy 131.910398 -235.264633) (xy 131.959761 -235.256814) (xy 132.009739 -235.256814) (xy 132.059102 -235.264633)
			(xy 132.106634 -235.280077) (xy 132.151166 -235.302767) (xy 132.191599 -235.332143) (xy 132.226939 -235.367483)
			(xy 132.256315 -235.407916) (xy 132.279005 -235.452448) (xy 132.294449 -235.49998) (xy 132.302268 -235.549343)
			(xy 132.302758 -235.574332) (xy 132.608569 -235.574332) (xy 132.612664 -235.523604) (xy 132.624843 -235.47419)
			(xy 132.644791 -235.42737) (xy 132.671992 -235.384356) (xy 132.70574 -235.346262) (xy 132.745162 -235.314075)
			(xy 132.789236 -235.288629) (xy 132.836822 -235.270582) (xy 132.886686 -235.260402) (xy 132.937538 -235.258353)
			(xy 132.988059 -235.264487) (xy 133.036943 -235.278647) (xy 133.082922 -235.300464) (xy 133.124806 -235.329374)
			(xy 133.16151 -235.364629) (xy 133.192083 -235.405315) (xy 133.215734 -235.450378) (xy 133.23185 -235.498652)
			(xy 133.240014 -235.548886) (xy 133.240526 -235.574332) (xy 133.240023 -235.599321) (xy 133.54734 -235.599321)
			(xy 133.54734 -235.549343) (xy 133.555159 -235.49998) (xy 133.570603 -235.452448) (xy 133.593293 -235.407916)
			(xy 133.622669 -235.367483) (xy 133.658009 -235.332143) (xy 133.698442 -235.302767) (xy 133.742974 -235.280077)
			(xy 133.790506 -235.264633) (xy 133.839869 -235.256814) (xy 133.889847 -235.256814) (xy 133.93921 -235.264633)
			(xy 133.986742 -235.280077) (xy 134.031274 -235.302767) (xy 134.071707 -235.332143) (xy 134.107047 -235.367483)
			(xy 134.136423 -235.407916) (xy 134.159113 -235.452448) (xy 134.174557 -235.49998) (xy 134.182376 -235.549343)
			(xy 134.182866 -235.574332) (xy 134.488423 -235.574332) (xy 134.492518 -235.523604) (xy 134.504697 -235.47419)
			(xy 134.524645 -235.42737) (xy 134.551846 -235.384356) (xy 134.585594 -235.346262) (xy 134.625016 -235.314075)
			(xy 134.66909 -235.288629) (xy 134.716676 -235.270582) (xy 134.76654 -235.260402) (xy 134.817392 -235.258353)
			(xy 134.867913 -235.264487) (xy 134.916797 -235.278647) (xy 134.962776 -235.300464) (xy 135.00466 -235.329374)
			(xy 135.041364 -235.364629) (xy 135.071937 -235.405315) (xy 135.095588 -235.450378) (xy 135.111704 -235.498652)
			(xy 135.119868 -235.548886) (xy 135.12038 -235.574332) (xy 135.428477 -235.574332) (xy 135.432572 -235.523604)
			(xy 135.444751 -235.47419) (xy 135.464699 -235.42737) (xy 135.4919 -235.384356) (xy 135.525648 -235.346262)
			(xy 135.56507 -235.314075) (xy 135.609144 -235.288629) (xy 135.65673 -235.270582) (xy 135.706594 -235.260402)
			(xy 135.757446 -235.258353) (xy 135.807967 -235.264487) (xy 135.856851 -235.278647) (xy 135.90283 -235.300464)
			(xy 135.944714 -235.329374) (xy 135.981418 -235.364629) (xy 136.011991 -235.405315) (xy 136.035642 -235.450378)
			(xy 136.051758 -235.498652) (xy 136.059922 -235.548886) (xy 136.060434 -235.574332) (xy 136.059931 -235.599321)
			(xy 136.367248 -235.599321) (xy 136.367248 -235.549343) (xy 136.375067 -235.49998) (xy 136.390511 -235.452448)
			(xy 136.413201 -235.407916) (xy 136.442577 -235.367483) (xy 136.477917 -235.332143) (xy 136.51835 -235.302767)
			(xy 136.562882 -235.280077) (xy 136.610414 -235.264633) (xy 136.659777 -235.256814) (xy 136.709755 -235.256814)
			(xy 136.759118 -235.264633) (xy 136.80665 -235.280077) (xy 136.851182 -235.302767) (xy 136.891615 -235.332143)
			(xy 136.926955 -235.367483) (xy 136.956331 -235.407916) (xy 136.979021 -235.452448) (xy 136.994465 -235.49998)
			(xy 137.002284 -235.549343) (xy 137.002774 -235.574332) (xy 137.308585 -235.574332) (xy 137.31268 -235.523604)
			(xy 137.324859 -235.47419) (xy 137.344807 -235.42737) (xy 137.372008 -235.384356) (xy 137.405756 -235.346262)
			(xy 137.445178 -235.314075) (xy 137.489252 -235.288629) (xy 137.536838 -235.270582) (xy 137.586702 -235.260402)
			(xy 137.637554 -235.258353) (xy 137.688075 -235.264487) (xy 137.736959 -235.278647) (xy 137.782938 -235.300464)
			(xy 137.824822 -235.329374) (xy 137.861526 -235.364629) (xy 137.892099 -235.405315) (xy 137.91575 -235.450378)
			(xy 137.931866 -235.498652) (xy 137.94003 -235.548886) (xy 137.940542 -235.574332) (xy 137.940039 -235.599321)
			(xy 138.247356 -235.599321) (xy 138.247356 -235.549343) (xy 138.255175 -235.49998) (xy 138.270619 -235.452448)
			(xy 138.293309 -235.407916) (xy 138.322685 -235.367483) (xy 138.358025 -235.332143) (xy 138.398458 -235.302767)
			(xy 138.44299 -235.280077) (xy 138.490522 -235.264633) (xy 138.539885 -235.256814) (xy 138.589863 -235.256814)
			(xy 138.639226 -235.264633) (xy 138.686758 -235.280077) (xy 138.73129 -235.302767) (xy 138.771723 -235.332143)
			(xy 138.807063 -235.367483) (xy 138.836439 -235.407916) (xy 138.859129 -235.452448) (xy 138.874573 -235.49998)
			(xy 138.882392 -235.549343) (xy 138.882882 -235.574332) (xy 139.188439 -235.574332) (xy 139.192534 -235.523604)
			(xy 139.204713 -235.47419) (xy 139.224661 -235.42737) (xy 139.251862 -235.384356) (xy 139.28561 -235.346262)
			(xy 139.325032 -235.314075) (xy 139.369106 -235.288629) (xy 139.416692 -235.270582) (xy 139.466556 -235.260402)
			(xy 139.517408 -235.258353) (xy 139.567929 -235.264487) (xy 139.616813 -235.278647) (xy 139.662792 -235.300464)
			(xy 139.704676 -235.329374) (xy 139.74138 -235.364629) (xy 139.771953 -235.405315) (xy 139.795604 -235.450378)
			(xy 139.81172 -235.498652) (xy 139.819884 -235.548886) (xy 139.820396 -235.574332) (xy 139.819893 -235.599321)
			(xy 140.12721 -235.599321) (xy 140.12721 -235.549343) (xy 140.135029 -235.49998) (xy 140.150473 -235.452448)
			(xy 140.173163 -235.407916) (xy 140.202539 -235.367483) (xy 140.237879 -235.332143) (xy 140.278312 -235.302767)
			(xy 140.322844 -235.280077) (xy 140.370376 -235.264633) (xy 140.419739 -235.256814) (xy 140.469717 -235.256814)
			(xy 140.51908 -235.264633) (xy 140.566612 -235.280077) (xy 140.611144 -235.302767) (xy 140.651577 -235.332143)
			(xy 140.686917 -235.367483) (xy 140.716293 -235.407916) (xy 140.738983 -235.452448) (xy 140.754427 -235.49998)
			(xy 140.762246 -235.549343) (xy 140.762736 -235.574332) (xy 141.068547 -235.574332) (xy 141.072642 -235.523604)
			(xy 141.084821 -235.47419) (xy 141.104769 -235.42737) (xy 141.13197 -235.384356) (xy 141.165718 -235.346262)
			(xy 141.20514 -235.314075) (xy 141.249214 -235.288629) (xy 141.2968 -235.270582) (xy 141.346664 -235.260402)
			(xy 141.397516 -235.258353) (xy 141.448037 -235.264487) (xy 141.496921 -235.278647) (xy 141.5429 -235.300464)
			(xy 141.584784 -235.329374) (xy 141.621488 -235.364629) (xy 141.652061 -235.405315) (xy 141.675712 -235.450378)
			(xy 141.691828 -235.498652) (xy 141.699992 -235.548886) (xy 141.700504 -235.574332) (xy 142.008601 -235.574332)
			(xy 142.012696 -235.523604) (xy 142.024875 -235.47419) (xy 142.044823 -235.42737) (xy 142.072024 -235.384356)
			(xy 142.105772 -235.346262) (xy 142.145194 -235.314075) (xy 142.189268 -235.288629) (xy 142.236854 -235.270582)
			(xy 142.286718 -235.260402) (xy 142.33757 -235.258353) (xy 142.388091 -235.264487) (xy 142.436975 -235.278647)
			(xy 142.482954 -235.300464) (xy 142.524838 -235.329374) (xy 142.561542 -235.364629) (xy 142.592115 -235.405315)
			(xy 142.615766 -235.450378) (xy 142.631882 -235.498652) (xy 142.640046 -235.548886) (xy 142.640558 -235.574332)
			(xy 142.640055 -235.599321) (xy 142.947118 -235.599321) (xy 142.947118 -235.549343) (xy 142.954937 -235.49998)
			(xy 142.970381 -235.452448) (xy 142.993071 -235.407916) (xy 143.022447 -235.367483) (xy 143.057787 -235.332143)
			(xy 143.09822 -235.302767) (xy 143.142752 -235.280077) (xy 143.190284 -235.264633) (xy 143.239647 -235.256814)
			(xy 143.289625 -235.256814) (xy 143.338988 -235.264633) (xy 143.38652 -235.280077) (xy 143.431052 -235.302767)
			(xy 143.471485 -235.332143) (xy 143.506825 -235.367483) (xy 143.536201 -235.407916) (xy 143.558891 -235.452448)
			(xy 143.574335 -235.49998) (xy 143.582154 -235.549343) (xy 143.582644 -235.574332) (xy 143.582154 -235.599321)
			(xy 143.574335 -235.648684) (xy 143.558891 -235.696216) (xy 143.536201 -235.740748) (xy 143.506825 -235.781181)
			(xy 143.471485 -235.816521) (xy 143.431052 -235.845897) (xy 143.38652 -235.868587) (xy 143.338988 -235.884031)
			(xy 143.289625 -235.89185) (xy 143.239647 -235.89185) (xy 143.190284 -235.884031) (xy 143.142752 -235.868587)
			(xy 143.09822 -235.845897) (xy 143.057787 -235.816521) (xy 143.022447 -235.781181) (xy 142.993071 -235.740748)
			(xy 142.970381 -235.696216) (xy 142.954937 -235.648684) (xy 142.947118 -235.599321) (xy 142.640055 -235.599321)
			(xy 142.640046 -235.599778) (xy 142.631882 -235.650012) (xy 142.615766 -235.698286) (xy 142.592115 -235.743349)
			(xy 142.561542 -235.784035) (xy 142.524838 -235.81929) (xy 142.482954 -235.8482) (xy 142.436975 -235.870017)
			(xy 142.388091 -235.884177) (xy 142.33757 -235.890311) (xy 142.286718 -235.888262) (xy 142.236854 -235.878082)
			(xy 142.189268 -235.860035) (xy 142.145194 -235.834589) (xy 142.105772 -235.802402) (xy 142.072024 -235.764308)
			(xy 142.044823 -235.721294) (xy 142.024875 -235.674474) (xy 142.012696 -235.62506) (xy 142.008601 -235.574332)
			(xy 141.700504 -235.574332) (xy 141.699992 -235.599778) (xy 141.691828 -235.650012) (xy 141.675712 -235.698286)
			(xy 141.652061 -235.743349) (xy 141.621488 -235.784035) (xy 141.584784 -235.81929) (xy 141.5429 -235.8482)
			(xy 141.496921 -235.870017) (xy 141.448037 -235.884177) (xy 141.397516 -235.890311) (xy 141.346664 -235.888262)
			(xy 141.2968 -235.878082) (xy 141.249214 -235.860035) (xy 141.20514 -235.834589) (xy 141.165718 -235.802402)
			(xy 141.13197 -235.764308) (xy 141.104769 -235.721294) (xy 141.084821 -235.674474) (xy 141.072642 -235.62506)
			(xy 141.068547 -235.574332) (xy 140.762736 -235.574332) (xy 140.762246 -235.599321) (xy 140.754427 -235.648684)
			(xy 140.738983 -235.696216) (xy 140.716293 -235.740748) (xy 140.686917 -235.781181) (xy 140.651577 -235.816521)
			(xy 140.611144 -235.845897) (xy 140.566612 -235.868587) (xy 140.51908 -235.884031) (xy 140.469717 -235.89185)
			(xy 140.419739 -235.89185) (xy 140.370376 -235.884031) (xy 140.322844 -235.868587) (xy 140.278312 -235.845897)
			(xy 140.237879 -235.816521) (xy 140.202539 -235.781181) (xy 140.173163 -235.740748) (xy 140.150473 -235.696216)
			(xy 140.135029 -235.648684) (xy 140.12721 -235.599321) (xy 139.819893 -235.599321) (xy 139.819884 -235.599778)
			(xy 139.81172 -235.650012) (xy 139.795604 -235.698286) (xy 139.771953 -235.743349) (xy 139.74138 -235.784035)
			(xy 139.704676 -235.81929) (xy 139.662792 -235.8482) (xy 139.616813 -235.870017) (xy 139.567929 -235.884177)
			(xy 139.517408 -235.890311) (xy 139.466556 -235.888262) (xy 139.416692 -235.878082) (xy 139.369106 -235.860035)
			(xy 139.325032 -235.834589) (xy 139.28561 -235.802402) (xy 139.251862 -235.764308) (xy 139.224661 -235.721294)
			(xy 139.204713 -235.674474) (xy 139.192534 -235.62506) (xy 139.188439 -235.574332) (xy 138.882882 -235.574332)
			(xy 138.882392 -235.599321) (xy 138.874573 -235.648684) (xy 138.859129 -235.696216) (xy 138.836439 -235.740748)
			(xy 138.807063 -235.781181) (xy 138.771723 -235.816521) (xy 138.73129 -235.845897) (xy 138.686758 -235.868587)
			(xy 138.639226 -235.884031) (xy 138.589863 -235.89185) (xy 138.539885 -235.89185) (xy 138.490522 -235.884031)
			(xy 138.44299 -235.868587) (xy 138.398458 -235.845897) (xy 138.358025 -235.816521) (xy 138.322685 -235.781181)
			(xy 138.293309 -235.740748) (xy 138.270619 -235.696216) (xy 138.255175 -235.648684) (xy 138.247356 -235.599321)
			(xy 137.940039 -235.599321) (xy 137.94003 -235.599778) (xy 137.931866 -235.650012) (xy 137.91575 -235.698286)
			(xy 137.892099 -235.743349) (xy 137.861526 -235.784035) (xy 137.824822 -235.81929) (xy 137.782938 -235.8482)
			(xy 137.736959 -235.870017) (xy 137.688075 -235.884177) (xy 137.637554 -235.890311) (xy 137.586702 -235.888262)
			(xy 137.536838 -235.878082) (xy 137.489252 -235.860035) (xy 137.445178 -235.834589) (xy 137.405756 -235.802402)
			(xy 137.372008 -235.764308) (xy 137.344807 -235.721294) (xy 137.324859 -235.674474) (xy 137.31268 -235.62506)
			(xy 137.308585 -235.574332) (xy 137.002774 -235.574332) (xy 137.002284 -235.599321) (xy 136.994465 -235.648684)
			(xy 136.979021 -235.696216) (xy 136.956331 -235.740748) (xy 136.926955 -235.781181) (xy 136.891615 -235.816521)
			(xy 136.851182 -235.845897) (xy 136.80665 -235.868587) (xy 136.759118 -235.884031) (xy 136.709755 -235.89185)
			(xy 136.659777 -235.89185) (xy 136.610414 -235.884031) (xy 136.562882 -235.868587) (xy 136.51835 -235.845897)
			(xy 136.477917 -235.816521) (xy 136.442577 -235.781181) (xy 136.413201 -235.740748) (xy 136.390511 -235.696216)
			(xy 136.375067 -235.648684) (xy 136.367248 -235.599321) (xy 136.059931 -235.599321) (xy 136.059922 -235.599778)
			(xy 136.051758 -235.650012) (xy 136.035642 -235.698286) (xy 136.011991 -235.743349) (xy 135.981418 -235.784035)
			(xy 135.944714 -235.81929) (xy 135.90283 -235.8482) (xy 135.856851 -235.870017) (xy 135.807967 -235.884177)
			(xy 135.757446 -235.890311) (xy 135.706594 -235.888262) (xy 135.65673 -235.878082) (xy 135.609144 -235.860035)
			(xy 135.56507 -235.834589) (xy 135.525648 -235.802402) (xy 135.4919 -235.764308) (xy 135.464699 -235.721294)
			(xy 135.444751 -235.674474) (xy 135.432572 -235.62506) (xy 135.428477 -235.574332) (xy 135.12038 -235.574332)
			(xy 135.119868 -235.599778) (xy 135.111704 -235.650012) (xy 135.095588 -235.698286) (xy 135.071937 -235.743349)
			(xy 135.041364 -235.784035) (xy 135.00466 -235.81929) (xy 134.962776 -235.8482) (xy 134.916797 -235.870017)
			(xy 134.867913 -235.884177) (xy 134.817392 -235.890311) (xy 134.76654 -235.888262) (xy 134.716676 -235.878082)
			(xy 134.66909 -235.860035) (xy 134.625016 -235.834589) (xy 134.585594 -235.802402) (xy 134.551846 -235.764308)
			(xy 134.524645 -235.721294) (xy 134.504697 -235.674474) (xy 134.492518 -235.62506) (xy 134.488423 -235.574332)
			(xy 134.182866 -235.574332) (xy 134.182376 -235.599321) (xy 134.174557 -235.648684) (xy 134.159113 -235.696216)
			(xy 134.136423 -235.740748) (xy 134.107047 -235.781181) (xy 134.071707 -235.816521) (xy 134.031274 -235.845897)
			(xy 133.986742 -235.868587) (xy 133.93921 -235.884031) (xy 133.889847 -235.89185) (xy 133.839869 -235.89185)
			(xy 133.790506 -235.884031) (xy 133.742974 -235.868587) (xy 133.698442 -235.845897) (xy 133.658009 -235.816521)
			(xy 133.622669 -235.781181) (xy 133.593293 -235.740748) (xy 133.570603 -235.696216) (xy 133.555159 -235.648684)
			(xy 133.54734 -235.599321) (xy 133.240023 -235.599321) (xy 133.240014 -235.599778) (xy 133.23185 -235.650012)
			(xy 133.215734 -235.698286) (xy 133.192083 -235.743349) (xy 133.16151 -235.784035) (xy 133.124806 -235.81929)
			(xy 133.082922 -235.8482) (xy 133.036943 -235.870017) (xy 132.988059 -235.884177) (xy 132.937538 -235.890311)
			(xy 132.886686 -235.888262) (xy 132.836822 -235.878082) (xy 132.789236 -235.860035) (xy 132.745162 -235.834589)
			(xy 132.70574 -235.802402) (xy 132.671992 -235.764308) (xy 132.644791 -235.721294) (xy 132.624843 -235.674474)
			(xy 132.612664 -235.62506) (xy 132.608569 -235.574332) (xy 132.302758 -235.574332) (xy 132.302268 -235.599321)
			(xy 132.294449 -235.648684) (xy 132.279005 -235.696216) (xy 132.256315 -235.740748) (xy 132.226939 -235.781181)
			(xy 132.191599 -235.816521) (xy 132.151166 -235.845897) (xy 132.106634 -235.868587) (xy 132.059102 -235.884031)
			(xy 132.009739 -235.89185) (xy 131.959761 -235.89185) (xy 131.910398 -235.884031) (xy 131.862866 -235.868587)
			(xy 131.818334 -235.845897) (xy 131.777901 -235.816521) (xy 131.742561 -235.781181) (xy 131.713185 -235.740748)
			(xy 131.690495 -235.696216) (xy 131.675051 -235.648684) (xy 131.667232 -235.599321) (xy 131.359915 -235.599321)
			(xy 131.359906 -235.599778) (xy 131.351742 -235.650012) (xy 131.335626 -235.698286) (xy 131.311975 -235.743349)
			(xy 131.281402 -235.784035) (xy 131.244698 -235.81929) (xy 131.202814 -235.8482) (xy 131.156835 -235.870017)
			(xy 131.107951 -235.884177) (xy 131.05743 -235.890311) (xy 131.006578 -235.888262) (xy 130.956714 -235.878082)
			(xy 130.909128 -235.860035) (xy 130.865054 -235.834589) (xy 130.825632 -235.802402) (xy 130.791884 -235.764308)
			(xy 130.764683 -235.721294) (xy 130.744735 -235.674474) (xy 130.732556 -235.62506) (xy 130.728461 -235.574332)
			(xy 130.42265 -235.574332) (xy 130.42216 -235.599321) (xy 130.414341 -235.648684) (xy 130.398897 -235.696216)
			(xy 130.376207 -235.740748) (xy 130.346831 -235.781181) (xy 130.311491 -235.816521) (xy 130.271058 -235.845897)
			(xy 130.226526 -235.868587) (xy 130.178994 -235.884031) (xy 130.129631 -235.89185) (xy 130.079653 -235.89185)
			(xy 130.03029 -235.884031) (xy 129.982758 -235.868587) (xy 129.938226 -235.845897) (xy 129.897793 -235.816521)
			(xy 129.862453 -235.781181) (xy 129.833077 -235.740748) (xy 129.810387 -235.696216) (xy 129.794943 -235.648684)
			(xy 129.787124 -235.599321) (xy 129.480061 -235.599321) (xy 129.480052 -235.599778) (xy 129.471888 -235.650012)
			(xy 129.455772 -235.698286) (xy 129.432121 -235.743349) (xy 129.401548 -235.784035) (xy 129.364844 -235.81929)
			(xy 129.32296 -235.8482) (xy 129.276981 -235.870017) (xy 129.228097 -235.884177) (xy 129.177576 -235.890311)
			(xy 129.126724 -235.888262) (xy 129.07686 -235.878082) (xy 129.029274 -235.860035) (xy 128.9852 -235.834589)
			(xy 128.945778 -235.802402) (xy 128.91203 -235.764308) (xy 128.884829 -235.721294) (xy 128.864881 -235.674474)
			(xy 128.852702 -235.62506) (xy 128.848607 -235.574332) (xy 128.54051 -235.574332) (xy 128.539998 -235.599778)
			(xy 128.531834 -235.650012) (xy 128.515718 -235.698286) (xy 128.492067 -235.743349) (xy 128.461494 -235.784035)
			(xy 128.42479 -235.81929) (xy 128.382906 -235.8482) (xy 128.336927 -235.870017) (xy 128.288043 -235.884177)
			(xy 128.237522 -235.890311) (xy 128.18667 -235.888262) (xy 128.136806 -235.878082) (xy 128.08922 -235.860035)
			(xy 128.045146 -235.834589) (xy 128.005724 -235.802402) (xy 127.971976 -235.764308) (xy 127.944775 -235.721294)
			(xy 127.924827 -235.674474) (xy 127.912648 -235.62506) (xy 127.908553 -235.574332) (xy 126.662688 -235.574332)
			(xy 126.662434 -235.588048) (xy 126.661376 -235.60685) (xy 126.655397 -235.644033) (xy 126.650496 -235.662216)
			(xy 126.648464 -235.669074) (xy 126.648464 -235.97108) (xy 126.648464 -235.973874) (xy 126.649356 -235.983303)
			(xy 126.657181 -236.000536) (xy 126.663704 -236.007402) (xy 126.665736 -236.00918) (xy 126.705614 -236.04347)
			(xy 126.706122 -236.043978) (xy 126.725172 -236.05998) (xy 126.731963 -236.064909) (xy 126.747779 -236.070479)
			(xy 126.75616 -236.070902) (xy 126.763526 -236.070394) (xy 126.765304 -236.07014) (xy 126.777607 -236.068343)
			(xy 126.802401 -236.066436) (xy 126.814834 -236.06633) (xy 126.839818 -236.066823) (xy 126.889172 -236.074644)
			(xy 126.936694 -236.09009) (xy 126.981215 -236.112778) (xy 127.021638 -236.142152) (xy 127.05697 -236.177487)
			(xy 127.086339 -236.217914) (xy 127.109023 -236.262438) (xy 127.124464 -236.309962) (xy 127.13228 -236.359315)
			(xy 127.13228 -236.384338) (xy 127.438399 -236.384338) (xy 127.442494 -236.33361) (xy 127.454673 -236.284196)
			(xy 127.474621 -236.237376) (xy 127.501822 -236.194362) (xy 127.53557 -236.156268) (xy 127.574992 -236.124081)
			(xy 127.619066 -236.098635) (xy 127.666652 -236.080588) (xy 127.716516 -236.070408) (xy 127.767368 -236.068359)
			(xy 127.817889 -236.074493) (xy 127.866773 -236.088653) (xy 127.912752 -236.11047) (xy 127.954636 -236.13938)
			(xy 127.99134 -236.174635) (xy 128.021913 -236.215321) (xy 128.045564 -236.260384) (xy 128.06168 -236.308658)
			(xy 128.069844 -236.358892) (xy 128.070356 -236.384338) (xy 128.069853 -236.409327) (xy 128.37717 -236.409327)
			(xy 128.37717 -236.359349) (xy 128.384989 -236.309986) (xy 128.400433 -236.262454) (xy 128.423123 -236.217922)
			(xy 128.452499 -236.177489) (xy 128.487839 -236.142149) (xy 128.528272 -236.112773) (xy 128.572804 -236.090083)
			(xy 128.620336 -236.074639) (xy 128.669699 -236.06682) (xy 128.719677 -236.06682) (xy 128.76904 -236.074639)
			(xy 128.816572 -236.090083) (xy 128.861104 -236.112773) (xy 128.901537 -236.142149) (xy 128.936877 -236.177489)
			(xy 128.966253 -236.217922) (xy 128.988943 -236.262454) (xy 129.004387 -236.309986) (xy 129.012206 -236.359349)
			(xy 129.012696 -236.384338) (xy 129.318507 -236.384338) (xy 129.322602 -236.33361) (xy 129.334781 -236.284196)
			(xy 129.354729 -236.237376) (xy 129.38193 -236.194362) (xy 129.415678 -236.156268) (xy 129.4551 -236.124081)
			(xy 129.499174 -236.098635) (xy 129.54676 -236.080588) (xy 129.596624 -236.070408) (xy 129.647476 -236.068359)
			(xy 129.697997 -236.074493) (xy 129.746881 -236.088653) (xy 129.79286 -236.11047) (xy 129.834744 -236.13938)
			(xy 129.871448 -236.174635) (xy 129.902021 -236.215321) (xy 129.925672 -236.260384) (xy 129.941788 -236.308658)
			(xy 129.949952 -236.358892) (xy 129.950464 -236.384338) (xy 129.949961 -236.409327) (xy 130.257278 -236.409327)
			(xy 130.257278 -236.359349) (xy 130.265097 -236.309986) (xy 130.280541 -236.262454) (xy 130.303231 -236.217922)
			(xy 130.332607 -236.177489) (xy 130.367947 -236.142149) (xy 130.40838 -236.112773) (xy 130.452912 -236.090083)
			(xy 130.500444 -236.074639) (xy 130.549807 -236.06682) (xy 130.599785 -236.06682) (xy 130.649148 -236.074639)
			(xy 130.69668 -236.090083) (xy 130.741212 -236.112773) (xy 130.781645 -236.142149) (xy 130.816985 -236.177489)
			(xy 130.846361 -236.217922) (xy 130.869051 -236.262454) (xy 130.884495 -236.309986) (xy 130.892314 -236.359349)
			(xy 130.892804 -236.384338) (xy 131.198615 -236.384338) (xy 131.20271 -236.33361) (xy 131.214889 -236.284196)
			(xy 131.234837 -236.237376) (xy 131.262038 -236.194362) (xy 131.295786 -236.156268) (xy 131.335208 -236.124081)
			(xy 131.379282 -236.098635) (xy 131.426868 -236.080588) (xy 131.476732 -236.070408) (xy 131.527584 -236.068359)
			(xy 131.578105 -236.074493) (xy 131.626989 -236.088653) (xy 131.672968 -236.11047) (xy 131.714852 -236.13938)
			(xy 131.751556 -236.174635) (xy 131.782129 -236.215321) (xy 131.80578 -236.260384) (xy 131.821896 -236.308658)
			(xy 131.83006 -236.358892) (xy 131.830572 -236.384338) (xy 132.138415 -236.384338) (xy 132.14251 -236.33361)
			(xy 132.154689 -236.284196) (xy 132.174637 -236.237376) (xy 132.201838 -236.194362) (xy 132.235586 -236.156268)
			(xy 132.275008 -236.124081) (xy 132.319082 -236.098635) (xy 132.366668 -236.080588) (xy 132.416532 -236.070408)
			(xy 132.467384 -236.068359) (xy 132.517905 -236.074493) (xy 132.566789 -236.088653) (xy 132.612768 -236.11047)
			(xy 132.654652 -236.13938) (xy 132.691356 -236.174635) (xy 132.721929 -236.215321) (xy 132.74558 -236.260384)
			(xy 132.761696 -236.308658) (xy 132.76986 -236.358892) (xy 132.770372 -236.384338) (xy 132.769869 -236.409327)
			(xy 133.077186 -236.409327) (xy 133.077186 -236.359349) (xy 133.085005 -236.309986) (xy 133.100449 -236.262454)
			(xy 133.123139 -236.217922) (xy 133.152515 -236.177489) (xy 133.187855 -236.142149) (xy 133.228288 -236.112773)
			(xy 133.27282 -236.090083) (xy 133.320352 -236.074639) (xy 133.369715 -236.06682) (xy 133.419693 -236.06682)
			(xy 133.469056 -236.074639) (xy 133.516588 -236.090083) (xy 133.56112 -236.112773) (xy 133.601553 -236.142149)
			(xy 133.636893 -236.177489) (xy 133.666269 -236.217922) (xy 133.688959 -236.262454) (xy 133.704403 -236.309986)
			(xy 133.712222 -236.359349) (xy 133.712712 -236.384338) (xy 134.018523 -236.384338) (xy 134.022618 -236.33361)
			(xy 134.034797 -236.284196) (xy 134.054745 -236.237376) (xy 134.081946 -236.194362) (xy 134.115694 -236.156268)
			(xy 134.155116 -236.124081) (xy 134.19919 -236.098635) (xy 134.246776 -236.080588) (xy 134.29664 -236.070408)
			(xy 134.347492 -236.068359) (xy 134.398013 -236.074493) (xy 134.446897 -236.088653) (xy 134.492876 -236.11047)
			(xy 134.53476 -236.13938) (xy 134.571464 -236.174635) (xy 134.602037 -236.215321) (xy 134.625688 -236.260384)
			(xy 134.641804 -236.308658) (xy 134.649968 -236.358892) (xy 134.65048 -236.384338) (xy 134.649977 -236.409327)
			(xy 134.957294 -236.409327) (xy 134.957294 -236.359349) (xy 134.965113 -236.309986) (xy 134.980557 -236.262454)
			(xy 135.003247 -236.217922) (xy 135.032623 -236.177489) (xy 135.067963 -236.142149) (xy 135.108396 -236.112773)
			(xy 135.152928 -236.090083) (xy 135.20046 -236.074639) (xy 135.249823 -236.06682) (xy 135.299801 -236.06682)
			(xy 135.349164 -236.074639) (xy 135.396696 -236.090083) (xy 135.441228 -236.112773) (xy 135.481661 -236.142149)
			(xy 135.517001 -236.177489) (xy 135.546377 -236.217922) (xy 135.569067 -236.262454) (xy 135.584511 -236.309986)
			(xy 135.59233 -236.359349) (xy 135.59282 -236.384338) (xy 135.898631 -236.384338) (xy 135.902726 -236.33361)
			(xy 135.914905 -236.284196) (xy 135.934853 -236.237376) (xy 135.962054 -236.194362) (xy 135.995802 -236.156268)
			(xy 136.035224 -236.124081) (xy 136.079298 -236.098635) (xy 136.126884 -236.080588) (xy 136.176748 -236.070408)
			(xy 136.2276 -236.068359) (xy 136.278121 -236.074493) (xy 136.327005 -236.088653) (xy 136.372984 -236.11047)
			(xy 136.414868 -236.13938) (xy 136.451572 -236.174635) (xy 136.482145 -236.215321) (xy 136.505796 -236.260384)
			(xy 136.521912 -236.308658) (xy 136.530076 -236.358892) (xy 136.530588 -236.384338) (xy 136.530085 -236.409327)
			(xy 136.837148 -236.409327) (xy 136.837148 -236.359349) (xy 136.844967 -236.309986) (xy 136.860411 -236.262454)
			(xy 136.883101 -236.217922) (xy 136.912477 -236.177489) (xy 136.947817 -236.142149) (xy 136.98825 -236.112773)
			(xy 137.032782 -236.090083) (xy 137.080314 -236.074639) (xy 137.129677 -236.06682) (xy 137.179655 -236.06682)
			(xy 137.229018 -236.074639) (xy 137.27655 -236.090083) (xy 137.321082 -236.112773) (xy 137.361515 -236.142149)
			(xy 137.396855 -236.177489) (xy 137.426231 -236.217922) (xy 137.448921 -236.262454) (xy 137.464365 -236.309986)
			(xy 137.472184 -236.359349) (xy 137.472674 -236.384338) (xy 137.778485 -236.384338) (xy 137.78258 -236.33361)
			(xy 137.794759 -236.284196) (xy 137.814707 -236.237376) (xy 137.841908 -236.194362) (xy 137.875656 -236.156268)
			(xy 137.915078 -236.124081) (xy 137.959152 -236.098635) (xy 138.006738 -236.080588) (xy 138.056602 -236.070408)
			(xy 138.107454 -236.068359) (xy 138.157975 -236.074493) (xy 138.206859 -236.088653) (xy 138.252838 -236.11047)
			(xy 138.294722 -236.13938) (xy 138.331426 -236.174635) (xy 138.361999 -236.215321) (xy 138.38565 -236.260384)
			(xy 138.401766 -236.308658) (xy 138.40993 -236.358892) (xy 138.410442 -236.384338) (xy 138.718539 -236.384338)
			(xy 138.722634 -236.33361) (xy 138.734813 -236.284196) (xy 138.754761 -236.237376) (xy 138.781962 -236.194362)
			(xy 138.81571 -236.156268) (xy 138.855132 -236.124081) (xy 138.899206 -236.098635) (xy 138.946792 -236.080588)
			(xy 138.996656 -236.070408) (xy 139.047508 -236.068359) (xy 139.098029 -236.074493) (xy 139.146913 -236.088653)
			(xy 139.192892 -236.11047) (xy 139.234776 -236.13938) (xy 139.27148 -236.174635) (xy 139.302053 -236.215321)
			(xy 139.325704 -236.260384) (xy 139.34182 -236.308658) (xy 139.349984 -236.358892) (xy 139.350496 -236.384338)
			(xy 139.349993 -236.409327) (xy 139.65731 -236.409327) (xy 139.65731 -236.359349) (xy 139.665129 -236.309986)
			(xy 139.680573 -236.262454) (xy 139.703263 -236.217922) (xy 139.732639 -236.177489) (xy 139.767979 -236.142149)
			(xy 139.808412 -236.112773) (xy 139.852944 -236.090083) (xy 139.900476 -236.074639) (xy 139.949839 -236.06682)
			(xy 139.999817 -236.06682) (xy 140.04918 -236.074639) (xy 140.096712 -236.090083) (xy 140.141244 -236.112773)
			(xy 140.181677 -236.142149) (xy 140.217017 -236.177489) (xy 140.246393 -236.217922) (xy 140.269083 -236.262454)
			(xy 140.284527 -236.309986) (xy 140.292346 -236.359349) (xy 140.292836 -236.384338) (xy 140.598647 -236.384338)
			(xy 140.602742 -236.33361) (xy 140.614921 -236.284196) (xy 140.634869 -236.237376) (xy 140.66207 -236.194362)
			(xy 140.695818 -236.156268) (xy 140.73524 -236.124081) (xy 140.779314 -236.098635) (xy 140.8269 -236.080588)
			(xy 140.876764 -236.070408) (xy 140.927616 -236.068359) (xy 140.978137 -236.074493) (xy 141.027021 -236.088653)
			(xy 141.073 -236.11047) (xy 141.114884 -236.13938) (xy 141.151588 -236.174635) (xy 141.182161 -236.215321)
			(xy 141.205812 -236.260384) (xy 141.221928 -236.308658) (xy 141.230092 -236.358892) (xy 141.230604 -236.384338)
			(xy 141.230101 -236.409327) (xy 141.537164 -236.409327) (xy 141.537164 -236.359349) (xy 141.544983 -236.309986)
			(xy 141.560427 -236.262454) (xy 141.583117 -236.217922) (xy 141.612493 -236.177489) (xy 141.647833 -236.142149)
			(xy 141.688266 -236.112773) (xy 141.732798 -236.090083) (xy 141.78033 -236.074639) (xy 141.829693 -236.06682)
			(xy 141.879671 -236.06682) (xy 141.929034 -236.074639) (xy 141.976566 -236.090083) (xy 142.021098 -236.112773)
			(xy 142.061531 -236.142149) (xy 142.096871 -236.177489) (xy 142.126247 -236.217922) (xy 142.148937 -236.262454)
			(xy 142.164381 -236.309986) (xy 142.1722 -236.359349) (xy 142.17269 -236.384338) (xy 142.478501 -236.384338)
			(xy 142.482596 -236.33361) (xy 142.494775 -236.284196) (xy 142.514723 -236.237376) (xy 142.541924 -236.194362)
			(xy 142.575672 -236.156268) (xy 142.615094 -236.124081) (xy 142.659168 -236.098635) (xy 142.706754 -236.080588)
			(xy 142.756618 -236.070408) (xy 142.80747 -236.068359) (xy 142.857991 -236.074493) (xy 142.906875 -236.088653)
			(xy 142.952854 -236.11047) (xy 142.994738 -236.13938) (xy 143.031442 -236.174635) (xy 143.062015 -236.215321)
			(xy 143.085666 -236.260384) (xy 143.101782 -236.308658) (xy 143.109946 -236.358892) (xy 143.110458 -236.384338)
			(xy 143.109955 -236.409327) (xy 143.417272 -236.409327) (xy 143.417272 -236.359349) (xy 143.425091 -236.309986)
			(xy 143.440535 -236.262454) (xy 143.463225 -236.217922) (xy 143.492601 -236.177489) (xy 143.527941 -236.142149)
			(xy 143.568374 -236.112773) (xy 143.612906 -236.090083) (xy 143.660438 -236.074639) (xy 143.709801 -236.06682)
			(xy 143.759779 -236.06682) (xy 143.809142 -236.074639) (xy 143.856674 -236.090083) (xy 143.901206 -236.112773)
			(xy 143.941639 -236.142149) (xy 143.976979 -236.177489) (xy 144.006355 -236.217922) (xy 144.029045 -236.262454)
			(xy 144.044489 -236.309986) (xy 144.052308 -236.359349) (xy 144.052798 -236.384338) (xy 144.052308 -236.409327)
			(xy 144.044489 -236.45869) (xy 144.029045 -236.506222) (xy 144.006355 -236.550754) (xy 143.976979 -236.591187)
			(xy 143.941639 -236.626527) (xy 143.901206 -236.655903) (xy 143.856674 -236.678593) (xy 143.809142 -236.694037)
			(xy 143.759779 -236.701856) (xy 143.709801 -236.701856) (xy 143.660438 -236.694037) (xy 143.612906 -236.678593)
			(xy 143.568374 -236.655903) (xy 143.527941 -236.626527) (xy 143.492601 -236.591187) (xy 143.463225 -236.550754)
			(xy 143.440535 -236.506222) (xy 143.425091 -236.45869) (xy 143.417272 -236.409327) (xy 143.109955 -236.409327)
			(xy 143.109946 -236.409784) (xy 143.101782 -236.460018) (xy 143.085666 -236.508292) (xy 143.062015 -236.553355)
			(xy 143.031442 -236.594041) (xy 142.994738 -236.629296) (xy 142.952854 -236.658206) (xy 142.906875 -236.680023)
			(xy 142.857991 -236.694183) (xy 142.80747 -236.700317) (xy 142.756618 -236.698268) (xy 142.706754 -236.688088)
			(xy 142.659168 -236.670041) (xy 142.615094 -236.644595) (xy 142.575672 -236.612408) (xy 142.541924 -236.574314)
			(xy 142.514723 -236.5313) (xy 142.494775 -236.48448) (xy 142.482596 -236.435066) (xy 142.478501 -236.384338)
			(xy 142.17269 -236.384338) (xy 142.1722 -236.409327) (xy 142.164381 -236.45869) (xy 142.148937 -236.506222)
			(xy 142.126247 -236.550754) (xy 142.096871 -236.591187) (xy 142.061531 -236.626527) (xy 142.021098 -236.655903)
			(xy 141.976566 -236.678593) (xy 141.929034 -236.694037) (xy 141.879671 -236.701856) (xy 141.829693 -236.701856)
			(xy 141.78033 -236.694037) (xy 141.732798 -236.678593) (xy 141.688266 -236.655903) (xy 141.647833 -236.626527)
			(xy 141.612493 -236.591187) (xy 141.583117 -236.550754) (xy 141.560427 -236.506222) (xy 141.544983 -236.45869)
			(xy 141.537164 -236.409327) (xy 141.230101 -236.409327) (xy 141.230092 -236.409784) (xy 141.221928 -236.460018)
			(xy 141.205812 -236.508292) (xy 141.182161 -236.553355) (xy 141.151588 -236.594041) (xy 141.114884 -236.629296)
			(xy 141.073 -236.658206) (xy 141.027021 -236.680023) (xy 140.978137 -236.694183) (xy 140.927616 -236.700317)
			(xy 140.876764 -236.698268) (xy 140.8269 -236.688088) (xy 140.779314 -236.670041) (xy 140.73524 -236.644595)
			(xy 140.695818 -236.612408) (xy 140.66207 -236.574314) (xy 140.634869 -236.5313) (xy 140.614921 -236.48448)
			(xy 140.602742 -236.435066) (xy 140.598647 -236.384338) (xy 140.292836 -236.384338) (xy 140.292346 -236.409327)
			(xy 140.284527 -236.45869) (xy 140.269083 -236.506222) (xy 140.246393 -236.550754) (xy 140.217017 -236.591187)
			(xy 140.181677 -236.626527) (xy 140.141244 -236.655903) (xy 140.096712 -236.678593) (xy 140.04918 -236.694037)
			(xy 139.999817 -236.701856) (xy 139.949839 -236.701856) (xy 139.900476 -236.694037) (xy 139.852944 -236.678593)
			(xy 139.808412 -236.655903) (xy 139.767979 -236.626527) (xy 139.732639 -236.591187) (xy 139.703263 -236.550754)
			(xy 139.680573 -236.506222) (xy 139.665129 -236.45869) (xy 139.65731 -236.409327) (xy 139.349993 -236.409327)
			(xy 139.349984 -236.409784) (xy 139.34182 -236.460018) (xy 139.325704 -236.508292) (xy 139.302053 -236.553355)
			(xy 139.27148 -236.594041) (xy 139.234776 -236.629296) (xy 139.192892 -236.658206) (xy 139.146913 -236.680023)
			(xy 139.098029 -236.694183) (xy 139.047508 -236.700317) (xy 138.996656 -236.698268) (xy 138.946792 -236.688088)
			(xy 138.899206 -236.670041) (xy 138.855132 -236.644595) (xy 138.81571 -236.612408) (xy 138.781962 -236.574314)
			(xy 138.754761 -236.5313) (xy 138.734813 -236.48448) (xy 138.722634 -236.435066) (xy 138.718539 -236.384338)
			(xy 138.410442 -236.384338) (xy 138.40993 -236.409784) (xy 138.401766 -236.460018) (xy 138.38565 -236.508292)
			(xy 138.361999 -236.553355) (xy 138.331426 -236.594041) (xy 138.294722 -236.629296) (xy 138.252838 -236.658206)
			(xy 138.206859 -236.680023) (xy 138.157975 -236.694183) (xy 138.107454 -236.700317) (xy 138.056602 -236.698268)
			(xy 138.006738 -236.688088) (xy 137.959152 -236.670041) (xy 137.915078 -236.644595) (xy 137.875656 -236.612408)
			(xy 137.841908 -236.574314) (xy 137.814707 -236.5313) (xy 137.794759 -236.48448) (xy 137.78258 -236.435066)
			(xy 137.778485 -236.384338) (xy 137.472674 -236.384338) (xy 137.472184 -236.409327) (xy 137.464365 -236.45869)
			(xy 137.448921 -236.506222) (xy 137.426231 -236.550754) (xy 137.396855 -236.591187) (xy 137.361515 -236.626527)
			(xy 137.321082 -236.655903) (xy 137.27655 -236.678593) (xy 137.229018 -236.694037) (xy 137.179655 -236.701856)
			(xy 137.129677 -236.701856) (xy 137.080314 -236.694037) (xy 137.032782 -236.678593) (xy 136.98825 -236.655903)
			(xy 136.947817 -236.626527) (xy 136.912477 -236.591187) (xy 136.883101 -236.550754) (xy 136.860411 -236.506222)
			(xy 136.844967 -236.45869) (xy 136.837148 -236.409327) (xy 136.530085 -236.409327) (xy 136.530076 -236.409784)
			(xy 136.521912 -236.460018) (xy 136.505796 -236.508292) (xy 136.482145 -236.553355) (xy 136.451572 -236.594041)
			(xy 136.414868 -236.629296) (xy 136.372984 -236.658206) (xy 136.327005 -236.680023) (xy 136.278121 -236.694183)
			(xy 136.2276 -236.700317) (xy 136.176748 -236.698268) (xy 136.126884 -236.688088) (xy 136.079298 -236.670041)
			(xy 136.035224 -236.644595) (xy 135.995802 -236.612408) (xy 135.962054 -236.574314) (xy 135.934853 -236.5313)
			(xy 135.914905 -236.48448) (xy 135.902726 -236.435066) (xy 135.898631 -236.384338) (xy 135.59282 -236.384338)
			(xy 135.59233 -236.409327) (xy 135.584511 -236.45869) (xy 135.569067 -236.506222) (xy 135.546377 -236.550754)
			(xy 135.517001 -236.591187) (xy 135.481661 -236.626527) (xy 135.441228 -236.655903) (xy 135.396696 -236.678593)
			(xy 135.349164 -236.694037) (xy 135.299801 -236.701856) (xy 135.249823 -236.701856) (xy 135.20046 -236.694037)
			(xy 135.152928 -236.678593) (xy 135.108396 -236.655903) (xy 135.067963 -236.626527) (xy 135.032623 -236.591187)
			(xy 135.003247 -236.550754) (xy 134.980557 -236.506222) (xy 134.965113 -236.45869) (xy 134.957294 -236.409327)
			(xy 134.649977 -236.409327) (xy 134.649968 -236.409784) (xy 134.641804 -236.460018) (xy 134.625688 -236.508292)
			(xy 134.602037 -236.553355) (xy 134.571464 -236.594041) (xy 134.53476 -236.629296) (xy 134.492876 -236.658206)
			(xy 134.446897 -236.680023) (xy 134.398013 -236.694183) (xy 134.347492 -236.700317) (xy 134.29664 -236.698268)
			(xy 134.246776 -236.688088) (xy 134.19919 -236.670041) (xy 134.155116 -236.644595) (xy 134.115694 -236.612408)
			(xy 134.081946 -236.574314) (xy 134.054745 -236.5313) (xy 134.034797 -236.48448) (xy 134.022618 -236.435066)
			(xy 134.018523 -236.384338) (xy 133.712712 -236.384338) (xy 133.712222 -236.409327) (xy 133.704403 -236.45869)
			(xy 133.688959 -236.506222) (xy 133.666269 -236.550754) (xy 133.636893 -236.591187) (xy 133.601553 -236.626527)
			(xy 133.56112 -236.655903) (xy 133.516588 -236.678593) (xy 133.469056 -236.694037) (xy 133.419693 -236.701856)
			(xy 133.369715 -236.701856) (xy 133.320352 -236.694037) (xy 133.27282 -236.678593) (xy 133.228288 -236.655903)
			(xy 133.187855 -236.626527) (xy 133.152515 -236.591187) (xy 133.123139 -236.550754) (xy 133.100449 -236.506222)
			(xy 133.085005 -236.45869) (xy 133.077186 -236.409327) (xy 132.769869 -236.409327) (xy 132.76986 -236.409784)
			(xy 132.761696 -236.460018) (xy 132.74558 -236.508292) (xy 132.721929 -236.553355) (xy 132.691356 -236.594041)
			(xy 132.654652 -236.629296) (xy 132.612768 -236.658206) (xy 132.566789 -236.680023) (xy 132.517905 -236.694183)
			(xy 132.467384 -236.700317) (xy 132.416532 -236.698268) (xy 132.366668 -236.688088) (xy 132.319082 -236.670041)
			(xy 132.275008 -236.644595) (xy 132.235586 -236.612408) (xy 132.201838 -236.574314) (xy 132.174637 -236.5313)
			(xy 132.154689 -236.48448) (xy 132.14251 -236.435066) (xy 132.138415 -236.384338) (xy 131.830572 -236.384338)
			(xy 131.83006 -236.409784) (xy 131.821896 -236.460018) (xy 131.80578 -236.508292) (xy 131.782129 -236.553355)
			(xy 131.751556 -236.594041) (xy 131.714852 -236.629296) (xy 131.672968 -236.658206) (xy 131.626989 -236.680023)
			(xy 131.578105 -236.694183) (xy 131.527584 -236.700317) (xy 131.476732 -236.698268) (xy 131.426868 -236.688088)
			(xy 131.379282 -236.670041) (xy 131.335208 -236.644595) (xy 131.295786 -236.612408) (xy 131.262038 -236.574314)
			(xy 131.234837 -236.5313) (xy 131.214889 -236.48448) (xy 131.20271 -236.435066) (xy 131.198615 -236.384338)
			(xy 130.892804 -236.384338) (xy 130.892314 -236.409327) (xy 130.884495 -236.45869) (xy 130.869051 -236.506222)
			(xy 130.846361 -236.550754) (xy 130.816985 -236.591187) (xy 130.781645 -236.626527) (xy 130.741212 -236.655903)
			(xy 130.69668 -236.678593) (xy 130.649148 -236.694037) (xy 130.599785 -236.701856) (xy 130.549807 -236.701856)
			(xy 130.500444 -236.694037) (xy 130.452912 -236.678593) (xy 130.40838 -236.655903) (xy 130.367947 -236.626527)
			(xy 130.332607 -236.591187) (xy 130.303231 -236.550754) (xy 130.280541 -236.506222) (xy 130.265097 -236.45869)
			(xy 130.257278 -236.409327) (xy 129.949961 -236.409327) (xy 129.949952 -236.409784) (xy 129.941788 -236.460018)
			(xy 129.925672 -236.508292) (xy 129.902021 -236.553355) (xy 129.871448 -236.594041) (xy 129.834744 -236.629296)
			(xy 129.79286 -236.658206) (xy 129.746881 -236.680023) (xy 129.697997 -236.694183) (xy 129.647476 -236.700317)
			(xy 129.596624 -236.698268) (xy 129.54676 -236.688088) (xy 129.499174 -236.670041) (xy 129.4551 -236.644595)
			(xy 129.415678 -236.612408) (xy 129.38193 -236.574314) (xy 129.354729 -236.5313) (xy 129.334781 -236.48448)
			(xy 129.322602 -236.435066) (xy 129.318507 -236.384338) (xy 129.012696 -236.384338) (xy 129.012206 -236.409327)
			(xy 129.004387 -236.45869) (xy 128.988943 -236.506222) (xy 128.966253 -236.550754) (xy 128.936877 -236.591187)
			(xy 128.901537 -236.626527) (xy 128.861104 -236.655903) (xy 128.816572 -236.678593) (xy 128.76904 -236.694037)
			(xy 128.719677 -236.701856) (xy 128.669699 -236.701856) (xy 128.620336 -236.694037) (xy 128.572804 -236.678593)
			(xy 128.528272 -236.655903) (xy 128.487839 -236.626527) (xy 128.452499 -236.591187) (xy 128.423123 -236.550754)
			(xy 128.400433 -236.506222) (xy 128.384989 -236.45869) (xy 128.37717 -236.409327) (xy 128.069853 -236.409327)
			(xy 128.069844 -236.409784) (xy 128.06168 -236.460018) (xy 128.045564 -236.508292) (xy 128.021913 -236.553355)
			(xy 127.99134 -236.594041) (xy 127.954636 -236.629296) (xy 127.912752 -236.658206) (xy 127.866773 -236.680023)
			(xy 127.817889 -236.694183) (xy 127.767368 -236.700317) (xy 127.716516 -236.698268) (xy 127.666652 -236.688088)
			(xy 127.619066 -236.670041) (xy 127.574992 -236.644595) (xy 127.53557 -236.612408) (xy 127.501822 -236.574314)
			(xy 127.474621 -236.5313) (xy 127.454673 -236.48448) (xy 127.442494 -236.435066) (xy 127.438399 -236.384338)
			(xy 127.13228 -236.384338) (xy 127.13228 -236.409285) (xy 127.124464 -236.458638) (xy 127.109023 -236.506162)
			(xy 127.086339 -236.550686) (xy 127.05697 -236.591113) (xy 127.021638 -236.626448) (xy 126.981215 -236.655822)
			(xy 126.936694 -236.67851) (xy 126.889171 -236.693956) (xy 126.839818 -236.701777) (xy 126.814834 -236.702346)
			(xy 126.8024 -236.702248) (xy 126.777607 -236.700338) (xy 126.765304 -236.698536) (xy 126.763526 -236.698282)
			(xy 126.75616 -236.697774) (xy 126.747781 -236.698201) (xy 126.731969 -236.703777) (xy 126.725172 -236.708696)
			(xy 126.701042 -236.729016) (xy 126.700534 -236.729524) (xy 126.666244 -236.758988) (xy 126.658714 -236.766055)
			(xy 126.64953 -236.784531) (xy 126.648464 -236.794802) (xy 126.648464 -237.092236) (xy 126.648972 -237.095792)
			(xy 126.650496 -237.106714) (xy 126.651004 -237.108746) (xy 126.651512 -237.11027) (xy 126.656771 -237.130888)
			(xy 126.662372 -237.173068) (xy 126.662688 -237.194344) (xy 126.662434 -237.20806) (xy 126.661799 -237.219333)
			(xy 126.967216 -237.219333) (xy 126.967216 -237.169355) (xy 126.975035 -237.119992) (xy 126.990479 -237.07246)
			(xy 127.013169 -237.027928) (xy 127.042545 -236.987495) (xy 127.077885 -236.952155) (xy 127.118318 -236.922779)
			(xy 127.16285 -236.900089) (xy 127.210382 -236.884645) (xy 127.259745 -236.876826) (xy 127.309723 -236.876826)
			(xy 127.359086 -236.884645) (xy 127.406618 -236.900089) (xy 127.45115 -236.922779) (xy 127.491583 -236.952155)
			(xy 127.526923 -236.987495) (xy 127.556299 -237.027928) (xy 127.578989 -237.07246) (xy 127.594433 -237.119992)
			(xy 127.602252 -237.169355) (xy 127.602742 -237.194344) (xy 127.908553 -237.194344) (xy 127.912648 -237.143616)
			(xy 127.924827 -237.094202) (xy 127.944775 -237.047382) (xy 127.971976 -237.004368) (xy 128.005724 -236.966274)
			(xy 128.045146 -236.934087) (xy 128.08922 -236.908641) (xy 128.136806 -236.890594) (xy 128.18667 -236.880414)
			(xy 128.237522 -236.878365) (xy 128.288043 -236.884499) (xy 128.336927 -236.898659) (xy 128.382906 -236.920476)
			(xy 128.42479 -236.949386) (xy 128.461494 -236.984641) (xy 128.492067 -237.025327) (xy 128.515718 -237.07039)
			(xy 128.531834 -237.118664) (xy 128.539998 -237.168898) (xy 128.54051 -237.194344) (xy 128.848607 -237.194344)
			(xy 128.852702 -237.143616) (xy 128.864881 -237.094202) (xy 128.884829 -237.047382) (xy 128.91203 -237.004368)
			(xy 128.945778 -236.966274) (xy 128.9852 -236.934087) (xy 129.029274 -236.908641) (xy 129.07686 -236.890594)
			(xy 129.126724 -236.880414) (xy 129.177576 -236.878365) (xy 129.228097 -236.884499) (xy 129.276981 -236.898659)
			(xy 129.32296 -236.920476) (xy 129.364844 -236.949386) (xy 129.401548 -236.984641) (xy 129.432121 -237.025327)
			(xy 129.455772 -237.07039) (xy 129.471888 -237.118664) (xy 129.480052 -237.168898) (xy 129.480564 -237.194344)
			(xy 130.728461 -237.194344) (xy 130.732556 -237.143616) (xy 130.744735 -237.094202) (xy 130.764683 -237.047382)
			(xy 130.791884 -237.004368) (xy 130.825632 -236.966274) (xy 130.865054 -236.934087) (xy 130.909128 -236.908641)
			(xy 130.956714 -236.890594) (xy 131.006578 -236.880414) (xy 131.05743 -236.878365) (xy 131.107951 -236.884499)
			(xy 131.156835 -236.898659) (xy 131.202814 -236.920476) (xy 131.244698 -236.949386) (xy 131.281402 -236.984641)
			(xy 131.311975 -237.025327) (xy 131.335626 -237.07039) (xy 131.351742 -237.118664) (xy 131.359906 -237.168898)
			(xy 131.360418 -237.194344) (xy 131.359915 -237.219333) (xy 131.667232 -237.219333) (xy 131.667232 -237.169355)
			(xy 131.675051 -237.119992) (xy 131.690495 -237.07246) (xy 131.713185 -237.027928) (xy 131.742561 -236.987495)
			(xy 131.777901 -236.952155) (xy 131.818334 -236.922779) (xy 131.862866 -236.900089) (xy 131.910398 -236.884645)
			(xy 131.959761 -236.876826) (xy 132.009739 -236.876826) (xy 132.059102 -236.884645) (xy 132.106634 -236.900089)
			(xy 132.151166 -236.922779) (xy 132.191599 -236.952155) (xy 132.226939 -236.987495) (xy 132.256315 -237.027928)
			(xy 132.279005 -237.07246) (xy 132.294449 -237.119992) (xy 132.302268 -237.169355) (xy 132.302758 -237.194344)
			(xy 132.608569 -237.194344) (xy 132.612664 -237.143616) (xy 132.624843 -237.094202) (xy 132.644791 -237.047382)
			(xy 132.671992 -237.004368) (xy 132.70574 -236.966274) (xy 132.745162 -236.934087) (xy 132.789236 -236.908641)
			(xy 132.836822 -236.890594) (xy 132.886686 -236.880414) (xy 132.937538 -236.878365) (xy 132.988059 -236.884499)
			(xy 133.036943 -236.898659) (xy 133.082922 -236.920476) (xy 133.124806 -236.949386) (xy 133.16151 -236.984641)
			(xy 133.192083 -237.025327) (xy 133.215734 -237.07039) (xy 133.23185 -237.118664) (xy 133.240014 -237.168898)
			(xy 133.240526 -237.194344) (xy 133.240023 -237.219333) (xy 133.54734 -237.219333) (xy 133.54734 -237.169355)
			(xy 133.555159 -237.119992) (xy 133.570603 -237.07246) (xy 133.593293 -237.027928) (xy 133.622669 -236.987495)
			(xy 133.658009 -236.952155) (xy 133.698442 -236.922779) (xy 133.742974 -236.900089) (xy 133.790506 -236.884645)
			(xy 133.839869 -236.876826) (xy 133.889847 -236.876826) (xy 133.93921 -236.884645) (xy 133.986742 -236.900089)
			(xy 134.031274 -236.922779) (xy 134.071707 -236.952155) (xy 134.107047 -236.987495) (xy 134.136423 -237.027928)
			(xy 134.159113 -237.07246) (xy 134.174557 -237.119992) (xy 134.182376 -237.169355) (xy 134.182866 -237.194344)
			(xy 134.488423 -237.194344) (xy 134.492518 -237.143616) (xy 134.504697 -237.094202) (xy 134.524645 -237.047382)
			(xy 134.551846 -237.004368) (xy 134.585594 -236.966274) (xy 134.625016 -236.934087) (xy 134.66909 -236.908641)
			(xy 134.716676 -236.890594) (xy 134.76654 -236.880414) (xy 134.817392 -236.878365) (xy 134.867913 -236.884499)
			(xy 134.916797 -236.898659) (xy 134.962776 -236.920476) (xy 135.00466 -236.949386) (xy 135.041364 -236.984641)
			(xy 135.071937 -237.025327) (xy 135.095588 -237.07039) (xy 135.111704 -237.118664) (xy 135.119868 -237.168898)
			(xy 135.12038 -237.194344) (xy 135.428477 -237.194344) (xy 135.432572 -237.143616) (xy 135.444751 -237.094202)
			(xy 135.464699 -237.047382) (xy 135.4919 -237.004368) (xy 135.525648 -236.966274) (xy 135.56507 -236.934087)
			(xy 135.609144 -236.908641) (xy 135.65673 -236.890594) (xy 135.706594 -236.880414) (xy 135.757446 -236.878365)
			(xy 135.807967 -236.884499) (xy 135.856851 -236.898659) (xy 135.90283 -236.920476) (xy 135.944714 -236.949386)
			(xy 135.981418 -236.984641) (xy 136.011991 -237.025327) (xy 136.035642 -237.07039) (xy 136.051758 -237.118664)
			(xy 136.059922 -237.168898) (xy 136.060434 -237.194344) (xy 137.308585 -237.194344) (xy 137.31268 -237.143616)
			(xy 137.324859 -237.094202) (xy 137.344807 -237.047382) (xy 137.372008 -237.004368) (xy 137.405756 -236.966274)
			(xy 137.445178 -236.934087) (xy 137.489252 -236.908641) (xy 137.536838 -236.890594) (xy 137.586702 -236.880414)
			(xy 137.637554 -236.878365) (xy 137.688075 -236.884499) (xy 137.736959 -236.898659) (xy 137.782938 -236.920476)
			(xy 137.824822 -236.949386) (xy 137.861526 -236.984641) (xy 137.892099 -237.025327) (xy 137.91575 -237.07039)
			(xy 137.931866 -237.118664) (xy 137.94003 -237.168898) (xy 137.940542 -237.194344) (xy 137.940039 -237.219333)
			(xy 138.247356 -237.219333) (xy 138.247356 -237.169355) (xy 138.255175 -237.119992) (xy 138.270619 -237.07246)
			(xy 138.293309 -237.027928) (xy 138.322685 -236.987495) (xy 138.358025 -236.952155) (xy 138.398458 -236.922779)
			(xy 138.44299 -236.900089) (xy 138.490522 -236.884645) (xy 138.539885 -236.876826) (xy 138.589863 -236.876826)
			(xy 138.639226 -236.884645) (xy 138.686758 -236.900089) (xy 138.73129 -236.922779) (xy 138.771723 -236.952155)
			(xy 138.807063 -236.987495) (xy 138.836439 -237.027928) (xy 138.859129 -237.07246) (xy 138.874573 -237.119992)
			(xy 138.882392 -237.169355) (xy 138.882882 -237.194344) (xy 139.188439 -237.194344) (xy 139.192534 -237.143616)
			(xy 139.204713 -237.094202) (xy 139.224661 -237.047382) (xy 139.251862 -237.004368) (xy 139.28561 -236.966274)
			(xy 139.325032 -236.934087) (xy 139.369106 -236.908641) (xy 139.416692 -236.890594) (xy 139.466556 -236.880414)
			(xy 139.517408 -236.878365) (xy 139.567929 -236.884499) (xy 139.616813 -236.898659) (xy 139.662792 -236.920476)
			(xy 139.704676 -236.949386) (xy 139.74138 -236.984641) (xy 139.771953 -237.025327) (xy 139.795604 -237.07039)
			(xy 139.81172 -237.118664) (xy 139.819884 -237.168898) (xy 139.820396 -237.194344) (xy 139.819893 -237.219333)
			(xy 140.12721 -237.219333) (xy 140.12721 -237.169355) (xy 140.135029 -237.119992) (xy 140.150473 -237.07246)
			(xy 140.173163 -237.027928) (xy 140.202539 -236.987495) (xy 140.237879 -236.952155) (xy 140.278312 -236.922779)
			(xy 140.322844 -236.900089) (xy 140.370376 -236.884645) (xy 140.419739 -236.876826) (xy 140.469717 -236.876826)
			(xy 140.51908 -236.884645) (xy 140.566612 -236.900089) (xy 140.611144 -236.922779) (xy 140.651577 -236.952155)
			(xy 140.686917 -236.987495) (xy 140.716293 -237.027928) (xy 140.738983 -237.07246) (xy 140.754427 -237.119992)
			(xy 140.762246 -237.169355) (xy 140.762736 -237.194344) (xy 141.068547 -237.194344) (xy 141.072642 -237.143616)
			(xy 141.084821 -237.094202) (xy 141.104769 -237.047382) (xy 141.13197 -237.004368) (xy 141.165718 -236.966274)
			(xy 141.20514 -236.934087) (xy 141.249214 -236.908641) (xy 141.2968 -236.890594) (xy 141.346664 -236.880414)
			(xy 141.397516 -236.878365) (xy 141.448037 -236.884499) (xy 141.496921 -236.898659) (xy 141.5429 -236.920476)
			(xy 141.584784 -236.949386) (xy 141.621488 -236.984641) (xy 141.652061 -237.025327) (xy 141.675712 -237.07039)
			(xy 141.691828 -237.118664) (xy 141.699992 -237.168898) (xy 141.700504 -237.194344) (xy 142.008601 -237.194344)
			(xy 142.012696 -237.143616) (xy 142.024875 -237.094202) (xy 142.044823 -237.047382) (xy 142.072024 -237.004368)
			(xy 142.105772 -236.966274) (xy 142.145194 -236.934087) (xy 142.189268 -236.908641) (xy 142.236854 -236.890594)
			(xy 142.286718 -236.880414) (xy 142.33757 -236.878365) (xy 142.388091 -236.884499) (xy 142.436975 -236.898659)
			(xy 142.482954 -236.920476) (xy 142.524838 -236.949386) (xy 142.561542 -236.984641) (xy 142.592115 -237.025327)
			(xy 142.615766 -237.07039) (xy 142.631882 -237.118664) (xy 142.640046 -237.168898) (xy 142.640558 -237.194344)
			(xy 142.640046 -237.21979) (xy 142.631882 -237.270024) (xy 142.615766 -237.318298) (xy 142.592115 -237.363361)
			(xy 142.561542 -237.404047) (xy 142.524838 -237.439302) (xy 142.482954 -237.468212) (xy 142.436975 -237.490029)
			(xy 142.388091 -237.504189) (xy 142.33757 -237.510323) (xy 142.286718 -237.508274) (xy 142.236854 -237.498094)
			(xy 142.189268 -237.480047) (xy 142.145194 -237.454601) (xy 142.105772 -237.422414) (xy 142.072024 -237.38432)
			(xy 142.044823 -237.341306) (xy 142.024875 -237.294486) (xy 142.012696 -237.245072) (xy 142.008601 -237.194344)
			(xy 141.700504 -237.194344) (xy 141.699992 -237.21979) (xy 141.691828 -237.270024) (xy 141.675712 -237.318298)
			(xy 141.652061 -237.363361) (xy 141.621488 -237.404047) (xy 141.584784 -237.439302) (xy 141.5429 -237.468212)
			(xy 141.496921 -237.490029) (xy 141.448037 -237.504189) (xy 141.397516 -237.510323) (xy 141.346664 -237.508274)
			(xy 141.2968 -237.498094) (xy 141.249214 -237.480047) (xy 141.20514 -237.454601) (xy 141.165718 -237.422414)
			(xy 141.13197 -237.38432) (xy 141.104769 -237.341306) (xy 141.084821 -237.294486) (xy 141.072642 -237.245072)
			(xy 141.068547 -237.194344) (xy 140.762736 -237.194344) (xy 140.762246 -237.219333) (xy 140.754427 -237.268696)
			(xy 140.738983 -237.316228) (xy 140.716293 -237.36076) (xy 140.686917 -237.401193) (xy 140.651577 -237.436533)
			(xy 140.611144 -237.465909) (xy 140.566612 -237.488599) (xy 140.51908 -237.504043) (xy 140.469717 -237.511862)
			(xy 140.419739 -237.511862) (xy 140.370376 -237.504043) (xy 140.322844 -237.488599) (xy 140.278312 -237.465909)
			(xy 140.237879 -237.436533) (xy 140.202539 -237.401193) (xy 140.173163 -237.36076) (xy 140.150473 -237.316228)
			(xy 140.135029 -237.268696) (xy 140.12721 -237.219333) (xy 139.819893 -237.219333) (xy 139.819884 -237.21979)
			(xy 139.81172 -237.270024) (xy 139.795604 -237.318298) (xy 139.771953 -237.363361) (xy 139.74138 -237.404047)
			(xy 139.704676 -237.439302) (xy 139.662792 -237.468212) (xy 139.616813 -237.490029) (xy 139.567929 -237.504189)
			(xy 139.517408 -237.510323) (xy 139.466556 -237.508274) (xy 139.416692 -237.498094) (xy 139.369106 -237.480047)
			(xy 139.325032 -237.454601) (xy 139.28561 -237.422414) (xy 139.251862 -237.38432) (xy 139.224661 -237.341306)
			(xy 139.204713 -237.294486) (xy 139.192534 -237.245072) (xy 139.188439 -237.194344) (xy 138.882882 -237.194344)
			(xy 138.882392 -237.219333) (xy 138.874573 -237.268696) (xy 138.859129 -237.316228) (xy 138.836439 -237.36076)
			(xy 138.807063 -237.401193) (xy 138.771723 -237.436533) (xy 138.73129 -237.465909) (xy 138.686758 -237.488599)
			(xy 138.639226 -237.504043) (xy 138.589863 -237.511862) (xy 138.539885 -237.511862) (xy 138.490522 -237.504043)
			(xy 138.44299 -237.488599) (xy 138.398458 -237.465909) (xy 138.358025 -237.436533) (xy 138.322685 -237.401193)
			(xy 138.293309 -237.36076) (xy 138.270619 -237.316228) (xy 138.255175 -237.268696) (xy 138.247356 -237.219333)
			(xy 137.940039 -237.219333) (xy 137.94003 -237.21979) (xy 137.931866 -237.270024) (xy 137.91575 -237.318298)
			(xy 137.892099 -237.363361) (xy 137.861526 -237.404047) (xy 137.824822 -237.439302) (xy 137.782938 -237.468212)
			(xy 137.736959 -237.490029) (xy 137.688075 -237.504189) (xy 137.637554 -237.510323) (xy 137.586702 -237.508274)
			(xy 137.536838 -237.498094) (xy 137.489252 -237.480047) (xy 137.445178 -237.454601) (xy 137.405756 -237.422414)
			(xy 137.372008 -237.38432) (xy 137.344807 -237.341306) (xy 137.324859 -237.294486) (xy 137.31268 -237.245072)
			(xy 137.308585 -237.194344) (xy 136.060434 -237.194344) (xy 136.059922 -237.21979) (xy 136.051758 -237.270024)
			(xy 136.035642 -237.318298) (xy 136.011991 -237.363361) (xy 135.981418 -237.404047) (xy 135.944714 -237.439302)
			(xy 135.90283 -237.468212) (xy 135.856851 -237.490029) (xy 135.807967 -237.504189) (xy 135.757446 -237.510323)
			(xy 135.706594 -237.508274) (xy 135.65673 -237.498094) (xy 135.609144 -237.480047) (xy 135.56507 -237.454601)
			(xy 135.525648 -237.422414) (xy 135.4919 -237.38432) (xy 135.464699 -237.341306) (xy 135.444751 -237.294486)
			(xy 135.432572 -237.245072) (xy 135.428477 -237.194344) (xy 135.12038 -237.194344) (xy 135.119868 -237.21979)
			(xy 135.111704 -237.270024) (xy 135.095588 -237.318298) (xy 135.071937 -237.363361) (xy 135.041364 -237.404047)
			(xy 135.00466 -237.439302) (xy 134.962776 -237.468212) (xy 134.916797 -237.490029) (xy 134.867913 -237.504189)
			(xy 134.817392 -237.510323) (xy 134.76654 -237.508274) (xy 134.716676 -237.498094) (xy 134.66909 -237.480047)
			(xy 134.625016 -237.454601) (xy 134.585594 -237.422414) (xy 134.551846 -237.38432) (xy 134.524645 -237.341306)
			(xy 134.504697 -237.294486) (xy 134.492518 -237.245072) (xy 134.488423 -237.194344) (xy 134.182866 -237.194344)
			(xy 134.182376 -237.219333) (xy 134.174557 -237.268696) (xy 134.159113 -237.316228) (xy 134.136423 -237.36076)
			(xy 134.107047 -237.401193) (xy 134.071707 -237.436533) (xy 134.031274 -237.465909) (xy 133.986742 -237.488599)
			(xy 133.93921 -237.504043) (xy 133.889847 -237.511862) (xy 133.839869 -237.511862) (xy 133.790506 -237.504043)
			(xy 133.742974 -237.488599) (xy 133.698442 -237.465909) (xy 133.658009 -237.436533) (xy 133.622669 -237.401193)
			(xy 133.593293 -237.36076) (xy 133.570603 -237.316228) (xy 133.555159 -237.268696) (xy 133.54734 -237.219333)
			(xy 133.240023 -237.219333) (xy 133.240014 -237.21979) (xy 133.23185 -237.270024) (xy 133.215734 -237.318298)
			(xy 133.192083 -237.363361) (xy 133.16151 -237.404047) (xy 133.124806 -237.439302) (xy 133.082922 -237.468212)
			(xy 133.036943 -237.490029) (xy 132.988059 -237.504189) (xy 132.937538 -237.510323) (xy 132.886686 -237.508274)
			(xy 132.836822 -237.498094) (xy 132.789236 -237.480047) (xy 132.745162 -237.454601) (xy 132.70574 -237.422414)
			(xy 132.671992 -237.38432) (xy 132.644791 -237.341306) (xy 132.624843 -237.294486) (xy 132.612664 -237.245072)
			(xy 132.608569 -237.194344) (xy 132.302758 -237.194344) (xy 132.302268 -237.219333) (xy 132.294449 -237.268696)
			(xy 132.279005 -237.316228) (xy 132.256315 -237.36076) (xy 132.226939 -237.401193) (xy 132.191599 -237.436533)
			(xy 132.151166 -237.465909) (xy 132.106634 -237.488599) (xy 132.059102 -237.504043) (xy 132.009739 -237.511862)
			(xy 131.959761 -237.511862) (xy 131.910398 -237.504043) (xy 131.862866 -237.488599) (xy 131.818334 -237.465909)
			(xy 131.777901 -237.436533) (xy 131.742561 -237.401193) (xy 131.713185 -237.36076) (xy 131.690495 -237.316228)
			(xy 131.675051 -237.268696) (xy 131.667232 -237.219333) (xy 131.359915 -237.219333) (xy 131.359906 -237.21979)
			(xy 131.351742 -237.270024) (xy 131.335626 -237.318298) (xy 131.311975 -237.363361) (xy 131.281402 -237.404047)
			(xy 131.244698 -237.439302) (xy 131.202814 -237.468212) (xy 131.156835 -237.490029) (xy 131.107951 -237.504189)
			(xy 131.05743 -237.510323) (xy 131.006578 -237.508274) (xy 130.956714 -237.498094) (xy 130.909128 -237.480047)
			(xy 130.865054 -237.454601) (xy 130.825632 -237.422414) (xy 130.791884 -237.38432) (xy 130.764683 -237.341306)
			(xy 130.744735 -237.294486) (xy 130.732556 -237.245072) (xy 130.728461 -237.194344) (xy 129.480564 -237.194344)
			(xy 129.480052 -237.21979) (xy 129.471888 -237.270024) (xy 129.455772 -237.318298) (xy 129.432121 -237.363361)
			(xy 129.401548 -237.404047) (xy 129.364844 -237.439302) (xy 129.32296 -237.468212) (xy 129.276981 -237.490029)
			(xy 129.228097 -237.504189) (xy 129.177576 -237.510323) (xy 129.126724 -237.508274) (xy 129.07686 -237.498094)
			(xy 129.029274 -237.480047) (xy 128.9852 -237.454601) (xy 128.945778 -237.422414) (xy 128.91203 -237.38432)
			(xy 128.884829 -237.341306) (xy 128.864881 -237.294486) (xy 128.852702 -237.245072) (xy 128.848607 -237.194344)
			(xy 128.54051 -237.194344) (xy 128.539998 -237.21979) (xy 128.531834 -237.270024) (xy 128.515718 -237.318298)
			(xy 128.492067 -237.363361) (xy 128.461494 -237.404047) (xy 128.42479 -237.439302) (xy 128.382906 -237.468212)
			(xy 128.336927 -237.490029) (xy 128.288043 -237.504189) (xy 128.237522 -237.510323) (xy 128.18667 -237.508274)
			(xy 128.136806 -237.498094) (xy 128.08922 -237.480047) (xy 128.045146 -237.454601) (xy 128.005724 -237.422414)
			(xy 127.971976 -237.38432) (xy 127.944775 -237.341306) (xy 127.924827 -237.294486) (xy 127.912648 -237.245072)
			(xy 127.908553 -237.194344) (xy 127.602742 -237.194344) (xy 127.602252 -237.219333) (xy 127.594433 -237.268696)
			(xy 127.578989 -237.316228) (xy 127.556299 -237.36076) (xy 127.526923 -237.401193) (xy 127.491583 -237.436533)
			(xy 127.45115 -237.465909) (xy 127.406618 -237.488599) (xy 127.359086 -237.504043) (xy 127.309723 -237.511862)
			(xy 127.259745 -237.511862) (xy 127.210382 -237.504043) (xy 127.16285 -237.488599) (xy 127.118318 -237.465909)
			(xy 127.077885 -237.436533) (xy 127.042545 -237.401193) (xy 127.013169 -237.36076) (xy 126.990479 -237.316228)
			(xy 126.975035 -237.268696) (xy 126.967216 -237.219333) (xy 126.661799 -237.219333) (xy 126.661375 -237.226862)
			(xy 126.655395 -237.264045) (xy 126.650496 -237.282228) (xy 126.648464 -237.289086) (xy 126.648464 -238.00435)
			(xy 127.438399 -238.00435) (xy 127.442494 -237.953622) (xy 127.454673 -237.904208) (xy 127.474621 -237.857388)
			(xy 127.501822 -237.814374) (xy 127.53557 -237.77628) (xy 127.574992 -237.744093) (xy 127.619066 -237.718647)
			(xy 127.666652 -237.7006) (xy 127.716516 -237.69042) (xy 127.767368 -237.688371) (xy 127.817889 -237.694505)
			(xy 127.866773 -237.708665) (xy 127.912752 -237.730482) (xy 127.954636 -237.759392) (xy 127.99134 -237.794647)
			(xy 128.021913 -237.835333) (xy 128.045564 -237.880396) (xy 128.06168 -237.92867) (xy 128.069844 -237.978904)
			(xy 128.070356 -238.00435) (xy 128.069853 -238.029339) (xy 128.37717 -238.029339) (xy 128.37717 -237.979361)
			(xy 128.384989 -237.929998) (xy 128.400433 -237.882466) (xy 128.423123 -237.837934) (xy 128.452499 -237.797501)
			(xy 128.487839 -237.762161) (xy 128.528272 -237.732785) (xy 128.572804 -237.710095) (xy 128.620336 -237.694651)
			(xy 128.669699 -237.686832) (xy 128.719677 -237.686832) (xy 128.76904 -237.694651) (xy 128.816572 -237.710095)
			(xy 128.861104 -237.732785) (xy 128.901537 -237.762161) (xy 128.936877 -237.797501) (xy 128.966253 -237.837934)
			(xy 128.988943 -237.882466) (xy 129.004387 -237.929998) (xy 129.012206 -237.979361) (xy 129.012696 -238.00435)
			(xy 129.318507 -238.00435) (xy 129.322602 -237.953622) (xy 129.334781 -237.904208) (xy 129.354729 -237.857388)
			(xy 129.38193 -237.814374) (xy 129.415678 -237.77628) (xy 129.4551 -237.744093) (xy 129.499174 -237.718647)
			(xy 129.54676 -237.7006) (xy 129.596624 -237.69042) (xy 129.647476 -237.688371) (xy 129.697997 -237.694505)
			(xy 129.746881 -237.708665) (xy 129.79286 -237.730482) (xy 129.834744 -237.759392) (xy 129.871448 -237.794647)
			(xy 129.902021 -237.835333) (xy 129.925672 -237.880396) (xy 129.941788 -237.92867) (xy 129.949952 -237.978904)
			(xy 129.950464 -238.00435) (xy 129.949961 -238.029339) (xy 130.257278 -238.029339) (xy 130.257278 -237.979361)
			(xy 130.265097 -237.929998) (xy 130.280541 -237.882466) (xy 130.303231 -237.837934) (xy 130.332607 -237.797501)
			(xy 130.367947 -237.762161) (xy 130.40838 -237.732785) (xy 130.452912 -237.710095) (xy 130.500444 -237.694651)
			(xy 130.549807 -237.686832) (xy 130.599785 -237.686832) (xy 130.649148 -237.694651) (xy 130.69668 -237.710095)
			(xy 130.741212 -237.732785) (xy 130.781645 -237.762161) (xy 130.816985 -237.797501) (xy 130.846361 -237.837934)
			(xy 130.869051 -237.882466) (xy 130.884495 -237.929998) (xy 130.892314 -237.979361) (xy 130.892804 -238.00435)
			(xy 131.198615 -238.00435) (xy 131.20271 -237.953622) (xy 131.214889 -237.904208) (xy 131.234837 -237.857388)
			(xy 131.262038 -237.814374) (xy 131.295786 -237.77628) (xy 131.335208 -237.744093) (xy 131.379282 -237.718647)
			(xy 131.426868 -237.7006) (xy 131.476732 -237.69042) (xy 131.527584 -237.688371) (xy 131.578105 -237.694505)
			(xy 131.626989 -237.708665) (xy 131.672968 -237.730482) (xy 131.714852 -237.759392) (xy 131.751556 -237.794647)
			(xy 131.782129 -237.835333) (xy 131.80578 -237.880396) (xy 131.821896 -237.92867) (xy 131.83006 -237.978904)
			(xy 131.830572 -238.00435) (xy 132.138415 -238.00435) (xy 132.14251 -237.953622) (xy 132.154689 -237.904208)
			(xy 132.174637 -237.857388) (xy 132.201838 -237.814374) (xy 132.235586 -237.77628) (xy 132.275008 -237.744093)
			(xy 132.319082 -237.718647) (xy 132.366668 -237.7006) (xy 132.416532 -237.69042) (xy 132.467384 -237.688371)
			(xy 132.517905 -237.694505) (xy 132.566789 -237.708665) (xy 132.612768 -237.730482) (xy 132.654652 -237.759392)
			(xy 132.691356 -237.794647) (xy 132.721929 -237.835333) (xy 132.74558 -237.880396) (xy 132.761696 -237.92867)
			(xy 132.76986 -237.978904) (xy 132.770372 -238.00435) (xy 132.769869 -238.029339) (xy 133.077186 -238.029339)
			(xy 133.077186 -237.979361) (xy 133.085005 -237.929998) (xy 133.100449 -237.882466) (xy 133.123139 -237.837934)
			(xy 133.152515 -237.797501) (xy 133.187855 -237.762161) (xy 133.228288 -237.732785) (xy 133.27282 -237.710095)
			(xy 133.320352 -237.694651) (xy 133.369715 -237.686832) (xy 133.419693 -237.686832) (xy 133.469056 -237.694651)
			(xy 133.516588 -237.710095) (xy 133.56112 -237.732785) (xy 133.601553 -237.762161) (xy 133.636893 -237.797501)
			(xy 133.666269 -237.837934) (xy 133.688959 -237.882466) (xy 133.704403 -237.929998) (xy 133.712222 -237.979361)
			(xy 133.712712 -238.00435) (xy 134.018523 -238.00435) (xy 134.022618 -237.953622) (xy 134.034797 -237.904208)
			(xy 134.054745 -237.857388) (xy 134.081946 -237.814374) (xy 134.115694 -237.77628) (xy 134.155116 -237.744093)
			(xy 134.19919 -237.718647) (xy 134.246776 -237.7006) (xy 134.29664 -237.69042) (xy 134.347492 -237.688371)
			(xy 134.398013 -237.694505) (xy 134.446897 -237.708665) (xy 134.492876 -237.730482) (xy 134.53476 -237.759392)
			(xy 134.571464 -237.794647) (xy 134.602037 -237.835333) (xy 134.625688 -237.880396) (xy 134.641804 -237.92867)
			(xy 134.649968 -237.978904) (xy 134.65048 -238.00435) (xy 134.649977 -238.029339) (xy 134.957294 -238.029339)
			(xy 134.957294 -237.979361) (xy 134.965113 -237.929998) (xy 134.980557 -237.882466) (xy 135.003247 -237.837934)
			(xy 135.032623 -237.797501) (xy 135.067963 -237.762161) (xy 135.108396 -237.732785) (xy 135.152928 -237.710095)
			(xy 135.20046 -237.694651) (xy 135.249823 -237.686832) (xy 135.299801 -237.686832) (xy 135.349164 -237.694651)
			(xy 135.396696 -237.710095) (xy 135.441228 -237.732785) (xy 135.481661 -237.762161) (xy 135.517001 -237.797501)
			(xy 135.546377 -237.837934) (xy 135.569067 -237.882466) (xy 135.584511 -237.929998) (xy 135.59233 -237.979361)
			(xy 135.59282 -238.00435) (xy 135.898631 -238.00435) (xy 135.902726 -237.953622) (xy 135.914905 -237.904208)
			(xy 135.934853 -237.857388) (xy 135.962054 -237.814374) (xy 135.995802 -237.77628) (xy 136.035224 -237.744093)
			(xy 136.079298 -237.718647) (xy 136.126884 -237.7006) (xy 136.176748 -237.69042) (xy 136.2276 -237.688371)
			(xy 136.278121 -237.694505) (xy 136.327005 -237.708665) (xy 136.372984 -237.730482) (xy 136.414868 -237.759392)
			(xy 136.451572 -237.794647) (xy 136.482145 -237.835333) (xy 136.505796 -237.880396) (xy 136.521912 -237.92867)
			(xy 136.530076 -237.978904) (xy 136.530588 -238.00435) (xy 136.530085 -238.029339) (xy 136.837148 -238.029339)
			(xy 136.837148 -237.979361) (xy 136.844967 -237.929998) (xy 136.860411 -237.882466) (xy 136.883101 -237.837934)
			(xy 136.912477 -237.797501) (xy 136.947817 -237.762161) (xy 136.98825 -237.732785) (xy 137.032782 -237.710095)
			(xy 137.080314 -237.694651) (xy 137.129677 -237.686832) (xy 137.179655 -237.686832) (xy 137.229018 -237.694651)
			(xy 137.27655 -237.710095) (xy 137.321082 -237.732785) (xy 137.361515 -237.762161) (xy 137.396855 -237.797501)
			(xy 137.426231 -237.837934) (xy 137.448921 -237.882466) (xy 137.464365 -237.929998) (xy 137.472184 -237.979361)
			(xy 137.472674 -238.00435) (xy 137.778485 -238.00435) (xy 137.78258 -237.953622) (xy 137.794759 -237.904208)
			(xy 137.814707 -237.857388) (xy 137.841908 -237.814374) (xy 137.875656 -237.77628) (xy 137.915078 -237.744093)
			(xy 137.959152 -237.718647) (xy 138.006738 -237.7006) (xy 138.056602 -237.69042) (xy 138.107454 -237.688371)
			(xy 138.157975 -237.694505) (xy 138.206859 -237.708665) (xy 138.252838 -237.730482) (xy 138.294722 -237.759392)
			(xy 138.331426 -237.794647) (xy 138.361999 -237.835333) (xy 138.38565 -237.880396) (xy 138.401766 -237.92867)
			(xy 138.40993 -237.978904) (xy 138.410442 -238.00435) (xy 138.718539 -238.00435) (xy 138.722634 -237.953622)
			(xy 138.734813 -237.904208) (xy 138.754761 -237.857388) (xy 138.781962 -237.814374) (xy 138.81571 -237.77628)
			(xy 138.855132 -237.744093) (xy 138.899206 -237.718647) (xy 138.946792 -237.7006) (xy 138.996656 -237.69042)
			(xy 139.047508 -237.688371) (xy 139.098029 -237.694505) (xy 139.146913 -237.708665) (xy 139.192892 -237.730482)
			(xy 139.234776 -237.759392) (xy 139.27148 -237.794647) (xy 139.302053 -237.835333) (xy 139.325704 -237.880396)
			(xy 139.34182 -237.92867) (xy 139.349984 -237.978904) (xy 139.350496 -238.00435) (xy 139.349993 -238.029339)
			(xy 139.65731 -238.029339) (xy 139.65731 -237.979361) (xy 139.665129 -237.929998) (xy 139.680573 -237.882466)
			(xy 139.703263 -237.837934) (xy 139.732639 -237.797501) (xy 139.767979 -237.762161) (xy 139.808412 -237.732785)
			(xy 139.852944 -237.710095) (xy 139.900476 -237.694651) (xy 139.949839 -237.686832) (xy 139.999817 -237.686832)
			(xy 140.04918 -237.694651) (xy 140.096712 -237.710095) (xy 140.141244 -237.732785) (xy 140.181677 -237.762161)
			(xy 140.217017 -237.797501) (xy 140.246393 -237.837934) (xy 140.269083 -237.882466) (xy 140.284527 -237.929998)
			(xy 140.292346 -237.979361) (xy 140.292836 -238.00435) (xy 140.598647 -238.00435) (xy 140.602742 -237.953622)
			(xy 140.614921 -237.904208) (xy 140.634869 -237.857388) (xy 140.66207 -237.814374) (xy 140.695818 -237.77628)
			(xy 140.73524 -237.744093) (xy 140.779314 -237.718647) (xy 140.8269 -237.7006) (xy 140.876764 -237.69042)
			(xy 140.927616 -237.688371) (xy 140.978137 -237.694505) (xy 141.027021 -237.708665) (xy 141.073 -237.730482)
			(xy 141.114884 -237.759392) (xy 141.151588 -237.794647) (xy 141.182161 -237.835333) (xy 141.205812 -237.880396)
			(xy 141.221928 -237.92867) (xy 141.230092 -237.978904) (xy 141.230604 -238.00435) (xy 141.230101 -238.029339)
			(xy 141.537164 -238.029339) (xy 141.537164 -237.979361) (xy 141.544983 -237.929998) (xy 141.560427 -237.882466)
			(xy 141.583117 -237.837934) (xy 141.612493 -237.797501) (xy 141.647833 -237.762161) (xy 141.688266 -237.732785)
			(xy 141.732798 -237.710095) (xy 141.78033 -237.694651) (xy 141.829693 -237.686832) (xy 141.879671 -237.686832)
			(xy 141.929034 -237.694651) (xy 141.976566 -237.710095) (xy 142.021098 -237.732785) (xy 142.061531 -237.762161)
			(xy 142.096871 -237.797501) (xy 142.126247 -237.837934) (xy 142.148937 -237.882466) (xy 142.164381 -237.929998)
			(xy 142.1722 -237.979361) (xy 142.17269 -238.00435) (xy 142.478501 -238.00435) (xy 142.482596 -237.953622)
			(xy 142.494775 -237.904208) (xy 142.514723 -237.857388) (xy 142.541924 -237.814374) (xy 142.575672 -237.77628)
			(xy 142.615094 -237.744093) (xy 142.659168 -237.718647) (xy 142.706754 -237.7006) (xy 142.756618 -237.69042)
			(xy 142.80747 -237.688371) (xy 142.857991 -237.694505) (xy 142.906875 -237.708665) (xy 142.952854 -237.730482)
			(xy 142.994738 -237.759392) (xy 143.031442 -237.794647) (xy 143.062015 -237.835333) (xy 143.085666 -237.880396)
			(xy 143.101782 -237.92867) (xy 143.109946 -237.978904) (xy 143.110458 -238.00435) (xy 143.109955 -238.029339)
			(xy 143.417272 -238.029339) (xy 143.417272 -237.979361) (xy 143.425091 -237.929998) (xy 143.440535 -237.882466)
			(xy 143.463225 -237.837934) (xy 143.492601 -237.797501) (xy 143.527941 -237.762161) (xy 143.568374 -237.732785)
			(xy 143.612906 -237.710095) (xy 143.660438 -237.694651) (xy 143.709801 -237.686832) (xy 143.759779 -237.686832)
			(xy 143.809142 -237.694651) (xy 143.856674 -237.710095) (xy 143.901206 -237.732785) (xy 143.941639 -237.762161)
			(xy 143.976979 -237.797501) (xy 144.006355 -237.837934) (xy 144.029045 -237.882466) (xy 144.044489 -237.929998)
			(xy 144.052308 -237.979361) (xy 144.052798 -238.00435) (xy 144.052308 -238.029339) (xy 144.044489 -238.078702)
			(xy 144.029045 -238.126234) (xy 144.006355 -238.170766) (xy 143.976979 -238.211199) (xy 143.941639 -238.246539)
			(xy 143.901206 -238.275915) (xy 143.856674 -238.298605) (xy 143.809142 -238.314049) (xy 143.759779 -238.321868)
			(xy 143.709801 -238.321868) (xy 143.660438 -238.314049) (xy 143.612906 -238.298605) (xy 143.568374 -238.275915)
			(xy 143.527941 -238.246539) (xy 143.492601 -238.211199) (xy 143.463225 -238.170766) (xy 143.440535 -238.126234)
			(xy 143.425091 -238.078702) (xy 143.417272 -238.029339) (xy 143.109955 -238.029339) (xy 143.109946 -238.029796)
			(xy 143.101782 -238.08003) (xy 143.085666 -238.128304) (xy 143.062015 -238.173367) (xy 143.031442 -238.214053)
			(xy 142.994738 -238.249308) (xy 142.952854 -238.278218) (xy 142.906875 -238.300035) (xy 142.857991 -238.314195)
			(xy 142.80747 -238.320329) (xy 142.756618 -238.31828) (xy 142.706754 -238.3081) (xy 142.659168 -238.290053)
			(xy 142.615094 -238.264607) (xy 142.575672 -238.23242) (xy 142.541924 -238.194326) (xy 142.514723 -238.151312)
			(xy 142.494775 -238.104492) (xy 142.482596 -238.055078) (xy 142.478501 -238.00435) (xy 142.17269 -238.00435)
			(xy 142.1722 -238.029339) (xy 142.164381 -238.078702) (xy 142.148937 -238.126234) (xy 142.126247 -238.170766)
			(xy 142.096871 -238.211199) (xy 142.061531 -238.246539) (xy 142.021098 -238.275915) (xy 141.976566 -238.298605)
			(xy 141.929034 -238.314049) (xy 141.879671 -238.321868) (xy 141.829693 -238.321868) (xy 141.78033 -238.314049)
			(xy 141.732798 -238.298605) (xy 141.688266 -238.275915) (xy 141.647833 -238.246539) (xy 141.612493 -238.211199)
			(xy 141.583117 -238.170766) (xy 141.560427 -238.126234) (xy 141.544983 -238.078702) (xy 141.537164 -238.029339)
			(xy 141.230101 -238.029339) (xy 141.230092 -238.029796) (xy 141.221928 -238.08003) (xy 141.205812 -238.128304)
			(xy 141.182161 -238.173367) (xy 141.151588 -238.214053) (xy 141.114884 -238.249308) (xy 141.073 -238.278218)
			(xy 141.027021 -238.300035) (xy 140.978137 -238.314195) (xy 140.927616 -238.320329) (xy 140.876764 -238.31828)
			(xy 140.8269 -238.3081) (xy 140.779314 -238.290053) (xy 140.73524 -238.264607) (xy 140.695818 -238.23242)
			(xy 140.66207 -238.194326) (xy 140.634869 -238.151312) (xy 140.614921 -238.104492) (xy 140.602742 -238.055078)
			(xy 140.598647 -238.00435) (xy 140.292836 -238.00435) (xy 140.292346 -238.029339) (xy 140.284527 -238.078702)
			(xy 140.269083 -238.126234) (xy 140.246393 -238.170766) (xy 140.217017 -238.211199) (xy 140.181677 -238.246539)
			(xy 140.141244 -238.275915) (xy 140.096712 -238.298605) (xy 140.04918 -238.314049) (xy 139.999817 -238.321868)
			(xy 139.949839 -238.321868) (xy 139.900476 -238.314049) (xy 139.852944 -238.298605) (xy 139.808412 -238.275915)
			(xy 139.767979 -238.246539) (xy 139.732639 -238.211199) (xy 139.703263 -238.170766) (xy 139.680573 -238.126234)
			(xy 139.665129 -238.078702) (xy 139.65731 -238.029339) (xy 139.349993 -238.029339) (xy 139.349984 -238.029796)
			(xy 139.34182 -238.08003) (xy 139.325704 -238.128304) (xy 139.302053 -238.173367) (xy 139.27148 -238.214053)
			(xy 139.234776 -238.249308) (xy 139.192892 -238.278218) (xy 139.146913 -238.300035) (xy 139.098029 -238.314195)
			(xy 139.047508 -238.320329) (xy 138.996656 -238.31828) (xy 138.946792 -238.3081) (xy 138.899206 -238.290053)
			(xy 138.855132 -238.264607) (xy 138.81571 -238.23242) (xy 138.781962 -238.194326) (xy 138.754761 -238.151312)
			(xy 138.734813 -238.104492) (xy 138.722634 -238.055078) (xy 138.718539 -238.00435) (xy 138.410442 -238.00435)
			(xy 138.40993 -238.029796) (xy 138.401766 -238.08003) (xy 138.38565 -238.128304) (xy 138.361999 -238.173367)
			(xy 138.331426 -238.214053) (xy 138.294722 -238.249308) (xy 138.252838 -238.278218) (xy 138.206859 -238.300035)
			(xy 138.157975 -238.314195) (xy 138.107454 -238.320329) (xy 138.056602 -238.31828) (xy 138.006738 -238.3081)
			(xy 137.959152 -238.290053) (xy 137.915078 -238.264607) (xy 137.875656 -238.23242) (xy 137.841908 -238.194326)
			(xy 137.814707 -238.151312) (xy 137.794759 -238.104492) (xy 137.78258 -238.055078) (xy 137.778485 -238.00435)
			(xy 137.472674 -238.00435) (xy 137.472184 -238.029339) (xy 137.464365 -238.078702) (xy 137.448921 -238.126234)
			(xy 137.426231 -238.170766) (xy 137.396855 -238.211199) (xy 137.361515 -238.246539) (xy 137.321082 -238.275915)
			(xy 137.27655 -238.298605) (xy 137.229018 -238.314049) (xy 137.179655 -238.321868) (xy 137.129677 -238.321868)
			(xy 137.080314 -238.314049) (xy 137.032782 -238.298605) (xy 136.98825 -238.275915) (xy 136.947817 -238.246539)
			(xy 136.912477 -238.211199) (xy 136.883101 -238.170766) (xy 136.860411 -238.126234) (xy 136.844967 -238.078702)
			(xy 136.837148 -238.029339) (xy 136.530085 -238.029339) (xy 136.530076 -238.029796) (xy 136.521912 -238.08003)
			(xy 136.505796 -238.128304) (xy 136.482145 -238.173367) (xy 136.451572 -238.214053) (xy 136.414868 -238.249308)
			(xy 136.372984 -238.278218) (xy 136.327005 -238.300035) (xy 136.278121 -238.314195) (xy 136.2276 -238.320329)
			(xy 136.176748 -238.31828) (xy 136.126884 -238.3081) (xy 136.079298 -238.290053) (xy 136.035224 -238.264607)
			(xy 135.995802 -238.23242) (xy 135.962054 -238.194326) (xy 135.934853 -238.151312) (xy 135.914905 -238.104492)
			(xy 135.902726 -238.055078) (xy 135.898631 -238.00435) (xy 135.59282 -238.00435) (xy 135.59233 -238.029339)
			(xy 135.584511 -238.078702) (xy 135.569067 -238.126234) (xy 135.546377 -238.170766) (xy 135.517001 -238.211199)
			(xy 135.481661 -238.246539) (xy 135.441228 -238.275915) (xy 135.396696 -238.298605) (xy 135.349164 -238.314049)
			(xy 135.299801 -238.321868) (xy 135.249823 -238.321868) (xy 135.20046 -238.314049) (xy 135.152928 -238.298605)
			(xy 135.108396 -238.275915) (xy 135.067963 -238.246539) (xy 135.032623 -238.211199) (xy 135.003247 -238.170766)
			(xy 134.980557 -238.126234) (xy 134.965113 -238.078702) (xy 134.957294 -238.029339) (xy 134.649977 -238.029339)
			(xy 134.649968 -238.029796) (xy 134.641804 -238.08003) (xy 134.625688 -238.128304) (xy 134.602037 -238.173367)
			(xy 134.571464 -238.214053) (xy 134.53476 -238.249308) (xy 134.492876 -238.278218) (xy 134.446897 -238.300035)
			(xy 134.398013 -238.314195) (xy 134.347492 -238.320329) (xy 134.29664 -238.31828) (xy 134.246776 -238.3081)
			(xy 134.19919 -238.290053) (xy 134.155116 -238.264607) (xy 134.115694 -238.23242) (xy 134.081946 -238.194326)
			(xy 134.054745 -238.151312) (xy 134.034797 -238.104492) (xy 134.022618 -238.055078) (xy 134.018523 -238.00435)
			(xy 133.712712 -238.00435) (xy 133.712222 -238.029339) (xy 133.704403 -238.078702) (xy 133.688959 -238.126234)
			(xy 133.666269 -238.170766) (xy 133.636893 -238.211199) (xy 133.601553 -238.246539) (xy 133.56112 -238.275915)
			(xy 133.516588 -238.298605) (xy 133.469056 -238.314049) (xy 133.419693 -238.321868) (xy 133.369715 -238.321868)
			(xy 133.320352 -238.314049) (xy 133.27282 -238.298605) (xy 133.228288 -238.275915) (xy 133.187855 -238.246539)
			(xy 133.152515 -238.211199) (xy 133.123139 -238.170766) (xy 133.100449 -238.126234) (xy 133.085005 -238.078702)
			(xy 133.077186 -238.029339) (xy 132.769869 -238.029339) (xy 132.76986 -238.029796) (xy 132.761696 -238.08003)
			(xy 132.74558 -238.128304) (xy 132.721929 -238.173367) (xy 132.691356 -238.214053) (xy 132.654652 -238.249308)
			(xy 132.612768 -238.278218) (xy 132.566789 -238.300035) (xy 132.517905 -238.314195) (xy 132.467384 -238.320329)
			(xy 132.416532 -238.31828) (xy 132.366668 -238.3081) (xy 132.319082 -238.290053) (xy 132.275008 -238.264607)
			(xy 132.235586 -238.23242) (xy 132.201838 -238.194326) (xy 132.174637 -238.151312) (xy 132.154689 -238.104492)
			(xy 132.14251 -238.055078) (xy 132.138415 -238.00435) (xy 131.830572 -238.00435) (xy 131.83006 -238.029796)
			(xy 131.821896 -238.08003) (xy 131.80578 -238.128304) (xy 131.782129 -238.173367) (xy 131.751556 -238.214053)
			(xy 131.714852 -238.249308) (xy 131.672968 -238.278218) (xy 131.626989 -238.300035) (xy 131.578105 -238.314195)
			(xy 131.527584 -238.320329) (xy 131.476732 -238.31828) (xy 131.426868 -238.3081) (xy 131.379282 -238.290053)
			(xy 131.335208 -238.264607) (xy 131.295786 -238.23242) (xy 131.262038 -238.194326) (xy 131.234837 -238.151312)
			(xy 131.214889 -238.104492) (xy 131.20271 -238.055078) (xy 131.198615 -238.00435) (xy 130.892804 -238.00435)
			(xy 130.892314 -238.029339) (xy 130.884495 -238.078702) (xy 130.869051 -238.126234) (xy 130.846361 -238.170766)
			(xy 130.816985 -238.211199) (xy 130.781645 -238.246539) (xy 130.741212 -238.275915) (xy 130.69668 -238.298605)
			(xy 130.649148 -238.314049) (xy 130.599785 -238.321868) (xy 130.549807 -238.321868) (xy 130.500444 -238.314049)
			(xy 130.452912 -238.298605) (xy 130.40838 -238.275915) (xy 130.367947 -238.246539) (xy 130.332607 -238.211199)
			(xy 130.303231 -238.170766) (xy 130.280541 -238.126234) (xy 130.265097 -238.078702) (xy 130.257278 -238.029339)
			(xy 129.949961 -238.029339) (xy 129.949952 -238.029796) (xy 129.941788 -238.08003) (xy 129.925672 -238.128304)
			(xy 129.902021 -238.173367) (xy 129.871448 -238.214053) (xy 129.834744 -238.249308) (xy 129.79286 -238.278218)
			(xy 129.746881 -238.300035) (xy 129.697997 -238.314195) (xy 129.647476 -238.320329) (xy 129.596624 -238.31828)
			(xy 129.54676 -238.3081) (xy 129.499174 -238.290053) (xy 129.4551 -238.264607) (xy 129.415678 -238.23242)
			(xy 129.38193 -238.194326) (xy 129.354729 -238.151312) (xy 129.334781 -238.104492) (xy 129.322602 -238.055078)
			(xy 129.318507 -238.00435) (xy 129.012696 -238.00435) (xy 129.012206 -238.029339) (xy 129.004387 -238.078702)
			(xy 128.988943 -238.126234) (xy 128.966253 -238.170766) (xy 128.936877 -238.211199) (xy 128.901537 -238.246539)
			(xy 128.861104 -238.275915) (xy 128.816572 -238.298605) (xy 128.76904 -238.314049) (xy 128.719677 -238.321868)
			(xy 128.669699 -238.321868) (xy 128.620336 -238.314049) (xy 128.572804 -238.298605) (xy 128.528272 -238.275915)
			(xy 128.487839 -238.246539) (xy 128.452499 -238.211199) (xy 128.423123 -238.170766) (xy 128.400433 -238.126234)
			(xy 128.384989 -238.078702) (xy 128.37717 -238.029339) (xy 128.069853 -238.029339) (xy 128.069844 -238.029796)
			(xy 128.06168 -238.08003) (xy 128.045564 -238.128304) (xy 128.021913 -238.173367) (xy 127.99134 -238.214053)
			(xy 127.954636 -238.249308) (xy 127.912752 -238.278218) (xy 127.866773 -238.300035) (xy 127.817889 -238.314195)
			(xy 127.767368 -238.320329) (xy 127.716516 -238.31828) (xy 127.666652 -238.3081) (xy 127.619066 -238.290053)
			(xy 127.574992 -238.264607) (xy 127.53557 -238.23242) (xy 127.501822 -238.194326) (xy 127.474621 -238.151312)
			(xy 127.454673 -238.104492) (xy 127.442494 -238.055078) (xy 127.438399 -238.00435) (xy 126.648464 -238.00435)
			(xy 126.648464 -238.708692) (xy 126.648972 -238.715804) (xy 126.650496 -238.726726) (xy 126.656204 -238.748182)
			(xy 126.66232 -238.792157) (xy 126.662688 -238.814356) (xy 126.662369 -238.836622) (xy 126.661991 -238.839345)
			(xy 126.967216 -238.839345) (xy 126.967216 -238.789367) (xy 126.975035 -238.740004) (xy 126.990479 -238.692472)
			(xy 127.013169 -238.64794) (xy 127.042545 -238.607507) (xy 127.077885 -238.572167) (xy 127.118318 -238.542791)
			(xy 127.16285 -238.520101) (xy 127.210382 -238.504657) (xy 127.259745 -238.496838) (xy 127.309723 -238.496838)
			(xy 127.359086 -238.504657) (xy 127.406618 -238.520101) (xy 127.45115 -238.542791) (xy 127.491583 -238.572167)
			(xy 127.526923 -238.607507) (xy 127.556299 -238.64794) (xy 127.578989 -238.692472) (xy 127.594433 -238.740004)
			(xy 127.602252 -238.789367) (xy 127.602742 -238.814356) (xy 127.908553 -238.814356) (xy 127.912648 -238.763628)
			(xy 127.924827 -238.714214) (xy 127.944775 -238.667394) (xy 127.971976 -238.62438) (xy 128.005724 -238.586286)
			(xy 128.045146 -238.554099) (xy 128.08922 -238.528653) (xy 128.136806 -238.510606) (xy 128.18667 -238.500426)
			(xy 128.237522 -238.498377) (xy 128.288043 -238.504511) (xy 128.336927 -238.518671) (xy 128.382906 -238.540488)
			(xy 128.42479 -238.569398) (xy 128.461494 -238.604653) (xy 128.492067 -238.645339) (xy 128.515718 -238.690402)
			(xy 128.531834 -238.738676) (xy 128.539998 -238.78891) (xy 128.54051 -238.814356) (xy 128.848607 -238.814356)
			(xy 128.852702 -238.763628) (xy 128.864881 -238.714214) (xy 128.884829 -238.667394) (xy 128.91203 -238.62438)
			(xy 128.945778 -238.586286) (xy 128.9852 -238.554099) (xy 129.029274 -238.528653) (xy 129.07686 -238.510606)
			(xy 129.126724 -238.500426) (xy 129.177576 -238.498377) (xy 129.228097 -238.504511) (xy 129.276981 -238.518671)
			(xy 129.32296 -238.540488) (xy 129.364844 -238.569398) (xy 129.401548 -238.604653) (xy 129.432121 -238.645339)
			(xy 129.455772 -238.690402) (xy 129.471888 -238.738676) (xy 129.480052 -238.78891) (xy 129.480564 -238.814356)
			(xy 129.480061 -238.839345) (xy 129.787124 -238.839345) (xy 129.787124 -238.789367) (xy 129.794943 -238.740004)
			(xy 129.810387 -238.692472) (xy 129.833077 -238.64794) (xy 129.862453 -238.607507) (xy 129.897793 -238.572167)
			(xy 129.938226 -238.542791) (xy 129.982758 -238.520101) (xy 130.03029 -238.504657) (xy 130.079653 -238.496838)
			(xy 130.129631 -238.496838) (xy 130.178994 -238.504657) (xy 130.226526 -238.520101) (xy 130.271058 -238.542791)
			(xy 130.311491 -238.572167) (xy 130.346831 -238.607507) (xy 130.376207 -238.64794) (xy 130.398897 -238.692472)
			(xy 130.414341 -238.740004) (xy 130.42216 -238.789367) (xy 130.42265 -238.814356) (xy 130.728461 -238.814356)
			(xy 130.732556 -238.763628) (xy 130.744735 -238.714214) (xy 130.764683 -238.667394) (xy 130.791884 -238.62438)
			(xy 130.825632 -238.586286) (xy 130.865054 -238.554099) (xy 130.909128 -238.528653) (xy 130.956714 -238.510606)
			(xy 131.006578 -238.500426) (xy 131.05743 -238.498377) (xy 131.107951 -238.504511) (xy 131.156835 -238.518671)
			(xy 131.202814 -238.540488) (xy 131.244698 -238.569398) (xy 131.281402 -238.604653) (xy 131.311975 -238.645339)
			(xy 131.335626 -238.690402) (xy 131.351742 -238.738676) (xy 131.359906 -238.78891) (xy 131.360418 -238.814356)
			(xy 131.359915 -238.839345) (xy 131.667232 -238.839345) (xy 131.667232 -238.789367) (xy 131.675051 -238.740004)
			(xy 131.690495 -238.692472) (xy 131.713185 -238.64794) (xy 131.742561 -238.607507) (xy 131.777901 -238.572167)
			(xy 131.818334 -238.542791) (xy 131.862866 -238.520101) (xy 131.910398 -238.504657) (xy 131.959761 -238.496838)
			(xy 132.009739 -238.496838) (xy 132.059102 -238.504657) (xy 132.106634 -238.520101) (xy 132.151166 -238.542791)
			(xy 132.191599 -238.572167) (xy 132.226939 -238.607507) (xy 132.256315 -238.64794) (xy 132.279005 -238.692472)
			(xy 132.294449 -238.740004) (xy 132.302268 -238.789367) (xy 132.302758 -238.814356) (xy 132.608569 -238.814356)
			(xy 132.612664 -238.763628) (xy 132.624843 -238.714214) (xy 132.644791 -238.667394) (xy 132.671992 -238.62438)
			(xy 132.70574 -238.586286) (xy 132.745162 -238.554099) (xy 132.789236 -238.528653) (xy 132.836822 -238.510606)
			(xy 132.886686 -238.500426) (xy 132.937538 -238.498377) (xy 132.988059 -238.504511) (xy 133.036943 -238.518671)
			(xy 133.082922 -238.540488) (xy 133.124806 -238.569398) (xy 133.16151 -238.604653) (xy 133.192083 -238.645339)
			(xy 133.215734 -238.690402) (xy 133.23185 -238.738676) (xy 133.240014 -238.78891) (xy 133.240526 -238.814356)
			(xy 133.240023 -238.839345) (xy 133.54734 -238.839345) (xy 133.54734 -238.789367) (xy 133.555159 -238.740004)
			(xy 133.570603 -238.692472) (xy 133.593293 -238.64794) (xy 133.622669 -238.607507) (xy 133.658009 -238.572167)
			(xy 133.698442 -238.542791) (xy 133.742974 -238.520101) (xy 133.790506 -238.504657) (xy 133.839869 -238.496838)
			(xy 133.889847 -238.496838) (xy 133.93921 -238.504657) (xy 133.986742 -238.520101) (xy 134.031274 -238.542791)
			(xy 134.071707 -238.572167) (xy 134.107047 -238.607507) (xy 134.136423 -238.64794) (xy 134.159113 -238.692472)
			(xy 134.174557 -238.740004) (xy 134.182376 -238.789367) (xy 134.182866 -238.814356) (xy 134.488423 -238.814356)
			(xy 134.492518 -238.763628) (xy 134.504697 -238.714214) (xy 134.524645 -238.667394) (xy 134.551846 -238.62438)
			(xy 134.585594 -238.586286) (xy 134.625016 -238.554099) (xy 134.66909 -238.528653) (xy 134.716676 -238.510606)
			(xy 134.76654 -238.500426) (xy 134.817392 -238.498377) (xy 134.867913 -238.504511) (xy 134.916797 -238.518671)
			(xy 134.962776 -238.540488) (xy 135.00466 -238.569398) (xy 135.041364 -238.604653) (xy 135.071937 -238.645339)
			(xy 135.095588 -238.690402) (xy 135.111704 -238.738676) (xy 135.119868 -238.78891) (xy 135.12038 -238.814356)
			(xy 135.428477 -238.814356) (xy 135.432572 -238.763628) (xy 135.444751 -238.714214) (xy 135.464699 -238.667394)
			(xy 135.4919 -238.62438) (xy 135.525648 -238.586286) (xy 135.56507 -238.554099) (xy 135.609144 -238.528653)
			(xy 135.65673 -238.510606) (xy 135.706594 -238.500426) (xy 135.757446 -238.498377) (xy 135.807967 -238.504511)
			(xy 135.856851 -238.518671) (xy 135.90283 -238.540488) (xy 135.944714 -238.569398) (xy 135.981418 -238.604653)
			(xy 136.011991 -238.645339) (xy 136.035642 -238.690402) (xy 136.051758 -238.738676) (xy 136.059922 -238.78891)
			(xy 136.060434 -238.814356) (xy 136.059931 -238.839345) (xy 136.367248 -238.839345) (xy 136.367248 -238.789367)
			(xy 136.375067 -238.740004) (xy 136.390511 -238.692472) (xy 136.413201 -238.64794) (xy 136.442577 -238.607507)
			(xy 136.477917 -238.572167) (xy 136.51835 -238.542791) (xy 136.562882 -238.520101) (xy 136.610414 -238.504657)
			(xy 136.659777 -238.496838) (xy 136.709755 -238.496838) (xy 136.759118 -238.504657) (xy 136.80665 -238.520101)
			(xy 136.851182 -238.542791) (xy 136.891615 -238.572167) (xy 136.926955 -238.607507) (xy 136.956331 -238.64794)
			(xy 136.979021 -238.692472) (xy 136.994465 -238.740004) (xy 137.002284 -238.789367) (xy 137.002774 -238.814356)
			(xy 137.308585 -238.814356) (xy 137.31268 -238.763628) (xy 137.324859 -238.714214) (xy 137.344807 -238.667394)
			(xy 137.372008 -238.62438) (xy 137.405756 -238.586286) (xy 137.445178 -238.554099) (xy 137.489252 -238.528653)
			(xy 137.536838 -238.510606) (xy 137.586702 -238.500426) (xy 137.637554 -238.498377) (xy 137.688075 -238.504511)
			(xy 137.736959 -238.518671) (xy 137.782938 -238.540488) (xy 137.824822 -238.569398) (xy 137.861526 -238.604653)
			(xy 137.892099 -238.645339) (xy 137.91575 -238.690402) (xy 137.931866 -238.738676) (xy 137.94003 -238.78891)
			(xy 137.940542 -238.814356) (xy 137.940039 -238.839345) (xy 138.247356 -238.839345) (xy 138.247356 -238.789367)
			(xy 138.255175 -238.740004) (xy 138.270619 -238.692472) (xy 138.293309 -238.64794) (xy 138.322685 -238.607507)
			(xy 138.358025 -238.572167) (xy 138.398458 -238.542791) (xy 138.44299 -238.520101) (xy 138.490522 -238.504657)
			(xy 138.539885 -238.496838) (xy 138.589863 -238.496838) (xy 138.639226 -238.504657) (xy 138.686758 -238.520101)
			(xy 138.73129 -238.542791) (xy 138.771723 -238.572167) (xy 138.807063 -238.607507) (xy 138.836439 -238.64794)
			(xy 138.859129 -238.692472) (xy 138.874573 -238.740004) (xy 138.882392 -238.789367) (xy 138.882882 -238.814356)
			(xy 139.188439 -238.814356) (xy 139.192534 -238.763628) (xy 139.204713 -238.714214) (xy 139.224661 -238.667394)
			(xy 139.251862 -238.62438) (xy 139.28561 -238.586286) (xy 139.325032 -238.554099) (xy 139.369106 -238.528653)
			(xy 139.416692 -238.510606) (xy 139.466556 -238.500426) (xy 139.517408 -238.498377) (xy 139.567929 -238.504511)
			(xy 139.616813 -238.518671) (xy 139.662792 -238.540488) (xy 139.704676 -238.569398) (xy 139.74138 -238.604653)
			(xy 139.771953 -238.645339) (xy 139.795604 -238.690402) (xy 139.81172 -238.738676) (xy 139.819884 -238.78891)
			(xy 139.820396 -238.814356) (xy 139.819893 -238.839345) (xy 140.12721 -238.839345) (xy 140.12721 -238.789367)
			(xy 140.135029 -238.740004) (xy 140.150473 -238.692472) (xy 140.173163 -238.64794) (xy 140.202539 -238.607507)
			(xy 140.237879 -238.572167) (xy 140.278312 -238.542791) (xy 140.322844 -238.520101) (xy 140.370376 -238.504657)
			(xy 140.419739 -238.496838) (xy 140.469717 -238.496838) (xy 140.51908 -238.504657) (xy 140.566612 -238.520101)
			(xy 140.611144 -238.542791) (xy 140.651577 -238.572167) (xy 140.686917 -238.607507) (xy 140.716293 -238.64794)
			(xy 140.738983 -238.692472) (xy 140.754427 -238.740004) (xy 140.762246 -238.789367) (xy 140.762736 -238.814356)
			(xy 141.068547 -238.814356) (xy 141.072642 -238.763628) (xy 141.084821 -238.714214) (xy 141.104769 -238.667394)
			(xy 141.13197 -238.62438) (xy 141.165718 -238.586286) (xy 141.20514 -238.554099) (xy 141.249214 -238.528653)
			(xy 141.2968 -238.510606) (xy 141.346664 -238.500426) (xy 141.397516 -238.498377) (xy 141.448037 -238.504511)
			(xy 141.496921 -238.518671) (xy 141.5429 -238.540488) (xy 141.584784 -238.569398) (xy 141.621488 -238.604653)
			(xy 141.652061 -238.645339) (xy 141.675712 -238.690402) (xy 141.691828 -238.738676) (xy 141.699992 -238.78891)
			(xy 141.700504 -238.814356) (xy 142.008601 -238.814356) (xy 142.012696 -238.763628) (xy 142.024875 -238.714214)
			(xy 142.044823 -238.667394) (xy 142.072024 -238.62438) (xy 142.105772 -238.586286) (xy 142.145194 -238.554099)
			(xy 142.189268 -238.528653) (xy 142.236854 -238.510606) (xy 142.286718 -238.500426) (xy 142.33757 -238.498377)
			(xy 142.388091 -238.504511) (xy 142.436975 -238.518671) (xy 142.482954 -238.540488) (xy 142.524838 -238.569398)
			(xy 142.561542 -238.604653) (xy 142.592115 -238.645339) (xy 142.615766 -238.690402) (xy 142.631882 -238.738676)
			(xy 142.640046 -238.78891) (xy 142.640558 -238.814356) (xy 142.640055 -238.839345) (xy 142.947118 -238.839345)
			(xy 142.947118 -238.789367) (xy 142.954937 -238.740004) (xy 142.970381 -238.692472) (xy 142.993071 -238.64794)
			(xy 143.022447 -238.607507) (xy 143.057787 -238.572167) (xy 143.09822 -238.542791) (xy 143.142752 -238.520101)
			(xy 143.190284 -238.504657) (xy 143.239647 -238.496838) (xy 143.289625 -238.496838) (xy 143.338988 -238.504657)
			(xy 143.38652 -238.520101) (xy 143.431052 -238.542791) (xy 143.471485 -238.572167) (xy 143.506825 -238.607507)
			(xy 143.536201 -238.64794) (xy 143.558891 -238.692472) (xy 143.574335 -238.740004) (xy 143.582154 -238.789367)
			(xy 143.582644 -238.814356) (xy 143.582154 -238.839345) (xy 143.574335 -238.888708) (xy 143.558891 -238.93624)
			(xy 143.536201 -238.980772) (xy 143.506825 -239.021205) (xy 143.471485 -239.056545) (xy 143.431052 -239.085921)
			(xy 143.38652 -239.108611) (xy 143.338988 -239.124055) (xy 143.289625 -239.131874) (xy 143.239647 -239.131874)
			(xy 143.190284 -239.124055) (xy 143.142752 -239.108611) (xy 143.09822 -239.085921) (xy 143.057787 -239.056545)
			(xy 143.022447 -239.021205) (xy 142.993071 -238.980772) (xy 142.970381 -238.93624) (xy 142.954937 -238.888708)
			(xy 142.947118 -238.839345) (xy 142.640055 -238.839345) (xy 142.640046 -238.839802) (xy 142.631882 -238.890036)
			(xy 142.615766 -238.93831) (xy 142.592115 -238.983373) (xy 142.561542 -239.024059) (xy 142.524838 -239.059314)
			(xy 142.482954 -239.088224) (xy 142.436975 -239.110041) (xy 142.388091 -239.124201) (xy 142.33757 -239.130335)
			(xy 142.286718 -239.128286) (xy 142.236854 -239.118106) (xy 142.189268 -239.100059) (xy 142.145194 -239.074613)
			(xy 142.105772 -239.042426) (xy 142.072024 -239.004332) (xy 142.044823 -238.961318) (xy 142.024875 -238.914498)
			(xy 142.012696 -238.865084) (xy 142.008601 -238.814356) (xy 141.700504 -238.814356) (xy 141.699992 -238.839802)
			(xy 141.691828 -238.890036) (xy 141.675712 -238.93831) (xy 141.652061 -238.983373) (xy 141.621488 -239.024059)
			(xy 141.584784 -239.059314) (xy 141.5429 -239.088224) (xy 141.496921 -239.110041) (xy 141.448037 -239.124201)
			(xy 141.397516 -239.130335) (xy 141.346664 -239.128286) (xy 141.2968 -239.118106) (xy 141.249214 -239.100059)
			(xy 141.20514 -239.074613) (xy 141.165718 -239.042426) (xy 141.13197 -239.004332) (xy 141.104769 -238.961318)
			(xy 141.084821 -238.914498) (xy 141.072642 -238.865084) (xy 141.068547 -238.814356) (xy 140.762736 -238.814356)
			(xy 140.762246 -238.839345) (xy 140.754427 -238.888708) (xy 140.738983 -238.93624) (xy 140.716293 -238.980772)
			(xy 140.686917 -239.021205) (xy 140.651577 -239.056545) (xy 140.611144 -239.085921) (xy 140.566612 -239.108611)
			(xy 140.51908 -239.124055) (xy 140.469717 -239.131874) (xy 140.419739 -239.131874) (xy 140.370376 -239.124055)
			(xy 140.322844 -239.108611) (xy 140.278312 -239.085921) (xy 140.237879 -239.056545) (xy 140.202539 -239.021205)
			(xy 140.173163 -238.980772) (xy 140.150473 -238.93624) (xy 140.135029 -238.888708) (xy 140.12721 -238.839345)
			(xy 139.819893 -238.839345) (xy 139.819884 -238.839802) (xy 139.81172 -238.890036) (xy 139.795604 -238.93831)
			(xy 139.771953 -238.983373) (xy 139.74138 -239.024059) (xy 139.704676 -239.059314) (xy 139.662792 -239.088224)
			(xy 139.616813 -239.110041) (xy 139.567929 -239.124201) (xy 139.517408 -239.130335) (xy 139.466556 -239.128286)
			(xy 139.416692 -239.118106) (xy 139.369106 -239.100059) (xy 139.325032 -239.074613) (xy 139.28561 -239.042426)
			(xy 139.251862 -239.004332) (xy 139.224661 -238.961318) (xy 139.204713 -238.914498) (xy 139.192534 -238.865084)
			(xy 139.188439 -238.814356) (xy 138.882882 -238.814356) (xy 138.882392 -238.839345) (xy 138.874573 -238.888708)
			(xy 138.859129 -238.93624) (xy 138.836439 -238.980772) (xy 138.807063 -239.021205) (xy 138.771723 -239.056545)
			(xy 138.73129 -239.085921) (xy 138.686758 -239.108611) (xy 138.639226 -239.124055) (xy 138.589863 -239.131874)
			(xy 138.539885 -239.131874) (xy 138.490522 -239.124055) (xy 138.44299 -239.108611) (xy 138.398458 -239.085921)
			(xy 138.358025 -239.056545) (xy 138.322685 -239.021205) (xy 138.293309 -238.980772) (xy 138.270619 -238.93624)
			(xy 138.255175 -238.888708) (xy 138.247356 -238.839345) (xy 137.940039 -238.839345) (xy 137.94003 -238.839802)
			(xy 137.931866 -238.890036) (xy 137.91575 -238.93831) (xy 137.892099 -238.983373) (xy 137.861526 -239.024059)
			(xy 137.824822 -239.059314) (xy 137.782938 -239.088224) (xy 137.736959 -239.110041) (xy 137.688075 -239.124201)
			(xy 137.637554 -239.130335) (xy 137.586702 -239.128286) (xy 137.536838 -239.118106) (xy 137.489252 -239.100059)
			(xy 137.445178 -239.074613) (xy 137.405756 -239.042426) (xy 137.372008 -239.004332) (xy 137.344807 -238.961318)
			(xy 137.324859 -238.914498) (xy 137.31268 -238.865084) (xy 137.308585 -238.814356) (xy 137.002774 -238.814356)
			(xy 137.002284 -238.839345) (xy 136.994465 -238.888708) (xy 136.979021 -238.93624) (xy 136.956331 -238.980772)
			(xy 136.926955 -239.021205) (xy 136.891615 -239.056545) (xy 136.851182 -239.085921) (xy 136.80665 -239.108611)
			(xy 136.759118 -239.124055) (xy 136.709755 -239.131874) (xy 136.659777 -239.131874) (xy 136.610414 -239.124055)
			(xy 136.562882 -239.108611) (xy 136.51835 -239.085921) (xy 136.477917 -239.056545) (xy 136.442577 -239.021205)
			(xy 136.413201 -238.980772) (xy 136.390511 -238.93624) (xy 136.375067 -238.888708) (xy 136.367248 -238.839345)
			(xy 136.059931 -238.839345) (xy 136.059922 -238.839802) (xy 136.051758 -238.890036) (xy 136.035642 -238.93831)
			(xy 136.011991 -238.983373) (xy 135.981418 -239.024059) (xy 135.944714 -239.059314) (xy 135.90283 -239.088224)
			(xy 135.856851 -239.110041) (xy 135.807967 -239.124201) (xy 135.757446 -239.130335) (xy 135.706594 -239.128286)
			(xy 135.65673 -239.118106) (xy 135.609144 -239.100059) (xy 135.56507 -239.074613) (xy 135.525648 -239.042426)
			(xy 135.4919 -239.004332) (xy 135.464699 -238.961318) (xy 135.444751 -238.914498) (xy 135.432572 -238.865084)
			(xy 135.428477 -238.814356) (xy 135.12038 -238.814356) (xy 135.119868 -238.839802) (xy 135.111704 -238.890036)
			(xy 135.095588 -238.93831) (xy 135.071937 -238.983373) (xy 135.041364 -239.024059) (xy 135.00466 -239.059314)
			(xy 134.962776 -239.088224) (xy 134.916797 -239.110041) (xy 134.867913 -239.124201) (xy 134.817392 -239.130335)
			(xy 134.76654 -239.128286) (xy 134.716676 -239.118106) (xy 134.66909 -239.100059) (xy 134.625016 -239.074613)
			(xy 134.585594 -239.042426) (xy 134.551846 -239.004332) (xy 134.524645 -238.961318) (xy 134.504697 -238.914498)
			(xy 134.492518 -238.865084) (xy 134.488423 -238.814356) (xy 134.182866 -238.814356) (xy 134.182376 -238.839345)
			(xy 134.174557 -238.888708) (xy 134.159113 -238.93624) (xy 134.136423 -238.980772) (xy 134.107047 -239.021205)
			(xy 134.071707 -239.056545) (xy 134.031274 -239.085921) (xy 133.986742 -239.108611) (xy 133.93921 -239.124055)
			(xy 133.889847 -239.131874) (xy 133.839869 -239.131874) (xy 133.790506 -239.124055) (xy 133.742974 -239.108611)
			(xy 133.698442 -239.085921) (xy 133.658009 -239.056545) (xy 133.622669 -239.021205) (xy 133.593293 -238.980772)
			(xy 133.570603 -238.93624) (xy 133.555159 -238.888708) (xy 133.54734 -238.839345) (xy 133.240023 -238.839345)
			(xy 133.240014 -238.839802) (xy 133.23185 -238.890036) (xy 133.215734 -238.93831) (xy 133.192083 -238.983373)
			(xy 133.16151 -239.024059) (xy 133.124806 -239.059314) (xy 133.082922 -239.088224) (xy 133.036943 -239.110041)
			(xy 132.988059 -239.124201) (xy 132.937538 -239.130335) (xy 132.886686 -239.128286) (xy 132.836822 -239.118106)
			(xy 132.789236 -239.100059) (xy 132.745162 -239.074613) (xy 132.70574 -239.042426) (xy 132.671992 -239.004332)
			(xy 132.644791 -238.961318) (xy 132.624843 -238.914498) (xy 132.612664 -238.865084) (xy 132.608569 -238.814356)
			(xy 132.302758 -238.814356) (xy 132.302268 -238.839345) (xy 132.294449 -238.888708) (xy 132.279005 -238.93624)
			(xy 132.256315 -238.980772) (xy 132.226939 -239.021205) (xy 132.191599 -239.056545) (xy 132.151166 -239.085921)
			(xy 132.106634 -239.108611) (xy 132.059102 -239.124055) (xy 132.009739 -239.131874) (xy 131.959761 -239.131874)
			(xy 131.910398 -239.124055) (xy 131.862866 -239.108611) (xy 131.818334 -239.085921) (xy 131.777901 -239.056545)
			(xy 131.742561 -239.021205) (xy 131.713185 -238.980772) (xy 131.690495 -238.93624) (xy 131.675051 -238.888708)
			(xy 131.667232 -238.839345) (xy 131.359915 -238.839345) (xy 131.359906 -238.839802) (xy 131.351742 -238.890036)
			(xy 131.335626 -238.93831) (xy 131.311975 -238.983373) (xy 131.281402 -239.024059) (xy 131.244698 -239.059314)
			(xy 131.202814 -239.088224) (xy 131.156835 -239.110041) (xy 131.107951 -239.124201) (xy 131.05743 -239.130335)
			(xy 131.006578 -239.128286) (xy 130.956714 -239.118106) (xy 130.909128 -239.100059) (xy 130.865054 -239.074613)
			(xy 130.825632 -239.042426) (xy 130.791884 -239.004332) (xy 130.764683 -238.961318) (xy 130.744735 -238.914498)
			(xy 130.732556 -238.865084) (xy 130.728461 -238.814356) (xy 130.42265 -238.814356) (xy 130.42216 -238.839345)
			(xy 130.414341 -238.888708) (xy 130.398897 -238.93624) (xy 130.376207 -238.980772) (xy 130.346831 -239.021205)
			(xy 130.311491 -239.056545) (xy 130.271058 -239.085921) (xy 130.226526 -239.108611) (xy 130.178994 -239.124055)
			(xy 130.129631 -239.131874) (xy 130.079653 -239.131874) (xy 130.03029 -239.124055) (xy 129.982758 -239.108611)
			(xy 129.938226 -239.085921) (xy 129.897793 -239.056545) (xy 129.862453 -239.021205) (xy 129.833077 -238.980772)
			(xy 129.810387 -238.93624) (xy 129.794943 -238.888708) (xy 129.787124 -238.839345) (xy 129.480061 -238.839345)
			(xy 129.480052 -238.839802) (xy 129.471888 -238.890036) (xy 129.455772 -238.93831) (xy 129.432121 -238.983373)
			(xy 129.401548 -239.024059) (xy 129.364844 -239.059314) (xy 129.32296 -239.088224) (xy 129.276981 -239.110041)
			(xy 129.228097 -239.124201) (xy 129.177576 -239.130335) (xy 129.126724 -239.128286) (xy 129.07686 -239.118106)
			(xy 129.029274 -239.100059) (xy 128.9852 -239.074613) (xy 128.945778 -239.042426) (xy 128.91203 -239.004332)
			(xy 128.884829 -238.961318) (xy 128.864881 -238.914498) (xy 128.852702 -238.865084) (xy 128.848607 -238.814356)
			(xy 128.54051 -238.814356) (xy 128.539998 -238.839802) (xy 128.531834 -238.890036) (xy 128.515718 -238.93831)
			(xy 128.492067 -238.983373) (xy 128.461494 -239.024059) (xy 128.42479 -239.059314) (xy 128.382906 -239.088224)
			(xy 128.336927 -239.110041) (xy 128.288043 -239.124201) (xy 128.237522 -239.130335) (xy 128.18667 -239.128286)
			(xy 128.136806 -239.118106) (xy 128.08922 -239.100059) (xy 128.045146 -239.074613) (xy 128.005724 -239.042426)
			(xy 127.971976 -239.004332) (xy 127.944775 -238.961318) (xy 127.924827 -238.914498) (xy 127.912648 -238.865084)
			(xy 127.908553 -238.814356) (xy 127.602742 -238.814356) (xy 127.602252 -238.839345) (xy 127.594433 -238.888708)
			(xy 127.578989 -238.93624) (xy 127.556299 -238.980772) (xy 127.526923 -239.021205) (xy 127.491583 -239.056545)
			(xy 127.45115 -239.085921) (xy 127.406618 -239.108611) (xy 127.359086 -239.124055) (xy 127.309723 -239.131874)
			(xy 127.259745 -239.131874) (xy 127.210382 -239.124055) (xy 127.16285 -239.108611) (xy 127.118318 -239.085921)
			(xy 127.077885 -239.056545) (xy 127.042545 -239.021205) (xy 127.013169 -238.980772) (xy 126.990479 -238.93624)
			(xy 126.975035 -238.888708) (xy 126.967216 -238.839345) (xy 126.661991 -238.839345) (xy 126.656249 -238.880728)
			(xy 126.650496 -238.90224) (xy 126.648464 -238.909098) (xy 126.648464 -239.211358) (xy 126.648464 -239.214406)
			(xy 126.649406 -239.223861) (xy 126.657354 -239.241104) (xy 126.663958 -239.247934) (xy 126.72441 -239.299242)
			(xy 126.728647 -239.302666) (xy 126.738253 -239.307801) (xy 126.74346 -239.309402) (xy 126.75362 -239.312196)
			(xy 126.764542 -239.310418) (xy 126.777028 -239.308518) (xy 126.802205 -239.306481) (xy 126.814834 -239.306354)
			(xy 126.839824 -239.306847) (xy 126.889189 -239.31467) (xy 126.936723 -239.330119) (xy 126.981254 -239.352814)
			(xy 127.021688 -239.382194) (xy 127.057028 -239.417538) (xy 127.086404 -239.457975) (xy 127.109094 -239.502509)
			(xy 127.124537 -239.550044) (xy 127.132356 -239.59941) (xy 127.132356 -239.624362) (xy 127.438399 -239.624362)
			(xy 127.442494 -239.573634) (xy 127.454673 -239.52422) (xy 127.474621 -239.4774) (xy 127.501822 -239.434386)
			(xy 127.53557 -239.396292) (xy 127.574992 -239.364105) (xy 127.619066 -239.338659) (xy 127.666652 -239.320612)
			(xy 127.716516 -239.310432) (xy 127.767368 -239.308383) (xy 127.817889 -239.314517) (xy 127.866773 -239.328677)
			(xy 127.912752 -239.350494) (xy 127.954636 -239.379404) (xy 127.99134 -239.414659) (xy 128.021913 -239.455345)
			(xy 128.045564 -239.500408) (xy 128.06168 -239.548682) (xy 128.069844 -239.598916) (xy 128.070356 -239.624362)
			(xy 128.069853 -239.649351) (xy 128.37717 -239.649351) (xy 128.37717 -239.599373) (xy 128.384989 -239.55001)
			(xy 128.400433 -239.502478) (xy 128.423123 -239.457946) (xy 128.452499 -239.417513) (xy 128.487839 -239.382173)
			(xy 128.528272 -239.352797) (xy 128.572804 -239.330107) (xy 128.620336 -239.314663) (xy 128.669699 -239.306844)
			(xy 128.719677 -239.306844) (xy 128.76904 -239.314663) (xy 128.816572 -239.330107) (xy 128.861104 -239.352797)
			(xy 128.901537 -239.382173) (xy 128.936877 -239.417513) (xy 128.966253 -239.457946) (xy 128.988943 -239.502478)
			(xy 129.004387 -239.55001) (xy 129.012206 -239.599373) (xy 129.012696 -239.624362) (xy 129.318507 -239.624362)
			(xy 129.322602 -239.573634) (xy 129.334781 -239.52422) (xy 129.354729 -239.4774) (xy 129.38193 -239.434386)
			(xy 129.415678 -239.396292) (xy 129.4551 -239.364105) (xy 129.499174 -239.338659) (xy 129.54676 -239.320612)
			(xy 129.596624 -239.310432) (xy 129.647476 -239.308383) (xy 129.697997 -239.314517) (xy 129.746881 -239.328677)
			(xy 129.79286 -239.350494) (xy 129.834744 -239.379404) (xy 129.871448 -239.414659) (xy 129.902021 -239.455345)
			(xy 129.925672 -239.500408) (xy 129.941788 -239.548682) (xy 129.949952 -239.598916) (xy 129.950464 -239.624362)
			(xy 131.198615 -239.624362) (xy 131.20271 -239.573634) (xy 131.214889 -239.52422) (xy 131.234837 -239.4774)
			(xy 131.262038 -239.434386) (xy 131.295786 -239.396292) (xy 131.335208 -239.364105) (xy 131.379282 -239.338659)
			(xy 131.426868 -239.320612) (xy 131.476732 -239.310432) (xy 131.527584 -239.308383) (xy 131.578105 -239.314517)
			(xy 131.626989 -239.328677) (xy 131.672968 -239.350494) (xy 131.714852 -239.379404) (xy 131.751556 -239.414659)
			(xy 131.782129 -239.455345) (xy 131.80578 -239.500408) (xy 131.821896 -239.548682) (xy 131.83006 -239.598916)
			(xy 131.830572 -239.624362) (xy 132.138415 -239.624362) (xy 132.14251 -239.573634) (xy 132.154689 -239.52422)
			(xy 132.174637 -239.4774) (xy 132.201838 -239.434386) (xy 132.235586 -239.396292) (xy 132.275008 -239.364105)
			(xy 132.319082 -239.338659) (xy 132.366668 -239.320612) (xy 132.416532 -239.310432) (xy 132.467384 -239.308383)
			(xy 132.517905 -239.314517) (xy 132.566789 -239.328677) (xy 132.612768 -239.350494) (xy 132.654652 -239.379404)
			(xy 132.691356 -239.414659) (xy 132.721929 -239.455345) (xy 132.74558 -239.500408) (xy 132.761696 -239.548682)
			(xy 132.76986 -239.598916) (xy 132.770372 -239.624362) (xy 132.769869 -239.649351) (xy 133.077186 -239.649351)
			(xy 133.077186 -239.599373) (xy 133.085005 -239.55001) (xy 133.100449 -239.502478) (xy 133.123139 -239.457946)
			(xy 133.152515 -239.417513) (xy 133.187855 -239.382173) (xy 133.228288 -239.352797) (xy 133.27282 -239.330107)
			(xy 133.320352 -239.314663) (xy 133.369715 -239.306844) (xy 133.419693 -239.306844) (xy 133.469056 -239.314663)
			(xy 133.516588 -239.330107) (xy 133.56112 -239.352797) (xy 133.601553 -239.382173) (xy 133.636893 -239.417513)
			(xy 133.666269 -239.457946) (xy 133.688959 -239.502478) (xy 133.704403 -239.55001) (xy 133.712222 -239.599373)
			(xy 133.712712 -239.624362) (xy 134.018523 -239.624362) (xy 134.022618 -239.573634) (xy 134.034797 -239.52422)
			(xy 134.054745 -239.4774) (xy 134.081946 -239.434386) (xy 134.115694 -239.396292) (xy 134.155116 -239.364105)
			(xy 134.19919 -239.338659) (xy 134.246776 -239.320612) (xy 134.29664 -239.310432) (xy 134.347492 -239.308383)
			(xy 134.398013 -239.314517) (xy 134.446897 -239.328677) (xy 134.492876 -239.350494) (xy 134.53476 -239.379404)
			(xy 134.571464 -239.414659) (xy 134.602037 -239.455345) (xy 134.625688 -239.500408) (xy 134.641804 -239.548682)
			(xy 134.649968 -239.598916) (xy 134.65048 -239.624362) (xy 134.649977 -239.649351) (xy 134.957294 -239.649351)
			(xy 134.957294 -239.599373) (xy 134.965113 -239.55001) (xy 134.980557 -239.502478) (xy 135.003247 -239.457946)
			(xy 135.032623 -239.417513) (xy 135.067963 -239.382173) (xy 135.108396 -239.352797) (xy 135.152928 -239.330107)
			(xy 135.20046 -239.314663) (xy 135.249823 -239.306844) (xy 135.299801 -239.306844) (xy 135.349164 -239.314663)
			(xy 135.396696 -239.330107) (xy 135.441228 -239.352797) (xy 135.481661 -239.382173) (xy 135.517001 -239.417513)
			(xy 135.546377 -239.457946) (xy 135.569067 -239.502478) (xy 135.584511 -239.55001) (xy 135.59233 -239.599373)
			(xy 135.59282 -239.624362) (xy 135.898631 -239.624362) (xy 135.902726 -239.573634) (xy 135.914905 -239.52422)
			(xy 135.934853 -239.4774) (xy 135.962054 -239.434386) (xy 135.995802 -239.396292) (xy 136.035224 -239.364105)
			(xy 136.079298 -239.338659) (xy 136.126884 -239.320612) (xy 136.176748 -239.310432) (xy 136.2276 -239.308383)
			(xy 136.278121 -239.314517) (xy 136.327005 -239.328677) (xy 136.372984 -239.350494) (xy 136.414868 -239.379404)
			(xy 136.451572 -239.414659) (xy 136.482145 -239.455345) (xy 136.505796 -239.500408) (xy 136.521912 -239.548682)
			(xy 136.530076 -239.598916) (xy 136.530588 -239.624362) (xy 137.778485 -239.624362) (xy 137.78258 -239.573634)
			(xy 137.794759 -239.52422) (xy 137.814707 -239.4774) (xy 137.841908 -239.434386) (xy 137.875656 -239.396292)
			(xy 137.915078 -239.364105) (xy 137.959152 -239.338659) (xy 138.006738 -239.320612) (xy 138.056602 -239.310432)
			(xy 138.107454 -239.308383) (xy 138.157975 -239.314517) (xy 138.206859 -239.328677) (xy 138.252838 -239.350494)
			(xy 138.294722 -239.379404) (xy 138.331426 -239.414659) (xy 138.361999 -239.455345) (xy 138.38565 -239.500408)
			(xy 138.401766 -239.548682) (xy 138.40993 -239.598916) (xy 138.410442 -239.624362) (xy 138.718539 -239.624362)
			(xy 138.722634 -239.573634) (xy 138.734813 -239.52422) (xy 138.754761 -239.4774) (xy 138.781962 -239.434386)
			(xy 138.81571 -239.396292) (xy 138.855132 -239.364105) (xy 138.899206 -239.338659) (xy 138.946792 -239.320612)
			(xy 138.996656 -239.310432) (xy 139.047508 -239.308383) (xy 139.098029 -239.314517) (xy 139.146913 -239.328677)
			(xy 139.192892 -239.350494) (xy 139.234776 -239.379404) (xy 139.27148 -239.414659) (xy 139.302053 -239.455345)
			(xy 139.325704 -239.500408) (xy 139.34182 -239.548682) (xy 139.349984 -239.598916) (xy 139.350496 -239.624362)
			(xy 139.349993 -239.649351) (xy 139.65731 -239.649351) (xy 139.65731 -239.599373) (xy 139.665129 -239.55001)
			(xy 139.680573 -239.502478) (xy 139.703263 -239.457946) (xy 139.732639 -239.417513) (xy 139.767979 -239.382173)
			(xy 139.808412 -239.352797) (xy 139.852944 -239.330107) (xy 139.900476 -239.314663) (xy 139.949839 -239.306844)
			(xy 139.999817 -239.306844) (xy 140.04918 -239.314663) (xy 140.096712 -239.330107) (xy 140.141244 -239.352797)
			(xy 140.181677 -239.382173) (xy 140.217017 -239.417513) (xy 140.246393 -239.457946) (xy 140.269083 -239.502478)
			(xy 140.284527 -239.55001) (xy 140.292346 -239.599373) (xy 140.292836 -239.624362) (xy 140.598647 -239.624362)
			(xy 140.602742 -239.573634) (xy 140.614921 -239.52422) (xy 140.634869 -239.4774) (xy 140.66207 -239.434386)
			(xy 140.695818 -239.396292) (xy 140.73524 -239.364105) (xy 140.779314 -239.338659) (xy 140.8269 -239.320612)
			(xy 140.876764 -239.310432) (xy 140.927616 -239.308383) (xy 140.978137 -239.314517) (xy 141.027021 -239.328677)
			(xy 141.073 -239.350494) (xy 141.114884 -239.379404) (xy 141.151588 -239.414659) (xy 141.182161 -239.455345)
			(xy 141.205812 -239.500408) (xy 141.221928 -239.548682) (xy 141.230092 -239.598916) (xy 141.230604 -239.624362)
			(xy 141.230101 -239.649351) (xy 141.537164 -239.649351) (xy 141.537164 -239.599373) (xy 141.544983 -239.55001)
			(xy 141.560427 -239.502478) (xy 141.583117 -239.457946) (xy 141.612493 -239.417513) (xy 141.647833 -239.382173)
			(xy 141.688266 -239.352797) (xy 141.732798 -239.330107) (xy 141.78033 -239.314663) (xy 141.829693 -239.306844)
			(xy 141.879671 -239.306844) (xy 141.929034 -239.314663) (xy 141.976566 -239.330107) (xy 142.021098 -239.352797)
			(xy 142.061531 -239.382173) (xy 142.096871 -239.417513) (xy 142.126247 -239.457946) (xy 142.148937 -239.502478)
			(xy 142.164381 -239.55001) (xy 142.1722 -239.599373) (xy 142.17269 -239.624362) (xy 142.478501 -239.624362)
			(xy 142.482596 -239.573634) (xy 142.494775 -239.52422) (xy 142.514723 -239.4774) (xy 142.541924 -239.434386)
			(xy 142.575672 -239.396292) (xy 142.615094 -239.364105) (xy 142.659168 -239.338659) (xy 142.706754 -239.320612)
			(xy 142.756618 -239.310432) (xy 142.80747 -239.308383) (xy 142.857991 -239.314517) (xy 142.906875 -239.328677)
			(xy 142.952854 -239.350494) (xy 142.994738 -239.379404) (xy 143.031442 -239.414659) (xy 143.062015 -239.455345)
			(xy 143.085666 -239.500408) (xy 143.101782 -239.548682) (xy 143.109946 -239.598916) (xy 143.110458 -239.624362)
			(xy 143.109946 -239.649808) (xy 143.101782 -239.700042) (xy 143.085666 -239.748316) (xy 143.062015 -239.793379)
			(xy 143.031442 -239.834065) (xy 142.994738 -239.86932) (xy 142.952854 -239.89823) (xy 142.906875 -239.920047)
			(xy 142.857991 -239.934207) (xy 142.80747 -239.940341) (xy 142.756618 -239.938292) (xy 142.706754 -239.928112)
			(xy 142.659168 -239.910065) (xy 142.615094 -239.884619) (xy 142.575672 -239.852432) (xy 142.541924 -239.814338)
			(xy 142.514723 -239.771324) (xy 142.494775 -239.724504) (xy 142.482596 -239.67509) (xy 142.478501 -239.624362)
			(xy 142.17269 -239.624362) (xy 142.1722 -239.649351) (xy 142.164381 -239.698714) (xy 142.148937 -239.746246)
			(xy 142.126247 -239.790778) (xy 142.096871 -239.831211) (xy 142.061531 -239.866551) (xy 142.021098 -239.895927)
			(xy 141.976566 -239.918617) (xy 141.929034 -239.934061) (xy 141.879671 -239.94188) (xy 141.829693 -239.94188)
			(xy 141.78033 -239.934061) (xy 141.732798 -239.918617) (xy 141.688266 -239.895927) (xy 141.647833 -239.866551)
			(xy 141.612493 -239.831211) (xy 141.583117 -239.790778) (xy 141.560427 -239.746246) (xy 141.544983 -239.698714)
			(xy 141.537164 -239.649351) (xy 141.230101 -239.649351) (xy 141.230092 -239.649808) (xy 141.221928 -239.700042)
			(xy 141.205812 -239.748316) (xy 141.182161 -239.793379) (xy 141.151588 -239.834065) (xy 141.114884 -239.86932)
			(xy 141.073 -239.89823) (xy 141.027021 -239.920047) (xy 140.978137 -239.934207) (xy 140.927616 -239.940341)
			(xy 140.876764 -239.938292) (xy 140.8269 -239.928112) (xy 140.779314 -239.910065) (xy 140.73524 -239.884619)
			(xy 140.695818 -239.852432) (xy 140.66207 -239.814338) (xy 140.634869 -239.771324) (xy 140.614921 -239.724504)
			(xy 140.602742 -239.67509) (xy 140.598647 -239.624362) (xy 140.292836 -239.624362) (xy 140.292346 -239.649351)
			(xy 140.284527 -239.698714) (xy 140.269083 -239.746246) (xy 140.246393 -239.790778) (xy 140.217017 -239.831211)
			(xy 140.181677 -239.866551) (xy 140.141244 -239.895927) (xy 140.096712 -239.918617) (xy 140.04918 -239.934061)
			(xy 139.999817 -239.94188) (xy 139.949839 -239.94188) (xy 139.900476 -239.934061) (xy 139.852944 -239.918617)
			(xy 139.808412 -239.895927) (xy 139.767979 -239.866551) (xy 139.732639 -239.831211) (xy 139.703263 -239.790778)
			(xy 139.680573 -239.746246) (xy 139.665129 -239.698714) (xy 139.65731 -239.649351) (xy 139.349993 -239.649351)
			(xy 139.349984 -239.649808) (xy 139.34182 -239.700042) (xy 139.325704 -239.748316) (xy 139.302053 -239.793379)
			(xy 139.27148 -239.834065) (xy 139.234776 -239.86932) (xy 139.192892 -239.89823) (xy 139.146913 -239.920047)
			(xy 139.098029 -239.934207) (xy 139.047508 -239.940341) (xy 138.996656 -239.938292) (xy 138.946792 -239.928112)
			(xy 138.899206 -239.910065) (xy 138.855132 -239.884619) (xy 138.81571 -239.852432) (xy 138.781962 -239.814338)
			(xy 138.754761 -239.771324) (xy 138.734813 -239.724504) (xy 138.722634 -239.67509) (xy 138.718539 -239.624362)
			(xy 138.410442 -239.624362) (xy 138.40993 -239.649808) (xy 138.401766 -239.700042) (xy 138.38565 -239.748316)
			(xy 138.361999 -239.793379) (xy 138.331426 -239.834065) (xy 138.294722 -239.86932) (xy 138.252838 -239.89823)
			(xy 138.206859 -239.920047) (xy 138.157975 -239.934207) (xy 138.107454 -239.940341) (xy 138.056602 -239.938292)
			(xy 138.006738 -239.928112) (xy 137.959152 -239.910065) (xy 137.915078 -239.884619) (xy 137.875656 -239.852432)
			(xy 137.841908 -239.814338) (xy 137.814707 -239.771324) (xy 137.794759 -239.724504) (xy 137.78258 -239.67509)
			(xy 137.778485 -239.624362) (xy 136.530588 -239.624362) (xy 136.530076 -239.649808) (xy 136.521912 -239.700042)
			(xy 136.505796 -239.748316) (xy 136.482145 -239.793379) (xy 136.451572 -239.834065) (xy 136.414868 -239.86932)
			(xy 136.372984 -239.89823) (xy 136.327005 -239.920047) (xy 136.278121 -239.934207) (xy 136.2276 -239.940341)
			(xy 136.176748 -239.938292) (xy 136.126884 -239.928112) (xy 136.079298 -239.910065) (xy 136.035224 -239.884619)
			(xy 135.995802 -239.852432) (xy 135.962054 -239.814338) (xy 135.934853 -239.771324) (xy 135.914905 -239.724504)
			(xy 135.902726 -239.67509) (xy 135.898631 -239.624362) (xy 135.59282 -239.624362) (xy 135.59233 -239.649351)
			(xy 135.584511 -239.698714) (xy 135.569067 -239.746246) (xy 135.546377 -239.790778) (xy 135.517001 -239.831211)
			(xy 135.481661 -239.866551) (xy 135.441228 -239.895927) (xy 135.396696 -239.918617) (xy 135.349164 -239.934061)
			(xy 135.299801 -239.94188) (xy 135.249823 -239.94188) (xy 135.20046 -239.934061) (xy 135.152928 -239.918617)
			(xy 135.108396 -239.895927) (xy 135.067963 -239.866551) (xy 135.032623 -239.831211) (xy 135.003247 -239.790778)
			(xy 134.980557 -239.746246) (xy 134.965113 -239.698714) (xy 134.957294 -239.649351) (xy 134.649977 -239.649351)
			(xy 134.649968 -239.649808) (xy 134.641804 -239.700042) (xy 134.625688 -239.748316) (xy 134.602037 -239.793379)
			(xy 134.571464 -239.834065) (xy 134.53476 -239.86932) (xy 134.492876 -239.89823) (xy 134.446897 -239.920047)
			(xy 134.398013 -239.934207) (xy 134.347492 -239.940341) (xy 134.29664 -239.938292) (xy 134.246776 -239.928112)
			(xy 134.19919 -239.910065) (xy 134.155116 -239.884619) (xy 134.115694 -239.852432) (xy 134.081946 -239.814338)
			(xy 134.054745 -239.771324) (xy 134.034797 -239.724504) (xy 134.022618 -239.67509) (xy 134.018523 -239.624362)
			(xy 133.712712 -239.624362) (xy 133.712222 -239.649351) (xy 133.704403 -239.698714) (xy 133.688959 -239.746246)
			(xy 133.666269 -239.790778) (xy 133.636893 -239.831211) (xy 133.601553 -239.866551) (xy 133.56112 -239.895927)
			(xy 133.516588 -239.918617) (xy 133.469056 -239.934061) (xy 133.419693 -239.94188) (xy 133.369715 -239.94188)
			(xy 133.320352 -239.934061) (xy 133.27282 -239.918617) (xy 133.228288 -239.895927) (xy 133.187855 -239.866551)
			(xy 133.152515 -239.831211) (xy 133.123139 -239.790778) (xy 133.100449 -239.746246) (xy 133.085005 -239.698714)
			(xy 133.077186 -239.649351) (xy 132.769869 -239.649351) (xy 132.76986 -239.649808) (xy 132.761696 -239.700042)
			(xy 132.74558 -239.748316) (xy 132.721929 -239.793379) (xy 132.691356 -239.834065) (xy 132.654652 -239.86932)
			(xy 132.612768 -239.89823) (xy 132.566789 -239.920047) (xy 132.517905 -239.934207) (xy 132.467384 -239.940341)
			(xy 132.416532 -239.938292) (xy 132.366668 -239.928112) (xy 132.319082 -239.910065) (xy 132.275008 -239.884619)
			(xy 132.235586 -239.852432) (xy 132.201838 -239.814338) (xy 132.174637 -239.771324) (xy 132.154689 -239.724504)
			(xy 132.14251 -239.67509) (xy 132.138415 -239.624362) (xy 131.830572 -239.624362) (xy 131.83006 -239.649808)
			(xy 131.821896 -239.700042) (xy 131.80578 -239.748316) (xy 131.782129 -239.793379) (xy 131.751556 -239.834065)
			(xy 131.714852 -239.86932) (xy 131.672968 -239.89823) (xy 131.626989 -239.920047) (xy 131.578105 -239.934207)
			(xy 131.527584 -239.940341) (xy 131.476732 -239.938292) (xy 131.426868 -239.928112) (xy 131.379282 -239.910065)
			(xy 131.335208 -239.884619) (xy 131.295786 -239.852432) (xy 131.262038 -239.814338) (xy 131.234837 -239.771324)
			(xy 131.214889 -239.724504) (xy 131.20271 -239.67509) (xy 131.198615 -239.624362) (xy 129.950464 -239.624362)
			(xy 129.949952 -239.649808) (xy 129.941788 -239.700042) (xy 129.925672 -239.748316) (xy 129.902021 -239.793379)
			(xy 129.871448 -239.834065) (xy 129.834744 -239.86932) (xy 129.79286 -239.89823) (xy 129.746881 -239.920047)
			(xy 129.697997 -239.934207) (xy 129.647476 -239.940341) (xy 129.596624 -239.938292) (xy 129.54676 -239.928112)
			(xy 129.499174 -239.910065) (xy 129.4551 -239.884619) (xy 129.415678 -239.852432) (xy 129.38193 -239.814338)
			(xy 129.354729 -239.771324) (xy 129.334781 -239.724504) (xy 129.322602 -239.67509) (xy 129.318507 -239.624362)
			(xy 129.012696 -239.624362) (xy 129.012206 -239.649351) (xy 129.004387 -239.698714) (xy 128.988943 -239.746246)
			(xy 128.966253 -239.790778) (xy 128.936877 -239.831211) (xy 128.901537 -239.866551) (xy 128.861104 -239.895927)
			(xy 128.816572 -239.918617) (xy 128.76904 -239.934061) (xy 128.719677 -239.94188) (xy 128.669699 -239.94188)
			(xy 128.620336 -239.934061) (xy 128.572804 -239.918617) (xy 128.528272 -239.895927) (xy 128.487839 -239.866551)
			(xy 128.452499 -239.831211) (xy 128.423123 -239.790778) (xy 128.400433 -239.746246) (xy 128.384989 -239.698714)
			(xy 128.37717 -239.649351) (xy 128.069853 -239.649351) (xy 128.069844 -239.649808) (xy 128.06168 -239.700042)
			(xy 128.045564 -239.748316) (xy 128.021913 -239.793379) (xy 127.99134 -239.834065) (xy 127.954636 -239.86932)
			(xy 127.912752 -239.89823) (xy 127.866773 -239.920047) (xy 127.817889 -239.934207) (xy 127.767368 -239.940341)
			(xy 127.716516 -239.938292) (xy 127.666652 -239.928112) (xy 127.619066 -239.910065) (xy 127.574992 -239.884619)
			(xy 127.53557 -239.852432) (xy 127.501822 -239.814338) (xy 127.474621 -239.771324) (xy 127.454673 -239.724504)
			(xy 127.442494 -239.67509) (xy 127.438399 -239.624362) (xy 127.132356 -239.624362) (xy 127.132356 -239.64939)
			(xy 127.124537 -239.698756) (xy 127.109094 -239.746291) (xy 127.086404 -239.790825) (xy 127.057028 -239.831262)
			(xy 127.021688 -239.866606) (xy 126.981254 -239.895986) (xy 126.936723 -239.918681) (xy 126.889189 -239.93413)
			(xy 126.839824 -239.941953) (xy 126.814834 -239.94237) (xy 126.8024 -239.942272) (xy 126.777607 -239.940363)
			(xy 126.765304 -239.93856) (xy 126.763526 -239.938306) (xy 126.75616 -239.937798) (xy 126.747781 -239.938225)
			(xy 126.731971 -239.943803) (xy 126.725172 -239.94872) (xy 126.706122 -239.964722) (xy 126.705614 -239.96523)
			(xy 126.666244 -239.999012) (xy 126.658717 -240.00608) (xy 126.649541 -240.024557) (xy 126.648464 -240.034826)
			(xy 126.648464 -240.33226) (xy 126.648972 -240.335816) (xy 126.650496 -240.346738) (xy 126.651004 -240.34877)
			(xy 126.651512 -240.350294) (xy 126.656776 -240.370911) (xy 126.662387 -240.413092) (xy 126.662688 -240.434368)
			(xy 127.908553 -240.434368) (xy 127.912648 -240.38364) (xy 127.924827 -240.334226) (xy 127.944775 -240.287406)
			(xy 127.971976 -240.244392) (xy 128.005724 -240.206298) (xy 128.045146 -240.174111) (xy 128.08922 -240.148665)
			(xy 128.136806 -240.130618) (xy 128.18667 -240.120438) (xy 128.237522 -240.118389) (xy 128.288043 -240.124523)
			(xy 128.336927 -240.138683) (xy 128.382906 -240.1605) (xy 128.42479 -240.18941) (xy 128.461494 -240.224665)
			(xy 128.492067 -240.265351) (xy 128.515718 -240.310414) (xy 128.531834 -240.358688) (xy 128.539998 -240.408922)
			(xy 128.54051 -240.434368) (xy 128.848607 -240.434368) (xy 128.852702 -240.38364) (xy 128.864881 -240.334226)
			(xy 128.884829 -240.287406) (xy 128.91203 -240.244392) (xy 128.945778 -240.206298) (xy 128.9852 -240.174111)
			(xy 129.029274 -240.148665) (xy 129.07686 -240.130618) (xy 129.126724 -240.120438) (xy 129.177576 -240.118389)
			(xy 129.228097 -240.124523) (xy 129.276981 -240.138683) (xy 129.32296 -240.1605) (xy 129.364844 -240.18941)
			(xy 129.401548 -240.224665) (xy 129.432121 -240.265351) (xy 129.455772 -240.310414) (xy 129.471888 -240.358688)
			(xy 129.480052 -240.408922) (xy 129.480564 -240.434368) (xy 129.480061 -240.459357) (xy 129.787124 -240.459357)
			(xy 129.787124 -240.409379) (xy 129.794943 -240.360016) (xy 129.810387 -240.312484) (xy 129.833077 -240.267952)
			(xy 129.862453 -240.227519) (xy 129.897793 -240.192179) (xy 129.938226 -240.162803) (xy 129.982758 -240.140113)
			(xy 130.03029 -240.124669) (xy 130.079653 -240.11685) (xy 130.129631 -240.11685) (xy 130.178994 -240.124669)
			(xy 130.226526 -240.140113) (xy 130.271058 -240.162803) (xy 130.311491 -240.192179) (xy 130.346831 -240.227519)
			(xy 130.376207 -240.267952) (xy 130.398897 -240.312484) (xy 130.414341 -240.360016) (xy 130.42216 -240.409379)
			(xy 130.42265 -240.434368) (xy 130.728461 -240.434368) (xy 130.732556 -240.38364) (xy 130.744735 -240.334226)
			(xy 130.764683 -240.287406) (xy 130.791884 -240.244392) (xy 130.825632 -240.206298) (xy 130.865054 -240.174111)
			(xy 130.909128 -240.148665) (xy 130.956714 -240.130618) (xy 131.006578 -240.120438) (xy 131.05743 -240.118389)
			(xy 131.107951 -240.124523) (xy 131.156835 -240.138683) (xy 131.202814 -240.1605) (xy 131.244698 -240.18941)
			(xy 131.281402 -240.224665) (xy 131.311975 -240.265351) (xy 131.335626 -240.310414) (xy 131.351742 -240.358688)
			(xy 131.359906 -240.408922) (xy 131.360418 -240.434368) (xy 131.359915 -240.459357) (xy 131.667232 -240.459357)
			(xy 131.667232 -240.409379) (xy 131.675051 -240.360016) (xy 131.690495 -240.312484) (xy 131.713185 -240.267952)
			(xy 131.742561 -240.227519) (xy 131.777901 -240.192179) (xy 131.818334 -240.162803) (xy 131.862866 -240.140113)
			(xy 131.910398 -240.124669) (xy 131.959761 -240.11685) (xy 132.009739 -240.11685) (xy 132.059102 -240.124669)
			(xy 132.106634 -240.140113) (xy 132.151166 -240.162803) (xy 132.191599 -240.192179) (xy 132.226939 -240.227519)
			(xy 132.256315 -240.267952) (xy 132.279005 -240.312484) (xy 132.294449 -240.360016) (xy 132.302268 -240.409379)
			(xy 132.302758 -240.434368) (xy 132.608569 -240.434368) (xy 132.612664 -240.38364) (xy 132.624843 -240.334226)
			(xy 132.644791 -240.287406) (xy 132.671992 -240.244392) (xy 132.70574 -240.206298) (xy 132.745162 -240.174111)
			(xy 132.789236 -240.148665) (xy 132.836822 -240.130618) (xy 132.886686 -240.120438) (xy 132.937538 -240.118389)
			(xy 132.988059 -240.124523) (xy 133.036943 -240.138683) (xy 133.082922 -240.1605) (xy 133.124806 -240.18941)
			(xy 133.16151 -240.224665) (xy 133.192083 -240.265351) (xy 133.215734 -240.310414) (xy 133.23185 -240.358688)
			(xy 133.240014 -240.408922) (xy 133.240526 -240.434368) (xy 133.240023 -240.459357) (xy 133.54734 -240.459357)
			(xy 133.54734 -240.409379) (xy 133.555159 -240.360016) (xy 133.570603 -240.312484) (xy 133.593293 -240.267952)
			(xy 133.622669 -240.227519) (xy 133.658009 -240.192179) (xy 133.698442 -240.162803) (xy 133.742974 -240.140113)
			(xy 133.790506 -240.124669) (xy 133.839869 -240.11685) (xy 133.889847 -240.11685) (xy 133.93921 -240.124669)
			(xy 133.986742 -240.140113) (xy 134.031274 -240.162803) (xy 134.071707 -240.192179) (xy 134.107047 -240.227519)
			(xy 134.136423 -240.267952) (xy 134.159113 -240.312484) (xy 134.174557 -240.360016) (xy 134.182376 -240.409379)
			(xy 134.182866 -240.434368) (xy 134.488423 -240.434368) (xy 134.492518 -240.38364) (xy 134.504697 -240.334226)
			(xy 134.524645 -240.287406) (xy 134.551846 -240.244392) (xy 134.585594 -240.206298) (xy 134.625016 -240.174111)
			(xy 134.66909 -240.148665) (xy 134.716676 -240.130618) (xy 134.76654 -240.120438) (xy 134.817392 -240.118389)
			(xy 134.867913 -240.124523) (xy 134.916797 -240.138683) (xy 134.962776 -240.1605) (xy 135.00466 -240.18941)
			(xy 135.041364 -240.224665) (xy 135.071937 -240.265351) (xy 135.095588 -240.310414) (xy 135.111704 -240.358688)
			(xy 135.119868 -240.408922) (xy 135.12038 -240.434368) (xy 135.428477 -240.434368) (xy 135.432572 -240.38364)
			(xy 135.444751 -240.334226) (xy 135.464699 -240.287406) (xy 135.4919 -240.244392) (xy 135.525648 -240.206298)
			(xy 135.56507 -240.174111) (xy 135.609144 -240.148665) (xy 135.65673 -240.130618) (xy 135.706594 -240.120438)
			(xy 135.757446 -240.118389) (xy 135.807967 -240.124523) (xy 135.856851 -240.138683) (xy 135.90283 -240.1605)
			(xy 135.944714 -240.18941) (xy 135.981418 -240.224665) (xy 136.011991 -240.265351) (xy 136.035642 -240.310414)
			(xy 136.051758 -240.358688) (xy 136.059922 -240.408922) (xy 136.060434 -240.434368) (xy 136.059931 -240.459357)
			(xy 136.367248 -240.459357) (xy 136.367248 -240.409379) (xy 136.375067 -240.360016) (xy 136.390511 -240.312484)
			(xy 136.413201 -240.267952) (xy 136.442577 -240.227519) (xy 136.477917 -240.192179) (xy 136.51835 -240.162803)
			(xy 136.562882 -240.140113) (xy 136.610414 -240.124669) (xy 136.659777 -240.11685) (xy 136.709755 -240.11685)
			(xy 136.759118 -240.124669) (xy 136.80665 -240.140113) (xy 136.851182 -240.162803) (xy 136.891615 -240.192179)
			(xy 136.926955 -240.227519) (xy 136.956331 -240.267952) (xy 136.979021 -240.312484) (xy 136.994465 -240.360016)
			(xy 137.002284 -240.409379) (xy 137.002774 -240.434368) (xy 137.308585 -240.434368) (xy 137.31268 -240.38364)
			(xy 137.324859 -240.334226) (xy 137.344807 -240.287406) (xy 137.372008 -240.244392) (xy 137.405756 -240.206298)
			(xy 137.445178 -240.174111) (xy 137.489252 -240.148665) (xy 137.536838 -240.130618) (xy 137.586702 -240.120438)
			(xy 137.637554 -240.118389) (xy 137.688075 -240.124523) (xy 137.736959 -240.138683) (xy 137.782938 -240.1605)
			(xy 137.824822 -240.18941) (xy 137.861526 -240.224665) (xy 137.892099 -240.265351) (xy 137.91575 -240.310414)
			(xy 137.931866 -240.358688) (xy 137.94003 -240.408922) (xy 137.940542 -240.434368) (xy 137.940039 -240.459357)
			(xy 138.247356 -240.459357) (xy 138.247356 -240.409379) (xy 138.255175 -240.360016) (xy 138.270619 -240.312484)
			(xy 138.293309 -240.267952) (xy 138.322685 -240.227519) (xy 138.358025 -240.192179) (xy 138.398458 -240.162803)
			(xy 138.44299 -240.140113) (xy 138.490522 -240.124669) (xy 138.539885 -240.11685) (xy 138.589863 -240.11685)
			(xy 138.639226 -240.124669) (xy 138.686758 -240.140113) (xy 138.73129 -240.162803) (xy 138.771723 -240.192179)
			(xy 138.807063 -240.227519) (xy 138.836439 -240.267952) (xy 138.859129 -240.312484) (xy 138.874573 -240.360016)
			(xy 138.882392 -240.409379) (xy 138.882882 -240.434368) (xy 139.188439 -240.434368) (xy 139.192534 -240.38364)
			(xy 139.204713 -240.334226) (xy 139.224661 -240.287406) (xy 139.251862 -240.244392) (xy 139.28561 -240.206298)
			(xy 139.325032 -240.174111) (xy 139.369106 -240.148665) (xy 139.416692 -240.130618) (xy 139.466556 -240.120438)
			(xy 139.517408 -240.118389) (xy 139.567929 -240.124523) (xy 139.616813 -240.138683) (xy 139.662792 -240.1605)
			(xy 139.704676 -240.18941) (xy 139.74138 -240.224665) (xy 139.771953 -240.265351) (xy 139.795604 -240.310414)
			(xy 139.81172 -240.358688) (xy 139.819884 -240.408922) (xy 139.820396 -240.434368) (xy 139.819893 -240.459357)
			(xy 140.12721 -240.459357) (xy 140.12721 -240.409379) (xy 140.135029 -240.360016) (xy 140.150473 -240.312484)
			(xy 140.173163 -240.267952) (xy 140.202539 -240.227519) (xy 140.237879 -240.192179) (xy 140.278312 -240.162803)
			(xy 140.322844 -240.140113) (xy 140.370376 -240.124669) (xy 140.419739 -240.11685) (xy 140.469717 -240.11685)
			(xy 140.51908 -240.124669) (xy 140.566612 -240.140113) (xy 140.611144 -240.162803) (xy 140.651577 -240.192179)
			(xy 140.686917 -240.227519) (xy 140.716293 -240.267952) (xy 140.738983 -240.312484) (xy 140.754427 -240.360016)
			(xy 140.762246 -240.409379) (xy 140.762736 -240.434368) (xy 141.068547 -240.434368) (xy 141.072642 -240.38364)
			(xy 141.084821 -240.334226) (xy 141.104769 -240.287406) (xy 141.13197 -240.244392) (xy 141.165718 -240.206298)
			(xy 141.20514 -240.174111) (xy 141.249214 -240.148665) (xy 141.2968 -240.130618) (xy 141.346664 -240.120438)
			(xy 141.397516 -240.118389) (xy 141.448037 -240.124523) (xy 141.496921 -240.138683) (xy 141.5429 -240.1605)
			(xy 141.584784 -240.18941) (xy 141.621488 -240.224665) (xy 141.652061 -240.265351) (xy 141.675712 -240.310414)
			(xy 141.691828 -240.358688) (xy 141.699992 -240.408922) (xy 141.700504 -240.434368) (xy 142.008601 -240.434368)
			(xy 142.012696 -240.38364) (xy 142.024875 -240.334226) (xy 142.044823 -240.287406) (xy 142.072024 -240.244392)
			(xy 142.105772 -240.206298) (xy 142.145194 -240.174111) (xy 142.189268 -240.148665) (xy 142.236854 -240.130618)
			(xy 142.286718 -240.120438) (xy 142.33757 -240.118389) (xy 142.388091 -240.124523) (xy 142.436975 -240.138683)
			(xy 142.482954 -240.1605) (xy 142.524838 -240.18941) (xy 142.561542 -240.224665) (xy 142.592115 -240.265351)
			(xy 142.615766 -240.310414) (xy 142.631882 -240.358688) (xy 142.640046 -240.408922) (xy 142.640558 -240.434368)
			(xy 142.640055 -240.459357) (xy 142.947118 -240.459357) (xy 142.947118 -240.409379) (xy 142.954937 -240.360016)
			(xy 142.970381 -240.312484) (xy 142.993071 -240.267952) (xy 143.022447 -240.227519) (xy 143.057787 -240.192179)
			(xy 143.09822 -240.162803) (xy 143.142752 -240.140113) (xy 143.190284 -240.124669) (xy 143.239647 -240.11685)
			(xy 143.289625 -240.11685) (xy 143.338988 -240.124669) (xy 143.38652 -240.140113) (xy 143.431052 -240.162803)
			(xy 143.471485 -240.192179) (xy 143.506825 -240.227519) (xy 143.536201 -240.267952) (xy 143.558891 -240.312484)
			(xy 143.574335 -240.360016) (xy 143.582154 -240.409379) (xy 143.582644 -240.434368) (xy 143.582154 -240.459357)
			(xy 143.574335 -240.50872) (xy 143.558891 -240.556252) (xy 143.536201 -240.600784) (xy 143.506825 -240.641217)
			(xy 143.471485 -240.676557) (xy 143.431052 -240.705933) (xy 143.38652 -240.728623) (xy 143.338988 -240.744067)
			(xy 143.289625 -240.751886) (xy 143.239647 -240.751886) (xy 143.190284 -240.744067) (xy 143.142752 -240.728623)
			(xy 143.09822 -240.705933) (xy 143.057787 -240.676557) (xy 143.022447 -240.641217) (xy 142.993071 -240.600784)
			(xy 142.970381 -240.556252) (xy 142.954937 -240.50872) (xy 142.947118 -240.459357) (xy 142.640055 -240.459357)
			(xy 142.640046 -240.459814) (xy 142.631882 -240.510048) (xy 142.615766 -240.558322) (xy 142.592115 -240.603385)
			(xy 142.561542 -240.644071) (xy 142.524838 -240.679326) (xy 142.482954 -240.708236) (xy 142.436975 -240.730053)
			(xy 142.388091 -240.744213) (xy 142.33757 -240.750347) (xy 142.286718 -240.748298) (xy 142.236854 -240.738118)
			(xy 142.189268 -240.720071) (xy 142.145194 -240.694625) (xy 142.105772 -240.662438) (xy 142.072024 -240.624344)
			(xy 142.044823 -240.58133) (xy 142.024875 -240.53451) (xy 142.012696 -240.485096) (xy 142.008601 -240.434368)
			(xy 141.700504 -240.434368) (xy 141.699992 -240.459814) (xy 141.691828 -240.510048) (xy 141.675712 -240.558322)
			(xy 141.652061 -240.603385) (xy 141.621488 -240.644071) (xy 141.584784 -240.679326) (xy 141.5429 -240.708236)
			(xy 141.496921 -240.730053) (xy 141.448037 -240.744213) (xy 141.397516 -240.750347) (xy 141.346664 -240.748298)
			(xy 141.2968 -240.738118) (xy 141.249214 -240.720071) (xy 141.20514 -240.694625) (xy 141.165718 -240.662438)
			(xy 141.13197 -240.624344) (xy 141.104769 -240.58133) (xy 141.084821 -240.53451) (xy 141.072642 -240.485096)
			(xy 141.068547 -240.434368) (xy 140.762736 -240.434368) (xy 140.762246 -240.459357) (xy 140.754427 -240.50872)
			(xy 140.738983 -240.556252) (xy 140.716293 -240.600784) (xy 140.686917 -240.641217) (xy 140.651577 -240.676557)
			(xy 140.611144 -240.705933) (xy 140.566612 -240.728623) (xy 140.51908 -240.744067) (xy 140.469717 -240.751886)
			(xy 140.419739 -240.751886) (xy 140.370376 -240.744067) (xy 140.322844 -240.728623) (xy 140.278312 -240.705933)
			(xy 140.237879 -240.676557) (xy 140.202539 -240.641217) (xy 140.173163 -240.600784) (xy 140.150473 -240.556252)
			(xy 140.135029 -240.50872) (xy 140.12721 -240.459357) (xy 139.819893 -240.459357) (xy 139.819884 -240.459814)
			(xy 139.81172 -240.510048) (xy 139.795604 -240.558322) (xy 139.771953 -240.603385) (xy 139.74138 -240.644071)
			(xy 139.704676 -240.679326) (xy 139.662792 -240.708236) (xy 139.616813 -240.730053) (xy 139.567929 -240.744213)
			(xy 139.517408 -240.750347) (xy 139.466556 -240.748298) (xy 139.416692 -240.738118) (xy 139.369106 -240.720071)
			(xy 139.325032 -240.694625) (xy 139.28561 -240.662438) (xy 139.251862 -240.624344) (xy 139.224661 -240.58133)
			(xy 139.204713 -240.53451) (xy 139.192534 -240.485096) (xy 139.188439 -240.434368) (xy 138.882882 -240.434368)
			(xy 138.882392 -240.459357) (xy 138.874573 -240.50872) (xy 138.859129 -240.556252) (xy 138.836439 -240.600784)
			(xy 138.807063 -240.641217) (xy 138.771723 -240.676557) (xy 138.73129 -240.705933) (xy 138.686758 -240.728623)
			(xy 138.639226 -240.744067) (xy 138.589863 -240.751886) (xy 138.539885 -240.751886) (xy 138.490522 -240.744067)
			(xy 138.44299 -240.728623) (xy 138.398458 -240.705933) (xy 138.358025 -240.676557) (xy 138.322685 -240.641217)
			(xy 138.293309 -240.600784) (xy 138.270619 -240.556252) (xy 138.255175 -240.50872) (xy 138.247356 -240.459357)
			(xy 137.940039 -240.459357) (xy 137.94003 -240.459814) (xy 137.931866 -240.510048) (xy 137.91575 -240.558322)
			(xy 137.892099 -240.603385) (xy 137.861526 -240.644071) (xy 137.824822 -240.679326) (xy 137.782938 -240.708236)
			(xy 137.736959 -240.730053) (xy 137.688075 -240.744213) (xy 137.637554 -240.750347) (xy 137.586702 -240.748298)
			(xy 137.536838 -240.738118) (xy 137.489252 -240.720071) (xy 137.445178 -240.694625) (xy 137.405756 -240.662438)
			(xy 137.372008 -240.624344) (xy 137.344807 -240.58133) (xy 137.324859 -240.53451) (xy 137.31268 -240.485096)
			(xy 137.308585 -240.434368) (xy 137.002774 -240.434368) (xy 137.002284 -240.459357) (xy 136.994465 -240.50872)
			(xy 136.979021 -240.556252) (xy 136.956331 -240.600784) (xy 136.926955 -240.641217) (xy 136.891615 -240.676557)
			(xy 136.851182 -240.705933) (xy 136.80665 -240.728623) (xy 136.759118 -240.744067) (xy 136.709755 -240.751886)
			(xy 136.659777 -240.751886) (xy 136.610414 -240.744067) (xy 136.562882 -240.728623) (xy 136.51835 -240.705933)
			(xy 136.477917 -240.676557) (xy 136.442577 -240.641217) (xy 136.413201 -240.600784) (xy 136.390511 -240.556252)
			(xy 136.375067 -240.50872) (xy 136.367248 -240.459357) (xy 136.059931 -240.459357) (xy 136.059922 -240.459814)
			(xy 136.051758 -240.510048) (xy 136.035642 -240.558322) (xy 136.011991 -240.603385) (xy 135.981418 -240.644071)
			(xy 135.944714 -240.679326) (xy 135.90283 -240.708236) (xy 135.856851 -240.730053) (xy 135.807967 -240.744213)
			(xy 135.757446 -240.750347) (xy 135.706594 -240.748298) (xy 135.65673 -240.738118) (xy 135.609144 -240.720071)
			(xy 135.56507 -240.694625) (xy 135.525648 -240.662438) (xy 135.4919 -240.624344) (xy 135.464699 -240.58133)
			(xy 135.444751 -240.53451) (xy 135.432572 -240.485096) (xy 135.428477 -240.434368) (xy 135.12038 -240.434368)
			(xy 135.119868 -240.459814) (xy 135.111704 -240.510048) (xy 135.095588 -240.558322) (xy 135.071937 -240.603385)
			(xy 135.041364 -240.644071) (xy 135.00466 -240.679326) (xy 134.962776 -240.708236) (xy 134.916797 -240.730053)
			(xy 134.867913 -240.744213) (xy 134.817392 -240.750347) (xy 134.76654 -240.748298) (xy 134.716676 -240.738118)
			(xy 134.66909 -240.720071) (xy 134.625016 -240.694625) (xy 134.585594 -240.662438) (xy 134.551846 -240.624344)
			(xy 134.524645 -240.58133) (xy 134.504697 -240.53451) (xy 134.492518 -240.485096) (xy 134.488423 -240.434368)
			(xy 134.182866 -240.434368) (xy 134.182376 -240.459357) (xy 134.174557 -240.50872) (xy 134.159113 -240.556252)
			(xy 134.136423 -240.600784) (xy 134.107047 -240.641217) (xy 134.071707 -240.676557) (xy 134.031274 -240.705933)
			(xy 133.986742 -240.728623) (xy 133.93921 -240.744067) (xy 133.889847 -240.751886) (xy 133.839869 -240.751886)
			(xy 133.790506 -240.744067) (xy 133.742974 -240.728623) (xy 133.698442 -240.705933) (xy 133.658009 -240.676557)
			(xy 133.622669 -240.641217) (xy 133.593293 -240.600784) (xy 133.570603 -240.556252) (xy 133.555159 -240.50872)
			(xy 133.54734 -240.459357) (xy 133.240023 -240.459357) (xy 133.240014 -240.459814) (xy 133.23185 -240.510048)
			(xy 133.215734 -240.558322) (xy 133.192083 -240.603385) (xy 133.16151 -240.644071) (xy 133.124806 -240.679326)
			(xy 133.082922 -240.708236) (xy 133.036943 -240.730053) (xy 132.988059 -240.744213) (xy 132.937538 -240.750347)
			(xy 132.886686 -240.748298) (xy 132.836822 -240.738118) (xy 132.789236 -240.720071) (xy 132.745162 -240.694625)
			(xy 132.70574 -240.662438) (xy 132.671992 -240.624344) (xy 132.644791 -240.58133) (xy 132.624843 -240.53451)
			(xy 132.612664 -240.485096) (xy 132.608569 -240.434368) (xy 132.302758 -240.434368) (xy 132.302268 -240.459357)
			(xy 132.294449 -240.50872) (xy 132.279005 -240.556252) (xy 132.256315 -240.600784) (xy 132.226939 -240.641217)
			(xy 132.191599 -240.676557) (xy 132.151166 -240.705933) (xy 132.106634 -240.728623) (xy 132.059102 -240.744067)
			(xy 132.009739 -240.751886) (xy 131.959761 -240.751886) (xy 131.910398 -240.744067) (xy 131.862866 -240.728623)
			(xy 131.818334 -240.705933) (xy 131.777901 -240.676557) (xy 131.742561 -240.641217) (xy 131.713185 -240.600784)
			(xy 131.690495 -240.556252) (xy 131.675051 -240.50872) (xy 131.667232 -240.459357) (xy 131.359915 -240.459357)
			(xy 131.359906 -240.459814) (xy 131.351742 -240.510048) (xy 131.335626 -240.558322) (xy 131.311975 -240.603385)
			(xy 131.281402 -240.644071) (xy 131.244698 -240.679326) (xy 131.202814 -240.708236) (xy 131.156835 -240.730053)
			(xy 131.107951 -240.744213) (xy 131.05743 -240.750347) (xy 131.006578 -240.748298) (xy 130.956714 -240.738118)
			(xy 130.909128 -240.720071) (xy 130.865054 -240.694625) (xy 130.825632 -240.662438) (xy 130.791884 -240.624344)
			(xy 130.764683 -240.58133) (xy 130.744735 -240.53451) (xy 130.732556 -240.485096) (xy 130.728461 -240.434368)
			(xy 130.42265 -240.434368) (xy 130.42216 -240.459357) (xy 130.414341 -240.50872) (xy 130.398897 -240.556252)
			(xy 130.376207 -240.600784) (xy 130.346831 -240.641217) (xy 130.311491 -240.676557) (xy 130.271058 -240.705933)
			(xy 130.226526 -240.728623) (xy 130.178994 -240.744067) (xy 130.129631 -240.751886) (xy 130.079653 -240.751886)
			(xy 130.03029 -240.744067) (xy 129.982758 -240.728623) (xy 129.938226 -240.705933) (xy 129.897793 -240.676557)
			(xy 129.862453 -240.641217) (xy 129.833077 -240.600784) (xy 129.810387 -240.556252) (xy 129.794943 -240.50872)
			(xy 129.787124 -240.459357) (xy 129.480061 -240.459357) (xy 129.480052 -240.459814) (xy 129.471888 -240.510048)
			(xy 129.455772 -240.558322) (xy 129.432121 -240.603385) (xy 129.401548 -240.644071) (xy 129.364844 -240.679326)
			(xy 129.32296 -240.708236) (xy 129.276981 -240.730053) (xy 129.228097 -240.744213) (xy 129.177576 -240.750347)
			(xy 129.126724 -240.748298) (xy 129.07686 -240.738118) (xy 129.029274 -240.720071) (xy 128.9852 -240.694625)
			(xy 128.945778 -240.662438) (xy 128.91203 -240.624344) (xy 128.884829 -240.58133) (xy 128.864881 -240.53451)
			(xy 128.852702 -240.485096) (xy 128.848607 -240.434368) (xy 128.54051 -240.434368) (xy 128.539998 -240.459814)
			(xy 128.531834 -240.510048) (xy 128.515718 -240.558322) (xy 128.492067 -240.603385) (xy 128.461494 -240.644071)
			(xy 128.42479 -240.679326) (xy 128.382906 -240.708236) (xy 128.336927 -240.730053) (xy 128.288043 -240.744213)
			(xy 128.237522 -240.750347) (xy 128.18667 -240.748298) (xy 128.136806 -240.738118) (xy 128.08922 -240.720071)
			(xy 128.045146 -240.694625) (xy 128.005724 -240.662438) (xy 127.971976 -240.624344) (xy 127.944775 -240.58133)
			(xy 127.924827 -240.53451) (xy 127.912648 -240.485096) (xy 127.908553 -240.434368) (xy 126.662688 -240.434368)
			(xy 126.662434 -240.448084) (xy 126.661374 -240.466886) (xy 126.655391 -240.504068) (xy 126.650496 -240.522252)
			(xy 126.648464 -240.52911) (xy 126.648464 -240.831116) (xy 126.648464 -240.83391) (xy 126.649361 -240.843336)
			(xy 126.657195 -240.860561) (xy 126.663704 -240.867438) (xy 126.665736 -240.869216) (xy 126.700534 -240.899188)
			(xy 126.701042 -240.899696) (xy 126.725172 -240.920016) (xy 126.731961 -240.92495) (xy 126.747778 -240.930528)
			(xy 126.75616 -240.930938) (xy 126.763526 -240.93043) (xy 126.765304 -240.930176) (xy 126.777607 -240.928379)
			(xy 126.802401 -240.926472) (xy 126.814834 -240.926366) (xy 126.839823 -240.926859) (xy 126.889186 -240.934682)
			(xy 126.936718 -240.950131) (xy 126.981248 -240.972824) (xy 127.02168 -241.002203) (xy 127.057019 -241.037546)
			(xy 127.086394 -241.077981) (xy 127.109082 -241.122513) (xy 127.124526 -241.170047) (xy 127.132344 -241.21941)
			(xy 127.132344 -241.244374) (xy 127.438399 -241.244374) (xy 127.442494 -241.193646) (xy 127.454673 -241.144232)
			(xy 127.474621 -241.097412) (xy 127.501822 -241.054398) (xy 127.53557 -241.016304) (xy 127.574992 -240.984117)
			(xy 127.619066 -240.958671) (xy 127.666652 -240.940624) (xy 127.716516 -240.930444) (xy 127.767368 -240.928395)
			(xy 127.817889 -240.934529) (xy 127.866773 -240.948689) (xy 127.912752 -240.970506) (xy 127.954636 -240.999416)
			(xy 127.99134 -241.034671) (xy 128.021913 -241.075357) (xy 128.045564 -241.12042) (xy 128.06168 -241.168694)
			(xy 128.069844 -241.218928) (xy 128.070356 -241.244374) (xy 128.069853 -241.269363) (xy 128.37717 -241.269363)
			(xy 128.37717 -241.219385) (xy 128.384989 -241.170022) (xy 128.400433 -241.12249) (xy 128.423123 -241.077958)
			(xy 128.452499 -241.037525) (xy 128.487839 -241.002185) (xy 128.528272 -240.972809) (xy 128.572804 -240.950119)
			(xy 128.620336 -240.934675) (xy 128.669699 -240.926856) (xy 128.719677 -240.926856) (xy 128.76904 -240.934675)
			(xy 128.816572 -240.950119) (xy 128.861104 -240.972809) (xy 128.901537 -241.002185) (xy 128.936877 -241.037525)
			(xy 128.966253 -241.077958) (xy 128.988943 -241.12249) (xy 129.004387 -241.170022) (xy 129.012206 -241.219385)
			(xy 129.012696 -241.244374) (xy 129.318507 -241.244374) (xy 129.322602 -241.193646) (xy 129.334781 -241.144232)
			(xy 129.354729 -241.097412) (xy 129.38193 -241.054398) (xy 129.415678 -241.016304) (xy 129.4551 -240.984117)
			(xy 129.499174 -240.958671) (xy 129.54676 -240.940624) (xy 129.596624 -240.930444) (xy 129.647476 -240.928395)
			(xy 129.697997 -240.934529) (xy 129.746881 -240.948689) (xy 129.79286 -240.970506) (xy 129.834744 -240.999416)
			(xy 129.871448 -241.034671) (xy 129.902021 -241.075357) (xy 129.925672 -241.12042) (xy 129.941788 -241.168694)
			(xy 129.949952 -241.218928) (xy 129.950464 -241.244374) (xy 129.949961 -241.269363) (xy 130.257278 -241.269363)
			(xy 130.257278 -241.219385) (xy 130.265097 -241.170022) (xy 130.280541 -241.12249) (xy 130.303231 -241.077958)
			(xy 130.332607 -241.037525) (xy 130.367947 -241.002185) (xy 130.40838 -240.972809) (xy 130.452912 -240.950119)
			(xy 130.500444 -240.934675) (xy 130.549807 -240.926856) (xy 130.599785 -240.926856) (xy 130.649148 -240.934675)
			(xy 130.69668 -240.950119) (xy 130.741212 -240.972809) (xy 130.781645 -241.002185) (xy 130.816985 -241.037525)
			(xy 130.846361 -241.077958) (xy 130.869051 -241.12249) (xy 130.884495 -241.170022) (xy 130.892314 -241.219385)
			(xy 130.892804 -241.244374) (xy 131.198615 -241.244374) (xy 131.20271 -241.193646) (xy 131.214889 -241.144232)
			(xy 131.234837 -241.097412) (xy 131.262038 -241.054398) (xy 131.295786 -241.016304) (xy 131.335208 -240.984117)
			(xy 131.379282 -240.958671) (xy 131.426868 -240.940624) (xy 131.476732 -240.930444) (xy 131.527584 -240.928395)
			(xy 131.578105 -240.934529) (xy 131.626989 -240.948689) (xy 131.672968 -240.970506) (xy 131.714852 -240.999416)
			(xy 131.751556 -241.034671) (xy 131.782129 -241.075357) (xy 131.80578 -241.12042) (xy 131.821896 -241.168694)
			(xy 131.83006 -241.218928) (xy 131.830572 -241.244374) (xy 132.138415 -241.244374) (xy 132.14251 -241.193646)
			(xy 132.154689 -241.144232) (xy 132.174637 -241.097412) (xy 132.201838 -241.054398) (xy 132.235586 -241.016304)
			(xy 132.275008 -240.984117) (xy 132.319082 -240.958671) (xy 132.366668 -240.940624) (xy 132.416532 -240.930444)
			(xy 132.467384 -240.928395) (xy 132.517905 -240.934529) (xy 132.566789 -240.948689) (xy 132.612768 -240.970506)
			(xy 132.654652 -240.999416) (xy 132.691356 -241.034671) (xy 132.721929 -241.075357) (xy 132.74558 -241.12042)
			(xy 132.761696 -241.168694) (xy 132.76986 -241.218928) (xy 132.770372 -241.244374) (xy 132.769869 -241.269363)
			(xy 133.077186 -241.269363) (xy 133.077186 -241.219385) (xy 133.085005 -241.170022) (xy 133.100449 -241.12249)
			(xy 133.123139 -241.077958) (xy 133.152515 -241.037525) (xy 133.187855 -241.002185) (xy 133.228288 -240.972809)
			(xy 133.27282 -240.950119) (xy 133.320352 -240.934675) (xy 133.369715 -240.926856) (xy 133.419693 -240.926856)
			(xy 133.469056 -240.934675) (xy 133.516588 -240.950119) (xy 133.56112 -240.972809) (xy 133.601553 -241.002185)
			(xy 133.636893 -241.037525) (xy 133.666269 -241.077958) (xy 133.688959 -241.12249) (xy 133.704403 -241.170022)
			(xy 133.712222 -241.219385) (xy 133.712712 -241.244374) (xy 134.018523 -241.244374) (xy 134.022618 -241.193646)
			(xy 134.034797 -241.144232) (xy 134.054745 -241.097412) (xy 134.081946 -241.054398) (xy 134.115694 -241.016304)
			(xy 134.155116 -240.984117) (xy 134.19919 -240.958671) (xy 134.246776 -240.940624) (xy 134.29664 -240.930444)
			(xy 134.347492 -240.928395) (xy 134.398013 -240.934529) (xy 134.446897 -240.948689) (xy 134.492876 -240.970506)
			(xy 134.53476 -240.999416) (xy 134.571464 -241.034671) (xy 134.602037 -241.075357) (xy 134.625688 -241.12042)
			(xy 134.641804 -241.168694) (xy 134.649968 -241.218928) (xy 134.65048 -241.244374) (xy 134.649977 -241.269363)
			(xy 134.957294 -241.269363) (xy 134.957294 -241.219385) (xy 134.965113 -241.170022) (xy 134.980557 -241.12249)
			(xy 135.003247 -241.077958) (xy 135.032623 -241.037525) (xy 135.067963 -241.002185) (xy 135.108396 -240.972809)
			(xy 135.152928 -240.950119) (xy 135.20046 -240.934675) (xy 135.249823 -240.926856) (xy 135.299801 -240.926856)
			(xy 135.349164 -240.934675) (xy 135.396696 -240.950119) (xy 135.441228 -240.972809) (xy 135.481661 -241.002185)
			(xy 135.517001 -241.037525) (xy 135.546377 -241.077958) (xy 135.569067 -241.12249) (xy 135.584511 -241.170022)
			(xy 135.59233 -241.219385) (xy 135.59282 -241.244374) (xy 135.898631 -241.244374) (xy 135.902726 -241.193646)
			(xy 135.914905 -241.144232) (xy 135.934853 -241.097412) (xy 135.962054 -241.054398) (xy 135.995802 -241.016304)
			(xy 136.035224 -240.984117) (xy 136.079298 -240.958671) (xy 136.126884 -240.940624) (xy 136.176748 -240.930444)
			(xy 136.2276 -240.928395) (xy 136.278121 -240.934529) (xy 136.327005 -240.948689) (xy 136.372984 -240.970506)
			(xy 136.414868 -240.999416) (xy 136.451572 -241.034671) (xy 136.482145 -241.075357) (xy 136.505796 -241.12042)
			(xy 136.521912 -241.168694) (xy 136.530076 -241.218928) (xy 136.530588 -241.244374) (xy 136.530085 -241.269363)
			(xy 136.837148 -241.269363) (xy 136.837148 -241.219385) (xy 136.844967 -241.170022) (xy 136.860411 -241.12249)
			(xy 136.883101 -241.077958) (xy 136.912477 -241.037525) (xy 136.947817 -241.002185) (xy 136.98825 -240.972809)
			(xy 137.032782 -240.950119) (xy 137.080314 -240.934675) (xy 137.129677 -240.926856) (xy 137.179655 -240.926856)
			(xy 137.229018 -240.934675) (xy 137.27655 -240.950119) (xy 137.321082 -240.972809) (xy 137.361515 -241.002185)
			(xy 137.396855 -241.037525) (xy 137.426231 -241.077958) (xy 137.448921 -241.12249) (xy 137.464365 -241.170022)
			(xy 137.472184 -241.219385) (xy 137.472674 -241.244374) (xy 137.778485 -241.244374) (xy 137.78258 -241.193646)
			(xy 137.794759 -241.144232) (xy 137.814707 -241.097412) (xy 137.841908 -241.054398) (xy 137.875656 -241.016304)
			(xy 137.915078 -240.984117) (xy 137.959152 -240.958671) (xy 138.006738 -240.940624) (xy 138.056602 -240.930444)
			(xy 138.107454 -240.928395) (xy 138.157975 -240.934529) (xy 138.206859 -240.948689) (xy 138.252838 -240.970506)
			(xy 138.294722 -240.999416) (xy 138.331426 -241.034671) (xy 138.361999 -241.075357) (xy 138.38565 -241.12042)
			(xy 138.401766 -241.168694) (xy 138.40993 -241.218928) (xy 138.410442 -241.244374) (xy 138.718539 -241.244374)
			(xy 138.722634 -241.193646) (xy 138.734813 -241.144232) (xy 138.754761 -241.097412) (xy 138.781962 -241.054398)
			(xy 138.81571 -241.016304) (xy 138.855132 -240.984117) (xy 138.899206 -240.958671) (xy 138.946792 -240.940624)
			(xy 138.996656 -240.930444) (xy 139.047508 -240.928395) (xy 139.098029 -240.934529) (xy 139.146913 -240.948689)
			(xy 139.192892 -240.970506) (xy 139.234776 -240.999416) (xy 139.27148 -241.034671) (xy 139.302053 -241.075357)
			(xy 139.325704 -241.12042) (xy 139.34182 -241.168694) (xy 139.349984 -241.218928) (xy 139.350496 -241.244374)
			(xy 139.349993 -241.269363) (xy 139.65731 -241.269363) (xy 139.65731 -241.219385) (xy 139.665129 -241.170022)
			(xy 139.680573 -241.12249) (xy 139.703263 -241.077958) (xy 139.732639 -241.037525) (xy 139.767979 -241.002185)
			(xy 139.808412 -240.972809) (xy 139.852944 -240.950119) (xy 139.900476 -240.934675) (xy 139.949839 -240.926856)
			(xy 139.999817 -240.926856) (xy 140.04918 -240.934675) (xy 140.096712 -240.950119) (xy 140.141244 -240.972809)
			(xy 140.181677 -241.002185) (xy 140.217017 -241.037525) (xy 140.246393 -241.077958) (xy 140.269083 -241.12249)
			(xy 140.284527 -241.170022) (xy 140.292346 -241.219385) (xy 140.292836 -241.244374) (xy 140.598647 -241.244374)
			(xy 140.602742 -241.193646) (xy 140.614921 -241.144232) (xy 140.634869 -241.097412) (xy 140.66207 -241.054398)
			(xy 140.695818 -241.016304) (xy 140.73524 -240.984117) (xy 140.779314 -240.958671) (xy 140.8269 -240.940624)
			(xy 140.876764 -240.930444) (xy 140.927616 -240.928395) (xy 140.978137 -240.934529) (xy 141.027021 -240.948689)
			(xy 141.073 -240.970506) (xy 141.114884 -240.999416) (xy 141.151588 -241.034671) (xy 141.182161 -241.075357)
			(xy 141.205812 -241.12042) (xy 141.221928 -241.168694) (xy 141.230092 -241.218928) (xy 141.230604 -241.244374)
			(xy 141.230101 -241.269363) (xy 141.537164 -241.269363) (xy 141.537164 -241.219385) (xy 141.544983 -241.170022)
			(xy 141.560427 -241.12249) (xy 141.583117 -241.077958) (xy 141.612493 -241.037525) (xy 141.647833 -241.002185)
			(xy 141.688266 -240.972809) (xy 141.732798 -240.950119) (xy 141.78033 -240.934675) (xy 141.829693 -240.926856)
			(xy 141.879671 -240.926856) (xy 141.929034 -240.934675) (xy 141.976566 -240.950119) (xy 142.021098 -240.972809)
			(xy 142.061531 -241.002185) (xy 142.096871 -241.037525) (xy 142.126247 -241.077958) (xy 142.148937 -241.12249)
			(xy 142.164381 -241.170022) (xy 142.1722 -241.219385) (xy 142.17269 -241.244374) (xy 142.478501 -241.244374)
			(xy 142.482596 -241.193646) (xy 142.494775 -241.144232) (xy 142.514723 -241.097412) (xy 142.541924 -241.054398)
			(xy 142.575672 -241.016304) (xy 142.615094 -240.984117) (xy 142.659168 -240.958671) (xy 142.706754 -240.940624)
			(xy 142.756618 -240.930444) (xy 142.80747 -240.928395) (xy 142.857991 -240.934529) (xy 142.906875 -240.948689)
			(xy 142.952854 -240.970506) (xy 142.994738 -240.999416) (xy 143.031442 -241.034671) (xy 143.062015 -241.075357)
			(xy 143.085666 -241.12042) (xy 143.101782 -241.168694) (xy 143.109946 -241.218928) (xy 143.110458 -241.244374)
			(xy 143.109955 -241.269363) (xy 143.417272 -241.269363) (xy 143.417272 -241.219385) (xy 143.425091 -241.170022)
			(xy 143.440535 -241.12249) (xy 143.463225 -241.077958) (xy 143.492601 -241.037525) (xy 143.527941 -241.002185)
			(xy 143.568374 -240.972809) (xy 143.612906 -240.950119) (xy 143.660438 -240.934675) (xy 143.709801 -240.926856)
			(xy 143.759779 -240.926856) (xy 143.809142 -240.934675) (xy 143.856674 -240.950119) (xy 143.901206 -240.972809)
			(xy 143.941639 -241.002185) (xy 143.976979 -241.037525) (xy 144.006355 -241.077958) (xy 144.029045 -241.12249)
			(xy 144.044489 -241.170022) (xy 144.052308 -241.219385) (xy 144.052798 -241.244374) (xy 144.052308 -241.269363)
			(xy 144.044489 -241.318726) (xy 144.029045 -241.366258) (xy 144.006355 -241.41079) (xy 143.976979 -241.451223)
			(xy 143.941639 -241.486563) (xy 143.901206 -241.515939) (xy 143.856674 -241.538629) (xy 143.809142 -241.554073)
			(xy 143.759779 -241.561892) (xy 143.709801 -241.561892) (xy 143.660438 -241.554073) (xy 143.612906 -241.538629)
			(xy 143.568374 -241.515939) (xy 143.527941 -241.486563) (xy 143.492601 -241.451223) (xy 143.463225 -241.41079)
			(xy 143.440535 -241.366258) (xy 143.425091 -241.318726) (xy 143.417272 -241.269363) (xy 143.109955 -241.269363)
			(xy 143.109946 -241.26982) (xy 143.101782 -241.320054) (xy 143.085666 -241.368328) (xy 143.062015 -241.413391)
			(xy 143.031442 -241.454077) (xy 142.994738 -241.489332) (xy 142.952854 -241.518242) (xy 142.906875 -241.540059)
			(xy 142.857991 -241.554219) (xy 142.80747 -241.560353) (xy 142.756618 -241.558304) (xy 142.706754 -241.548124)
			(xy 142.659168 -241.530077) (xy 142.615094 -241.504631) (xy 142.575672 -241.472444) (xy 142.541924 -241.43435)
			(xy 142.514723 -241.391336) (xy 142.494775 -241.344516) (xy 142.482596 -241.295102) (xy 142.478501 -241.244374)
			(xy 142.17269 -241.244374) (xy 142.1722 -241.269363) (xy 142.164381 -241.318726) (xy 142.148937 -241.366258)
			(xy 142.126247 -241.41079) (xy 142.096871 -241.451223) (xy 142.061531 -241.486563) (xy 142.021098 -241.515939)
			(xy 141.976566 -241.538629) (xy 141.929034 -241.554073) (xy 141.879671 -241.561892) (xy 141.829693 -241.561892)
			(xy 141.78033 -241.554073) (xy 141.732798 -241.538629) (xy 141.688266 -241.515939) (xy 141.647833 -241.486563)
			(xy 141.612493 -241.451223) (xy 141.583117 -241.41079) (xy 141.560427 -241.366258) (xy 141.544983 -241.318726)
			(xy 141.537164 -241.269363) (xy 141.230101 -241.269363) (xy 141.230092 -241.26982) (xy 141.221928 -241.320054)
			(xy 141.205812 -241.368328) (xy 141.182161 -241.413391) (xy 141.151588 -241.454077) (xy 141.114884 -241.489332)
			(xy 141.073 -241.518242) (xy 141.027021 -241.540059) (xy 140.978137 -241.554219) (xy 140.927616 -241.560353)
			(xy 140.876764 -241.558304) (xy 140.8269 -241.548124) (xy 140.779314 -241.530077) (xy 140.73524 -241.504631)
			(xy 140.695818 -241.472444) (xy 140.66207 -241.43435) (xy 140.634869 -241.391336) (xy 140.614921 -241.344516)
			(xy 140.602742 -241.295102) (xy 140.598647 -241.244374) (xy 140.292836 -241.244374) (xy 140.292346 -241.269363)
			(xy 140.284527 -241.318726) (xy 140.269083 -241.366258) (xy 140.246393 -241.41079) (xy 140.217017 -241.451223)
			(xy 140.181677 -241.486563) (xy 140.141244 -241.515939) (xy 140.096712 -241.538629) (xy 140.04918 -241.554073)
			(xy 139.999817 -241.561892) (xy 139.949839 -241.561892) (xy 139.900476 -241.554073) (xy 139.852944 -241.538629)
			(xy 139.808412 -241.515939) (xy 139.767979 -241.486563) (xy 139.732639 -241.451223) (xy 139.703263 -241.41079)
			(xy 139.680573 -241.366258) (xy 139.665129 -241.318726) (xy 139.65731 -241.269363) (xy 139.349993 -241.269363)
			(xy 139.349984 -241.26982) (xy 139.34182 -241.320054) (xy 139.325704 -241.368328) (xy 139.302053 -241.413391)
			(xy 139.27148 -241.454077) (xy 139.234776 -241.489332) (xy 139.192892 -241.518242) (xy 139.146913 -241.540059)
			(xy 139.098029 -241.554219) (xy 139.047508 -241.560353) (xy 138.996656 -241.558304) (xy 138.946792 -241.548124)
			(xy 138.899206 -241.530077) (xy 138.855132 -241.504631) (xy 138.81571 -241.472444) (xy 138.781962 -241.43435)
			(xy 138.754761 -241.391336) (xy 138.734813 -241.344516) (xy 138.722634 -241.295102) (xy 138.718539 -241.244374)
			(xy 138.410442 -241.244374) (xy 138.40993 -241.26982) (xy 138.401766 -241.320054) (xy 138.38565 -241.368328)
			(xy 138.361999 -241.413391) (xy 138.331426 -241.454077) (xy 138.294722 -241.489332) (xy 138.252838 -241.518242)
			(xy 138.206859 -241.540059) (xy 138.157975 -241.554219) (xy 138.107454 -241.560353) (xy 138.056602 -241.558304)
			(xy 138.006738 -241.548124) (xy 137.959152 -241.530077) (xy 137.915078 -241.504631) (xy 137.875656 -241.472444)
			(xy 137.841908 -241.43435) (xy 137.814707 -241.391336) (xy 137.794759 -241.344516) (xy 137.78258 -241.295102)
			(xy 137.778485 -241.244374) (xy 137.472674 -241.244374) (xy 137.472184 -241.269363) (xy 137.464365 -241.318726)
			(xy 137.448921 -241.366258) (xy 137.426231 -241.41079) (xy 137.396855 -241.451223) (xy 137.361515 -241.486563)
			(xy 137.321082 -241.515939) (xy 137.27655 -241.538629) (xy 137.229018 -241.554073) (xy 137.179655 -241.561892)
			(xy 137.129677 -241.561892) (xy 137.080314 -241.554073) (xy 137.032782 -241.538629) (xy 136.98825 -241.515939)
			(xy 136.947817 -241.486563) (xy 136.912477 -241.451223) (xy 136.883101 -241.41079) (xy 136.860411 -241.366258)
			(xy 136.844967 -241.318726) (xy 136.837148 -241.269363) (xy 136.530085 -241.269363) (xy 136.530076 -241.26982)
			(xy 136.521912 -241.320054) (xy 136.505796 -241.368328) (xy 136.482145 -241.413391) (xy 136.451572 -241.454077)
			(xy 136.414868 -241.489332) (xy 136.372984 -241.518242) (xy 136.327005 -241.540059) (xy 136.278121 -241.554219)
			(xy 136.2276 -241.560353) (xy 136.176748 -241.558304) (xy 136.126884 -241.548124) (xy 136.079298 -241.530077)
			(xy 136.035224 -241.504631) (xy 135.995802 -241.472444) (xy 135.962054 -241.43435) (xy 135.934853 -241.391336)
			(xy 135.914905 -241.344516) (xy 135.902726 -241.295102) (xy 135.898631 -241.244374) (xy 135.59282 -241.244374)
			(xy 135.59233 -241.269363) (xy 135.584511 -241.318726) (xy 135.569067 -241.366258) (xy 135.546377 -241.41079)
			(xy 135.517001 -241.451223) (xy 135.481661 -241.486563) (xy 135.441228 -241.515939) (xy 135.396696 -241.538629)
			(xy 135.349164 -241.554073) (xy 135.299801 -241.561892) (xy 135.249823 -241.561892) (xy 135.20046 -241.554073)
			(xy 135.152928 -241.538629) (xy 135.108396 -241.515939) (xy 135.067963 -241.486563) (xy 135.032623 -241.451223)
			(xy 135.003247 -241.41079) (xy 134.980557 -241.366258) (xy 134.965113 -241.318726) (xy 134.957294 -241.269363)
			(xy 134.649977 -241.269363) (xy 134.649968 -241.26982) (xy 134.641804 -241.320054) (xy 134.625688 -241.368328)
			(xy 134.602037 -241.413391) (xy 134.571464 -241.454077) (xy 134.53476 -241.489332) (xy 134.492876 -241.518242)
			(xy 134.446897 -241.540059) (xy 134.398013 -241.554219) (xy 134.347492 -241.560353) (xy 134.29664 -241.558304)
			(xy 134.246776 -241.548124) (xy 134.19919 -241.530077) (xy 134.155116 -241.504631) (xy 134.115694 -241.472444)
			(xy 134.081946 -241.43435) (xy 134.054745 -241.391336) (xy 134.034797 -241.344516) (xy 134.022618 -241.295102)
			(xy 134.018523 -241.244374) (xy 133.712712 -241.244374) (xy 133.712222 -241.269363) (xy 133.704403 -241.318726)
			(xy 133.688959 -241.366258) (xy 133.666269 -241.41079) (xy 133.636893 -241.451223) (xy 133.601553 -241.486563)
			(xy 133.56112 -241.515939) (xy 133.516588 -241.538629) (xy 133.469056 -241.554073) (xy 133.419693 -241.561892)
			(xy 133.369715 -241.561892) (xy 133.320352 -241.554073) (xy 133.27282 -241.538629) (xy 133.228288 -241.515939)
			(xy 133.187855 -241.486563) (xy 133.152515 -241.451223) (xy 133.123139 -241.41079) (xy 133.100449 -241.366258)
			(xy 133.085005 -241.318726) (xy 133.077186 -241.269363) (xy 132.769869 -241.269363) (xy 132.76986 -241.26982)
			(xy 132.761696 -241.320054) (xy 132.74558 -241.368328) (xy 132.721929 -241.413391) (xy 132.691356 -241.454077)
			(xy 132.654652 -241.489332) (xy 132.612768 -241.518242) (xy 132.566789 -241.540059) (xy 132.517905 -241.554219)
			(xy 132.467384 -241.560353) (xy 132.416532 -241.558304) (xy 132.366668 -241.548124) (xy 132.319082 -241.530077)
			(xy 132.275008 -241.504631) (xy 132.235586 -241.472444) (xy 132.201838 -241.43435) (xy 132.174637 -241.391336)
			(xy 132.154689 -241.344516) (xy 132.14251 -241.295102) (xy 132.138415 -241.244374) (xy 131.830572 -241.244374)
			(xy 131.83006 -241.26982) (xy 131.821896 -241.320054) (xy 131.80578 -241.368328) (xy 131.782129 -241.413391)
			(xy 131.751556 -241.454077) (xy 131.714852 -241.489332) (xy 131.672968 -241.518242) (xy 131.626989 -241.540059)
			(xy 131.578105 -241.554219) (xy 131.527584 -241.560353) (xy 131.476732 -241.558304) (xy 131.426868 -241.548124)
			(xy 131.379282 -241.530077) (xy 131.335208 -241.504631) (xy 131.295786 -241.472444) (xy 131.262038 -241.43435)
			(xy 131.234837 -241.391336) (xy 131.214889 -241.344516) (xy 131.20271 -241.295102) (xy 131.198615 -241.244374)
			(xy 130.892804 -241.244374) (xy 130.892314 -241.269363) (xy 130.884495 -241.318726) (xy 130.869051 -241.366258)
			(xy 130.846361 -241.41079) (xy 130.816985 -241.451223) (xy 130.781645 -241.486563) (xy 130.741212 -241.515939)
			(xy 130.69668 -241.538629) (xy 130.649148 -241.554073) (xy 130.599785 -241.561892) (xy 130.549807 -241.561892)
			(xy 130.500444 -241.554073) (xy 130.452912 -241.538629) (xy 130.40838 -241.515939) (xy 130.367947 -241.486563)
			(xy 130.332607 -241.451223) (xy 130.303231 -241.41079) (xy 130.280541 -241.366258) (xy 130.265097 -241.318726)
			(xy 130.257278 -241.269363) (xy 129.949961 -241.269363) (xy 129.949952 -241.26982) (xy 129.941788 -241.320054)
			(xy 129.925672 -241.368328) (xy 129.902021 -241.413391) (xy 129.871448 -241.454077) (xy 129.834744 -241.489332)
			(xy 129.79286 -241.518242) (xy 129.746881 -241.540059) (xy 129.697997 -241.554219) (xy 129.647476 -241.560353)
			(xy 129.596624 -241.558304) (xy 129.54676 -241.548124) (xy 129.499174 -241.530077) (xy 129.4551 -241.504631)
			(xy 129.415678 -241.472444) (xy 129.38193 -241.43435) (xy 129.354729 -241.391336) (xy 129.334781 -241.344516)
			(xy 129.322602 -241.295102) (xy 129.318507 -241.244374) (xy 129.012696 -241.244374) (xy 129.012206 -241.269363)
			(xy 129.004387 -241.318726) (xy 128.988943 -241.366258) (xy 128.966253 -241.41079) (xy 128.936877 -241.451223)
			(xy 128.901537 -241.486563) (xy 128.861104 -241.515939) (xy 128.816572 -241.538629) (xy 128.76904 -241.554073)
			(xy 128.719677 -241.561892) (xy 128.669699 -241.561892) (xy 128.620336 -241.554073) (xy 128.572804 -241.538629)
			(xy 128.528272 -241.515939) (xy 128.487839 -241.486563) (xy 128.452499 -241.451223) (xy 128.423123 -241.41079)
			(xy 128.400433 -241.366258) (xy 128.384989 -241.318726) (xy 128.37717 -241.269363) (xy 128.069853 -241.269363)
			(xy 128.069844 -241.26982) (xy 128.06168 -241.320054) (xy 128.045564 -241.368328) (xy 128.021913 -241.413391)
			(xy 127.99134 -241.454077) (xy 127.954636 -241.489332) (xy 127.912752 -241.518242) (xy 127.866773 -241.540059)
			(xy 127.817889 -241.554219) (xy 127.767368 -241.560353) (xy 127.716516 -241.558304) (xy 127.666652 -241.548124)
			(xy 127.619066 -241.530077) (xy 127.574992 -241.504631) (xy 127.53557 -241.472444) (xy 127.501822 -241.43435)
			(xy 127.474621 -241.391336) (xy 127.454673 -241.344516) (xy 127.442494 -241.295102) (xy 127.438399 -241.244374)
			(xy 127.132344 -241.244374) (xy 127.132344 -241.26939) (xy 127.124526 -241.318753) (xy 127.109082 -241.366287)
			(xy 127.086394 -241.410819) (xy 127.057019 -241.451254) (xy 127.02168 -241.486597) (xy 126.981248 -241.515976)
			(xy 126.936718 -241.538669) (xy 126.889186 -241.554118) (xy 126.839823 -241.561941) (xy 126.814834 -241.562382)
			(xy 126.802206 -241.562234) (xy 126.777031 -241.560196) (xy 126.764542 -241.558318) (xy 126.75362 -241.55654)
			(xy 126.74346 -241.559334) (xy 126.738263 -241.560961) (xy 126.728656 -241.566084) (xy 126.72441 -241.569494)
			(xy 126.663958 -241.620802) (xy 126.657454 -241.627703) (xy 126.649511 -241.644904) (xy 126.648464 -241.65433)
			(xy 126.648464 -241.948716) (xy 126.648972 -241.955828) (xy 126.650496 -241.96675) (xy 126.656202 -241.988206)
			(xy 126.662315 -242.032181) (xy 126.662688 -242.05438) (xy 126.662368 -242.076645) (xy 126.66199 -242.079369)
			(xy 126.967216 -242.079369) (xy 126.967216 -242.029391) (xy 126.975035 -241.980028) (xy 126.990479 -241.932496)
			(xy 127.013169 -241.887964) (xy 127.042545 -241.847531) (xy 127.077885 -241.812191) (xy 127.118318 -241.782815)
			(xy 127.16285 -241.760125) (xy 127.210382 -241.744681) (xy 127.259745 -241.736862) (xy 127.309723 -241.736862)
			(xy 127.359086 -241.744681) (xy 127.406618 -241.760125) (xy 127.45115 -241.782815) (xy 127.491583 -241.812191)
			(xy 127.526923 -241.847531) (xy 127.556299 -241.887964) (xy 127.578989 -241.932496) (xy 127.594433 -241.980028)
			(xy 127.602252 -242.029391) (xy 127.602742 -242.05438) (xy 127.908553 -242.05438) (xy 127.912648 -242.003652)
			(xy 127.924827 -241.954238) (xy 127.944775 -241.907418) (xy 127.971976 -241.864404) (xy 128.005724 -241.82631)
			(xy 128.045146 -241.794123) (xy 128.08922 -241.768677) (xy 128.136806 -241.75063) (xy 128.18667 -241.74045)
			(xy 128.237522 -241.738401) (xy 128.288043 -241.744535) (xy 128.336927 -241.758695) (xy 128.382906 -241.780512)
			(xy 128.42479 -241.809422) (xy 128.461494 -241.844677) (xy 128.492067 -241.885363) (xy 128.515718 -241.930426)
			(xy 128.531834 -241.9787) (xy 128.539998 -242.028934) (xy 128.54051 -242.05438) (xy 128.848607 -242.05438)
			(xy 128.852702 -242.003652) (xy 128.864881 -241.954238) (xy 128.884829 -241.907418) (xy 128.91203 -241.864404)
			(xy 128.945778 -241.82631) (xy 128.9852 -241.794123) (xy 129.029274 -241.768677) (xy 129.07686 -241.75063)
			(xy 129.126724 -241.74045) (xy 129.177576 -241.738401) (xy 129.228097 -241.744535) (xy 129.276981 -241.758695)
			(xy 129.32296 -241.780512) (xy 129.364844 -241.809422) (xy 129.401548 -241.844677) (xy 129.432121 -241.885363)
			(xy 129.455772 -241.930426) (xy 129.471888 -241.9787) (xy 129.480052 -242.028934) (xy 129.480564 -242.05438)
			(xy 130.728461 -242.05438) (xy 130.732556 -242.003652) (xy 130.744735 -241.954238) (xy 130.764683 -241.907418)
			(xy 130.791884 -241.864404) (xy 130.825632 -241.82631) (xy 130.865054 -241.794123) (xy 130.909128 -241.768677)
			(xy 130.956714 -241.75063) (xy 131.006578 -241.74045) (xy 131.05743 -241.738401) (xy 131.107951 -241.744535)
			(xy 131.156835 -241.758695) (xy 131.202814 -241.780512) (xy 131.244698 -241.809422) (xy 131.281402 -241.844677)
			(xy 131.311975 -241.885363) (xy 131.335626 -241.930426) (xy 131.351742 -241.9787) (xy 131.359906 -242.028934)
			(xy 131.360418 -242.05438) (xy 131.359915 -242.079369) (xy 131.667232 -242.079369) (xy 131.667232 -242.029391)
			(xy 131.675051 -241.980028) (xy 131.690495 -241.932496) (xy 131.713185 -241.887964) (xy 131.742561 -241.847531)
			(xy 131.777901 -241.812191) (xy 131.818334 -241.782815) (xy 131.862866 -241.760125) (xy 131.910398 -241.744681)
			(xy 131.959761 -241.736862) (xy 132.009739 -241.736862) (xy 132.059102 -241.744681) (xy 132.106634 -241.760125)
			(xy 132.151166 -241.782815) (xy 132.191599 -241.812191) (xy 132.226939 -241.847531) (xy 132.256315 -241.887964)
			(xy 132.279005 -241.932496) (xy 132.294449 -241.980028) (xy 132.302268 -242.029391) (xy 132.302758 -242.05438)
			(xy 132.608569 -242.05438) (xy 132.612664 -242.003652) (xy 132.624843 -241.954238) (xy 132.644791 -241.907418)
			(xy 132.671992 -241.864404) (xy 132.70574 -241.82631) (xy 132.745162 -241.794123) (xy 132.789236 -241.768677)
			(xy 132.836822 -241.75063) (xy 132.886686 -241.74045) (xy 132.937538 -241.738401) (xy 132.988059 -241.744535)
			(xy 133.036943 -241.758695) (xy 133.082922 -241.780512) (xy 133.124806 -241.809422) (xy 133.16151 -241.844677)
			(xy 133.192083 -241.885363) (xy 133.215734 -241.930426) (xy 133.23185 -241.9787) (xy 133.240014 -242.028934)
			(xy 133.240526 -242.05438) (xy 133.240023 -242.079369) (xy 133.54734 -242.079369) (xy 133.54734 -242.029391)
			(xy 133.555159 -241.980028) (xy 133.570603 -241.932496) (xy 133.593293 -241.887964) (xy 133.622669 -241.847531)
			(xy 133.658009 -241.812191) (xy 133.698442 -241.782815) (xy 133.742974 -241.760125) (xy 133.790506 -241.744681)
			(xy 133.839869 -241.736862) (xy 133.889847 -241.736862) (xy 133.93921 -241.744681) (xy 133.986742 -241.760125)
			(xy 134.031274 -241.782815) (xy 134.071707 -241.812191) (xy 134.107047 -241.847531) (xy 134.136423 -241.887964)
			(xy 134.159113 -241.932496) (xy 134.174557 -241.980028) (xy 134.182376 -242.029391) (xy 134.182866 -242.05438)
			(xy 134.488423 -242.05438) (xy 134.492518 -242.003652) (xy 134.504697 -241.954238) (xy 134.524645 -241.907418)
			(xy 134.551846 -241.864404) (xy 134.585594 -241.82631) (xy 134.625016 -241.794123) (xy 134.66909 -241.768677)
			(xy 134.716676 -241.75063) (xy 134.76654 -241.74045) (xy 134.817392 -241.738401) (xy 134.867913 -241.744535)
			(xy 134.916797 -241.758695) (xy 134.962776 -241.780512) (xy 135.00466 -241.809422) (xy 135.041364 -241.844677)
			(xy 135.071937 -241.885363) (xy 135.095588 -241.930426) (xy 135.111704 -241.9787) (xy 135.119868 -242.028934)
			(xy 135.12038 -242.05438) (xy 135.428477 -242.05438) (xy 135.432572 -242.003652) (xy 135.444751 -241.954238)
			(xy 135.464699 -241.907418) (xy 135.4919 -241.864404) (xy 135.525648 -241.82631) (xy 135.56507 -241.794123)
			(xy 135.609144 -241.768677) (xy 135.65673 -241.75063) (xy 135.706594 -241.74045) (xy 135.757446 -241.738401)
			(xy 135.807967 -241.744535) (xy 135.856851 -241.758695) (xy 135.90283 -241.780512) (xy 135.944714 -241.809422)
			(xy 135.981418 -241.844677) (xy 136.011991 -241.885363) (xy 136.035642 -241.930426) (xy 136.051758 -241.9787)
			(xy 136.059922 -242.028934) (xy 136.060434 -242.05438) (xy 137.308585 -242.05438) (xy 137.31268 -242.003652)
			(xy 137.324859 -241.954238) (xy 137.344807 -241.907418) (xy 137.372008 -241.864404) (xy 137.405756 -241.82631)
			(xy 137.445178 -241.794123) (xy 137.489252 -241.768677) (xy 137.536838 -241.75063) (xy 137.586702 -241.74045)
			(xy 137.637554 -241.738401) (xy 137.688075 -241.744535) (xy 137.736959 -241.758695) (xy 137.782938 -241.780512)
			(xy 137.824822 -241.809422) (xy 137.861526 -241.844677) (xy 137.892099 -241.885363) (xy 137.91575 -241.930426)
			(xy 137.931866 -241.9787) (xy 137.94003 -242.028934) (xy 137.940542 -242.05438) (xy 137.940039 -242.079369)
			(xy 138.247356 -242.079369) (xy 138.247356 -242.029391) (xy 138.255175 -241.980028) (xy 138.270619 -241.932496)
			(xy 138.293309 -241.887964) (xy 138.322685 -241.847531) (xy 138.358025 -241.812191) (xy 138.398458 -241.782815)
			(xy 138.44299 -241.760125) (xy 138.490522 -241.744681) (xy 138.539885 -241.736862) (xy 138.589863 -241.736862)
			(xy 138.639226 -241.744681) (xy 138.686758 -241.760125) (xy 138.73129 -241.782815) (xy 138.771723 -241.812191)
			(xy 138.807063 -241.847531) (xy 138.836439 -241.887964) (xy 138.859129 -241.932496) (xy 138.874573 -241.980028)
			(xy 138.882392 -242.029391) (xy 138.882882 -242.05438) (xy 139.188439 -242.05438) (xy 139.192534 -242.003652)
			(xy 139.204713 -241.954238) (xy 139.224661 -241.907418) (xy 139.251862 -241.864404) (xy 139.28561 -241.82631)
			(xy 139.325032 -241.794123) (xy 139.369106 -241.768677) (xy 139.416692 -241.75063) (xy 139.466556 -241.74045)
			(xy 139.517408 -241.738401) (xy 139.567929 -241.744535) (xy 139.616813 -241.758695) (xy 139.662792 -241.780512)
			(xy 139.704676 -241.809422) (xy 139.74138 -241.844677) (xy 139.771953 -241.885363) (xy 139.795604 -241.930426)
			(xy 139.81172 -241.9787) (xy 139.819884 -242.028934) (xy 139.820396 -242.05438) (xy 139.819893 -242.079369)
			(xy 140.12721 -242.079369) (xy 140.12721 -242.029391) (xy 140.135029 -241.980028) (xy 140.150473 -241.932496)
			(xy 140.173163 -241.887964) (xy 140.202539 -241.847531) (xy 140.237879 -241.812191) (xy 140.278312 -241.782815)
			(xy 140.322844 -241.760125) (xy 140.370376 -241.744681) (xy 140.419739 -241.736862) (xy 140.469717 -241.736862)
			(xy 140.51908 -241.744681) (xy 140.566612 -241.760125) (xy 140.611144 -241.782815) (xy 140.651577 -241.812191)
			(xy 140.686917 -241.847531) (xy 140.716293 -241.887964) (xy 140.738983 -241.932496) (xy 140.754427 -241.980028)
			(xy 140.762246 -242.029391) (xy 140.762736 -242.05438) (xy 141.068547 -242.05438) (xy 141.072642 -242.003652)
			(xy 141.084821 -241.954238) (xy 141.104769 -241.907418) (xy 141.13197 -241.864404) (xy 141.165718 -241.82631)
			(xy 141.20514 -241.794123) (xy 141.249214 -241.768677) (xy 141.2968 -241.75063) (xy 141.346664 -241.74045)
			(xy 141.397516 -241.738401) (xy 141.448037 -241.744535) (xy 141.496921 -241.758695) (xy 141.5429 -241.780512)
			(xy 141.584784 -241.809422) (xy 141.621488 -241.844677) (xy 141.652061 -241.885363) (xy 141.675712 -241.930426)
			(xy 141.691828 -241.9787) (xy 141.699992 -242.028934) (xy 141.700504 -242.05438) (xy 142.008601 -242.05438)
			(xy 142.012696 -242.003652) (xy 142.024875 -241.954238) (xy 142.044823 -241.907418) (xy 142.072024 -241.864404)
			(xy 142.105772 -241.82631) (xy 142.145194 -241.794123) (xy 142.189268 -241.768677) (xy 142.236854 -241.75063)
			(xy 142.286718 -241.74045) (xy 142.33757 -241.738401) (xy 142.388091 -241.744535) (xy 142.436975 -241.758695)
			(xy 142.482954 -241.780512) (xy 142.524838 -241.809422) (xy 142.561542 -241.844677) (xy 142.592115 -241.885363)
			(xy 142.615766 -241.930426) (xy 142.631882 -241.9787) (xy 142.640046 -242.028934) (xy 142.640558 -242.05438)
			(xy 142.640046 -242.079826) (xy 142.631882 -242.13006) (xy 142.615766 -242.178334) (xy 142.592115 -242.223397)
			(xy 142.561542 -242.264083) (xy 142.524838 -242.299338) (xy 142.482954 -242.328248) (xy 142.436975 -242.350065)
			(xy 142.388091 -242.364225) (xy 142.33757 -242.370359) (xy 142.286718 -242.36831) (xy 142.236854 -242.35813)
			(xy 142.189268 -242.340083) (xy 142.145194 -242.314637) (xy 142.105772 -242.28245) (xy 142.072024 -242.244356)
			(xy 142.044823 -242.201342) (xy 142.024875 -242.154522) (xy 142.012696 -242.105108) (xy 142.008601 -242.05438)
			(xy 141.700504 -242.05438) (xy 141.699992 -242.079826) (xy 141.691828 -242.13006) (xy 141.675712 -242.178334)
			(xy 141.652061 -242.223397) (xy 141.621488 -242.264083) (xy 141.584784 -242.299338) (xy 141.5429 -242.328248)
			(xy 141.496921 -242.350065) (xy 141.448037 -242.364225) (xy 141.397516 -242.370359) (xy 141.346664 -242.36831)
			(xy 141.2968 -242.35813) (xy 141.249214 -242.340083) (xy 141.20514 -242.314637) (xy 141.165718 -242.28245)
			(xy 141.13197 -242.244356) (xy 141.104769 -242.201342) (xy 141.084821 -242.154522) (xy 141.072642 -242.105108)
			(xy 141.068547 -242.05438) (xy 140.762736 -242.05438) (xy 140.762246 -242.079369) (xy 140.754427 -242.128732)
			(xy 140.738983 -242.176264) (xy 140.716293 -242.220796) (xy 140.686917 -242.261229) (xy 140.651577 -242.296569)
			(xy 140.611144 -242.325945) (xy 140.566612 -242.348635) (xy 140.51908 -242.364079) (xy 140.469717 -242.371898)
			(xy 140.419739 -242.371898) (xy 140.370376 -242.364079) (xy 140.322844 -242.348635) (xy 140.278312 -242.325945)
			(xy 140.237879 -242.296569) (xy 140.202539 -242.261229) (xy 140.173163 -242.220796) (xy 140.150473 -242.176264)
			(xy 140.135029 -242.128732) (xy 140.12721 -242.079369) (xy 139.819893 -242.079369) (xy 139.819884 -242.079826)
			(xy 139.81172 -242.13006) (xy 139.795604 -242.178334) (xy 139.771953 -242.223397) (xy 139.74138 -242.264083)
			(xy 139.704676 -242.299338) (xy 139.662792 -242.328248) (xy 139.616813 -242.350065) (xy 139.567929 -242.364225)
			(xy 139.517408 -242.370359) (xy 139.466556 -242.36831) (xy 139.416692 -242.35813) (xy 139.369106 -242.340083)
			(xy 139.325032 -242.314637) (xy 139.28561 -242.28245) (xy 139.251862 -242.244356) (xy 139.224661 -242.201342)
			(xy 139.204713 -242.154522) (xy 139.192534 -242.105108) (xy 139.188439 -242.05438) (xy 138.882882 -242.05438)
			(xy 138.882392 -242.079369) (xy 138.874573 -242.128732) (xy 138.859129 -242.176264) (xy 138.836439 -242.220796)
			(xy 138.807063 -242.261229) (xy 138.771723 -242.296569) (xy 138.73129 -242.325945) (xy 138.686758 -242.348635)
			(xy 138.639226 -242.364079) (xy 138.589863 -242.371898) (xy 138.539885 -242.371898) (xy 138.490522 -242.364079)
			(xy 138.44299 -242.348635) (xy 138.398458 -242.325945) (xy 138.358025 -242.296569) (xy 138.322685 -242.261229)
			(xy 138.293309 -242.220796) (xy 138.270619 -242.176264) (xy 138.255175 -242.128732) (xy 138.247356 -242.079369)
			(xy 137.940039 -242.079369) (xy 137.94003 -242.079826) (xy 137.931866 -242.13006) (xy 137.91575 -242.178334)
			(xy 137.892099 -242.223397) (xy 137.861526 -242.264083) (xy 137.824822 -242.299338) (xy 137.782938 -242.328248)
			(xy 137.736959 -242.350065) (xy 137.688075 -242.364225) (xy 137.637554 -242.370359) (xy 137.586702 -242.36831)
			(xy 137.536838 -242.35813) (xy 137.489252 -242.340083) (xy 137.445178 -242.314637) (xy 137.405756 -242.28245)
			(xy 137.372008 -242.244356) (xy 137.344807 -242.201342) (xy 137.324859 -242.154522) (xy 137.31268 -242.105108)
			(xy 137.308585 -242.05438) (xy 136.060434 -242.05438) (xy 136.059922 -242.079826) (xy 136.051758 -242.13006)
			(xy 136.035642 -242.178334) (xy 136.011991 -242.223397) (xy 135.981418 -242.264083) (xy 135.944714 -242.299338)
			(xy 135.90283 -242.328248) (xy 135.856851 -242.350065) (xy 135.807967 -242.364225) (xy 135.757446 -242.370359)
			(xy 135.706594 -242.36831) (xy 135.65673 -242.35813) (xy 135.609144 -242.340083) (xy 135.56507 -242.314637)
			(xy 135.525648 -242.28245) (xy 135.4919 -242.244356) (xy 135.464699 -242.201342) (xy 135.444751 -242.154522)
			(xy 135.432572 -242.105108) (xy 135.428477 -242.05438) (xy 135.12038 -242.05438) (xy 135.119868 -242.079826)
			(xy 135.111704 -242.13006) (xy 135.095588 -242.178334) (xy 135.071937 -242.223397) (xy 135.041364 -242.264083)
			(xy 135.00466 -242.299338) (xy 134.962776 -242.328248) (xy 134.916797 -242.350065) (xy 134.867913 -242.364225)
			(xy 134.817392 -242.370359) (xy 134.76654 -242.36831) (xy 134.716676 -242.35813) (xy 134.66909 -242.340083)
			(xy 134.625016 -242.314637) (xy 134.585594 -242.28245) (xy 134.551846 -242.244356) (xy 134.524645 -242.201342)
			(xy 134.504697 -242.154522) (xy 134.492518 -242.105108) (xy 134.488423 -242.05438) (xy 134.182866 -242.05438)
			(xy 134.182376 -242.079369) (xy 134.174557 -242.128732) (xy 134.159113 -242.176264) (xy 134.136423 -242.220796)
			(xy 134.107047 -242.261229) (xy 134.071707 -242.296569) (xy 134.031274 -242.325945) (xy 133.986742 -242.348635)
			(xy 133.93921 -242.364079) (xy 133.889847 -242.371898) (xy 133.839869 -242.371898) (xy 133.790506 -242.364079)
			(xy 133.742974 -242.348635) (xy 133.698442 -242.325945) (xy 133.658009 -242.296569) (xy 133.622669 -242.261229)
			(xy 133.593293 -242.220796) (xy 133.570603 -242.176264) (xy 133.555159 -242.128732) (xy 133.54734 -242.079369)
			(xy 133.240023 -242.079369) (xy 133.240014 -242.079826) (xy 133.23185 -242.13006) (xy 133.215734 -242.178334)
			(xy 133.192083 -242.223397) (xy 133.16151 -242.264083) (xy 133.124806 -242.299338) (xy 133.082922 -242.328248)
			(xy 133.036943 -242.350065) (xy 132.988059 -242.364225) (xy 132.937538 -242.370359) (xy 132.886686 -242.36831)
			(xy 132.836822 -242.35813) (xy 132.789236 -242.340083) (xy 132.745162 -242.314637) (xy 132.70574 -242.28245)
			(xy 132.671992 -242.244356) (xy 132.644791 -242.201342) (xy 132.624843 -242.154522) (xy 132.612664 -242.105108)
			(xy 132.608569 -242.05438) (xy 132.302758 -242.05438) (xy 132.302268 -242.079369) (xy 132.294449 -242.128732)
			(xy 132.279005 -242.176264) (xy 132.256315 -242.220796) (xy 132.226939 -242.261229) (xy 132.191599 -242.296569)
			(xy 132.151166 -242.325945) (xy 132.106634 -242.348635) (xy 132.059102 -242.364079) (xy 132.009739 -242.371898)
			(xy 131.959761 -242.371898) (xy 131.910398 -242.364079) (xy 131.862866 -242.348635) (xy 131.818334 -242.325945)
			(xy 131.777901 -242.296569) (xy 131.742561 -242.261229) (xy 131.713185 -242.220796) (xy 131.690495 -242.176264)
			(xy 131.675051 -242.128732) (xy 131.667232 -242.079369) (xy 131.359915 -242.079369) (xy 131.359906 -242.079826)
			(xy 131.351742 -242.13006) (xy 131.335626 -242.178334) (xy 131.311975 -242.223397) (xy 131.281402 -242.264083)
			(xy 131.244698 -242.299338) (xy 131.202814 -242.328248) (xy 131.156835 -242.350065) (xy 131.107951 -242.364225)
			(xy 131.05743 -242.370359) (xy 131.006578 -242.36831) (xy 130.956714 -242.35813) (xy 130.909128 -242.340083)
			(xy 130.865054 -242.314637) (xy 130.825632 -242.28245) (xy 130.791884 -242.244356) (xy 130.764683 -242.201342)
			(xy 130.744735 -242.154522) (xy 130.732556 -242.105108) (xy 130.728461 -242.05438) (xy 129.480564 -242.05438)
			(xy 129.480052 -242.079826) (xy 129.471888 -242.13006) (xy 129.455772 -242.178334) (xy 129.432121 -242.223397)
			(xy 129.401548 -242.264083) (xy 129.364844 -242.299338) (xy 129.32296 -242.328248) (xy 129.276981 -242.350065)
			(xy 129.228097 -242.364225) (xy 129.177576 -242.370359) (xy 129.126724 -242.36831) (xy 129.07686 -242.35813)
			(xy 129.029274 -242.340083) (xy 128.9852 -242.314637) (xy 128.945778 -242.28245) (xy 128.91203 -242.244356)
			(xy 128.884829 -242.201342) (xy 128.864881 -242.154522) (xy 128.852702 -242.105108) (xy 128.848607 -242.05438)
			(xy 128.54051 -242.05438) (xy 128.539998 -242.079826) (xy 128.531834 -242.13006) (xy 128.515718 -242.178334)
			(xy 128.492067 -242.223397) (xy 128.461494 -242.264083) (xy 128.42479 -242.299338) (xy 128.382906 -242.328248)
			(xy 128.336927 -242.350065) (xy 128.288043 -242.364225) (xy 128.237522 -242.370359) (xy 128.18667 -242.36831)
			(xy 128.136806 -242.35813) (xy 128.08922 -242.340083) (xy 128.045146 -242.314637) (xy 128.005724 -242.28245)
			(xy 127.971976 -242.244356) (xy 127.944775 -242.201342) (xy 127.924827 -242.154522) (xy 127.912648 -242.105108)
			(xy 127.908553 -242.05438) (xy 127.602742 -242.05438) (xy 127.602252 -242.079369) (xy 127.594433 -242.128732)
			(xy 127.578989 -242.176264) (xy 127.556299 -242.220796) (xy 127.526923 -242.261229) (xy 127.491583 -242.296569)
			(xy 127.45115 -242.325945) (xy 127.406618 -242.348635) (xy 127.359086 -242.364079) (xy 127.309723 -242.371898)
			(xy 127.259745 -242.371898) (xy 127.210382 -242.364079) (xy 127.16285 -242.348635) (xy 127.118318 -242.325945)
			(xy 127.077885 -242.296569) (xy 127.042545 -242.261229) (xy 127.013169 -242.220796) (xy 126.990479 -242.176264)
			(xy 126.975035 -242.128732) (xy 126.967216 -242.079369) (xy 126.66199 -242.079369) (xy 126.656244 -242.120751)
			(xy 126.650496 -242.142264) (xy 126.648464 -242.149122) (xy 126.648464 -242.451382) (xy 126.648464 -242.45443)
			(xy 126.64941 -242.463883) (xy 126.657364 -242.48112) (xy 126.663958 -242.487958) (xy 126.72441 -242.539266)
			(xy 126.728648 -242.542689) (xy 126.738255 -242.547821) (xy 126.74346 -242.549426) (xy 126.75362 -242.55222)
			(xy 126.764542 -242.550442) (xy 126.777028 -242.548542) (xy 126.802205 -242.546505) (xy 126.814834 -242.546378)
			(xy 126.839823 -242.546871) (xy 126.889184 -242.554694) (xy 126.936713 -242.570142) (xy 126.981242 -242.592834)
			(xy 127.021672 -242.622213) (xy 127.05701 -242.657554) (xy 127.086384 -242.697987) (xy 127.109071 -242.742518)
			(xy 127.124514 -242.790049) (xy 127.132332 -242.839411) (xy 127.132332 -242.864386) (xy 127.438399 -242.864386)
			(xy 127.442494 -242.813658) (xy 127.454673 -242.764244) (xy 127.474621 -242.717424) (xy 127.501822 -242.67441)
			(xy 127.53557 -242.636316) (xy 127.574992 -242.604129) (xy 127.619066 -242.578683) (xy 127.666652 -242.560636)
			(xy 127.716516 -242.550456) (xy 127.767368 -242.548407) (xy 127.817889 -242.554541) (xy 127.866773 -242.568701)
			(xy 127.912752 -242.590518) (xy 127.954636 -242.619428) (xy 127.99134 -242.654683) (xy 128.021913 -242.695369)
			(xy 128.045564 -242.740432) (xy 128.06168 -242.788706) (xy 128.069844 -242.83894) (xy 128.070356 -242.864386)
			(xy 128.069853 -242.889375) (xy 128.37717 -242.889375) (xy 128.37717 -242.839397) (xy 128.384989 -242.790034)
			(xy 128.400433 -242.742502) (xy 128.423123 -242.69797) (xy 128.452499 -242.657537) (xy 128.487839 -242.622197)
			(xy 128.528272 -242.592821) (xy 128.572804 -242.570131) (xy 128.620336 -242.554687) (xy 128.669699 -242.546868)
			(xy 128.719677 -242.546868) (xy 128.76904 -242.554687) (xy 128.816572 -242.570131) (xy 128.861104 -242.592821)
			(xy 128.901537 -242.622197) (xy 128.936877 -242.657537) (xy 128.966253 -242.69797) (xy 128.988943 -242.742502)
			(xy 129.004387 -242.790034) (xy 129.012206 -242.839397) (xy 129.012696 -242.864386) (xy 129.318507 -242.864386)
			(xy 129.322602 -242.813658) (xy 129.334781 -242.764244) (xy 129.354729 -242.717424) (xy 129.38193 -242.67441)
			(xy 129.415678 -242.636316) (xy 129.4551 -242.604129) (xy 129.499174 -242.578683) (xy 129.54676 -242.560636)
			(xy 129.596624 -242.550456) (xy 129.647476 -242.548407) (xy 129.697997 -242.554541) (xy 129.746881 -242.568701)
			(xy 129.79286 -242.590518) (xy 129.834744 -242.619428) (xy 129.871448 -242.654683) (xy 129.902021 -242.695369)
			(xy 129.925672 -242.740432) (xy 129.941788 -242.788706) (xy 129.949952 -242.83894) (xy 129.950464 -242.864386)
			(xy 129.949961 -242.889375) (xy 130.257278 -242.889375) (xy 130.257278 -242.839397) (xy 130.265097 -242.790034)
			(xy 130.280541 -242.742502) (xy 130.303231 -242.69797) (xy 130.332607 -242.657537) (xy 130.367947 -242.622197)
			(xy 130.40838 -242.592821) (xy 130.452912 -242.570131) (xy 130.500444 -242.554687) (xy 130.549807 -242.546868)
			(xy 130.599785 -242.546868) (xy 130.649148 -242.554687) (xy 130.69668 -242.570131) (xy 130.741212 -242.592821)
			(xy 130.781645 -242.622197) (xy 130.816985 -242.657537) (xy 130.846361 -242.69797) (xy 130.869051 -242.742502)
			(xy 130.884495 -242.790034) (xy 130.892314 -242.839397) (xy 130.892804 -242.864386) (xy 131.198615 -242.864386)
			(xy 131.20271 -242.813658) (xy 131.214889 -242.764244) (xy 131.234837 -242.717424) (xy 131.262038 -242.67441)
			(xy 131.295786 -242.636316) (xy 131.335208 -242.604129) (xy 131.379282 -242.578683) (xy 131.426868 -242.560636)
			(xy 131.476732 -242.550456) (xy 131.527584 -242.548407) (xy 131.578105 -242.554541) (xy 131.626989 -242.568701)
			(xy 131.672968 -242.590518) (xy 131.714852 -242.619428) (xy 131.751556 -242.654683) (xy 131.782129 -242.695369)
			(xy 131.80578 -242.740432) (xy 131.821896 -242.788706) (xy 131.83006 -242.83894) (xy 131.830572 -242.864386)
			(xy 132.138415 -242.864386) (xy 132.14251 -242.813658) (xy 132.154689 -242.764244) (xy 132.174637 -242.717424)
			(xy 132.201838 -242.67441) (xy 132.235586 -242.636316) (xy 132.275008 -242.604129) (xy 132.319082 -242.578683)
			(xy 132.366668 -242.560636) (xy 132.416532 -242.550456) (xy 132.467384 -242.548407) (xy 132.517905 -242.554541)
			(xy 132.566789 -242.568701) (xy 132.612768 -242.590518) (xy 132.654652 -242.619428) (xy 132.691356 -242.654683)
			(xy 132.721929 -242.695369) (xy 132.74558 -242.740432) (xy 132.761696 -242.788706) (xy 132.76986 -242.83894)
			(xy 132.770372 -242.864386) (xy 132.769869 -242.889375) (xy 133.077186 -242.889375) (xy 133.077186 -242.839397)
			(xy 133.085005 -242.790034) (xy 133.100449 -242.742502) (xy 133.123139 -242.69797) (xy 133.152515 -242.657537)
			(xy 133.187855 -242.622197) (xy 133.228288 -242.592821) (xy 133.27282 -242.570131) (xy 133.320352 -242.554687)
			(xy 133.369715 -242.546868) (xy 133.419693 -242.546868) (xy 133.469056 -242.554687) (xy 133.516588 -242.570131)
			(xy 133.56112 -242.592821) (xy 133.601553 -242.622197) (xy 133.636893 -242.657537) (xy 133.666269 -242.69797)
			(xy 133.688959 -242.742502) (xy 133.704403 -242.790034) (xy 133.712222 -242.839397) (xy 133.712712 -242.864386)
			(xy 134.018523 -242.864386) (xy 134.022618 -242.813658) (xy 134.034797 -242.764244) (xy 134.054745 -242.717424)
			(xy 134.081946 -242.67441) (xy 134.115694 -242.636316) (xy 134.155116 -242.604129) (xy 134.19919 -242.578683)
			(xy 134.246776 -242.560636) (xy 134.29664 -242.550456) (xy 134.347492 -242.548407) (xy 134.398013 -242.554541)
			(xy 134.446897 -242.568701) (xy 134.492876 -242.590518) (xy 134.53476 -242.619428) (xy 134.571464 -242.654683)
			(xy 134.602037 -242.695369) (xy 134.625688 -242.740432) (xy 134.641804 -242.788706) (xy 134.649968 -242.83894)
			(xy 134.65048 -242.864386) (xy 134.649977 -242.889375) (xy 134.957294 -242.889375) (xy 134.957294 -242.839397)
			(xy 134.965113 -242.790034) (xy 134.980557 -242.742502) (xy 135.003247 -242.69797) (xy 135.032623 -242.657537)
			(xy 135.067963 -242.622197) (xy 135.108396 -242.592821) (xy 135.152928 -242.570131) (xy 135.20046 -242.554687)
			(xy 135.249823 -242.546868) (xy 135.299801 -242.546868) (xy 135.349164 -242.554687) (xy 135.396696 -242.570131)
			(xy 135.441228 -242.592821) (xy 135.481661 -242.622197) (xy 135.517001 -242.657537) (xy 135.546377 -242.69797)
			(xy 135.569067 -242.742502) (xy 135.584511 -242.790034) (xy 135.59233 -242.839397) (xy 135.59282 -242.864386)
			(xy 135.898631 -242.864386) (xy 135.902726 -242.813658) (xy 135.914905 -242.764244) (xy 135.934853 -242.717424)
			(xy 135.962054 -242.67441) (xy 135.995802 -242.636316) (xy 136.035224 -242.604129) (xy 136.079298 -242.578683)
			(xy 136.126884 -242.560636) (xy 136.176748 -242.550456) (xy 136.2276 -242.548407) (xy 136.278121 -242.554541)
			(xy 136.327005 -242.568701) (xy 136.372984 -242.590518) (xy 136.414868 -242.619428) (xy 136.451572 -242.654683)
			(xy 136.482145 -242.695369) (xy 136.505796 -242.740432) (xy 136.521912 -242.788706) (xy 136.530076 -242.83894)
			(xy 136.530588 -242.864386) (xy 136.530085 -242.889375) (xy 136.837148 -242.889375) (xy 136.837148 -242.839397)
			(xy 136.844967 -242.790034) (xy 136.860411 -242.742502) (xy 136.883101 -242.69797) (xy 136.912477 -242.657537)
			(xy 136.947817 -242.622197) (xy 136.98825 -242.592821) (xy 137.032782 -242.570131) (xy 137.080314 -242.554687)
			(xy 137.129677 -242.546868) (xy 137.179655 -242.546868) (xy 137.229018 -242.554687) (xy 137.27655 -242.570131)
			(xy 137.321082 -242.592821) (xy 137.361515 -242.622197) (xy 137.396855 -242.657537) (xy 137.426231 -242.69797)
			(xy 137.448921 -242.742502) (xy 137.464365 -242.790034) (xy 137.472184 -242.839397) (xy 137.472674 -242.864386)
			(xy 137.778485 -242.864386) (xy 137.78258 -242.813658) (xy 137.794759 -242.764244) (xy 137.814707 -242.717424)
			(xy 137.841908 -242.67441) (xy 137.875656 -242.636316) (xy 137.915078 -242.604129) (xy 137.959152 -242.578683)
			(xy 138.006738 -242.560636) (xy 138.056602 -242.550456) (xy 138.107454 -242.548407) (xy 138.157975 -242.554541)
			(xy 138.206859 -242.568701) (xy 138.252838 -242.590518) (xy 138.294722 -242.619428) (xy 138.331426 -242.654683)
			(xy 138.361999 -242.695369) (xy 138.38565 -242.740432) (xy 138.401766 -242.788706) (xy 138.40993 -242.83894)
			(xy 138.410442 -242.864386) (xy 138.718539 -242.864386) (xy 138.722634 -242.813658) (xy 138.734813 -242.764244)
			(xy 138.754761 -242.717424) (xy 138.781962 -242.67441) (xy 138.81571 -242.636316) (xy 138.855132 -242.604129)
			(xy 138.899206 -242.578683) (xy 138.946792 -242.560636) (xy 138.996656 -242.550456) (xy 139.047508 -242.548407)
			(xy 139.098029 -242.554541) (xy 139.146913 -242.568701) (xy 139.192892 -242.590518) (xy 139.234776 -242.619428)
			(xy 139.27148 -242.654683) (xy 139.302053 -242.695369) (xy 139.325704 -242.740432) (xy 139.34182 -242.788706)
			(xy 139.349984 -242.83894) (xy 139.350496 -242.864386) (xy 139.349993 -242.889375) (xy 139.65731 -242.889375)
			(xy 139.65731 -242.839397) (xy 139.665129 -242.790034) (xy 139.680573 -242.742502) (xy 139.703263 -242.69797)
			(xy 139.732639 -242.657537) (xy 139.767979 -242.622197) (xy 139.808412 -242.592821) (xy 139.852944 -242.570131)
			(xy 139.900476 -242.554687) (xy 139.949839 -242.546868) (xy 139.999817 -242.546868) (xy 140.04918 -242.554687)
			(xy 140.096712 -242.570131) (xy 140.141244 -242.592821) (xy 140.181677 -242.622197) (xy 140.217017 -242.657537)
			(xy 140.246393 -242.69797) (xy 140.269083 -242.742502) (xy 140.284527 -242.790034) (xy 140.292346 -242.839397)
			(xy 140.292836 -242.864386) (xy 140.598647 -242.864386) (xy 140.602742 -242.813658) (xy 140.614921 -242.764244)
			(xy 140.634869 -242.717424) (xy 140.66207 -242.67441) (xy 140.695818 -242.636316) (xy 140.73524 -242.604129)
			(xy 140.779314 -242.578683) (xy 140.8269 -242.560636) (xy 140.876764 -242.550456) (xy 140.927616 -242.548407)
			(xy 140.978137 -242.554541) (xy 141.027021 -242.568701) (xy 141.073 -242.590518) (xy 141.114884 -242.619428)
			(xy 141.151588 -242.654683) (xy 141.182161 -242.695369) (xy 141.205812 -242.740432) (xy 141.221928 -242.788706)
			(xy 141.230092 -242.83894) (xy 141.230604 -242.864386) (xy 141.230101 -242.889375) (xy 141.537164 -242.889375)
			(xy 141.537164 -242.839397) (xy 141.544983 -242.790034) (xy 141.560427 -242.742502) (xy 141.583117 -242.69797)
			(xy 141.612493 -242.657537) (xy 141.647833 -242.622197) (xy 141.688266 -242.592821) (xy 141.732798 -242.570131)
			(xy 141.78033 -242.554687) (xy 141.829693 -242.546868) (xy 141.879671 -242.546868) (xy 141.929034 -242.554687)
			(xy 141.976566 -242.570131) (xy 142.021098 -242.592821) (xy 142.061531 -242.622197) (xy 142.096871 -242.657537)
			(xy 142.126247 -242.69797) (xy 142.148937 -242.742502) (xy 142.164381 -242.790034) (xy 142.1722 -242.839397)
			(xy 142.17269 -242.864386) (xy 142.478501 -242.864386) (xy 142.482596 -242.813658) (xy 142.494775 -242.764244)
			(xy 142.514723 -242.717424) (xy 142.541924 -242.67441) (xy 142.575672 -242.636316) (xy 142.615094 -242.604129)
			(xy 142.659168 -242.578683) (xy 142.706754 -242.560636) (xy 142.756618 -242.550456) (xy 142.80747 -242.548407)
			(xy 142.857991 -242.554541) (xy 142.906875 -242.568701) (xy 142.952854 -242.590518) (xy 142.994738 -242.619428)
			(xy 143.031442 -242.654683) (xy 143.062015 -242.695369) (xy 143.085666 -242.740432) (xy 143.101782 -242.788706)
			(xy 143.109946 -242.83894) (xy 143.110458 -242.864386) (xy 143.109955 -242.889375) (xy 143.417272 -242.889375)
			(xy 143.417272 -242.839397) (xy 143.425091 -242.790034) (xy 143.440535 -242.742502) (xy 143.463225 -242.69797)
			(xy 143.492601 -242.657537) (xy 143.527941 -242.622197) (xy 143.568374 -242.592821) (xy 143.612906 -242.570131)
			(xy 143.660438 -242.554687) (xy 143.709801 -242.546868) (xy 143.759779 -242.546868) (xy 143.809142 -242.554687)
			(xy 143.856674 -242.570131) (xy 143.901206 -242.592821) (xy 143.941639 -242.622197) (xy 143.976979 -242.657537)
			(xy 144.006355 -242.69797) (xy 144.029045 -242.742502) (xy 144.044489 -242.790034) (xy 144.052308 -242.839397)
			(xy 144.052798 -242.864386) (xy 144.052308 -242.889375) (xy 144.044489 -242.938738) (xy 144.029045 -242.98627)
			(xy 144.006355 -243.030802) (xy 143.976979 -243.071235) (xy 143.941639 -243.106575) (xy 143.901206 -243.135951)
			(xy 143.856674 -243.158641) (xy 143.809142 -243.174085) (xy 143.759779 -243.181904) (xy 143.709801 -243.181904)
			(xy 143.660438 -243.174085) (xy 143.612906 -243.158641) (xy 143.568374 -243.135951) (xy 143.527941 -243.106575)
			(xy 143.492601 -243.071235) (xy 143.463225 -243.030802) (xy 143.440535 -242.98627) (xy 143.425091 -242.938738)
			(xy 143.417272 -242.889375) (xy 143.109955 -242.889375) (xy 143.109946 -242.889832) (xy 143.101782 -242.940066)
			(xy 143.085666 -242.98834) (xy 143.062015 -243.033403) (xy 143.031442 -243.074089) (xy 142.994738 -243.109344)
			(xy 142.952854 -243.138254) (xy 142.906875 -243.160071) (xy 142.857991 -243.174231) (xy 142.80747 -243.180365)
			(xy 142.756618 -243.178316) (xy 142.706754 -243.168136) (xy 142.659168 -243.150089) (xy 142.615094 -243.124643)
			(xy 142.575672 -243.092456) (xy 142.541924 -243.054362) (xy 142.514723 -243.011348) (xy 142.494775 -242.964528)
			(xy 142.482596 -242.915114) (xy 142.478501 -242.864386) (xy 142.17269 -242.864386) (xy 142.1722 -242.889375)
			(xy 142.164381 -242.938738) (xy 142.148937 -242.98627) (xy 142.126247 -243.030802) (xy 142.096871 -243.071235)
			(xy 142.061531 -243.106575) (xy 142.021098 -243.135951) (xy 141.976566 -243.158641) (xy 141.929034 -243.174085)
			(xy 141.879671 -243.181904) (xy 141.829693 -243.181904) (xy 141.78033 -243.174085) (xy 141.732798 -243.158641)
			(xy 141.688266 -243.135951) (xy 141.647833 -243.106575) (xy 141.612493 -243.071235) (xy 141.583117 -243.030802)
			(xy 141.560427 -242.98627) (xy 141.544983 -242.938738) (xy 141.537164 -242.889375) (xy 141.230101 -242.889375)
			(xy 141.230092 -242.889832) (xy 141.221928 -242.940066) (xy 141.205812 -242.98834) (xy 141.182161 -243.033403)
			(xy 141.151588 -243.074089) (xy 141.114884 -243.109344) (xy 141.073 -243.138254) (xy 141.027021 -243.160071)
			(xy 140.978137 -243.174231) (xy 140.927616 -243.180365) (xy 140.876764 -243.178316) (xy 140.8269 -243.168136)
			(xy 140.779314 -243.150089) (xy 140.73524 -243.124643) (xy 140.695818 -243.092456) (xy 140.66207 -243.054362)
			(xy 140.634869 -243.011348) (xy 140.614921 -242.964528) (xy 140.602742 -242.915114) (xy 140.598647 -242.864386)
			(xy 140.292836 -242.864386) (xy 140.292346 -242.889375) (xy 140.284527 -242.938738) (xy 140.269083 -242.98627)
			(xy 140.246393 -243.030802) (xy 140.217017 -243.071235) (xy 140.181677 -243.106575) (xy 140.141244 -243.135951)
			(xy 140.096712 -243.158641) (xy 140.04918 -243.174085) (xy 139.999817 -243.181904) (xy 139.949839 -243.181904)
			(xy 139.900476 -243.174085) (xy 139.852944 -243.158641) (xy 139.808412 -243.135951) (xy 139.767979 -243.106575)
			(xy 139.732639 -243.071235) (xy 139.703263 -243.030802) (xy 139.680573 -242.98627) (xy 139.665129 -242.938738)
			(xy 139.65731 -242.889375) (xy 139.349993 -242.889375) (xy 139.349984 -242.889832) (xy 139.34182 -242.940066)
			(xy 139.325704 -242.98834) (xy 139.302053 -243.033403) (xy 139.27148 -243.074089) (xy 139.234776 -243.109344)
			(xy 139.192892 -243.138254) (xy 139.146913 -243.160071) (xy 139.098029 -243.174231) (xy 139.047508 -243.180365)
			(xy 138.996656 -243.178316) (xy 138.946792 -243.168136) (xy 138.899206 -243.150089) (xy 138.855132 -243.124643)
			(xy 138.81571 -243.092456) (xy 138.781962 -243.054362) (xy 138.754761 -243.011348) (xy 138.734813 -242.964528)
			(xy 138.722634 -242.915114) (xy 138.718539 -242.864386) (xy 138.410442 -242.864386) (xy 138.40993 -242.889832)
			(xy 138.401766 -242.940066) (xy 138.38565 -242.98834) (xy 138.361999 -243.033403) (xy 138.331426 -243.074089)
			(xy 138.294722 -243.109344) (xy 138.252838 -243.138254) (xy 138.206859 -243.160071) (xy 138.157975 -243.174231)
			(xy 138.107454 -243.180365) (xy 138.056602 -243.178316) (xy 138.006738 -243.168136) (xy 137.959152 -243.150089)
			(xy 137.915078 -243.124643) (xy 137.875656 -243.092456) (xy 137.841908 -243.054362) (xy 137.814707 -243.011348)
			(xy 137.794759 -242.964528) (xy 137.78258 -242.915114) (xy 137.778485 -242.864386) (xy 137.472674 -242.864386)
			(xy 137.472184 -242.889375) (xy 137.464365 -242.938738) (xy 137.448921 -242.98627) (xy 137.426231 -243.030802)
			(xy 137.396855 -243.071235) (xy 137.361515 -243.106575) (xy 137.321082 -243.135951) (xy 137.27655 -243.158641)
			(xy 137.229018 -243.174085) (xy 137.179655 -243.181904) (xy 137.129677 -243.181904) (xy 137.080314 -243.174085)
			(xy 137.032782 -243.158641) (xy 136.98825 -243.135951) (xy 136.947817 -243.106575) (xy 136.912477 -243.071235)
			(xy 136.883101 -243.030802) (xy 136.860411 -242.98627) (xy 136.844967 -242.938738) (xy 136.837148 -242.889375)
			(xy 136.530085 -242.889375) (xy 136.530076 -242.889832) (xy 136.521912 -242.940066) (xy 136.505796 -242.98834)
			(xy 136.482145 -243.033403) (xy 136.451572 -243.074089) (xy 136.414868 -243.109344) (xy 136.372984 -243.138254)
			(xy 136.327005 -243.160071) (xy 136.278121 -243.174231) (xy 136.2276 -243.180365) (xy 136.176748 -243.178316)
			(xy 136.126884 -243.168136) (xy 136.079298 -243.150089) (xy 136.035224 -243.124643) (xy 135.995802 -243.092456)
			(xy 135.962054 -243.054362) (xy 135.934853 -243.011348) (xy 135.914905 -242.964528) (xy 135.902726 -242.915114)
			(xy 135.898631 -242.864386) (xy 135.59282 -242.864386) (xy 135.59233 -242.889375) (xy 135.584511 -242.938738)
			(xy 135.569067 -242.98627) (xy 135.546377 -243.030802) (xy 135.517001 -243.071235) (xy 135.481661 -243.106575)
			(xy 135.441228 -243.135951) (xy 135.396696 -243.158641) (xy 135.349164 -243.174085) (xy 135.299801 -243.181904)
			(xy 135.249823 -243.181904) (xy 135.20046 -243.174085) (xy 135.152928 -243.158641) (xy 135.108396 -243.135951)
			(xy 135.067963 -243.106575) (xy 135.032623 -243.071235) (xy 135.003247 -243.030802) (xy 134.980557 -242.98627)
			(xy 134.965113 -242.938738) (xy 134.957294 -242.889375) (xy 134.649977 -242.889375) (xy 134.649968 -242.889832)
			(xy 134.641804 -242.940066) (xy 134.625688 -242.98834) (xy 134.602037 -243.033403) (xy 134.571464 -243.074089)
			(xy 134.53476 -243.109344) (xy 134.492876 -243.138254) (xy 134.446897 -243.160071) (xy 134.398013 -243.174231)
			(xy 134.347492 -243.180365) (xy 134.29664 -243.178316) (xy 134.246776 -243.168136) (xy 134.19919 -243.150089)
			(xy 134.155116 -243.124643) (xy 134.115694 -243.092456) (xy 134.081946 -243.054362) (xy 134.054745 -243.011348)
			(xy 134.034797 -242.964528) (xy 134.022618 -242.915114) (xy 134.018523 -242.864386) (xy 133.712712 -242.864386)
			(xy 133.712222 -242.889375) (xy 133.704403 -242.938738) (xy 133.688959 -242.98627) (xy 133.666269 -243.030802)
			(xy 133.636893 -243.071235) (xy 133.601553 -243.106575) (xy 133.56112 -243.135951) (xy 133.516588 -243.158641)
			(xy 133.469056 -243.174085) (xy 133.419693 -243.181904) (xy 133.369715 -243.181904) (xy 133.320352 -243.174085)
			(xy 133.27282 -243.158641) (xy 133.228288 -243.135951) (xy 133.187855 -243.106575) (xy 133.152515 -243.071235)
			(xy 133.123139 -243.030802) (xy 133.100449 -242.98627) (xy 133.085005 -242.938738) (xy 133.077186 -242.889375)
			(xy 132.769869 -242.889375) (xy 132.76986 -242.889832) (xy 132.761696 -242.940066) (xy 132.74558 -242.98834)
			(xy 132.721929 -243.033403) (xy 132.691356 -243.074089) (xy 132.654652 -243.109344) (xy 132.612768 -243.138254)
			(xy 132.566789 -243.160071) (xy 132.517905 -243.174231) (xy 132.467384 -243.180365) (xy 132.416532 -243.178316)
			(xy 132.366668 -243.168136) (xy 132.319082 -243.150089) (xy 132.275008 -243.124643) (xy 132.235586 -243.092456)
			(xy 132.201838 -243.054362) (xy 132.174637 -243.011348) (xy 132.154689 -242.964528) (xy 132.14251 -242.915114)
			(xy 132.138415 -242.864386) (xy 131.830572 -242.864386) (xy 131.83006 -242.889832) (xy 131.821896 -242.940066)
			(xy 131.80578 -242.98834) (xy 131.782129 -243.033403) (xy 131.751556 -243.074089) (xy 131.714852 -243.109344)
			(xy 131.672968 -243.138254) (xy 131.626989 -243.160071) (xy 131.578105 -243.174231) (xy 131.527584 -243.180365)
			(xy 131.476732 -243.178316) (xy 131.426868 -243.168136) (xy 131.379282 -243.150089) (xy 131.335208 -243.124643)
			(xy 131.295786 -243.092456) (xy 131.262038 -243.054362) (xy 131.234837 -243.011348) (xy 131.214889 -242.964528)
			(xy 131.20271 -242.915114) (xy 131.198615 -242.864386) (xy 130.892804 -242.864386) (xy 130.892314 -242.889375)
			(xy 130.884495 -242.938738) (xy 130.869051 -242.98627) (xy 130.846361 -243.030802) (xy 130.816985 -243.071235)
			(xy 130.781645 -243.106575) (xy 130.741212 -243.135951) (xy 130.69668 -243.158641) (xy 130.649148 -243.174085)
			(xy 130.599785 -243.181904) (xy 130.549807 -243.181904) (xy 130.500444 -243.174085) (xy 130.452912 -243.158641)
			(xy 130.40838 -243.135951) (xy 130.367947 -243.106575) (xy 130.332607 -243.071235) (xy 130.303231 -243.030802)
			(xy 130.280541 -242.98627) (xy 130.265097 -242.938738) (xy 130.257278 -242.889375) (xy 129.949961 -242.889375)
			(xy 129.949952 -242.889832) (xy 129.941788 -242.940066) (xy 129.925672 -242.98834) (xy 129.902021 -243.033403)
			(xy 129.871448 -243.074089) (xy 129.834744 -243.109344) (xy 129.79286 -243.138254) (xy 129.746881 -243.160071)
			(xy 129.697997 -243.174231) (xy 129.647476 -243.180365) (xy 129.596624 -243.178316) (xy 129.54676 -243.168136)
			(xy 129.499174 -243.150089) (xy 129.4551 -243.124643) (xy 129.415678 -243.092456) (xy 129.38193 -243.054362)
			(xy 129.354729 -243.011348) (xy 129.334781 -242.964528) (xy 129.322602 -242.915114) (xy 129.318507 -242.864386)
			(xy 129.012696 -242.864386) (xy 129.012206 -242.889375) (xy 129.004387 -242.938738) (xy 128.988943 -242.98627)
			(xy 128.966253 -243.030802) (xy 128.936877 -243.071235) (xy 128.901537 -243.106575) (xy 128.861104 -243.135951)
			(xy 128.816572 -243.158641) (xy 128.76904 -243.174085) (xy 128.719677 -243.181904) (xy 128.669699 -243.181904)
			(xy 128.620336 -243.174085) (xy 128.572804 -243.158641) (xy 128.528272 -243.135951) (xy 128.487839 -243.106575)
			(xy 128.452499 -243.071235) (xy 128.423123 -243.030802) (xy 128.400433 -242.98627) (xy 128.384989 -242.938738)
			(xy 128.37717 -242.889375) (xy 128.069853 -242.889375) (xy 128.069844 -242.889832) (xy 128.06168 -242.940066)
			(xy 128.045564 -242.98834) (xy 128.021913 -243.033403) (xy 127.99134 -243.074089) (xy 127.954636 -243.109344)
			(xy 127.912752 -243.138254) (xy 127.866773 -243.160071) (xy 127.817889 -243.174231) (xy 127.767368 -243.180365)
			(xy 127.716516 -243.178316) (xy 127.666652 -243.168136) (xy 127.619066 -243.150089) (xy 127.574992 -243.124643)
			(xy 127.53557 -243.092456) (xy 127.501822 -243.054362) (xy 127.474621 -243.011348) (xy 127.454673 -242.964528)
			(xy 127.442494 -242.915114) (xy 127.438399 -242.864386) (xy 127.132332 -242.864386) (xy 127.132332 -242.889389)
			(xy 127.124514 -242.938751) (xy 127.109071 -242.986282) (xy 127.086384 -243.030813) (xy 127.05701 -243.071246)
			(xy 127.021672 -243.106587) (xy 126.981242 -243.135966) (xy 126.936713 -243.158658) (xy 126.889184 -243.174106)
			(xy 126.839823 -243.181929) (xy 126.814834 -243.182394) (xy 126.8024 -243.182293) (xy 126.777607 -243.180384)
			(xy 126.765304 -243.178584) (xy 126.763526 -243.17833) (xy 126.75616 -243.177822) (xy 126.747781 -243.178249)
			(xy 126.731972 -243.18383) (xy 126.725172 -243.188744) (xy 126.706122 -243.204746) (xy 126.705614 -243.205254)
			(xy 126.666244 -243.239036) (xy 126.658721 -243.246106) (xy 126.649554 -243.264583) (xy 126.648464 -243.27485)
			(xy 126.648464 -243.572284) (xy 126.648972 -243.57584) (xy 126.650496 -243.586762) (xy 126.651004 -243.588794)
			(xy 126.651512 -243.590318) (xy 126.656774 -243.610935) (xy 126.662382 -243.653116) (xy 126.662688 -243.674392)
			(xy 127.908553 -243.674392) (xy 127.912648 -243.623664) (xy 127.924827 -243.57425) (xy 127.944775 -243.52743)
			(xy 127.971976 -243.484416) (xy 128.005724 -243.446322) (xy 128.045146 -243.414135) (xy 128.08922 -243.388689)
			(xy 128.136806 -243.370642) (xy 128.18667 -243.360462) (xy 128.237522 -243.358413) (xy 128.288043 -243.364547)
			(xy 128.336927 -243.378707) (xy 128.382906 -243.400524) (xy 128.42479 -243.429434) (xy 128.461494 -243.464689)
			(xy 128.492067 -243.505375) (xy 128.515718 -243.550438) (xy 128.531834 -243.598712) (xy 128.539998 -243.648946)
			(xy 128.54051 -243.674392) (xy 128.848607 -243.674392) (xy 128.852702 -243.623664) (xy 128.864881 -243.57425)
			(xy 128.884829 -243.52743) (xy 128.91203 -243.484416) (xy 128.945778 -243.446322) (xy 128.9852 -243.414135)
			(xy 129.029274 -243.388689) (xy 129.07686 -243.370642) (xy 129.126724 -243.360462) (xy 129.177576 -243.358413)
			(xy 129.228097 -243.364547) (xy 129.276981 -243.378707) (xy 129.32296 -243.400524) (xy 129.364844 -243.429434)
			(xy 129.401548 -243.464689) (xy 129.432121 -243.505375) (xy 129.455772 -243.550438) (xy 129.471888 -243.598712)
			(xy 129.480052 -243.648946) (xy 129.480564 -243.674392) (xy 129.480061 -243.699381) (xy 129.787124 -243.699381)
			(xy 129.787124 -243.649403) (xy 129.794943 -243.60004) (xy 129.810387 -243.552508) (xy 129.833077 -243.507976)
			(xy 129.862453 -243.467543) (xy 129.897793 -243.432203) (xy 129.938226 -243.402827) (xy 129.982758 -243.380137)
			(xy 130.03029 -243.364693) (xy 130.079653 -243.356874) (xy 130.129631 -243.356874) (xy 130.178994 -243.364693)
			(xy 130.226526 -243.380137) (xy 130.271058 -243.402827) (xy 130.311491 -243.432203) (xy 130.346831 -243.467543)
			(xy 130.376207 -243.507976) (xy 130.398897 -243.552508) (xy 130.414341 -243.60004) (xy 130.42216 -243.649403)
			(xy 130.42265 -243.674392) (xy 130.728461 -243.674392) (xy 130.732556 -243.623664) (xy 130.744735 -243.57425)
			(xy 130.764683 -243.52743) (xy 130.791884 -243.484416) (xy 130.825632 -243.446322) (xy 130.865054 -243.414135)
			(xy 130.909128 -243.388689) (xy 130.956714 -243.370642) (xy 131.006578 -243.360462) (xy 131.05743 -243.358413)
			(xy 131.107951 -243.364547) (xy 131.156835 -243.378707) (xy 131.202814 -243.400524) (xy 131.244698 -243.429434)
			(xy 131.281402 -243.464689) (xy 131.311975 -243.505375) (xy 131.335626 -243.550438) (xy 131.351742 -243.598712)
			(xy 131.359906 -243.648946) (xy 131.360418 -243.674392) (xy 131.359915 -243.699381) (xy 131.667232 -243.699381)
			(xy 131.667232 -243.649403) (xy 131.675051 -243.60004) (xy 131.690495 -243.552508) (xy 131.713185 -243.507976)
			(xy 131.742561 -243.467543) (xy 131.777901 -243.432203) (xy 131.818334 -243.402827) (xy 131.862866 -243.380137)
			(xy 131.910398 -243.364693) (xy 131.959761 -243.356874) (xy 132.009739 -243.356874) (xy 132.059102 -243.364693)
			(xy 132.106634 -243.380137) (xy 132.151166 -243.402827) (xy 132.191599 -243.432203) (xy 132.226939 -243.467543)
			(xy 132.256315 -243.507976) (xy 132.279005 -243.552508) (xy 132.294449 -243.60004) (xy 132.302268 -243.649403)
			(xy 132.302758 -243.674392) (xy 132.608569 -243.674392) (xy 132.612664 -243.623664) (xy 132.624843 -243.57425)
			(xy 132.644791 -243.52743) (xy 132.671992 -243.484416) (xy 132.70574 -243.446322) (xy 132.745162 -243.414135)
			(xy 132.789236 -243.388689) (xy 132.836822 -243.370642) (xy 132.886686 -243.360462) (xy 132.937538 -243.358413)
			(xy 132.988059 -243.364547) (xy 133.036943 -243.378707) (xy 133.082922 -243.400524) (xy 133.124806 -243.429434)
			(xy 133.16151 -243.464689) (xy 133.192083 -243.505375) (xy 133.215734 -243.550438) (xy 133.23185 -243.598712)
			(xy 133.240014 -243.648946) (xy 133.240526 -243.674392) (xy 133.240023 -243.699381) (xy 133.54734 -243.699381)
			(xy 133.54734 -243.649403) (xy 133.555159 -243.60004) (xy 133.570603 -243.552508) (xy 133.593293 -243.507976)
			(xy 133.622669 -243.467543) (xy 133.658009 -243.432203) (xy 133.698442 -243.402827) (xy 133.742974 -243.380137)
			(xy 133.790506 -243.364693) (xy 133.839869 -243.356874) (xy 133.889847 -243.356874) (xy 133.93921 -243.364693)
			(xy 133.986742 -243.380137) (xy 134.031274 -243.402827) (xy 134.071707 -243.432203) (xy 134.107047 -243.467543)
			(xy 134.136423 -243.507976) (xy 134.159113 -243.552508) (xy 134.174557 -243.60004) (xy 134.182376 -243.649403)
			(xy 134.182866 -243.674392) (xy 134.488423 -243.674392) (xy 134.492518 -243.623664) (xy 134.504697 -243.57425)
			(xy 134.524645 -243.52743) (xy 134.551846 -243.484416) (xy 134.585594 -243.446322) (xy 134.625016 -243.414135)
			(xy 134.66909 -243.388689) (xy 134.716676 -243.370642) (xy 134.76654 -243.360462) (xy 134.817392 -243.358413)
			(xy 134.867913 -243.364547) (xy 134.916797 -243.378707) (xy 134.962776 -243.400524) (xy 135.00466 -243.429434)
			(xy 135.041364 -243.464689) (xy 135.071937 -243.505375) (xy 135.095588 -243.550438) (xy 135.111704 -243.598712)
			(xy 135.119868 -243.648946) (xy 135.12038 -243.674392) (xy 135.428477 -243.674392) (xy 135.432572 -243.623664)
			(xy 135.444751 -243.57425) (xy 135.464699 -243.52743) (xy 135.4919 -243.484416) (xy 135.525648 -243.446322)
			(xy 135.56507 -243.414135) (xy 135.609144 -243.388689) (xy 135.65673 -243.370642) (xy 135.706594 -243.360462)
			(xy 135.757446 -243.358413) (xy 135.807967 -243.364547) (xy 135.856851 -243.378707) (xy 135.90283 -243.400524)
			(xy 135.944714 -243.429434) (xy 135.981418 -243.464689) (xy 136.011991 -243.505375) (xy 136.035642 -243.550438)
			(xy 136.051758 -243.598712) (xy 136.059922 -243.648946) (xy 136.060434 -243.674392) (xy 136.059931 -243.699381)
			(xy 136.367248 -243.699381) (xy 136.367248 -243.649403) (xy 136.375067 -243.60004) (xy 136.390511 -243.552508)
			(xy 136.413201 -243.507976) (xy 136.442577 -243.467543) (xy 136.477917 -243.432203) (xy 136.51835 -243.402827)
			(xy 136.562882 -243.380137) (xy 136.610414 -243.364693) (xy 136.659777 -243.356874) (xy 136.709755 -243.356874)
			(xy 136.759118 -243.364693) (xy 136.80665 -243.380137) (xy 136.851182 -243.402827) (xy 136.891615 -243.432203)
			(xy 136.926955 -243.467543) (xy 136.956331 -243.507976) (xy 136.979021 -243.552508) (xy 136.994465 -243.60004)
			(xy 137.002284 -243.649403) (xy 137.002774 -243.674392) (xy 137.308585 -243.674392) (xy 137.31268 -243.623664)
			(xy 137.324859 -243.57425) (xy 137.344807 -243.52743) (xy 137.372008 -243.484416) (xy 137.405756 -243.446322)
			(xy 137.445178 -243.414135) (xy 137.489252 -243.388689) (xy 137.536838 -243.370642) (xy 137.586702 -243.360462)
			(xy 137.637554 -243.358413) (xy 137.688075 -243.364547) (xy 137.736959 -243.378707) (xy 137.782938 -243.400524)
			(xy 137.824822 -243.429434) (xy 137.861526 -243.464689) (xy 137.892099 -243.505375) (xy 137.91575 -243.550438)
			(xy 137.931866 -243.598712) (xy 137.94003 -243.648946) (xy 137.940542 -243.674392) (xy 137.940039 -243.699381)
			(xy 138.247356 -243.699381) (xy 138.247356 -243.649403) (xy 138.255175 -243.60004) (xy 138.270619 -243.552508)
			(xy 138.293309 -243.507976) (xy 138.322685 -243.467543) (xy 138.358025 -243.432203) (xy 138.398458 -243.402827)
			(xy 138.44299 -243.380137) (xy 138.490522 -243.364693) (xy 138.539885 -243.356874) (xy 138.589863 -243.356874)
			(xy 138.639226 -243.364693) (xy 138.686758 -243.380137) (xy 138.73129 -243.402827) (xy 138.771723 -243.432203)
			(xy 138.807063 -243.467543) (xy 138.836439 -243.507976) (xy 138.859129 -243.552508) (xy 138.874573 -243.60004)
			(xy 138.882392 -243.649403) (xy 138.882882 -243.674392) (xy 139.188439 -243.674392) (xy 139.192534 -243.623664)
			(xy 139.204713 -243.57425) (xy 139.224661 -243.52743) (xy 139.251862 -243.484416) (xy 139.28561 -243.446322)
			(xy 139.325032 -243.414135) (xy 139.369106 -243.388689) (xy 139.416692 -243.370642) (xy 139.466556 -243.360462)
			(xy 139.517408 -243.358413) (xy 139.567929 -243.364547) (xy 139.616813 -243.378707) (xy 139.662792 -243.400524)
			(xy 139.704676 -243.429434) (xy 139.74138 -243.464689) (xy 139.771953 -243.505375) (xy 139.795604 -243.550438)
			(xy 139.81172 -243.598712) (xy 139.819884 -243.648946) (xy 139.820396 -243.674392) (xy 139.819893 -243.699381)
			(xy 140.12721 -243.699381) (xy 140.12721 -243.649403) (xy 140.135029 -243.60004) (xy 140.150473 -243.552508)
			(xy 140.173163 -243.507976) (xy 140.202539 -243.467543) (xy 140.237879 -243.432203) (xy 140.278312 -243.402827)
			(xy 140.322844 -243.380137) (xy 140.370376 -243.364693) (xy 140.419739 -243.356874) (xy 140.469717 -243.356874)
			(xy 140.51908 -243.364693) (xy 140.566612 -243.380137) (xy 140.611144 -243.402827) (xy 140.651577 -243.432203)
			(xy 140.686917 -243.467543) (xy 140.716293 -243.507976) (xy 140.738983 -243.552508) (xy 140.754427 -243.60004)
			(xy 140.762246 -243.649403) (xy 140.762736 -243.674392) (xy 141.068547 -243.674392) (xy 141.072642 -243.623664)
			(xy 141.084821 -243.57425) (xy 141.104769 -243.52743) (xy 141.13197 -243.484416) (xy 141.165718 -243.446322)
			(xy 141.20514 -243.414135) (xy 141.249214 -243.388689) (xy 141.2968 -243.370642) (xy 141.346664 -243.360462)
			(xy 141.397516 -243.358413) (xy 141.448037 -243.364547) (xy 141.496921 -243.378707) (xy 141.5429 -243.400524)
			(xy 141.584784 -243.429434) (xy 141.621488 -243.464689) (xy 141.652061 -243.505375) (xy 141.675712 -243.550438)
			(xy 141.691828 -243.598712) (xy 141.699992 -243.648946) (xy 141.700504 -243.674392) (xy 142.008601 -243.674392)
			(xy 142.012696 -243.623664) (xy 142.024875 -243.57425) (xy 142.044823 -243.52743) (xy 142.072024 -243.484416)
			(xy 142.105772 -243.446322) (xy 142.145194 -243.414135) (xy 142.189268 -243.388689) (xy 142.236854 -243.370642)
			(xy 142.286718 -243.360462) (xy 142.33757 -243.358413) (xy 142.388091 -243.364547) (xy 142.436975 -243.378707)
			(xy 142.482954 -243.400524) (xy 142.524838 -243.429434) (xy 142.561542 -243.464689) (xy 142.592115 -243.505375)
			(xy 142.615766 -243.550438) (xy 142.631882 -243.598712) (xy 142.640046 -243.648946) (xy 142.640558 -243.674392)
			(xy 142.640055 -243.699381) (xy 142.947118 -243.699381) (xy 142.947118 -243.649403) (xy 142.954937 -243.60004)
			(xy 142.970381 -243.552508) (xy 142.993071 -243.507976) (xy 143.022447 -243.467543) (xy 143.057787 -243.432203)
			(xy 143.09822 -243.402827) (xy 143.142752 -243.380137) (xy 143.190284 -243.364693) (xy 143.239647 -243.356874)
			(xy 143.289625 -243.356874) (xy 143.338988 -243.364693) (xy 143.38652 -243.380137) (xy 143.431052 -243.402827)
			(xy 143.471485 -243.432203) (xy 143.506825 -243.467543) (xy 143.536201 -243.507976) (xy 143.558891 -243.552508)
			(xy 143.574335 -243.60004) (xy 143.582154 -243.649403) (xy 143.582644 -243.674392) (xy 143.582154 -243.699381)
			(xy 143.574335 -243.748744) (xy 143.558891 -243.796276) (xy 143.536201 -243.840808) (xy 143.506825 -243.881241)
			(xy 143.471485 -243.916581) (xy 143.431052 -243.945957) (xy 143.38652 -243.968647) (xy 143.338988 -243.984091)
			(xy 143.289625 -243.99191) (xy 143.239647 -243.99191) (xy 143.190284 -243.984091) (xy 143.142752 -243.968647)
			(xy 143.09822 -243.945957) (xy 143.057787 -243.916581) (xy 143.022447 -243.881241) (xy 142.993071 -243.840808)
			(xy 142.970381 -243.796276) (xy 142.954937 -243.748744) (xy 142.947118 -243.699381) (xy 142.640055 -243.699381)
			(xy 142.640046 -243.699838) (xy 142.631882 -243.750072) (xy 142.615766 -243.798346) (xy 142.592115 -243.843409)
			(xy 142.561542 -243.884095) (xy 142.524838 -243.91935) (xy 142.482954 -243.94826) (xy 142.436975 -243.970077)
			(xy 142.388091 -243.984237) (xy 142.33757 -243.990371) (xy 142.286718 -243.988322) (xy 142.236854 -243.978142)
			(xy 142.189268 -243.960095) (xy 142.145194 -243.934649) (xy 142.105772 -243.902462) (xy 142.072024 -243.864368)
			(xy 142.044823 -243.821354) (xy 142.024875 -243.774534) (xy 142.012696 -243.72512) (xy 142.008601 -243.674392)
			(xy 141.700504 -243.674392) (xy 141.699992 -243.699838) (xy 141.691828 -243.750072) (xy 141.675712 -243.798346)
			(xy 141.652061 -243.843409) (xy 141.621488 -243.884095) (xy 141.584784 -243.91935) (xy 141.5429 -243.94826)
			(xy 141.496921 -243.970077) (xy 141.448037 -243.984237) (xy 141.397516 -243.990371) (xy 141.346664 -243.988322)
			(xy 141.2968 -243.978142) (xy 141.249214 -243.960095) (xy 141.20514 -243.934649) (xy 141.165718 -243.902462)
			(xy 141.13197 -243.864368) (xy 141.104769 -243.821354) (xy 141.084821 -243.774534) (xy 141.072642 -243.72512)
			(xy 141.068547 -243.674392) (xy 140.762736 -243.674392) (xy 140.762246 -243.699381) (xy 140.754427 -243.748744)
			(xy 140.738983 -243.796276) (xy 140.716293 -243.840808) (xy 140.686917 -243.881241) (xy 140.651577 -243.916581)
			(xy 140.611144 -243.945957) (xy 140.566612 -243.968647) (xy 140.51908 -243.984091) (xy 140.469717 -243.99191)
			(xy 140.419739 -243.99191) (xy 140.370376 -243.984091) (xy 140.322844 -243.968647) (xy 140.278312 -243.945957)
			(xy 140.237879 -243.916581) (xy 140.202539 -243.881241) (xy 140.173163 -243.840808) (xy 140.150473 -243.796276)
			(xy 140.135029 -243.748744) (xy 140.12721 -243.699381) (xy 139.819893 -243.699381) (xy 139.819884 -243.699838)
			(xy 139.81172 -243.750072) (xy 139.795604 -243.798346) (xy 139.771953 -243.843409) (xy 139.74138 -243.884095)
			(xy 139.704676 -243.91935) (xy 139.662792 -243.94826) (xy 139.616813 -243.970077) (xy 139.567929 -243.984237)
			(xy 139.517408 -243.990371) (xy 139.466556 -243.988322) (xy 139.416692 -243.978142) (xy 139.369106 -243.960095)
			(xy 139.325032 -243.934649) (xy 139.28561 -243.902462) (xy 139.251862 -243.864368) (xy 139.224661 -243.821354)
			(xy 139.204713 -243.774534) (xy 139.192534 -243.72512) (xy 139.188439 -243.674392) (xy 138.882882 -243.674392)
			(xy 138.882392 -243.699381) (xy 138.874573 -243.748744) (xy 138.859129 -243.796276) (xy 138.836439 -243.840808)
			(xy 138.807063 -243.881241) (xy 138.771723 -243.916581) (xy 138.73129 -243.945957) (xy 138.686758 -243.968647)
			(xy 138.639226 -243.984091) (xy 138.589863 -243.99191) (xy 138.539885 -243.99191) (xy 138.490522 -243.984091)
			(xy 138.44299 -243.968647) (xy 138.398458 -243.945957) (xy 138.358025 -243.916581) (xy 138.322685 -243.881241)
			(xy 138.293309 -243.840808) (xy 138.270619 -243.796276) (xy 138.255175 -243.748744) (xy 138.247356 -243.699381)
			(xy 137.940039 -243.699381) (xy 137.94003 -243.699838) (xy 137.931866 -243.750072) (xy 137.91575 -243.798346)
			(xy 137.892099 -243.843409) (xy 137.861526 -243.884095) (xy 137.824822 -243.91935) (xy 137.782938 -243.94826)
			(xy 137.736959 -243.970077) (xy 137.688075 -243.984237) (xy 137.637554 -243.990371) (xy 137.586702 -243.988322)
			(xy 137.536838 -243.978142) (xy 137.489252 -243.960095) (xy 137.445178 -243.934649) (xy 137.405756 -243.902462)
			(xy 137.372008 -243.864368) (xy 137.344807 -243.821354) (xy 137.324859 -243.774534) (xy 137.31268 -243.72512)
			(xy 137.308585 -243.674392) (xy 137.002774 -243.674392) (xy 137.002284 -243.699381) (xy 136.994465 -243.748744)
			(xy 136.979021 -243.796276) (xy 136.956331 -243.840808) (xy 136.926955 -243.881241) (xy 136.891615 -243.916581)
			(xy 136.851182 -243.945957) (xy 136.80665 -243.968647) (xy 136.759118 -243.984091) (xy 136.709755 -243.99191)
			(xy 136.659777 -243.99191) (xy 136.610414 -243.984091) (xy 136.562882 -243.968647) (xy 136.51835 -243.945957)
			(xy 136.477917 -243.916581) (xy 136.442577 -243.881241) (xy 136.413201 -243.840808) (xy 136.390511 -243.796276)
			(xy 136.375067 -243.748744) (xy 136.367248 -243.699381) (xy 136.059931 -243.699381) (xy 136.059922 -243.699838)
			(xy 136.051758 -243.750072) (xy 136.035642 -243.798346) (xy 136.011991 -243.843409) (xy 135.981418 -243.884095)
			(xy 135.944714 -243.91935) (xy 135.90283 -243.94826) (xy 135.856851 -243.970077) (xy 135.807967 -243.984237)
			(xy 135.757446 -243.990371) (xy 135.706594 -243.988322) (xy 135.65673 -243.978142) (xy 135.609144 -243.960095)
			(xy 135.56507 -243.934649) (xy 135.525648 -243.902462) (xy 135.4919 -243.864368) (xy 135.464699 -243.821354)
			(xy 135.444751 -243.774534) (xy 135.432572 -243.72512) (xy 135.428477 -243.674392) (xy 135.12038 -243.674392)
			(xy 135.119868 -243.699838) (xy 135.111704 -243.750072) (xy 135.095588 -243.798346) (xy 135.071937 -243.843409)
			(xy 135.041364 -243.884095) (xy 135.00466 -243.91935) (xy 134.962776 -243.94826) (xy 134.916797 -243.970077)
			(xy 134.867913 -243.984237) (xy 134.817392 -243.990371) (xy 134.76654 -243.988322) (xy 134.716676 -243.978142)
			(xy 134.66909 -243.960095) (xy 134.625016 -243.934649) (xy 134.585594 -243.902462) (xy 134.551846 -243.864368)
			(xy 134.524645 -243.821354) (xy 134.504697 -243.774534) (xy 134.492518 -243.72512) (xy 134.488423 -243.674392)
			(xy 134.182866 -243.674392) (xy 134.182376 -243.699381) (xy 134.174557 -243.748744) (xy 134.159113 -243.796276)
			(xy 134.136423 -243.840808) (xy 134.107047 -243.881241) (xy 134.071707 -243.916581) (xy 134.031274 -243.945957)
			(xy 133.986742 -243.968647) (xy 133.93921 -243.984091) (xy 133.889847 -243.99191) (xy 133.839869 -243.99191)
			(xy 133.790506 -243.984091) (xy 133.742974 -243.968647) (xy 133.698442 -243.945957) (xy 133.658009 -243.916581)
			(xy 133.622669 -243.881241) (xy 133.593293 -243.840808) (xy 133.570603 -243.796276) (xy 133.555159 -243.748744)
			(xy 133.54734 -243.699381) (xy 133.240023 -243.699381) (xy 133.240014 -243.699838) (xy 133.23185 -243.750072)
			(xy 133.215734 -243.798346) (xy 133.192083 -243.843409) (xy 133.16151 -243.884095) (xy 133.124806 -243.91935)
			(xy 133.082922 -243.94826) (xy 133.036943 -243.970077) (xy 132.988059 -243.984237) (xy 132.937538 -243.990371)
			(xy 132.886686 -243.988322) (xy 132.836822 -243.978142) (xy 132.789236 -243.960095) (xy 132.745162 -243.934649)
			(xy 132.70574 -243.902462) (xy 132.671992 -243.864368) (xy 132.644791 -243.821354) (xy 132.624843 -243.774534)
			(xy 132.612664 -243.72512) (xy 132.608569 -243.674392) (xy 132.302758 -243.674392) (xy 132.302268 -243.699381)
			(xy 132.294449 -243.748744) (xy 132.279005 -243.796276) (xy 132.256315 -243.840808) (xy 132.226939 -243.881241)
			(xy 132.191599 -243.916581) (xy 132.151166 -243.945957) (xy 132.106634 -243.968647) (xy 132.059102 -243.984091)
			(xy 132.009739 -243.99191) (xy 131.959761 -243.99191) (xy 131.910398 -243.984091) (xy 131.862866 -243.968647)
			(xy 131.818334 -243.945957) (xy 131.777901 -243.916581) (xy 131.742561 -243.881241) (xy 131.713185 -243.840808)
			(xy 131.690495 -243.796276) (xy 131.675051 -243.748744) (xy 131.667232 -243.699381) (xy 131.359915 -243.699381)
			(xy 131.359906 -243.699838) (xy 131.351742 -243.750072) (xy 131.335626 -243.798346) (xy 131.311975 -243.843409)
			(xy 131.281402 -243.884095) (xy 131.244698 -243.91935) (xy 131.202814 -243.94826) (xy 131.156835 -243.970077)
			(xy 131.107951 -243.984237) (xy 131.05743 -243.990371) (xy 131.006578 -243.988322) (xy 130.956714 -243.978142)
			(xy 130.909128 -243.960095) (xy 130.865054 -243.934649) (xy 130.825632 -243.902462) (xy 130.791884 -243.864368)
			(xy 130.764683 -243.821354) (xy 130.744735 -243.774534) (xy 130.732556 -243.72512) (xy 130.728461 -243.674392)
			(xy 130.42265 -243.674392) (xy 130.42216 -243.699381) (xy 130.414341 -243.748744) (xy 130.398897 -243.796276)
			(xy 130.376207 -243.840808) (xy 130.346831 -243.881241) (xy 130.311491 -243.916581) (xy 130.271058 -243.945957)
			(xy 130.226526 -243.968647) (xy 130.178994 -243.984091) (xy 130.129631 -243.99191) (xy 130.079653 -243.99191)
			(xy 130.03029 -243.984091) (xy 129.982758 -243.968647) (xy 129.938226 -243.945957) (xy 129.897793 -243.916581)
			(xy 129.862453 -243.881241) (xy 129.833077 -243.840808) (xy 129.810387 -243.796276) (xy 129.794943 -243.748744)
			(xy 129.787124 -243.699381) (xy 129.480061 -243.699381) (xy 129.480052 -243.699838) (xy 129.471888 -243.750072)
			(xy 129.455772 -243.798346) (xy 129.432121 -243.843409) (xy 129.401548 -243.884095) (xy 129.364844 -243.91935)
			(xy 129.32296 -243.94826) (xy 129.276981 -243.970077) (xy 129.228097 -243.984237) (xy 129.177576 -243.990371)
			(xy 129.126724 -243.988322) (xy 129.07686 -243.978142) (xy 129.029274 -243.960095) (xy 128.9852 -243.934649)
			(xy 128.945778 -243.902462) (xy 128.91203 -243.864368) (xy 128.884829 -243.821354) (xy 128.864881 -243.774534)
			(xy 128.852702 -243.72512) (xy 128.848607 -243.674392) (xy 128.54051 -243.674392) (xy 128.539998 -243.699838)
			(xy 128.531834 -243.750072) (xy 128.515718 -243.798346) (xy 128.492067 -243.843409) (xy 128.461494 -243.884095)
			(xy 128.42479 -243.91935) (xy 128.382906 -243.94826) (xy 128.336927 -243.970077) (xy 128.288043 -243.984237)
			(xy 128.237522 -243.990371) (xy 128.18667 -243.988322) (xy 128.136806 -243.978142) (xy 128.08922 -243.960095)
			(xy 128.045146 -243.934649) (xy 128.005724 -243.902462) (xy 127.971976 -243.864368) (xy 127.944775 -243.821354)
			(xy 127.924827 -243.774534) (xy 127.912648 -243.72512) (xy 127.908553 -243.674392) (xy 126.662688 -243.674392)
			(xy 126.662434 -243.688108) (xy 126.661372 -243.70691) (xy 126.655387 -243.744091) (xy 126.650496 -243.762276)
			(xy 126.648464 -243.769134) (xy 126.648464 -244.07114) (xy 126.648464 -244.073934) (xy 126.649365 -244.083358)
			(xy 126.657204 -244.100577) (xy 126.663704 -244.107462) (xy 126.665736 -244.10924) (xy 126.705614 -244.14353)
			(xy 126.706122 -244.144038) (xy 126.725172 -244.16004) (xy 126.731962 -244.164972) (xy 126.747778 -244.170547)
			(xy 126.75616 -244.170962) (xy 126.763526 -244.170454) (xy 126.765304 -244.1702) (xy 126.777607 -244.168403)
			(xy 126.802401 -244.166495) (xy 126.814834 -244.16639) (xy 126.839822 -244.166883) (xy 126.889181 -244.174705)
			(xy 126.936709 -244.190153) (xy 126.981235 -244.212844) (xy 127.021664 -244.242222) (xy 127.057 -244.277561)
			(xy 127.086373 -244.317994) (xy 127.10906 -244.362523) (xy 127.124502 -244.410052) (xy 127.13232 -244.459412)
			(xy 127.13232 -244.484398) (xy 127.438399 -244.484398) (xy 127.442494 -244.43367) (xy 127.454673 -244.384256)
			(xy 127.474621 -244.337436) (xy 127.501822 -244.294422) (xy 127.53557 -244.256328) (xy 127.574992 -244.224141)
			(xy 127.619066 -244.198695) (xy 127.666652 -244.180648) (xy 127.716516 -244.170468) (xy 127.767368 -244.168419)
			(xy 127.817889 -244.174553) (xy 127.866773 -244.188713) (xy 127.912752 -244.21053) (xy 127.954636 -244.23944)
			(xy 127.99134 -244.274695) (xy 128.021913 -244.315381) (xy 128.045564 -244.360444) (xy 128.06168 -244.408718)
			(xy 128.069844 -244.458952) (xy 128.070356 -244.484398) (xy 128.069853 -244.509387) (xy 128.37717 -244.509387)
			(xy 128.37717 -244.459409) (xy 128.384989 -244.410046) (xy 128.400433 -244.362514) (xy 128.423123 -244.317982)
			(xy 128.452499 -244.277549) (xy 128.487839 -244.242209) (xy 128.528272 -244.212833) (xy 128.572804 -244.190143)
			(xy 128.620336 -244.174699) (xy 128.669699 -244.16688) (xy 128.719677 -244.16688) (xy 128.76904 -244.174699)
			(xy 128.816572 -244.190143) (xy 128.861104 -244.212833) (xy 128.901537 -244.242209) (xy 128.936877 -244.277549)
			(xy 128.966253 -244.317982) (xy 128.988943 -244.362514) (xy 129.004387 -244.410046) (xy 129.012206 -244.459409)
			(xy 129.012696 -244.484398) (xy 129.318507 -244.484398) (xy 129.322602 -244.43367) (xy 129.334781 -244.384256)
			(xy 129.354729 -244.337436) (xy 129.38193 -244.294422) (xy 129.415678 -244.256328) (xy 129.4551 -244.224141)
			(xy 129.499174 -244.198695) (xy 129.54676 -244.180648) (xy 129.596624 -244.170468) (xy 129.647476 -244.168419)
			(xy 129.697997 -244.174553) (xy 129.746881 -244.188713) (xy 129.79286 -244.21053) (xy 129.834744 -244.23944)
			(xy 129.871448 -244.274695) (xy 129.902021 -244.315381) (xy 129.925672 -244.360444) (xy 129.941788 -244.408718)
			(xy 129.949952 -244.458952) (xy 129.950464 -244.484398) (xy 131.198615 -244.484398) (xy 131.20271 -244.43367)
			(xy 131.214889 -244.384256) (xy 131.234837 -244.337436) (xy 131.262038 -244.294422) (xy 131.295786 -244.256328)
			(xy 131.335208 -244.224141) (xy 131.379282 -244.198695) (xy 131.426868 -244.180648) (xy 131.476732 -244.170468)
			(xy 131.527584 -244.168419) (xy 131.578105 -244.174553) (xy 131.626989 -244.188713) (xy 131.672968 -244.21053)
			(xy 131.714852 -244.23944) (xy 131.751556 -244.274695) (xy 131.782129 -244.315381) (xy 131.80578 -244.360444)
			(xy 131.821896 -244.408718) (xy 131.83006 -244.458952) (xy 131.830572 -244.484398) (xy 132.138415 -244.484398)
			(xy 132.14251 -244.43367) (xy 132.154689 -244.384256) (xy 132.174637 -244.337436) (xy 132.201838 -244.294422)
			(xy 132.235586 -244.256328) (xy 132.275008 -244.224141) (xy 132.319082 -244.198695) (xy 132.366668 -244.180648)
			(xy 132.416532 -244.170468) (xy 132.467384 -244.168419) (xy 132.517905 -244.174553) (xy 132.566789 -244.188713)
			(xy 132.612768 -244.21053) (xy 132.654652 -244.23944) (xy 132.691356 -244.274695) (xy 132.721929 -244.315381)
			(xy 132.74558 -244.360444) (xy 132.761696 -244.408718) (xy 132.76986 -244.458952) (xy 132.770372 -244.484398)
			(xy 132.769869 -244.509387) (xy 133.077186 -244.509387) (xy 133.077186 -244.459409) (xy 133.085005 -244.410046)
			(xy 133.100449 -244.362514) (xy 133.123139 -244.317982) (xy 133.152515 -244.277549) (xy 133.187855 -244.242209)
			(xy 133.228288 -244.212833) (xy 133.27282 -244.190143) (xy 133.320352 -244.174699) (xy 133.369715 -244.16688)
			(xy 133.419693 -244.16688) (xy 133.469056 -244.174699) (xy 133.516588 -244.190143) (xy 133.56112 -244.212833)
			(xy 133.601553 -244.242209) (xy 133.636893 -244.277549) (xy 133.666269 -244.317982) (xy 133.688959 -244.362514)
			(xy 133.704403 -244.410046) (xy 133.712222 -244.459409) (xy 133.712712 -244.484398) (xy 134.018523 -244.484398)
			(xy 134.022618 -244.43367) (xy 134.034797 -244.384256) (xy 134.054745 -244.337436) (xy 134.081946 -244.294422)
			(xy 134.115694 -244.256328) (xy 134.155116 -244.224141) (xy 134.19919 -244.198695) (xy 134.246776 -244.180648)
			(xy 134.29664 -244.170468) (xy 134.347492 -244.168419) (xy 134.398013 -244.174553) (xy 134.446897 -244.188713)
			(xy 134.492876 -244.21053) (xy 134.53476 -244.23944) (xy 134.571464 -244.274695) (xy 134.602037 -244.315381)
			(xy 134.625688 -244.360444) (xy 134.641804 -244.408718) (xy 134.649968 -244.458952) (xy 134.65048 -244.484398)
			(xy 134.649977 -244.509387) (xy 134.957294 -244.509387) (xy 134.957294 -244.459409) (xy 134.965113 -244.410046)
			(xy 134.980557 -244.362514) (xy 135.003247 -244.317982) (xy 135.032623 -244.277549) (xy 135.067963 -244.242209)
			(xy 135.108396 -244.212833) (xy 135.152928 -244.190143) (xy 135.20046 -244.174699) (xy 135.249823 -244.16688)
			(xy 135.299801 -244.16688) (xy 135.349164 -244.174699) (xy 135.396696 -244.190143) (xy 135.441228 -244.212833)
			(xy 135.481661 -244.242209) (xy 135.517001 -244.277549) (xy 135.546377 -244.317982) (xy 135.569067 -244.362514)
			(xy 135.584511 -244.410046) (xy 135.59233 -244.459409) (xy 135.59282 -244.484398) (xy 135.898631 -244.484398)
			(xy 135.902726 -244.43367) (xy 135.914905 -244.384256) (xy 135.934853 -244.337436) (xy 135.962054 -244.294422)
			(xy 135.995802 -244.256328) (xy 136.035224 -244.224141) (xy 136.079298 -244.198695) (xy 136.126884 -244.180648)
			(xy 136.176748 -244.170468) (xy 136.2276 -244.168419) (xy 136.278121 -244.174553) (xy 136.327005 -244.188713)
			(xy 136.372984 -244.21053) (xy 136.414868 -244.23944) (xy 136.451572 -244.274695) (xy 136.482145 -244.315381)
			(xy 136.505796 -244.360444) (xy 136.521912 -244.408718) (xy 136.530076 -244.458952) (xy 136.530588 -244.484398)
			(xy 137.778485 -244.484398) (xy 137.78258 -244.43367) (xy 137.794759 -244.384256) (xy 137.814707 -244.337436)
			(xy 137.841908 -244.294422) (xy 137.875656 -244.256328) (xy 137.915078 -244.224141) (xy 137.959152 -244.198695)
			(xy 138.006738 -244.180648) (xy 138.056602 -244.170468) (xy 138.107454 -244.168419) (xy 138.157975 -244.174553)
			(xy 138.206859 -244.188713) (xy 138.252838 -244.21053) (xy 138.294722 -244.23944) (xy 138.331426 -244.274695)
			(xy 138.361999 -244.315381) (xy 138.38565 -244.360444) (xy 138.401766 -244.408718) (xy 138.40993 -244.458952)
			(xy 138.410442 -244.484398) (xy 138.718539 -244.484398) (xy 138.722634 -244.43367) (xy 138.734813 -244.384256)
			(xy 138.754761 -244.337436) (xy 138.781962 -244.294422) (xy 138.81571 -244.256328) (xy 138.855132 -244.224141)
			(xy 138.899206 -244.198695) (xy 138.946792 -244.180648) (xy 138.996656 -244.170468) (xy 139.047508 -244.168419)
			(xy 139.098029 -244.174553) (xy 139.146913 -244.188713) (xy 139.192892 -244.21053) (xy 139.234776 -244.23944)
			(xy 139.27148 -244.274695) (xy 139.302053 -244.315381) (xy 139.325704 -244.360444) (xy 139.34182 -244.408718)
			(xy 139.349984 -244.458952) (xy 139.350496 -244.484398) (xy 139.349993 -244.509387) (xy 139.65731 -244.509387)
			(xy 139.65731 -244.459409) (xy 139.665129 -244.410046) (xy 139.680573 -244.362514) (xy 139.703263 -244.317982)
			(xy 139.732639 -244.277549) (xy 139.767979 -244.242209) (xy 139.808412 -244.212833) (xy 139.852944 -244.190143)
			(xy 139.900476 -244.174699) (xy 139.949839 -244.16688) (xy 139.999817 -244.16688) (xy 140.04918 -244.174699)
			(xy 140.096712 -244.190143) (xy 140.141244 -244.212833) (xy 140.181677 -244.242209) (xy 140.217017 -244.277549)
			(xy 140.246393 -244.317982) (xy 140.269083 -244.362514) (xy 140.284527 -244.410046) (xy 140.292346 -244.459409)
			(xy 140.292836 -244.484398) (xy 140.598647 -244.484398) (xy 140.602742 -244.43367) (xy 140.614921 -244.384256)
			(xy 140.634869 -244.337436) (xy 140.66207 -244.294422) (xy 140.695818 -244.256328) (xy 140.73524 -244.224141)
			(xy 140.779314 -244.198695) (xy 140.8269 -244.180648) (xy 140.876764 -244.170468) (xy 140.927616 -244.168419)
			(xy 140.978137 -244.174553) (xy 141.027021 -244.188713) (xy 141.073 -244.21053) (xy 141.114884 -244.23944)
			(xy 141.151588 -244.274695) (xy 141.182161 -244.315381) (xy 141.205812 -244.360444) (xy 141.221928 -244.408718)
			(xy 141.230092 -244.458952) (xy 141.230604 -244.484398) (xy 141.230101 -244.509387) (xy 141.537164 -244.509387)
			(xy 141.537164 -244.459409) (xy 141.544983 -244.410046) (xy 141.560427 -244.362514) (xy 141.583117 -244.317982)
			(xy 141.612493 -244.277549) (xy 141.647833 -244.242209) (xy 141.688266 -244.212833) (xy 141.732798 -244.190143)
			(xy 141.78033 -244.174699) (xy 141.829693 -244.16688) (xy 141.879671 -244.16688) (xy 141.929034 -244.174699)
			(xy 141.976566 -244.190143) (xy 142.021098 -244.212833) (xy 142.061531 -244.242209) (xy 142.096871 -244.277549)
			(xy 142.126247 -244.317982) (xy 142.148937 -244.362514) (xy 142.164381 -244.410046) (xy 142.1722 -244.459409)
			(xy 142.17269 -244.484398) (xy 142.478501 -244.484398) (xy 142.482596 -244.43367) (xy 142.494775 -244.384256)
			(xy 142.514723 -244.337436) (xy 142.541924 -244.294422) (xy 142.575672 -244.256328) (xy 142.615094 -244.224141)
			(xy 142.659168 -244.198695) (xy 142.706754 -244.180648) (xy 142.756618 -244.170468) (xy 142.80747 -244.168419)
			(xy 142.857991 -244.174553) (xy 142.906875 -244.188713) (xy 142.952854 -244.21053) (xy 142.994738 -244.23944)
			(xy 143.031442 -244.274695) (xy 143.062015 -244.315381) (xy 143.085666 -244.360444) (xy 143.101782 -244.408718)
			(xy 143.109946 -244.458952) (xy 143.110458 -244.484398) (xy 143.109946 -244.509844) (xy 143.101782 -244.560078)
			(xy 143.085666 -244.608352) (xy 143.062015 -244.653415) (xy 143.031442 -244.694101) (xy 142.994738 -244.729356)
			(xy 142.952854 -244.758266) (xy 142.906875 -244.780083) (xy 142.857991 -244.794243) (xy 142.80747 -244.800377)
			(xy 142.756618 -244.798328) (xy 142.706754 -244.788148) (xy 142.659168 -244.770101) (xy 142.615094 -244.744655)
			(xy 142.575672 -244.712468) (xy 142.541924 -244.674374) (xy 142.514723 -244.63136) (xy 142.494775 -244.58454)
			(xy 142.482596 -244.535126) (xy 142.478501 -244.484398) (xy 142.17269 -244.484398) (xy 142.1722 -244.509387)
			(xy 142.164381 -244.55875) (xy 142.148937 -244.606282) (xy 142.126247 -244.650814) (xy 142.096871 -244.691247)
			(xy 142.061531 -244.726587) (xy 142.021098 -244.755963) (xy 141.976566 -244.778653) (xy 141.929034 -244.794097)
			(xy 141.879671 -244.801916) (xy 141.829693 -244.801916) (xy 141.78033 -244.794097) (xy 141.732798 -244.778653)
			(xy 141.688266 -244.755963) (xy 141.647833 -244.726587) (xy 141.612493 -244.691247) (xy 141.583117 -244.650814)
			(xy 141.560427 -244.606282) (xy 141.544983 -244.55875) (xy 141.537164 -244.509387) (xy 141.230101 -244.509387)
			(xy 141.230092 -244.509844) (xy 141.221928 -244.560078) (xy 141.205812 -244.608352) (xy 141.182161 -244.653415)
			(xy 141.151588 -244.694101) (xy 141.114884 -244.729356) (xy 141.073 -244.758266) (xy 141.027021 -244.780083)
			(xy 140.978137 -244.794243) (xy 140.927616 -244.800377) (xy 140.876764 -244.798328) (xy 140.8269 -244.788148)
			(xy 140.779314 -244.770101) (xy 140.73524 -244.744655) (xy 140.695818 -244.712468) (xy 140.66207 -244.674374)
			(xy 140.634869 -244.63136) (xy 140.614921 -244.58454) (xy 140.602742 -244.535126) (xy 140.598647 -244.484398)
			(xy 140.292836 -244.484398) (xy 140.292346 -244.509387) (xy 140.284527 -244.55875) (xy 140.269083 -244.606282)
			(xy 140.246393 -244.650814) (xy 140.217017 -244.691247) (xy 140.181677 -244.726587) (xy 140.141244 -244.755963)
			(xy 140.096712 -244.778653) (xy 140.04918 -244.794097) (xy 139.999817 -244.801916) (xy 139.949839 -244.801916)
			(xy 139.900476 -244.794097) (xy 139.852944 -244.778653) (xy 139.808412 -244.755963) (xy 139.767979 -244.726587)
			(xy 139.732639 -244.691247) (xy 139.703263 -244.650814) (xy 139.680573 -244.606282) (xy 139.665129 -244.55875)
			(xy 139.65731 -244.509387) (xy 139.349993 -244.509387) (xy 139.349984 -244.509844) (xy 139.34182 -244.560078)
			(xy 139.325704 -244.608352) (xy 139.302053 -244.653415) (xy 139.27148 -244.694101) (xy 139.234776 -244.729356)
			(xy 139.192892 -244.758266) (xy 139.146913 -244.780083) (xy 139.098029 -244.794243) (xy 139.047508 -244.800377)
			(xy 138.996656 -244.798328) (xy 138.946792 -244.788148) (xy 138.899206 -244.770101) (xy 138.855132 -244.744655)
			(xy 138.81571 -244.712468) (xy 138.781962 -244.674374) (xy 138.754761 -244.63136) (xy 138.734813 -244.58454)
			(xy 138.722634 -244.535126) (xy 138.718539 -244.484398) (xy 138.410442 -244.484398) (xy 138.40993 -244.509844)
			(xy 138.401766 -244.560078) (xy 138.38565 -244.608352) (xy 138.361999 -244.653415) (xy 138.331426 -244.694101)
			(xy 138.294722 -244.729356) (xy 138.252838 -244.758266) (xy 138.206859 -244.780083) (xy 138.157975 -244.794243)
			(xy 138.107454 -244.800377) (xy 138.056602 -244.798328) (xy 138.006738 -244.788148) (xy 137.959152 -244.770101)
			(xy 137.915078 -244.744655) (xy 137.875656 -244.712468) (xy 137.841908 -244.674374) (xy 137.814707 -244.63136)
			(xy 137.794759 -244.58454) (xy 137.78258 -244.535126) (xy 137.778485 -244.484398) (xy 136.530588 -244.484398)
			(xy 136.530076 -244.509844) (xy 136.521912 -244.560078) (xy 136.505796 -244.608352) (xy 136.482145 -244.653415)
			(xy 136.451572 -244.694101) (xy 136.414868 -244.729356) (xy 136.372984 -244.758266) (xy 136.327005 -244.780083)
			(xy 136.278121 -244.794243) (xy 136.2276 -244.800377) (xy 136.176748 -244.798328) (xy 136.126884 -244.788148)
			(xy 136.079298 -244.770101) (xy 136.035224 -244.744655) (xy 135.995802 -244.712468) (xy 135.962054 -244.674374)
			(xy 135.934853 -244.63136) (xy 135.914905 -244.58454) (xy 135.902726 -244.535126) (xy 135.898631 -244.484398)
			(xy 135.59282 -244.484398) (xy 135.59233 -244.509387) (xy 135.584511 -244.55875) (xy 135.569067 -244.606282)
			(xy 135.546377 -244.650814) (xy 135.517001 -244.691247) (xy 135.481661 -244.726587) (xy 135.441228 -244.755963)
			(xy 135.396696 -244.778653) (xy 135.349164 -244.794097) (xy 135.299801 -244.801916) (xy 135.249823 -244.801916)
			(xy 135.20046 -244.794097) (xy 135.152928 -244.778653) (xy 135.108396 -244.755963) (xy 135.067963 -244.726587)
			(xy 135.032623 -244.691247) (xy 135.003247 -244.650814) (xy 134.980557 -244.606282) (xy 134.965113 -244.55875)
			(xy 134.957294 -244.509387) (xy 134.649977 -244.509387) (xy 134.649968 -244.509844) (xy 134.641804 -244.560078)
			(xy 134.625688 -244.608352) (xy 134.602037 -244.653415) (xy 134.571464 -244.694101) (xy 134.53476 -244.729356)
			(xy 134.492876 -244.758266) (xy 134.446897 -244.780083) (xy 134.398013 -244.794243) (xy 134.347492 -244.800377)
			(xy 134.29664 -244.798328) (xy 134.246776 -244.788148) (xy 134.19919 -244.770101) (xy 134.155116 -244.744655)
			(xy 134.115694 -244.712468) (xy 134.081946 -244.674374) (xy 134.054745 -244.63136) (xy 134.034797 -244.58454)
			(xy 134.022618 -244.535126) (xy 134.018523 -244.484398) (xy 133.712712 -244.484398) (xy 133.712222 -244.509387)
			(xy 133.704403 -244.55875) (xy 133.688959 -244.606282) (xy 133.666269 -244.650814) (xy 133.636893 -244.691247)
			(xy 133.601553 -244.726587) (xy 133.56112 -244.755963) (xy 133.516588 -244.778653) (xy 133.469056 -244.794097)
			(xy 133.419693 -244.801916) (xy 133.369715 -244.801916) (xy 133.320352 -244.794097) (xy 133.27282 -244.778653)
			(xy 133.228288 -244.755963) (xy 133.187855 -244.726587) (xy 133.152515 -244.691247) (xy 133.123139 -244.650814)
			(xy 133.100449 -244.606282) (xy 133.085005 -244.55875) (xy 133.077186 -244.509387) (xy 132.769869 -244.509387)
			(xy 132.76986 -244.509844) (xy 132.761696 -244.560078) (xy 132.74558 -244.608352) (xy 132.721929 -244.653415)
			(xy 132.691356 -244.694101) (xy 132.654652 -244.729356) (xy 132.612768 -244.758266) (xy 132.566789 -244.780083)
			(xy 132.517905 -244.794243) (xy 132.467384 -244.800377) (xy 132.416532 -244.798328) (xy 132.366668 -244.788148)
			(xy 132.319082 -244.770101) (xy 132.275008 -244.744655) (xy 132.235586 -244.712468) (xy 132.201838 -244.674374)
			(xy 132.174637 -244.63136) (xy 132.154689 -244.58454) (xy 132.14251 -244.535126) (xy 132.138415 -244.484398)
			(xy 131.830572 -244.484398) (xy 131.83006 -244.509844) (xy 131.821896 -244.560078) (xy 131.80578 -244.608352)
			(xy 131.782129 -244.653415) (xy 131.751556 -244.694101) (xy 131.714852 -244.729356) (xy 131.672968 -244.758266)
			(xy 131.626989 -244.780083) (xy 131.578105 -244.794243) (xy 131.527584 -244.800377) (xy 131.476732 -244.798328)
			(xy 131.426868 -244.788148) (xy 131.379282 -244.770101) (xy 131.335208 -244.744655) (xy 131.295786 -244.712468)
			(xy 131.262038 -244.674374) (xy 131.234837 -244.63136) (xy 131.214889 -244.58454) (xy 131.20271 -244.535126)
			(xy 131.198615 -244.484398) (xy 129.950464 -244.484398) (xy 129.949952 -244.509844) (xy 129.941788 -244.560078)
			(xy 129.925672 -244.608352) (xy 129.902021 -244.653415) (xy 129.871448 -244.694101) (xy 129.834744 -244.729356)
			(xy 129.79286 -244.758266) (xy 129.746881 -244.780083) (xy 129.697997 -244.794243) (xy 129.647476 -244.800377)
			(xy 129.596624 -244.798328) (xy 129.54676 -244.788148) (xy 129.499174 -244.770101) (xy 129.4551 -244.744655)
			(xy 129.415678 -244.712468) (xy 129.38193 -244.674374) (xy 129.354729 -244.63136) (xy 129.334781 -244.58454)
			(xy 129.322602 -244.535126) (xy 129.318507 -244.484398) (xy 129.012696 -244.484398) (xy 129.012206 -244.509387)
			(xy 129.004387 -244.55875) (xy 128.988943 -244.606282) (xy 128.966253 -244.650814) (xy 128.936877 -244.691247)
			(xy 128.901537 -244.726587) (xy 128.861104 -244.755963) (xy 128.816572 -244.778653) (xy 128.76904 -244.794097)
			(xy 128.719677 -244.801916) (xy 128.669699 -244.801916) (xy 128.620336 -244.794097) (xy 128.572804 -244.778653)
			(xy 128.528272 -244.755963) (xy 128.487839 -244.726587) (xy 128.452499 -244.691247) (xy 128.423123 -244.650814)
			(xy 128.400433 -244.606282) (xy 128.384989 -244.55875) (xy 128.37717 -244.509387) (xy 128.069853 -244.509387)
			(xy 128.069844 -244.509844) (xy 128.06168 -244.560078) (xy 128.045564 -244.608352) (xy 128.021913 -244.653415)
			(xy 127.99134 -244.694101) (xy 127.954636 -244.729356) (xy 127.912752 -244.758266) (xy 127.866773 -244.780083)
			(xy 127.817889 -244.794243) (xy 127.767368 -244.800377) (xy 127.716516 -244.798328) (xy 127.666652 -244.788148)
			(xy 127.619066 -244.770101) (xy 127.574992 -244.744655) (xy 127.53557 -244.712468) (xy 127.501822 -244.674374)
			(xy 127.474621 -244.63136) (xy 127.454673 -244.58454) (xy 127.442494 -244.535126) (xy 127.438399 -244.484398)
			(xy 127.13232 -244.484398) (xy 127.13232 -244.509388) (xy 127.124502 -244.558748) (xy 127.10906 -244.606277)
			(xy 127.086373 -244.650806) (xy 127.057 -244.691239) (xy 127.021664 -244.726578) (xy 126.981235 -244.755956)
			(xy 126.936709 -244.778647) (xy 126.889181 -244.794095) (xy 126.839822 -244.801917) (xy 126.814834 -244.802406)
			(xy 126.802206 -244.802258) (xy 126.777031 -244.80022) (xy 126.764542 -244.798342) (xy 126.75362 -244.796564)
			(xy 126.74346 -244.799358) (xy 126.738264 -244.800986) (xy 126.728658 -244.806111) (xy 126.72441 -244.809518)
			(xy 126.663958 -244.860826) (xy 126.657457 -244.867729) (xy 126.649522 -244.88493) (xy 126.648464 -244.894354)
			(xy 126.648464 -245.18874) (xy 126.648972 -245.195852) (xy 126.650496 -245.206774) (xy 126.656207 -245.22823)
			(xy 126.66233 -245.272204) (xy 126.662688 -245.294404) (xy 126.662373 -245.31667) (xy 126.661996 -245.319393)
			(xy 126.967216 -245.319393) (xy 126.967216 -245.269415) (xy 126.975035 -245.220052) (xy 126.990479 -245.17252)
			(xy 127.013169 -245.127988) (xy 127.042545 -245.087555) (xy 127.077885 -245.052215) (xy 127.118318 -245.022839)
			(xy 127.16285 -245.000149) (xy 127.210382 -244.984705) (xy 127.259745 -244.976886) (xy 127.309723 -244.976886)
			(xy 127.359086 -244.984705) (xy 127.406618 -245.000149) (xy 127.45115 -245.022839) (xy 127.491583 -245.052215)
			(xy 127.526923 -245.087555) (xy 127.556299 -245.127988) (xy 127.578989 -245.17252) (xy 127.594433 -245.220052)
			(xy 127.602252 -245.269415) (xy 127.602742 -245.294404) (xy 127.908553 -245.294404) (xy 127.912648 -245.243676)
			(xy 127.924827 -245.194262) (xy 127.944775 -245.147442) (xy 127.971976 -245.104428) (xy 128.005724 -245.066334)
			(xy 128.045146 -245.034147) (xy 128.08922 -245.008701) (xy 128.136806 -244.990654) (xy 128.18667 -244.980474)
			(xy 128.237522 -244.978425) (xy 128.288043 -244.984559) (xy 128.336927 -244.998719) (xy 128.382906 -245.020536)
			(xy 128.42479 -245.049446) (xy 128.461494 -245.084701) (xy 128.492067 -245.125387) (xy 128.515718 -245.17045)
			(xy 128.531834 -245.218724) (xy 128.539998 -245.268958) (xy 128.54051 -245.294404) (xy 128.848607 -245.294404)
			(xy 128.852702 -245.243676) (xy 128.864881 -245.194262) (xy 128.884829 -245.147442) (xy 128.91203 -245.104428)
			(xy 128.945778 -245.066334) (xy 128.9852 -245.034147) (xy 129.029274 -245.008701) (xy 129.07686 -244.990654)
			(xy 129.126724 -244.980474) (xy 129.177576 -244.978425) (xy 129.228097 -244.984559) (xy 129.276981 -244.998719)
			(xy 129.32296 -245.020536) (xy 129.364844 -245.049446) (xy 129.401548 -245.084701) (xy 129.432121 -245.125387)
			(xy 129.455772 -245.17045) (xy 129.471888 -245.218724) (xy 129.480052 -245.268958) (xy 129.480564 -245.294404)
			(xy 129.480061 -245.319393) (xy 129.787124 -245.319393) (xy 129.787124 -245.269415) (xy 129.794943 -245.220052)
			(xy 129.810387 -245.17252) (xy 129.833077 -245.127988) (xy 129.862453 -245.087555) (xy 129.897793 -245.052215)
			(xy 129.938226 -245.022839) (xy 129.982758 -245.000149) (xy 130.03029 -244.984705) (xy 130.079653 -244.976886)
			(xy 130.129631 -244.976886) (xy 130.178994 -244.984705) (xy 130.226526 -245.000149) (xy 130.271058 -245.022839)
			(xy 130.311491 -245.052215) (xy 130.346831 -245.087555) (xy 130.376207 -245.127988) (xy 130.398897 -245.17252)
			(xy 130.414341 -245.220052) (xy 130.42216 -245.269415) (xy 130.42265 -245.294404) (xy 130.728461 -245.294404)
			(xy 130.732556 -245.243676) (xy 130.744735 -245.194262) (xy 130.764683 -245.147442) (xy 130.791884 -245.104428)
			(xy 130.825632 -245.066334) (xy 130.865054 -245.034147) (xy 130.909128 -245.008701) (xy 130.956714 -244.990654)
			(xy 131.006578 -244.980474) (xy 131.05743 -244.978425) (xy 131.107951 -244.984559) (xy 131.156835 -244.998719)
			(xy 131.202814 -245.020536) (xy 131.244698 -245.049446) (xy 131.281402 -245.084701) (xy 131.311975 -245.125387)
			(xy 131.335626 -245.17045) (xy 131.351742 -245.218724) (xy 131.359906 -245.268958) (xy 131.360418 -245.294404)
			(xy 131.359915 -245.319393) (xy 131.667232 -245.319393) (xy 131.667232 -245.269415) (xy 131.675051 -245.220052)
			(xy 131.690495 -245.17252) (xy 131.713185 -245.127988) (xy 131.742561 -245.087555) (xy 131.777901 -245.052215)
			(xy 131.818334 -245.022839) (xy 131.862866 -245.000149) (xy 131.910398 -244.984705) (xy 131.959761 -244.976886)
			(xy 132.009739 -244.976886) (xy 132.059102 -244.984705) (xy 132.106634 -245.000149) (xy 132.151166 -245.022839)
			(xy 132.191599 -245.052215) (xy 132.226939 -245.087555) (xy 132.256315 -245.127988) (xy 132.279005 -245.17252)
			(xy 132.294449 -245.220052) (xy 132.302268 -245.269415) (xy 132.302758 -245.294404) (xy 132.608569 -245.294404)
			(xy 132.612664 -245.243676) (xy 132.624843 -245.194262) (xy 132.644791 -245.147442) (xy 132.671992 -245.104428)
			(xy 132.70574 -245.066334) (xy 132.745162 -245.034147) (xy 132.789236 -245.008701) (xy 132.836822 -244.990654)
			(xy 132.886686 -244.980474) (xy 132.937538 -244.978425) (xy 132.988059 -244.984559) (xy 133.036943 -244.998719)
			(xy 133.082922 -245.020536) (xy 133.124806 -245.049446) (xy 133.16151 -245.084701) (xy 133.192083 -245.125387)
			(xy 133.215734 -245.17045) (xy 133.23185 -245.218724) (xy 133.240014 -245.268958) (xy 133.240526 -245.294404)
			(xy 133.240023 -245.319393) (xy 133.54734 -245.319393) (xy 133.54734 -245.269415) (xy 133.555159 -245.220052)
			(xy 133.570603 -245.17252) (xy 133.593293 -245.127988) (xy 133.622669 -245.087555) (xy 133.658009 -245.052215)
			(xy 133.698442 -245.022839) (xy 133.742974 -245.000149) (xy 133.790506 -244.984705) (xy 133.839869 -244.976886)
			(xy 133.889847 -244.976886) (xy 133.93921 -244.984705) (xy 133.986742 -245.000149) (xy 134.031274 -245.022839)
			(xy 134.071707 -245.052215) (xy 134.107047 -245.087555) (xy 134.136423 -245.127988) (xy 134.159113 -245.17252)
			(xy 134.174557 -245.220052) (xy 134.182376 -245.269415) (xy 134.182866 -245.294404) (xy 134.488423 -245.294404)
			(xy 134.492518 -245.243676) (xy 134.504697 -245.194262) (xy 134.524645 -245.147442) (xy 134.551846 -245.104428)
			(xy 134.585594 -245.066334) (xy 134.625016 -245.034147) (xy 134.66909 -245.008701) (xy 134.716676 -244.990654)
			(xy 134.76654 -244.980474) (xy 134.817392 -244.978425) (xy 134.867913 -244.984559) (xy 134.916797 -244.998719)
			(xy 134.962776 -245.020536) (xy 135.00466 -245.049446) (xy 135.041364 -245.084701) (xy 135.071937 -245.125387)
			(xy 135.095588 -245.17045) (xy 135.111704 -245.218724) (xy 135.119868 -245.268958) (xy 135.12038 -245.294404)
			(xy 135.428477 -245.294404) (xy 135.432572 -245.243676) (xy 135.444751 -245.194262) (xy 135.464699 -245.147442)
			(xy 135.4919 -245.104428) (xy 135.525648 -245.066334) (xy 135.56507 -245.034147) (xy 135.609144 -245.008701)
			(xy 135.65673 -244.990654) (xy 135.706594 -244.980474) (xy 135.757446 -244.978425) (xy 135.807967 -244.984559)
			(xy 135.856851 -244.998719) (xy 135.90283 -245.020536) (xy 135.944714 -245.049446) (xy 135.981418 -245.084701)
			(xy 136.011991 -245.125387) (xy 136.035642 -245.17045) (xy 136.051758 -245.218724) (xy 136.059922 -245.268958)
			(xy 136.060434 -245.294404) (xy 136.059931 -245.319393) (xy 136.367248 -245.319393) (xy 136.367248 -245.269415)
			(xy 136.375067 -245.220052) (xy 136.390511 -245.17252) (xy 136.413201 -245.127988) (xy 136.442577 -245.087555)
			(xy 136.477917 -245.052215) (xy 136.51835 -245.022839) (xy 136.562882 -245.000149) (xy 136.610414 -244.984705)
			(xy 136.659777 -244.976886) (xy 136.709755 -244.976886) (xy 136.759118 -244.984705) (xy 136.80665 -245.000149)
			(xy 136.851182 -245.022839) (xy 136.891615 -245.052215) (xy 136.926955 -245.087555) (xy 136.956331 -245.127988)
			(xy 136.979021 -245.17252) (xy 136.994465 -245.220052) (xy 137.002284 -245.269415) (xy 137.002774 -245.294404)
			(xy 137.308585 -245.294404) (xy 137.31268 -245.243676) (xy 137.324859 -245.194262) (xy 137.344807 -245.147442)
			(xy 137.372008 -245.104428) (xy 137.405756 -245.066334) (xy 137.445178 -245.034147) (xy 137.489252 -245.008701)
			(xy 137.536838 -244.990654) (xy 137.586702 -244.980474) (xy 137.637554 -244.978425) (xy 137.688075 -244.984559)
			(xy 137.736959 -244.998719) (xy 137.782938 -245.020536) (xy 137.824822 -245.049446) (xy 137.861526 -245.084701)
			(xy 137.892099 -245.125387) (xy 137.91575 -245.17045) (xy 137.931866 -245.218724) (xy 137.94003 -245.268958)
			(xy 137.940542 -245.294404) (xy 137.940039 -245.319393) (xy 138.247356 -245.319393) (xy 138.247356 -245.269415)
			(xy 138.255175 -245.220052) (xy 138.270619 -245.17252) (xy 138.293309 -245.127988) (xy 138.322685 -245.087555)
			(xy 138.358025 -245.052215) (xy 138.398458 -245.022839) (xy 138.44299 -245.000149) (xy 138.490522 -244.984705)
			(xy 138.539885 -244.976886) (xy 138.589863 -244.976886) (xy 138.639226 -244.984705) (xy 138.686758 -245.000149)
			(xy 138.73129 -245.022839) (xy 138.771723 -245.052215) (xy 138.807063 -245.087555) (xy 138.836439 -245.127988)
			(xy 138.859129 -245.17252) (xy 138.874573 -245.220052) (xy 138.882392 -245.269415) (xy 138.882882 -245.294404)
			(xy 139.188439 -245.294404) (xy 139.192534 -245.243676) (xy 139.204713 -245.194262) (xy 139.224661 -245.147442)
			(xy 139.251862 -245.104428) (xy 139.28561 -245.066334) (xy 139.325032 -245.034147) (xy 139.369106 -245.008701)
			(xy 139.416692 -244.990654) (xy 139.466556 -244.980474) (xy 139.517408 -244.978425) (xy 139.567929 -244.984559)
			(xy 139.616813 -244.998719) (xy 139.662792 -245.020536) (xy 139.704676 -245.049446) (xy 139.74138 -245.084701)
			(xy 139.771953 -245.125387) (xy 139.795604 -245.17045) (xy 139.81172 -245.218724) (xy 139.819884 -245.268958)
			(xy 139.820396 -245.294404) (xy 139.819893 -245.319393) (xy 140.12721 -245.319393) (xy 140.12721 -245.269415)
			(xy 140.135029 -245.220052) (xy 140.150473 -245.17252) (xy 140.173163 -245.127988) (xy 140.202539 -245.087555)
			(xy 140.237879 -245.052215) (xy 140.278312 -245.022839) (xy 140.322844 -245.000149) (xy 140.370376 -244.984705)
			(xy 140.419739 -244.976886) (xy 140.469717 -244.976886) (xy 140.51908 -244.984705) (xy 140.566612 -245.000149)
			(xy 140.611144 -245.022839) (xy 140.651577 -245.052215) (xy 140.686917 -245.087555) (xy 140.716293 -245.127988)
			(xy 140.738983 -245.17252) (xy 140.754427 -245.220052) (xy 140.762246 -245.269415) (xy 140.762736 -245.294404)
			(xy 141.068547 -245.294404) (xy 141.072642 -245.243676) (xy 141.084821 -245.194262) (xy 141.104769 -245.147442)
			(xy 141.13197 -245.104428) (xy 141.165718 -245.066334) (xy 141.20514 -245.034147) (xy 141.249214 -245.008701)
			(xy 141.2968 -244.990654) (xy 141.346664 -244.980474) (xy 141.397516 -244.978425) (xy 141.448037 -244.984559)
			(xy 141.496921 -244.998719) (xy 141.5429 -245.020536) (xy 141.584784 -245.049446) (xy 141.621488 -245.084701)
			(xy 141.652061 -245.125387) (xy 141.675712 -245.17045) (xy 141.691828 -245.218724) (xy 141.699992 -245.268958)
			(xy 141.700504 -245.294404) (xy 142.008601 -245.294404) (xy 142.012696 -245.243676) (xy 142.024875 -245.194262)
			(xy 142.044823 -245.147442) (xy 142.072024 -245.104428) (xy 142.105772 -245.066334) (xy 142.145194 -245.034147)
			(xy 142.189268 -245.008701) (xy 142.236854 -244.990654) (xy 142.286718 -244.980474) (xy 142.33757 -244.978425)
			(xy 142.388091 -244.984559) (xy 142.436975 -244.998719) (xy 142.482954 -245.020536) (xy 142.524838 -245.049446)
			(xy 142.561542 -245.084701) (xy 142.592115 -245.125387) (xy 142.615766 -245.17045) (xy 142.631882 -245.218724)
			(xy 142.640046 -245.268958) (xy 142.640558 -245.294404) (xy 142.640055 -245.319393) (xy 142.947118 -245.319393)
			(xy 142.947118 -245.269415) (xy 142.954937 -245.220052) (xy 142.970381 -245.17252) (xy 142.993071 -245.127988)
			(xy 143.022447 -245.087555) (xy 143.057787 -245.052215) (xy 143.09822 -245.022839) (xy 143.142752 -245.000149)
			(xy 143.190284 -244.984705) (xy 143.239647 -244.976886) (xy 143.289625 -244.976886) (xy 143.338988 -244.984705)
			(xy 143.38652 -245.000149) (xy 143.431052 -245.022839) (xy 143.471485 -245.052215) (xy 143.506825 -245.087555)
			(xy 143.536201 -245.127988) (xy 143.558891 -245.17252) (xy 143.574335 -245.220052) (xy 143.582154 -245.269415)
			(xy 143.582644 -245.294404) (xy 143.582154 -245.319393) (xy 143.574335 -245.368756) (xy 143.558891 -245.416288)
			(xy 143.536201 -245.46082) (xy 143.506825 -245.501253) (xy 143.471485 -245.536593) (xy 143.431052 -245.565969)
			(xy 143.38652 -245.588659) (xy 143.338988 -245.604103) (xy 143.289625 -245.611922) (xy 143.239647 -245.611922)
			(xy 143.190284 -245.604103) (xy 143.142752 -245.588659) (xy 143.09822 -245.565969) (xy 143.057787 -245.536593)
			(xy 143.022447 -245.501253) (xy 142.993071 -245.46082) (xy 142.970381 -245.416288) (xy 142.954937 -245.368756)
			(xy 142.947118 -245.319393) (xy 142.640055 -245.319393) (xy 142.640046 -245.31985) (xy 142.631882 -245.370084)
			(xy 142.615766 -245.418358) (xy 142.592115 -245.463421) (xy 142.561542 -245.504107) (xy 142.524838 -245.539362)
			(xy 142.482954 -245.568272) (xy 142.436975 -245.590089) (xy 142.388091 -245.604249) (xy 142.33757 -245.610383)
			(xy 142.286718 -245.608334) (xy 142.236854 -245.598154) (xy 142.189268 -245.580107) (xy 142.145194 -245.554661)
			(xy 142.105772 -245.522474) (xy 142.072024 -245.48438) (xy 142.044823 -245.441366) (xy 142.024875 -245.394546)
			(xy 142.012696 -245.345132) (xy 142.008601 -245.294404) (xy 141.700504 -245.294404) (xy 141.699992 -245.31985)
			(xy 141.691828 -245.370084) (xy 141.675712 -245.418358) (xy 141.652061 -245.463421) (xy 141.621488 -245.504107)
			(xy 141.584784 -245.539362) (xy 141.5429 -245.568272) (xy 141.496921 -245.590089) (xy 141.448037 -245.604249)
			(xy 141.397516 -245.610383) (xy 141.346664 -245.608334) (xy 141.2968 -245.598154) (xy 141.249214 -245.580107)
			(xy 141.20514 -245.554661) (xy 141.165718 -245.522474) (xy 141.13197 -245.48438) (xy 141.104769 -245.441366)
			(xy 141.084821 -245.394546) (xy 141.072642 -245.345132) (xy 141.068547 -245.294404) (xy 140.762736 -245.294404)
			(xy 140.762246 -245.319393) (xy 140.754427 -245.368756) (xy 140.738983 -245.416288) (xy 140.716293 -245.46082)
			(xy 140.686917 -245.501253) (xy 140.651577 -245.536593) (xy 140.611144 -245.565969) (xy 140.566612 -245.588659)
			(xy 140.51908 -245.604103) (xy 140.469717 -245.611922) (xy 140.419739 -245.611922) (xy 140.370376 -245.604103)
			(xy 140.322844 -245.588659) (xy 140.278312 -245.565969) (xy 140.237879 -245.536593) (xy 140.202539 -245.501253)
			(xy 140.173163 -245.46082) (xy 140.150473 -245.416288) (xy 140.135029 -245.368756) (xy 140.12721 -245.319393)
			(xy 139.819893 -245.319393) (xy 139.819884 -245.31985) (xy 139.81172 -245.370084) (xy 139.795604 -245.418358)
			(xy 139.771953 -245.463421) (xy 139.74138 -245.504107) (xy 139.704676 -245.539362) (xy 139.662792 -245.568272)
			(xy 139.616813 -245.590089) (xy 139.567929 -245.604249) (xy 139.517408 -245.610383) (xy 139.466556 -245.608334)
			(xy 139.416692 -245.598154) (xy 139.369106 -245.580107) (xy 139.325032 -245.554661) (xy 139.28561 -245.522474)
			(xy 139.251862 -245.48438) (xy 139.224661 -245.441366) (xy 139.204713 -245.394546) (xy 139.192534 -245.345132)
			(xy 139.188439 -245.294404) (xy 138.882882 -245.294404) (xy 138.882392 -245.319393) (xy 138.874573 -245.368756)
			(xy 138.859129 -245.416288) (xy 138.836439 -245.46082) (xy 138.807063 -245.501253) (xy 138.771723 -245.536593)
			(xy 138.73129 -245.565969) (xy 138.686758 -245.588659) (xy 138.639226 -245.604103) (xy 138.589863 -245.611922)
			(xy 138.539885 -245.611922) (xy 138.490522 -245.604103) (xy 138.44299 -245.588659) (xy 138.398458 -245.565969)
			(xy 138.358025 -245.536593) (xy 138.322685 -245.501253) (xy 138.293309 -245.46082) (xy 138.270619 -245.416288)
			(xy 138.255175 -245.368756) (xy 138.247356 -245.319393) (xy 137.940039 -245.319393) (xy 137.94003 -245.31985)
			(xy 137.931866 -245.370084) (xy 137.91575 -245.418358) (xy 137.892099 -245.463421) (xy 137.861526 -245.504107)
			(xy 137.824822 -245.539362) (xy 137.782938 -245.568272) (xy 137.736959 -245.590089) (xy 137.688075 -245.604249)
			(xy 137.637554 -245.610383) (xy 137.586702 -245.608334) (xy 137.536838 -245.598154) (xy 137.489252 -245.580107)
			(xy 137.445178 -245.554661) (xy 137.405756 -245.522474) (xy 137.372008 -245.48438) (xy 137.344807 -245.441366)
			(xy 137.324859 -245.394546) (xy 137.31268 -245.345132) (xy 137.308585 -245.294404) (xy 137.002774 -245.294404)
			(xy 137.002284 -245.319393) (xy 136.994465 -245.368756) (xy 136.979021 -245.416288) (xy 136.956331 -245.46082)
			(xy 136.926955 -245.501253) (xy 136.891615 -245.536593) (xy 136.851182 -245.565969) (xy 136.80665 -245.588659)
			(xy 136.759118 -245.604103) (xy 136.709755 -245.611922) (xy 136.659777 -245.611922) (xy 136.610414 -245.604103)
			(xy 136.562882 -245.588659) (xy 136.51835 -245.565969) (xy 136.477917 -245.536593) (xy 136.442577 -245.501253)
			(xy 136.413201 -245.46082) (xy 136.390511 -245.416288) (xy 136.375067 -245.368756) (xy 136.367248 -245.319393)
			(xy 136.059931 -245.319393) (xy 136.059922 -245.31985) (xy 136.051758 -245.370084) (xy 136.035642 -245.418358)
			(xy 136.011991 -245.463421) (xy 135.981418 -245.504107) (xy 135.944714 -245.539362) (xy 135.90283 -245.568272)
			(xy 135.856851 -245.590089) (xy 135.807967 -245.604249) (xy 135.757446 -245.610383) (xy 135.706594 -245.608334)
			(xy 135.65673 -245.598154) (xy 135.609144 -245.580107) (xy 135.56507 -245.554661) (xy 135.525648 -245.522474)
			(xy 135.4919 -245.48438) (xy 135.464699 -245.441366) (xy 135.444751 -245.394546) (xy 135.432572 -245.345132)
			(xy 135.428477 -245.294404) (xy 135.12038 -245.294404) (xy 135.119868 -245.31985) (xy 135.111704 -245.370084)
			(xy 135.095588 -245.418358) (xy 135.071937 -245.463421) (xy 135.041364 -245.504107) (xy 135.00466 -245.539362)
			(xy 134.962776 -245.568272) (xy 134.916797 -245.590089) (xy 134.867913 -245.604249) (xy 134.817392 -245.610383)
			(xy 134.76654 -245.608334) (xy 134.716676 -245.598154) (xy 134.66909 -245.580107) (xy 134.625016 -245.554661)
			(xy 134.585594 -245.522474) (xy 134.551846 -245.48438) (xy 134.524645 -245.441366) (xy 134.504697 -245.394546)
			(xy 134.492518 -245.345132) (xy 134.488423 -245.294404) (xy 134.182866 -245.294404) (xy 134.182376 -245.319393)
			(xy 134.174557 -245.368756) (xy 134.159113 -245.416288) (xy 134.136423 -245.46082) (xy 134.107047 -245.501253)
			(xy 134.071707 -245.536593) (xy 134.031274 -245.565969) (xy 133.986742 -245.588659) (xy 133.93921 -245.604103)
			(xy 133.889847 -245.611922) (xy 133.839869 -245.611922) (xy 133.790506 -245.604103) (xy 133.742974 -245.588659)
			(xy 133.698442 -245.565969) (xy 133.658009 -245.536593) (xy 133.622669 -245.501253) (xy 133.593293 -245.46082)
			(xy 133.570603 -245.416288) (xy 133.555159 -245.368756) (xy 133.54734 -245.319393) (xy 133.240023 -245.319393)
			(xy 133.240014 -245.31985) (xy 133.23185 -245.370084) (xy 133.215734 -245.418358) (xy 133.192083 -245.463421)
			(xy 133.16151 -245.504107) (xy 133.124806 -245.539362) (xy 133.082922 -245.568272) (xy 133.036943 -245.590089)
			(xy 132.988059 -245.604249) (xy 132.937538 -245.610383) (xy 132.886686 -245.608334) (xy 132.836822 -245.598154)
			(xy 132.789236 -245.580107) (xy 132.745162 -245.554661) (xy 132.70574 -245.522474) (xy 132.671992 -245.48438)
			(xy 132.644791 -245.441366) (xy 132.624843 -245.394546) (xy 132.612664 -245.345132) (xy 132.608569 -245.294404)
			(xy 132.302758 -245.294404) (xy 132.302268 -245.319393) (xy 132.294449 -245.368756) (xy 132.279005 -245.416288)
			(xy 132.256315 -245.46082) (xy 132.226939 -245.501253) (xy 132.191599 -245.536593) (xy 132.151166 -245.565969)
			(xy 132.106634 -245.588659) (xy 132.059102 -245.604103) (xy 132.009739 -245.611922) (xy 131.959761 -245.611922)
			(xy 131.910398 -245.604103) (xy 131.862866 -245.588659) (xy 131.818334 -245.565969) (xy 131.777901 -245.536593)
			(xy 131.742561 -245.501253) (xy 131.713185 -245.46082) (xy 131.690495 -245.416288) (xy 131.675051 -245.368756)
			(xy 131.667232 -245.319393) (xy 131.359915 -245.319393) (xy 131.359906 -245.31985) (xy 131.351742 -245.370084)
			(xy 131.335626 -245.418358) (xy 131.311975 -245.463421) (xy 131.281402 -245.504107) (xy 131.244698 -245.539362)
			(xy 131.202814 -245.568272) (xy 131.156835 -245.590089) (xy 131.107951 -245.604249) (xy 131.05743 -245.610383)
			(xy 131.006578 -245.608334) (xy 130.956714 -245.598154) (xy 130.909128 -245.580107) (xy 130.865054 -245.554661)
			(xy 130.825632 -245.522474) (xy 130.791884 -245.48438) (xy 130.764683 -245.441366) (xy 130.744735 -245.394546)
			(xy 130.732556 -245.345132) (xy 130.728461 -245.294404) (xy 130.42265 -245.294404) (xy 130.42216 -245.319393)
			(xy 130.414341 -245.368756) (xy 130.398897 -245.416288) (xy 130.376207 -245.46082) (xy 130.346831 -245.501253)
			(xy 130.311491 -245.536593) (xy 130.271058 -245.565969) (xy 130.226526 -245.588659) (xy 130.178994 -245.604103)
			(xy 130.129631 -245.611922) (xy 130.079653 -245.611922) (xy 130.03029 -245.604103) (xy 129.982758 -245.588659)
			(xy 129.938226 -245.565969) (xy 129.897793 -245.536593) (xy 129.862453 -245.501253) (xy 129.833077 -245.46082)
			(xy 129.810387 -245.416288) (xy 129.794943 -245.368756) (xy 129.787124 -245.319393) (xy 129.480061 -245.319393)
			(xy 129.480052 -245.31985) (xy 129.471888 -245.370084) (xy 129.455772 -245.418358) (xy 129.432121 -245.463421)
			(xy 129.401548 -245.504107) (xy 129.364844 -245.539362) (xy 129.32296 -245.568272) (xy 129.276981 -245.590089)
			(xy 129.228097 -245.604249) (xy 129.177576 -245.610383) (xy 129.126724 -245.608334) (xy 129.07686 -245.598154)
			(xy 129.029274 -245.580107) (xy 128.9852 -245.554661) (xy 128.945778 -245.522474) (xy 128.91203 -245.48438)
			(xy 128.884829 -245.441366) (xy 128.864881 -245.394546) (xy 128.852702 -245.345132) (xy 128.848607 -245.294404)
			(xy 128.54051 -245.294404) (xy 128.539998 -245.31985) (xy 128.531834 -245.370084) (xy 128.515718 -245.418358)
			(xy 128.492067 -245.463421) (xy 128.461494 -245.504107) (xy 128.42479 -245.539362) (xy 128.382906 -245.568272)
			(xy 128.336927 -245.590089) (xy 128.288043 -245.604249) (xy 128.237522 -245.610383) (xy 128.18667 -245.608334)
			(xy 128.136806 -245.598154) (xy 128.08922 -245.580107) (xy 128.045146 -245.554661) (xy 128.005724 -245.522474)
			(xy 127.971976 -245.48438) (xy 127.944775 -245.441366) (xy 127.924827 -245.394546) (xy 127.912648 -245.345132)
			(xy 127.908553 -245.294404) (xy 127.602742 -245.294404) (xy 127.602252 -245.319393) (xy 127.594433 -245.368756)
			(xy 127.578989 -245.416288) (xy 127.556299 -245.46082) (xy 127.526923 -245.501253) (xy 127.491583 -245.536593)
			(xy 127.45115 -245.565969) (xy 127.406618 -245.588659) (xy 127.359086 -245.604103) (xy 127.309723 -245.611922)
			(xy 127.259745 -245.611922) (xy 127.210382 -245.604103) (xy 127.16285 -245.588659) (xy 127.118318 -245.565969)
			(xy 127.077885 -245.536593) (xy 127.042545 -245.501253) (xy 127.013169 -245.46082) (xy 126.990479 -245.416288)
			(xy 126.975035 -245.368756) (xy 126.967216 -245.319393) (xy 126.661996 -245.319393) (xy 126.65626 -245.360779)
			(xy 126.650496 -245.382288) (xy 126.648464 -245.389146) (xy 126.648464 -245.691406) (xy 126.648464 -245.694454)
			(xy 126.649414 -245.703905) (xy 126.657373 -245.721136) (xy 126.663958 -245.727982) (xy 126.72441 -245.77929)
			(xy 126.728649 -245.782712) (xy 126.738256 -245.787841) (xy 126.74346 -245.78945) (xy 126.75362 -245.792244)
			(xy 126.764542 -245.790466) (xy 126.777028 -245.788566) (xy 126.802205 -245.786529) (xy 126.814834 -245.786402)
			(xy 126.839821 -245.786895) (xy 126.889178 -245.794717) (xy 126.936704 -245.810164) (xy 126.981229 -245.832855)
			(xy 127.021657 -245.862231) (xy 127.056991 -245.897569) (xy 127.086363 -245.938) (xy 127.109049 -245.982527)
			(xy 127.124491 -246.030055) (xy 127.132308 -246.079413) (xy 127.132308 -246.10441) (xy 127.438399 -246.10441)
			(xy 127.442494 -246.053682) (xy 127.454673 -246.004268) (xy 127.474621 -245.957448) (xy 127.501822 -245.914434)
			(xy 127.53557 -245.87634) (xy 127.574992 -245.844153) (xy 127.619066 -245.818707) (xy 127.666652 -245.80066)
			(xy 127.716516 -245.79048) (xy 127.767368 -245.788431) (xy 127.817889 -245.794565) (xy 127.866773 -245.808725)
			(xy 127.912752 -245.830542) (xy 127.954636 -245.859452) (xy 127.99134 -245.894707) (xy 128.021913 -245.935393)
			(xy 128.045564 -245.980456) (xy 128.06168 -246.02873) (xy 128.069844 -246.078964) (xy 128.070356 -246.10441)
			(xy 128.069853 -246.129399) (xy 128.37717 -246.129399) (xy 128.37717 -246.079421) (xy 128.384989 -246.030058)
			(xy 128.400433 -245.982526) (xy 128.423123 -245.937994) (xy 128.452499 -245.897561) (xy 128.487839 -245.862221)
			(xy 128.528272 -245.832845) (xy 128.572804 -245.810155) (xy 128.620336 -245.794711) (xy 128.669699 -245.786892)
			(xy 128.719677 -245.786892) (xy 128.76904 -245.794711) (xy 128.816572 -245.810155) (xy 128.861104 -245.832845)
			(xy 128.901537 -245.862221) (xy 128.936877 -245.897561) (xy 128.966253 -245.937994) (xy 128.988943 -245.982526)
			(xy 129.004387 -246.030058) (xy 129.012206 -246.079421) (xy 129.012696 -246.10441) (xy 129.318507 -246.10441)
			(xy 129.322602 -246.053682) (xy 129.334781 -246.004268) (xy 129.354729 -245.957448) (xy 129.38193 -245.914434)
			(xy 129.415678 -245.87634) (xy 129.4551 -245.844153) (xy 129.499174 -245.818707) (xy 129.54676 -245.80066)
			(xy 129.596624 -245.79048) (xy 129.647476 -245.788431) (xy 129.697997 -245.794565) (xy 129.746881 -245.808725)
			(xy 129.79286 -245.830542) (xy 129.834744 -245.859452) (xy 129.871448 -245.894707) (xy 129.902021 -245.935393)
			(xy 129.925672 -245.980456) (xy 129.941788 -246.02873) (xy 129.949952 -246.078964) (xy 129.950464 -246.10441)
			(xy 129.949961 -246.129399) (xy 130.257278 -246.129399) (xy 130.257278 -246.079421) (xy 130.265097 -246.030058)
			(xy 130.280541 -245.982526) (xy 130.303231 -245.937994) (xy 130.332607 -245.897561) (xy 130.367947 -245.862221)
			(xy 130.40838 -245.832845) (xy 130.452912 -245.810155) (xy 130.500444 -245.794711) (xy 130.549807 -245.786892)
			(xy 130.599785 -245.786892) (xy 130.649148 -245.794711) (xy 130.69668 -245.810155) (xy 130.741212 -245.832845)
			(xy 130.781645 -245.862221) (xy 130.816985 -245.897561) (xy 130.846361 -245.937994) (xy 130.869051 -245.982526)
			(xy 130.884495 -246.030058) (xy 130.892314 -246.079421) (xy 130.892804 -246.10441) (xy 131.198615 -246.10441)
			(xy 131.20271 -246.053682) (xy 131.214889 -246.004268) (xy 131.234837 -245.957448) (xy 131.262038 -245.914434)
			(xy 131.295786 -245.87634) (xy 131.335208 -245.844153) (xy 131.379282 -245.818707) (xy 131.426868 -245.80066)
			(xy 131.476732 -245.79048) (xy 131.527584 -245.788431) (xy 131.578105 -245.794565) (xy 131.626989 -245.808725)
			(xy 131.672968 -245.830542) (xy 131.714852 -245.859452) (xy 131.751556 -245.894707) (xy 131.782129 -245.935393)
			(xy 131.80578 -245.980456) (xy 131.821896 -246.02873) (xy 131.83006 -246.078964) (xy 131.830572 -246.10441)
			(xy 132.138415 -246.10441) (xy 132.14251 -246.053682) (xy 132.154689 -246.004268) (xy 132.174637 -245.957448)
			(xy 132.201838 -245.914434) (xy 132.235586 -245.87634) (xy 132.275008 -245.844153) (xy 132.319082 -245.818707)
			(xy 132.366668 -245.80066) (xy 132.416532 -245.79048) (xy 132.467384 -245.788431) (xy 132.517905 -245.794565)
			(xy 132.566789 -245.808725) (xy 132.612768 -245.830542) (xy 132.654652 -245.859452) (xy 132.691356 -245.894707)
			(xy 132.721929 -245.935393) (xy 132.74558 -245.980456) (xy 132.761696 -246.02873) (xy 132.76986 -246.078964)
			(xy 132.770372 -246.10441) (xy 132.769869 -246.129399) (xy 133.077186 -246.129399) (xy 133.077186 -246.079421)
			(xy 133.085005 -246.030058) (xy 133.100449 -245.982526) (xy 133.123139 -245.937994) (xy 133.152515 -245.897561)
			(xy 133.187855 -245.862221) (xy 133.228288 -245.832845) (xy 133.27282 -245.810155) (xy 133.320352 -245.794711)
			(xy 133.369715 -245.786892) (xy 133.419693 -245.786892) (xy 133.469056 -245.794711) (xy 133.516588 -245.810155)
			(xy 133.56112 -245.832845) (xy 133.601553 -245.862221) (xy 133.636893 -245.897561) (xy 133.666269 -245.937994)
			(xy 133.688959 -245.982526) (xy 133.704403 -246.030058) (xy 133.712222 -246.079421) (xy 133.712712 -246.10441)
			(xy 134.018523 -246.10441) (xy 134.022618 -246.053682) (xy 134.034797 -246.004268) (xy 134.054745 -245.957448)
			(xy 134.081946 -245.914434) (xy 134.115694 -245.87634) (xy 134.155116 -245.844153) (xy 134.19919 -245.818707)
			(xy 134.246776 -245.80066) (xy 134.29664 -245.79048) (xy 134.347492 -245.788431) (xy 134.398013 -245.794565)
			(xy 134.446897 -245.808725) (xy 134.492876 -245.830542) (xy 134.53476 -245.859452) (xy 134.571464 -245.894707)
			(xy 134.602037 -245.935393) (xy 134.625688 -245.980456) (xy 134.641804 -246.02873) (xy 134.649968 -246.078964)
			(xy 134.65048 -246.10441) (xy 134.649977 -246.129399) (xy 134.957294 -246.129399) (xy 134.957294 -246.079421)
			(xy 134.965113 -246.030058) (xy 134.980557 -245.982526) (xy 135.003247 -245.937994) (xy 135.032623 -245.897561)
			(xy 135.067963 -245.862221) (xy 135.108396 -245.832845) (xy 135.152928 -245.810155) (xy 135.20046 -245.794711)
			(xy 135.249823 -245.786892) (xy 135.299801 -245.786892) (xy 135.349164 -245.794711) (xy 135.396696 -245.810155)
			(xy 135.441228 -245.832845) (xy 135.481661 -245.862221) (xy 135.517001 -245.897561) (xy 135.546377 -245.937994)
			(xy 135.569067 -245.982526) (xy 135.584511 -246.030058) (xy 135.59233 -246.079421) (xy 135.59282 -246.10441)
			(xy 135.898631 -246.10441) (xy 135.902726 -246.053682) (xy 135.914905 -246.004268) (xy 135.934853 -245.957448)
			(xy 135.962054 -245.914434) (xy 135.995802 -245.87634) (xy 136.035224 -245.844153) (xy 136.079298 -245.818707)
			(xy 136.126884 -245.80066) (xy 136.176748 -245.79048) (xy 136.2276 -245.788431) (xy 136.278121 -245.794565)
			(xy 136.327005 -245.808725) (xy 136.372984 -245.830542) (xy 136.414868 -245.859452) (xy 136.451572 -245.894707)
			(xy 136.482145 -245.935393) (xy 136.505796 -245.980456) (xy 136.521912 -246.02873) (xy 136.530076 -246.078964)
			(xy 136.530588 -246.10441) (xy 136.530085 -246.129399) (xy 136.837148 -246.129399) (xy 136.837148 -246.079421)
			(xy 136.844967 -246.030058) (xy 136.860411 -245.982526) (xy 136.883101 -245.937994) (xy 136.912477 -245.897561)
			(xy 136.947817 -245.862221) (xy 136.98825 -245.832845) (xy 137.032782 -245.810155) (xy 137.080314 -245.794711)
			(xy 137.129677 -245.786892) (xy 137.179655 -245.786892) (xy 137.229018 -245.794711) (xy 137.27655 -245.810155)
			(xy 137.321082 -245.832845) (xy 137.361515 -245.862221) (xy 137.396855 -245.897561) (xy 137.426231 -245.937994)
			(xy 137.448921 -245.982526) (xy 137.464365 -246.030058) (xy 137.472184 -246.079421) (xy 137.472674 -246.10441)
			(xy 137.778485 -246.10441) (xy 137.78258 -246.053682) (xy 137.794759 -246.004268) (xy 137.814707 -245.957448)
			(xy 137.841908 -245.914434) (xy 137.875656 -245.87634) (xy 137.915078 -245.844153) (xy 137.959152 -245.818707)
			(xy 138.006738 -245.80066) (xy 138.056602 -245.79048) (xy 138.107454 -245.788431) (xy 138.157975 -245.794565)
			(xy 138.206859 -245.808725) (xy 138.252838 -245.830542) (xy 138.294722 -245.859452) (xy 138.331426 -245.894707)
			(xy 138.361999 -245.935393) (xy 138.38565 -245.980456) (xy 138.401766 -246.02873) (xy 138.40993 -246.078964)
			(xy 138.410442 -246.10441) (xy 138.718539 -246.10441) (xy 138.722634 -246.053682) (xy 138.734813 -246.004268)
			(xy 138.754761 -245.957448) (xy 138.781962 -245.914434) (xy 138.81571 -245.87634) (xy 138.855132 -245.844153)
			(xy 138.899206 -245.818707) (xy 138.946792 -245.80066) (xy 138.996656 -245.79048) (xy 139.047508 -245.788431)
			(xy 139.098029 -245.794565) (xy 139.146913 -245.808725) (xy 139.192892 -245.830542) (xy 139.234776 -245.859452)
			(xy 139.27148 -245.894707) (xy 139.302053 -245.935393) (xy 139.325704 -245.980456) (xy 139.34182 -246.02873)
			(xy 139.349984 -246.078964) (xy 139.350496 -246.10441) (xy 139.349993 -246.129399) (xy 139.65731 -246.129399)
			(xy 139.65731 -246.079421) (xy 139.665129 -246.030058) (xy 139.680573 -245.982526) (xy 139.703263 -245.937994)
			(xy 139.732639 -245.897561) (xy 139.767979 -245.862221) (xy 139.808412 -245.832845) (xy 139.852944 -245.810155)
			(xy 139.900476 -245.794711) (xy 139.949839 -245.786892) (xy 139.999817 -245.786892) (xy 140.04918 -245.794711)
			(xy 140.096712 -245.810155) (xy 140.141244 -245.832845) (xy 140.181677 -245.862221) (xy 140.217017 -245.897561)
			(xy 140.246393 -245.937994) (xy 140.269083 -245.982526) (xy 140.284527 -246.030058) (xy 140.292346 -246.079421)
			(xy 140.292836 -246.10441) (xy 140.598647 -246.10441) (xy 140.602742 -246.053682) (xy 140.614921 -246.004268)
			(xy 140.634869 -245.957448) (xy 140.66207 -245.914434) (xy 140.695818 -245.87634) (xy 140.73524 -245.844153)
			(xy 140.779314 -245.818707) (xy 140.8269 -245.80066) (xy 140.876764 -245.79048) (xy 140.927616 -245.788431)
			(xy 140.978137 -245.794565) (xy 141.027021 -245.808725) (xy 141.073 -245.830542) (xy 141.114884 -245.859452)
			(xy 141.151588 -245.894707) (xy 141.182161 -245.935393) (xy 141.205812 -245.980456) (xy 141.221928 -246.02873)
			(xy 141.230092 -246.078964) (xy 141.230604 -246.10441) (xy 141.230101 -246.129399) (xy 141.537164 -246.129399)
			(xy 141.537164 -246.079421) (xy 141.544983 -246.030058) (xy 141.560427 -245.982526) (xy 141.583117 -245.937994)
			(xy 141.612493 -245.897561) (xy 141.647833 -245.862221) (xy 141.688266 -245.832845) (xy 141.732798 -245.810155)
			(xy 141.78033 -245.794711) (xy 141.829693 -245.786892) (xy 141.879671 -245.786892) (xy 141.929034 -245.794711)
			(xy 141.976566 -245.810155) (xy 142.021098 -245.832845) (xy 142.061531 -245.862221) (xy 142.096871 -245.897561)
			(xy 142.126247 -245.937994) (xy 142.148937 -245.982526) (xy 142.164381 -246.030058) (xy 142.1722 -246.079421)
			(xy 142.17269 -246.10441) (xy 142.478501 -246.10441) (xy 142.482596 -246.053682) (xy 142.494775 -246.004268)
			(xy 142.514723 -245.957448) (xy 142.541924 -245.914434) (xy 142.575672 -245.87634) (xy 142.615094 -245.844153)
			(xy 142.659168 -245.818707) (xy 142.706754 -245.80066) (xy 142.756618 -245.79048) (xy 142.80747 -245.788431)
			(xy 142.857991 -245.794565) (xy 142.906875 -245.808725) (xy 142.952854 -245.830542) (xy 142.994738 -245.859452)
			(xy 143.031442 -245.894707) (xy 143.062015 -245.935393) (xy 143.085666 -245.980456) (xy 143.101782 -246.02873)
			(xy 143.109946 -246.078964) (xy 143.110458 -246.10441) (xy 143.109955 -246.129399) (xy 143.417272 -246.129399)
			(xy 143.417272 -246.079421) (xy 143.425091 -246.030058) (xy 143.440535 -245.982526) (xy 143.463225 -245.937994)
			(xy 143.492601 -245.897561) (xy 143.527941 -245.862221) (xy 143.568374 -245.832845) (xy 143.612906 -245.810155)
			(xy 143.660438 -245.794711) (xy 143.709801 -245.786892) (xy 143.759779 -245.786892) (xy 143.809142 -245.794711)
			(xy 143.856674 -245.810155) (xy 143.901206 -245.832845) (xy 143.941639 -245.862221) (xy 143.976979 -245.897561)
			(xy 144.006355 -245.937994) (xy 144.029045 -245.982526) (xy 144.044489 -246.030058) (xy 144.052308 -246.079421)
			(xy 144.052798 -246.10441) (xy 144.052308 -246.129399) (xy 144.044489 -246.178762) (xy 144.029045 -246.226294)
			(xy 144.006355 -246.270826) (xy 143.976979 -246.311259) (xy 143.941639 -246.346599) (xy 143.901206 -246.375975)
			(xy 143.856674 -246.398665) (xy 143.809142 -246.414109) (xy 143.759779 -246.421928) (xy 143.709801 -246.421928)
			(xy 143.660438 -246.414109) (xy 143.612906 -246.398665) (xy 143.568374 -246.375975) (xy 143.527941 -246.346599)
			(xy 143.492601 -246.311259) (xy 143.463225 -246.270826) (xy 143.440535 -246.226294) (xy 143.425091 -246.178762)
			(xy 143.417272 -246.129399) (xy 143.109955 -246.129399) (xy 143.109946 -246.129856) (xy 143.101782 -246.18009)
			(xy 143.085666 -246.228364) (xy 143.062015 -246.273427) (xy 143.031442 -246.314113) (xy 142.994738 -246.349368)
			(xy 142.952854 -246.378278) (xy 142.906875 -246.400095) (xy 142.857991 -246.414255) (xy 142.80747 -246.420389)
			(xy 142.756618 -246.41834) (xy 142.706754 -246.40816) (xy 142.659168 -246.390113) (xy 142.615094 -246.364667)
			(xy 142.575672 -246.33248) (xy 142.541924 -246.294386) (xy 142.514723 -246.251372) (xy 142.494775 -246.204552)
			(xy 142.482596 -246.155138) (xy 142.478501 -246.10441) (xy 142.17269 -246.10441) (xy 142.1722 -246.129399)
			(xy 142.164381 -246.178762) (xy 142.148937 -246.226294) (xy 142.126247 -246.270826) (xy 142.096871 -246.311259)
			(xy 142.061531 -246.346599) (xy 142.021098 -246.375975) (xy 141.976566 -246.398665) (xy 141.929034 -246.414109)
			(xy 141.879671 -246.421928) (xy 141.829693 -246.421928) (xy 141.78033 -246.414109) (xy 141.732798 -246.398665)
			(xy 141.688266 -246.375975) (xy 141.647833 -246.346599) (xy 141.612493 -246.311259) (xy 141.583117 -246.270826)
			(xy 141.560427 -246.226294) (xy 141.544983 -246.178762) (xy 141.537164 -246.129399) (xy 141.230101 -246.129399)
			(xy 141.230092 -246.129856) (xy 141.221928 -246.18009) (xy 141.205812 -246.228364) (xy 141.182161 -246.273427)
			(xy 141.151588 -246.314113) (xy 141.114884 -246.349368) (xy 141.073 -246.378278) (xy 141.027021 -246.400095)
			(xy 140.978137 -246.414255) (xy 140.927616 -246.420389) (xy 140.876764 -246.41834) (xy 140.8269 -246.40816)
			(xy 140.779314 -246.390113) (xy 140.73524 -246.364667) (xy 140.695818 -246.33248) (xy 140.66207 -246.294386)
			(xy 140.634869 -246.251372) (xy 140.614921 -246.204552) (xy 140.602742 -246.155138) (xy 140.598647 -246.10441)
			(xy 140.292836 -246.10441) (xy 140.292346 -246.129399) (xy 140.284527 -246.178762) (xy 140.269083 -246.226294)
			(xy 140.246393 -246.270826) (xy 140.217017 -246.311259) (xy 140.181677 -246.346599) (xy 140.141244 -246.375975)
			(xy 140.096712 -246.398665) (xy 140.04918 -246.414109) (xy 139.999817 -246.421928) (xy 139.949839 -246.421928)
			(xy 139.900476 -246.414109) (xy 139.852944 -246.398665) (xy 139.808412 -246.375975) (xy 139.767979 -246.346599)
			(xy 139.732639 -246.311259) (xy 139.703263 -246.270826) (xy 139.680573 -246.226294) (xy 139.665129 -246.178762)
			(xy 139.65731 -246.129399) (xy 139.349993 -246.129399) (xy 139.349984 -246.129856) (xy 139.34182 -246.18009)
			(xy 139.325704 -246.228364) (xy 139.302053 -246.273427) (xy 139.27148 -246.314113) (xy 139.234776 -246.349368)
			(xy 139.192892 -246.378278) (xy 139.146913 -246.400095) (xy 139.098029 -246.414255) (xy 139.047508 -246.420389)
			(xy 138.996656 -246.41834) (xy 138.946792 -246.40816) (xy 138.899206 -246.390113) (xy 138.855132 -246.364667)
			(xy 138.81571 -246.33248) (xy 138.781962 -246.294386) (xy 138.754761 -246.251372) (xy 138.734813 -246.204552)
			(xy 138.722634 -246.155138) (xy 138.718539 -246.10441) (xy 138.410442 -246.10441) (xy 138.40993 -246.129856)
			(xy 138.401766 -246.18009) (xy 138.38565 -246.228364) (xy 138.361999 -246.273427) (xy 138.331426 -246.314113)
			(xy 138.294722 -246.349368) (xy 138.252838 -246.378278) (xy 138.206859 -246.400095) (xy 138.157975 -246.414255)
			(xy 138.107454 -246.420389) (xy 138.056602 -246.41834) (xy 138.006738 -246.40816) (xy 137.959152 -246.390113)
			(xy 137.915078 -246.364667) (xy 137.875656 -246.33248) (xy 137.841908 -246.294386) (xy 137.814707 -246.251372)
			(xy 137.794759 -246.204552) (xy 137.78258 -246.155138) (xy 137.778485 -246.10441) (xy 137.472674 -246.10441)
			(xy 137.472184 -246.129399) (xy 137.464365 -246.178762) (xy 137.448921 -246.226294) (xy 137.426231 -246.270826)
			(xy 137.396855 -246.311259) (xy 137.361515 -246.346599) (xy 137.321082 -246.375975) (xy 137.27655 -246.398665)
			(xy 137.229018 -246.414109) (xy 137.179655 -246.421928) (xy 137.129677 -246.421928) (xy 137.080314 -246.414109)
			(xy 137.032782 -246.398665) (xy 136.98825 -246.375975) (xy 136.947817 -246.346599) (xy 136.912477 -246.311259)
			(xy 136.883101 -246.270826) (xy 136.860411 -246.226294) (xy 136.844967 -246.178762) (xy 136.837148 -246.129399)
			(xy 136.530085 -246.129399) (xy 136.530076 -246.129856) (xy 136.521912 -246.18009) (xy 136.505796 -246.228364)
			(xy 136.482145 -246.273427) (xy 136.451572 -246.314113) (xy 136.414868 -246.349368) (xy 136.372984 -246.378278)
			(xy 136.327005 -246.400095) (xy 136.278121 -246.414255) (xy 136.2276 -246.420389) (xy 136.176748 -246.41834)
			(xy 136.126884 -246.40816) (xy 136.079298 -246.390113) (xy 136.035224 -246.364667) (xy 135.995802 -246.33248)
			(xy 135.962054 -246.294386) (xy 135.934853 -246.251372) (xy 135.914905 -246.204552) (xy 135.902726 -246.155138)
			(xy 135.898631 -246.10441) (xy 135.59282 -246.10441) (xy 135.59233 -246.129399) (xy 135.584511 -246.178762)
			(xy 135.569067 -246.226294) (xy 135.546377 -246.270826) (xy 135.517001 -246.311259) (xy 135.481661 -246.346599)
			(xy 135.441228 -246.375975) (xy 135.396696 -246.398665) (xy 135.349164 -246.414109) (xy 135.299801 -246.421928)
			(xy 135.249823 -246.421928) (xy 135.20046 -246.414109) (xy 135.152928 -246.398665) (xy 135.108396 -246.375975)
			(xy 135.067963 -246.346599) (xy 135.032623 -246.311259) (xy 135.003247 -246.270826) (xy 134.980557 -246.226294)
			(xy 134.965113 -246.178762) (xy 134.957294 -246.129399) (xy 134.649977 -246.129399) (xy 134.649968 -246.129856)
			(xy 134.641804 -246.18009) (xy 134.625688 -246.228364) (xy 134.602037 -246.273427) (xy 134.571464 -246.314113)
			(xy 134.53476 -246.349368) (xy 134.492876 -246.378278) (xy 134.446897 -246.400095) (xy 134.398013 -246.414255)
			(xy 134.347492 -246.420389) (xy 134.29664 -246.41834) (xy 134.246776 -246.40816) (xy 134.19919 -246.390113)
			(xy 134.155116 -246.364667) (xy 134.115694 -246.33248) (xy 134.081946 -246.294386) (xy 134.054745 -246.251372)
			(xy 134.034797 -246.204552) (xy 134.022618 -246.155138) (xy 134.018523 -246.10441) (xy 133.712712 -246.10441)
			(xy 133.712222 -246.129399) (xy 133.704403 -246.178762) (xy 133.688959 -246.226294) (xy 133.666269 -246.270826)
			(xy 133.636893 -246.311259) (xy 133.601553 -246.346599) (xy 133.56112 -246.375975) (xy 133.516588 -246.398665)
			(xy 133.469056 -246.414109) (xy 133.419693 -246.421928) (xy 133.369715 -246.421928) (xy 133.320352 -246.414109)
			(xy 133.27282 -246.398665) (xy 133.228288 -246.375975) (xy 133.187855 -246.346599) (xy 133.152515 -246.311259)
			(xy 133.123139 -246.270826) (xy 133.100449 -246.226294) (xy 133.085005 -246.178762) (xy 133.077186 -246.129399)
			(xy 132.769869 -246.129399) (xy 132.76986 -246.129856) (xy 132.761696 -246.18009) (xy 132.74558 -246.228364)
			(xy 132.721929 -246.273427) (xy 132.691356 -246.314113) (xy 132.654652 -246.349368) (xy 132.612768 -246.378278)
			(xy 132.566789 -246.400095) (xy 132.517905 -246.414255) (xy 132.467384 -246.420389) (xy 132.416532 -246.41834)
			(xy 132.366668 -246.40816) (xy 132.319082 -246.390113) (xy 132.275008 -246.364667) (xy 132.235586 -246.33248)
			(xy 132.201838 -246.294386) (xy 132.174637 -246.251372) (xy 132.154689 -246.204552) (xy 132.14251 -246.155138)
			(xy 132.138415 -246.10441) (xy 131.830572 -246.10441) (xy 131.83006 -246.129856) (xy 131.821896 -246.18009)
			(xy 131.80578 -246.228364) (xy 131.782129 -246.273427) (xy 131.751556 -246.314113) (xy 131.714852 -246.349368)
			(xy 131.672968 -246.378278) (xy 131.626989 -246.400095) (xy 131.578105 -246.414255) (xy 131.527584 -246.420389)
			(xy 131.476732 -246.41834) (xy 131.426868 -246.40816) (xy 131.379282 -246.390113) (xy 131.335208 -246.364667)
			(xy 131.295786 -246.33248) (xy 131.262038 -246.294386) (xy 131.234837 -246.251372) (xy 131.214889 -246.204552)
			(xy 131.20271 -246.155138) (xy 131.198615 -246.10441) (xy 130.892804 -246.10441) (xy 130.892314 -246.129399)
			(xy 130.884495 -246.178762) (xy 130.869051 -246.226294) (xy 130.846361 -246.270826) (xy 130.816985 -246.311259)
			(xy 130.781645 -246.346599) (xy 130.741212 -246.375975) (xy 130.69668 -246.398665) (xy 130.649148 -246.414109)
			(xy 130.599785 -246.421928) (xy 130.549807 -246.421928) (xy 130.500444 -246.414109) (xy 130.452912 -246.398665)
			(xy 130.40838 -246.375975) (xy 130.367947 -246.346599) (xy 130.332607 -246.311259) (xy 130.303231 -246.270826)
			(xy 130.280541 -246.226294) (xy 130.265097 -246.178762) (xy 130.257278 -246.129399) (xy 129.949961 -246.129399)
			(xy 129.949952 -246.129856) (xy 129.941788 -246.18009) (xy 129.925672 -246.228364) (xy 129.902021 -246.273427)
			(xy 129.871448 -246.314113) (xy 129.834744 -246.349368) (xy 129.79286 -246.378278) (xy 129.746881 -246.400095)
			(xy 129.697997 -246.414255) (xy 129.647476 -246.420389) (xy 129.596624 -246.41834) (xy 129.54676 -246.40816)
			(xy 129.499174 -246.390113) (xy 129.4551 -246.364667) (xy 129.415678 -246.33248) (xy 129.38193 -246.294386)
			(xy 129.354729 -246.251372) (xy 129.334781 -246.204552) (xy 129.322602 -246.155138) (xy 129.318507 -246.10441)
			(xy 129.012696 -246.10441) (xy 129.012206 -246.129399) (xy 129.004387 -246.178762) (xy 128.988943 -246.226294)
			(xy 128.966253 -246.270826) (xy 128.936877 -246.311259) (xy 128.901537 -246.346599) (xy 128.861104 -246.375975)
			(xy 128.816572 -246.398665) (xy 128.76904 -246.414109) (xy 128.719677 -246.421928) (xy 128.669699 -246.421928)
			(xy 128.620336 -246.414109) (xy 128.572804 -246.398665) (xy 128.528272 -246.375975) (xy 128.487839 -246.346599)
			(xy 128.452499 -246.311259) (xy 128.423123 -246.270826) (xy 128.400433 -246.226294) (xy 128.384989 -246.178762)
			(xy 128.37717 -246.129399) (xy 128.069853 -246.129399) (xy 128.069844 -246.129856) (xy 128.06168 -246.18009)
			(xy 128.045564 -246.228364) (xy 128.021913 -246.273427) (xy 127.99134 -246.314113) (xy 127.954636 -246.349368)
			(xy 127.912752 -246.378278) (xy 127.866773 -246.400095) (xy 127.817889 -246.414255) (xy 127.767368 -246.420389)
			(xy 127.716516 -246.41834) (xy 127.666652 -246.40816) (xy 127.619066 -246.390113) (xy 127.574992 -246.364667)
			(xy 127.53557 -246.33248) (xy 127.501822 -246.294386) (xy 127.474621 -246.251372) (xy 127.454673 -246.204552)
			(xy 127.442494 -246.155138) (xy 127.438399 -246.10441) (xy 127.132308 -246.10441) (xy 127.132308 -246.129387)
			(xy 127.124491 -246.178745) (xy 127.109049 -246.226273) (xy 127.086363 -246.2708) (xy 127.056991 -246.311231)
			(xy 127.021657 -246.346569) (xy 126.981229 -246.375945) (xy 126.936704 -246.398636) (xy 126.889178 -246.414083)
			(xy 126.839821 -246.421905) (xy 126.814834 -246.422418) (xy 126.8024 -246.422317) (xy 126.777607 -246.420408)
			(xy 126.765304 -246.418608) (xy 126.763526 -246.418354) (xy 126.75616 -246.417846) (xy 126.74778 -246.418272)
			(xy 126.731967 -246.423845) (xy 126.725172 -246.428768) (xy 126.706122 -246.44477) (xy 126.705614 -246.445278)
			(xy 126.666244 -246.47906) (xy 126.65871 -246.486125) (xy 126.649516 -246.504601) (xy 126.648464 -246.514874)
			(xy 126.648464 -246.812308) (xy 126.648972 -246.815864) (xy 126.650496 -246.826786) (xy 126.651004 -246.828818)
			(xy 126.651512 -246.830342) (xy 126.656773 -246.85096) (xy 126.662377 -246.89314) (xy 126.662688 -246.914416)
			(xy 127.908553 -246.914416) (xy 127.912648 -246.863688) (xy 127.924827 -246.814274) (xy 127.944775 -246.767454)
			(xy 127.971976 -246.72444) (xy 128.005724 -246.686346) (xy 128.045146 -246.654159) (xy 128.08922 -246.628713)
			(xy 128.136806 -246.610666) (xy 128.18667 -246.600486) (xy 128.237522 -246.598437) (xy 128.288043 -246.604571)
			(xy 128.336927 -246.618731) (xy 128.382906 -246.640548) (xy 128.42479 -246.669458) (xy 128.461494 -246.704713)
			(xy 128.492067 -246.745399) (xy 128.515718 -246.790462) (xy 128.531834 -246.838736) (xy 128.539998 -246.88897)
			(xy 128.54051 -246.914416) (xy 128.848607 -246.914416) (xy 128.852702 -246.863688) (xy 128.864881 -246.814274)
			(xy 128.884829 -246.767454) (xy 128.91203 -246.72444) (xy 128.945778 -246.686346) (xy 128.9852 -246.654159)
			(xy 129.029274 -246.628713) (xy 129.07686 -246.610666) (xy 129.126724 -246.600486) (xy 129.177576 -246.598437)
			(xy 129.228097 -246.604571) (xy 129.276981 -246.618731) (xy 129.32296 -246.640548) (xy 129.364844 -246.669458)
			(xy 129.401548 -246.704713) (xy 129.432121 -246.745399) (xy 129.455772 -246.790462) (xy 129.471888 -246.838736)
			(xy 129.480052 -246.88897) (xy 129.480564 -246.914416) (xy 130.728461 -246.914416) (xy 130.732556 -246.863688)
			(xy 130.744735 -246.814274) (xy 130.764683 -246.767454) (xy 130.791884 -246.72444) (xy 130.825632 -246.686346)
			(xy 130.865054 -246.654159) (xy 130.909128 -246.628713) (xy 130.956714 -246.610666) (xy 131.006578 -246.600486)
			(xy 131.05743 -246.598437) (xy 131.107951 -246.604571) (xy 131.156835 -246.618731) (xy 131.202814 -246.640548)
			(xy 131.244698 -246.669458) (xy 131.281402 -246.704713) (xy 131.311975 -246.745399) (xy 131.335626 -246.790462)
			(xy 131.351742 -246.838736) (xy 131.359906 -246.88897) (xy 131.360418 -246.914416) (xy 131.359915 -246.939405)
			(xy 131.667232 -246.939405) (xy 131.667232 -246.889427) (xy 131.675051 -246.840064) (xy 131.690495 -246.792532)
			(xy 131.713185 -246.748) (xy 131.742561 -246.707567) (xy 131.777901 -246.672227) (xy 131.818334 -246.642851)
			(xy 131.862866 -246.620161) (xy 131.910398 -246.604717) (xy 131.959761 -246.596898) (xy 132.009739 -246.596898)
			(xy 132.059102 -246.604717) (xy 132.106634 -246.620161) (xy 132.151166 -246.642851) (xy 132.191599 -246.672227)
			(xy 132.226939 -246.707567) (xy 132.256315 -246.748) (xy 132.279005 -246.792532) (xy 132.294449 -246.840064)
			(xy 132.302268 -246.889427) (xy 132.302758 -246.914416) (xy 132.608569 -246.914416) (xy 132.612664 -246.863688)
			(xy 132.624843 -246.814274) (xy 132.644791 -246.767454) (xy 132.671992 -246.72444) (xy 132.70574 -246.686346)
			(xy 132.745162 -246.654159) (xy 132.789236 -246.628713) (xy 132.836822 -246.610666) (xy 132.886686 -246.600486)
			(xy 132.937538 -246.598437) (xy 132.988059 -246.604571) (xy 133.036943 -246.618731) (xy 133.082922 -246.640548)
			(xy 133.124806 -246.669458) (xy 133.16151 -246.704713) (xy 133.192083 -246.745399) (xy 133.215734 -246.790462)
			(xy 133.23185 -246.838736) (xy 133.240014 -246.88897) (xy 133.240526 -246.914416) (xy 133.240023 -246.939405)
			(xy 133.54734 -246.939405) (xy 133.54734 -246.889427) (xy 133.555159 -246.840064) (xy 133.570603 -246.792532)
			(xy 133.593293 -246.748) (xy 133.622669 -246.707567) (xy 133.658009 -246.672227) (xy 133.698442 -246.642851)
			(xy 133.742974 -246.620161) (xy 133.790506 -246.604717) (xy 133.839869 -246.596898) (xy 133.889847 -246.596898)
			(xy 133.93921 -246.604717) (xy 133.986742 -246.620161) (xy 134.031274 -246.642851) (xy 134.071707 -246.672227)
			(xy 134.107047 -246.707567) (xy 134.136423 -246.748) (xy 134.159113 -246.792532) (xy 134.174557 -246.840064)
			(xy 134.182376 -246.889427) (xy 134.182866 -246.914416) (xy 134.488423 -246.914416) (xy 134.492518 -246.863688)
			(xy 134.504697 -246.814274) (xy 134.524645 -246.767454) (xy 134.551846 -246.72444) (xy 134.585594 -246.686346)
			(xy 134.625016 -246.654159) (xy 134.66909 -246.628713) (xy 134.716676 -246.610666) (xy 134.76654 -246.600486)
			(xy 134.817392 -246.598437) (xy 134.867913 -246.604571) (xy 134.916797 -246.618731) (xy 134.962776 -246.640548)
			(xy 135.00466 -246.669458) (xy 135.041364 -246.704713) (xy 135.071937 -246.745399) (xy 135.095588 -246.790462)
			(xy 135.111704 -246.838736) (xy 135.119868 -246.88897) (xy 135.12038 -246.914416) (xy 135.428477 -246.914416)
			(xy 135.432572 -246.863688) (xy 135.444751 -246.814274) (xy 135.464699 -246.767454) (xy 135.4919 -246.72444)
			(xy 135.525648 -246.686346) (xy 135.56507 -246.654159) (xy 135.609144 -246.628713) (xy 135.65673 -246.610666)
			(xy 135.706594 -246.600486) (xy 135.757446 -246.598437) (xy 135.807967 -246.604571) (xy 135.856851 -246.618731)
			(xy 135.90283 -246.640548) (xy 135.944714 -246.669458) (xy 135.981418 -246.704713) (xy 136.011991 -246.745399)
			(xy 136.035642 -246.790462) (xy 136.051758 -246.838736) (xy 136.059922 -246.88897) (xy 136.060434 -246.914416)
			(xy 137.308585 -246.914416) (xy 137.31268 -246.863688) (xy 137.324859 -246.814274) (xy 137.344807 -246.767454)
			(xy 137.372008 -246.72444) (xy 137.405756 -246.686346) (xy 137.445178 -246.654159) (xy 137.489252 -246.628713)
			(xy 137.536838 -246.610666) (xy 137.586702 -246.600486) (xy 137.637554 -246.598437) (xy 137.688075 -246.604571)
			(xy 137.736959 -246.618731) (xy 137.782938 -246.640548) (xy 137.824822 -246.669458) (xy 137.861526 -246.704713)
			(xy 137.892099 -246.745399) (xy 137.91575 -246.790462) (xy 137.931866 -246.838736) (xy 137.94003 -246.88897)
			(xy 137.940542 -246.914416) (xy 137.940039 -246.939405) (xy 138.247356 -246.939405) (xy 138.247356 -246.889427)
			(xy 138.255175 -246.840064) (xy 138.270619 -246.792532) (xy 138.293309 -246.748) (xy 138.322685 -246.707567)
			(xy 138.358025 -246.672227) (xy 138.398458 -246.642851) (xy 138.44299 -246.620161) (xy 138.490522 -246.604717)
			(xy 138.539885 -246.596898) (xy 138.589863 -246.596898) (xy 138.639226 -246.604717) (xy 138.686758 -246.620161)
			(xy 138.73129 -246.642851) (xy 138.771723 -246.672227) (xy 138.807063 -246.707567) (xy 138.836439 -246.748)
			(xy 138.859129 -246.792532) (xy 138.874573 -246.840064) (xy 138.882392 -246.889427) (xy 138.882882 -246.914416)
			(xy 139.188439 -246.914416) (xy 139.192534 -246.863688) (xy 139.204713 -246.814274) (xy 139.224661 -246.767454)
			(xy 139.251862 -246.72444) (xy 139.28561 -246.686346) (xy 139.325032 -246.654159) (xy 139.369106 -246.628713)
			(xy 139.416692 -246.610666) (xy 139.466556 -246.600486) (xy 139.517408 -246.598437) (xy 139.567929 -246.604571)
			(xy 139.616813 -246.618731) (xy 139.662792 -246.640548) (xy 139.704676 -246.669458) (xy 139.74138 -246.704713)
			(xy 139.771953 -246.745399) (xy 139.795604 -246.790462) (xy 139.81172 -246.838736) (xy 139.819884 -246.88897)
			(xy 139.820396 -246.914416) (xy 139.819893 -246.939405) (xy 140.12721 -246.939405) (xy 140.12721 -246.889427)
			(xy 140.135029 -246.840064) (xy 140.150473 -246.792532) (xy 140.173163 -246.748) (xy 140.202539 -246.707567)
			(xy 140.237879 -246.672227) (xy 140.278312 -246.642851) (xy 140.322844 -246.620161) (xy 140.370376 -246.604717)
			(xy 140.419739 -246.596898) (xy 140.469717 -246.596898) (xy 140.51908 -246.604717) (xy 140.566612 -246.620161)
			(xy 140.611144 -246.642851) (xy 140.651577 -246.672227) (xy 140.686917 -246.707567) (xy 140.716293 -246.748)
			(xy 140.738983 -246.792532) (xy 140.754427 -246.840064) (xy 140.762246 -246.889427) (xy 140.762736 -246.914416)
			(xy 141.068547 -246.914416) (xy 141.072642 -246.863688) (xy 141.084821 -246.814274) (xy 141.104769 -246.767454)
			(xy 141.13197 -246.72444) (xy 141.165718 -246.686346) (xy 141.20514 -246.654159) (xy 141.249214 -246.628713)
			(xy 141.2968 -246.610666) (xy 141.346664 -246.600486) (xy 141.397516 -246.598437) (xy 141.448037 -246.604571)
			(xy 141.496921 -246.618731) (xy 141.5429 -246.640548) (xy 141.584784 -246.669458) (xy 141.621488 -246.704713)
			(xy 141.652061 -246.745399) (xy 141.675712 -246.790462) (xy 141.691828 -246.838736) (xy 141.699992 -246.88897)
			(xy 141.700504 -246.914416) (xy 142.008601 -246.914416) (xy 142.012696 -246.863688) (xy 142.024875 -246.814274)
			(xy 142.044823 -246.767454) (xy 142.072024 -246.72444) (xy 142.105772 -246.686346) (xy 142.145194 -246.654159)
			(xy 142.189268 -246.628713) (xy 142.236854 -246.610666) (xy 142.286718 -246.600486) (xy 142.33757 -246.598437)
			(xy 142.388091 -246.604571) (xy 142.436975 -246.618731) (xy 142.482954 -246.640548) (xy 142.524838 -246.669458)
			(xy 142.561542 -246.704713) (xy 142.592115 -246.745399) (xy 142.615766 -246.790462) (xy 142.631882 -246.838736)
			(xy 142.640046 -246.88897) (xy 142.640558 -246.914416) (xy 142.640046 -246.939862) (xy 142.631882 -246.990096)
			(xy 142.615766 -247.03837) (xy 142.592115 -247.083433) (xy 142.561542 -247.124119) (xy 142.524838 -247.159374)
			(xy 142.482954 -247.188284) (xy 142.436975 -247.210101) (xy 142.388091 -247.224261) (xy 142.33757 -247.230395)
			(xy 142.286718 -247.228346) (xy 142.236854 -247.218166) (xy 142.189268 -247.200119) (xy 142.145194 -247.174673)
			(xy 142.105772 -247.142486) (xy 142.072024 -247.104392) (xy 142.044823 -247.061378) (xy 142.024875 -247.014558)
			(xy 142.012696 -246.965144) (xy 142.008601 -246.914416) (xy 141.700504 -246.914416) (xy 141.699992 -246.939862)
			(xy 141.691828 -246.990096) (xy 141.675712 -247.03837) (xy 141.652061 -247.083433) (xy 141.621488 -247.124119)
			(xy 141.584784 -247.159374) (xy 141.5429 -247.188284) (xy 141.496921 -247.210101) (xy 141.448037 -247.224261)
			(xy 141.397516 -247.230395) (xy 141.346664 -247.228346) (xy 141.2968 -247.218166) (xy 141.249214 -247.200119)
			(xy 141.20514 -247.174673) (xy 141.165718 -247.142486) (xy 141.13197 -247.104392) (xy 141.104769 -247.061378)
			(xy 141.084821 -247.014558) (xy 141.072642 -246.965144) (xy 141.068547 -246.914416) (xy 140.762736 -246.914416)
			(xy 140.762246 -246.939405) (xy 140.754427 -246.988768) (xy 140.738983 -247.0363) (xy 140.716293 -247.080832)
			(xy 140.686917 -247.121265) (xy 140.651577 -247.156605) (xy 140.611144 -247.185981) (xy 140.566612 -247.208671)
			(xy 140.51908 -247.224115) (xy 140.469717 -247.231934) (xy 140.419739 -247.231934) (xy 140.370376 -247.224115)
			(xy 140.322844 -247.208671) (xy 140.278312 -247.185981) (xy 140.237879 -247.156605) (xy 140.202539 -247.121265)
			(xy 140.173163 -247.080832) (xy 140.150473 -247.0363) (xy 140.135029 -246.988768) (xy 140.12721 -246.939405)
			(xy 139.819893 -246.939405) (xy 139.819884 -246.939862) (xy 139.81172 -246.990096) (xy 139.795604 -247.03837)
			(xy 139.771953 -247.083433) (xy 139.74138 -247.124119) (xy 139.704676 -247.159374) (xy 139.662792 -247.188284)
			(xy 139.616813 -247.210101) (xy 139.567929 -247.224261) (xy 139.517408 -247.230395) (xy 139.466556 -247.228346)
			(xy 139.416692 -247.218166) (xy 139.369106 -247.200119) (xy 139.325032 -247.174673) (xy 139.28561 -247.142486)
			(xy 139.251862 -247.104392) (xy 139.224661 -247.061378) (xy 139.204713 -247.014558) (xy 139.192534 -246.965144)
			(xy 139.188439 -246.914416) (xy 138.882882 -246.914416) (xy 138.882392 -246.939405) (xy 138.874573 -246.988768)
			(xy 138.859129 -247.0363) (xy 138.836439 -247.080832) (xy 138.807063 -247.121265) (xy 138.771723 -247.156605)
			(xy 138.73129 -247.185981) (xy 138.686758 -247.208671) (xy 138.639226 -247.224115) (xy 138.589863 -247.231934)
			(xy 138.539885 -247.231934) (xy 138.490522 -247.224115) (xy 138.44299 -247.208671) (xy 138.398458 -247.185981)
			(xy 138.358025 -247.156605) (xy 138.322685 -247.121265) (xy 138.293309 -247.080832) (xy 138.270619 -247.0363)
			(xy 138.255175 -246.988768) (xy 138.247356 -246.939405) (xy 137.940039 -246.939405) (xy 137.94003 -246.939862)
			(xy 137.931866 -246.990096) (xy 137.91575 -247.03837) (xy 137.892099 -247.083433) (xy 137.861526 -247.124119)
			(xy 137.824822 -247.159374) (xy 137.782938 -247.188284) (xy 137.736959 -247.210101) (xy 137.688075 -247.224261)
			(xy 137.637554 -247.230395) (xy 137.586702 -247.228346) (xy 137.536838 -247.218166) (xy 137.489252 -247.200119)
			(xy 137.445178 -247.174673) (xy 137.405756 -247.142486) (xy 137.372008 -247.104392) (xy 137.344807 -247.061378)
			(xy 137.324859 -247.014558) (xy 137.31268 -246.965144) (xy 137.308585 -246.914416) (xy 136.060434 -246.914416)
			(xy 136.059922 -246.939862) (xy 136.051758 -246.990096) (xy 136.035642 -247.03837) (xy 136.011991 -247.083433)
			(xy 135.981418 -247.124119) (xy 135.944714 -247.159374) (xy 135.90283 -247.188284) (xy 135.856851 -247.210101)
			(xy 135.807967 -247.224261) (xy 135.757446 -247.230395) (xy 135.706594 -247.228346) (xy 135.65673 -247.218166)
			(xy 135.609144 -247.200119) (xy 135.56507 -247.174673) (xy 135.525648 -247.142486) (xy 135.4919 -247.104392)
			(xy 135.464699 -247.061378) (xy 135.444751 -247.014558) (xy 135.432572 -246.965144) (xy 135.428477 -246.914416)
			(xy 135.12038 -246.914416) (xy 135.119868 -246.939862) (xy 135.111704 -246.990096) (xy 135.095588 -247.03837)
			(xy 135.071937 -247.083433) (xy 135.041364 -247.124119) (xy 135.00466 -247.159374) (xy 134.962776 -247.188284)
			(xy 134.916797 -247.210101) (xy 134.867913 -247.224261) (xy 134.817392 -247.230395) (xy 134.76654 -247.228346)
			(xy 134.716676 -247.218166) (xy 134.66909 -247.200119) (xy 134.625016 -247.174673) (xy 134.585594 -247.142486)
			(xy 134.551846 -247.104392) (xy 134.524645 -247.061378) (xy 134.504697 -247.014558) (xy 134.492518 -246.965144)
			(xy 134.488423 -246.914416) (xy 134.182866 -246.914416) (xy 134.182376 -246.939405) (xy 134.174557 -246.988768)
			(xy 134.159113 -247.0363) (xy 134.136423 -247.080832) (xy 134.107047 -247.121265) (xy 134.071707 -247.156605)
			(xy 134.031274 -247.185981) (xy 133.986742 -247.208671) (xy 133.93921 -247.224115) (xy 133.889847 -247.231934)
			(xy 133.839869 -247.231934) (xy 133.790506 -247.224115) (xy 133.742974 -247.208671) (xy 133.698442 -247.185981)
			(xy 133.658009 -247.156605) (xy 133.622669 -247.121265) (xy 133.593293 -247.080832) (xy 133.570603 -247.0363)
			(xy 133.555159 -246.988768) (xy 133.54734 -246.939405) (xy 133.240023 -246.939405) (xy 133.240014 -246.939862)
			(xy 133.23185 -246.990096) (xy 133.215734 -247.03837) (xy 133.192083 -247.083433) (xy 133.16151 -247.124119)
			(xy 133.124806 -247.159374) (xy 133.082922 -247.188284) (xy 133.036943 -247.210101) (xy 132.988059 -247.224261)
			(xy 132.937538 -247.230395) (xy 132.886686 -247.228346) (xy 132.836822 -247.218166) (xy 132.789236 -247.200119)
			(xy 132.745162 -247.174673) (xy 132.70574 -247.142486) (xy 132.671992 -247.104392) (xy 132.644791 -247.061378)
			(xy 132.624843 -247.014558) (xy 132.612664 -246.965144) (xy 132.608569 -246.914416) (xy 132.302758 -246.914416)
			(xy 132.302268 -246.939405) (xy 132.294449 -246.988768) (xy 132.279005 -247.0363) (xy 132.256315 -247.080832)
			(xy 132.226939 -247.121265) (xy 132.191599 -247.156605) (xy 132.151166 -247.185981) (xy 132.106634 -247.208671)
			(xy 132.059102 -247.224115) (xy 132.009739 -247.231934) (xy 131.959761 -247.231934) (xy 131.910398 -247.224115)
			(xy 131.862866 -247.208671) (xy 131.818334 -247.185981) (xy 131.777901 -247.156605) (xy 131.742561 -247.121265)
			(xy 131.713185 -247.080832) (xy 131.690495 -247.0363) (xy 131.675051 -246.988768) (xy 131.667232 -246.939405)
			(xy 131.359915 -246.939405) (xy 131.359906 -246.939862) (xy 131.351742 -246.990096) (xy 131.335626 -247.03837)
			(xy 131.311975 -247.083433) (xy 131.281402 -247.124119) (xy 131.244698 -247.159374) (xy 131.202814 -247.188284)
			(xy 131.156835 -247.210101) (xy 131.107951 -247.224261) (xy 131.05743 -247.230395) (xy 131.006578 -247.228346)
			(xy 130.956714 -247.218166) (xy 130.909128 -247.200119) (xy 130.865054 -247.174673) (xy 130.825632 -247.142486)
			(xy 130.791884 -247.104392) (xy 130.764683 -247.061378) (xy 130.744735 -247.014558) (xy 130.732556 -246.965144)
			(xy 130.728461 -246.914416) (xy 129.480564 -246.914416) (xy 129.480052 -246.939862) (xy 129.471888 -246.990096)
			(xy 129.455772 -247.03837) (xy 129.432121 -247.083433) (xy 129.401548 -247.124119) (xy 129.364844 -247.159374)
			(xy 129.32296 -247.188284) (xy 129.276981 -247.210101) (xy 129.228097 -247.224261) (xy 129.177576 -247.230395)
			(xy 129.126724 -247.228346) (xy 129.07686 -247.218166) (xy 129.029274 -247.200119) (xy 128.9852 -247.174673)
			(xy 128.945778 -247.142486) (xy 128.91203 -247.104392) (xy 128.884829 -247.061378) (xy 128.864881 -247.014558)
			(xy 128.852702 -246.965144) (xy 128.848607 -246.914416) (xy 128.54051 -246.914416) (xy 128.539998 -246.939862)
			(xy 128.531834 -246.990096) (xy 128.515718 -247.03837) (xy 128.492067 -247.083433) (xy 128.461494 -247.124119)
			(xy 128.42479 -247.159374) (xy 128.382906 -247.188284) (xy 128.336927 -247.210101) (xy 128.288043 -247.224261)
			(xy 128.237522 -247.230395) (xy 128.18667 -247.228346) (xy 128.136806 -247.218166) (xy 128.08922 -247.200119)
			(xy 128.045146 -247.174673) (xy 128.005724 -247.142486) (xy 127.971976 -247.104392) (xy 127.944775 -247.061378)
			(xy 127.924827 -247.014558) (xy 127.912648 -246.965144) (xy 127.908553 -246.914416) (xy 126.662688 -246.914416)
			(xy 126.662434 -246.928132) (xy 126.661371 -246.946934) (xy 126.655383 -246.984114) (xy 126.650496 -247.0023)
			(xy 126.648464 -247.009158) (xy 126.648464 -247.311164) (xy 126.648464 -247.313958) (xy 126.649369 -247.32338)
			(xy 126.657214 -247.340593) (xy 126.663704 -247.347486) (xy 126.665736 -247.349264) (xy 126.700534 -247.379236)
			(xy 126.701042 -247.379744) (xy 126.725172 -247.400064) (xy 126.731963 -247.404994) (xy 126.747779 -247.410567)
			(xy 126.75616 -247.410986) (xy 126.763526 -247.410478) (xy 126.765304 -247.410224) (xy 126.777607 -247.408426)
			(xy 126.802401 -247.406519) (xy 126.814834 -247.406414) (xy 126.83982 -247.406907) (xy 126.889175 -247.414729)
			(xy 126.9367 -247.430175) (xy 126.981223 -247.452865) (xy 127.021649 -247.48224) (xy 127.056982 -247.517577)
			(xy 127.086353 -247.558006) (xy 127.109038 -247.602532) (xy 127.124479 -247.650058) (xy 127.132296 -247.699414)
			(xy 127.132296 -247.724422) (xy 127.438399 -247.724422) (xy 127.442494 -247.673694) (xy 127.454673 -247.62428)
			(xy 127.474621 -247.57746) (xy 127.501822 -247.534446) (xy 127.53557 -247.496352) (xy 127.574992 -247.464165)
			(xy 127.619066 -247.438719) (xy 127.666652 -247.420672) (xy 127.716516 -247.410492) (xy 127.767368 -247.408443)
			(xy 127.817889 -247.414577) (xy 127.866773 -247.428737) (xy 127.912752 -247.450554) (xy 127.954636 -247.479464)
			(xy 127.99134 -247.514719) (xy 128.021913 -247.555405) (xy 128.045564 -247.600468) (xy 128.06168 -247.648742)
			(xy 128.069844 -247.698976) (xy 128.070356 -247.724422) (xy 128.069853 -247.749411) (xy 128.37717 -247.749411)
			(xy 128.37717 -247.699433) (xy 128.384989 -247.65007) (xy 128.400433 -247.602538) (xy 128.423123 -247.558006)
			(xy 128.452499 -247.517573) (xy 128.487839 -247.482233) (xy 128.528272 -247.452857) (xy 128.572804 -247.430167)
			(xy 128.620336 -247.414723) (xy 128.669699 -247.406904) (xy 128.719677 -247.406904) (xy 128.76904 -247.414723)
			(xy 128.816572 -247.430167) (xy 128.861104 -247.452857) (xy 128.901537 -247.482233) (xy 128.936877 -247.517573)
			(xy 128.966253 -247.558006) (xy 128.988943 -247.602538) (xy 129.004387 -247.65007) (xy 129.012206 -247.699433)
			(xy 129.012696 -247.724422) (xy 129.318507 -247.724422) (xy 129.322602 -247.673694) (xy 129.334781 -247.62428)
			(xy 129.354729 -247.57746) (xy 129.38193 -247.534446) (xy 129.415678 -247.496352) (xy 129.4551 -247.464165)
			(xy 129.499174 -247.438719) (xy 129.54676 -247.420672) (xy 129.596624 -247.410492) (xy 129.647476 -247.408443)
			(xy 129.697997 -247.414577) (xy 129.746881 -247.428737) (xy 129.79286 -247.450554) (xy 129.834744 -247.479464)
			(xy 129.871448 -247.514719) (xy 129.902021 -247.555405) (xy 129.925672 -247.600468) (xy 129.941788 -247.648742)
			(xy 129.949952 -247.698976) (xy 129.950464 -247.724422) (xy 129.949961 -247.749411) (xy 130.257278 -247.749411)
			(xy 130.257278 -247.699433) (xy 130.265097 -247.65007) (xy 130.280541 -247.602538) (xy 130.303231 -247.558006)
			(xy 130.332607 -247.517573) (xy 130.367947 -247.482233) (xy 130.40838 -247.452857) (xy 130.452912 -247.430167)
			(xy 130.500444 -247.414723) (xy 130.549807 -247.406904) (xy 130.599785 -247.406904) (xy 130.649148 -247.414723)
			(xy 130.69668 -247.430167) (xy 130.741212 -247.452857) (xy 130.781645 -247.482233) (xy 130.816985 -247.517573)
			(xy 130.846361 -247.558006) (xy 130.869051 -247.602538) (xy 130.884495 -247.65007) (xy 130.892314 -247.699433)
			(xy 130.892804 -247.724422) (xy 131.198615 -247.724422) (xy 131.20271 -247.673694) (xy 131.214889 -247.62428)
			(xy 131.234837 -247.57746) (xy 131.262038 -247.534446) (xy 131.295786 -247.496352) (xy 131.335208 -247.464165)
			(xy 131.379282 -247.438719) (xy 131.426868 -247.420672) (xy 131.476732 -247.410492) (xy 131.527584 -247.408443)
			(xy 131.578105 -247.414577) (xy 131.626989 -247.428737) (xy 131.672968 -247.450554) (xy 131.714852 -247.479464)
			(xy 131.751556 -247.514719) (xy 131.782129 -247.555405) (xy 131.80578 -247.600468) (xy 131.821896 -247.648742)
			(xy 131.83006 -247.698976) (xy 131.830572 -247.724422) (xy 132.138415 -247.724422) (xy 132.14251 -247.673694)
			(xy 132.154689 -247.62428) (xy 132.174637 -247.57746) (xy 132.201838 -247.534446) (xy 132.235586 -247.496352)
			(xy 132.275008 -247.464165) (xy 132.319082 -247.438719) (xy 132.366668 -247.420672) (xy 132.416532 -247.410492)
			(xy 132.467384 -247.408443) (xy 132.517905 -247.414577) (xy 132.566789 -247.428737) (xy 132.612768 -247.450554)
			(xy 132.654652 -247.479464) (xy 132.691356 -247.514719) (xy 132.721929 -247.555405) (xy 132.74558 -247.600468)
			(xy 132.761696 -247.648742) (xy 132.76986 -247.698976) (xy 132.770372 -247.724422) (xy 132.769869 -247.749411)
			(xy 133.077186 -247.749411) (xy 133.077186 -247.699433) (xy 133.085005 -247.65007) (xy 133.100449 -247.602538)
			(xy 133.123139 -247.558006) (xy 133.152515 -247.517573) (xy 133.187855 -247.482233) (xy 133.228288 -247.452857)
			(xy 133.27282 -247.430167) (xy 133.320352 -247.414723) (xy 133.369715 -247.406904) (xy 133.419693 -247.406904)
			(xy 133.469056 -247.414723) (xy 133.516588 -247.430167) (xy 133.56112 -247.452857) (xy 133.601553 -247.482233)
			(xy 133.636893 -247.517573) (xy 133.666269 -247.558006) (xy 133.688959 -247.602538) (xy 133.704403 -247.65007)
			(xy 133.712222 -247.699433) (xy 133.712712 -247.724422) (xy 134.018523 -247.724422) (xy 134.022618 -247.673694)
			(xy 134.034797 -247.62428) (xy 134.054745 -247.57746) (xy 134.081946 -247.534446) (xy 134.115694 -247.496352)
			(xy 134.155116 -247.464165) (xy 134.19919 -247.438719) (xy 134.246776 -247.420672) (xy 134.29664 -247.410492)
			(xy 134.347492 -247.408443) (xy 134.398013 -247.414577) (xy 134.446897 -247.428737) (xy 134.492876 -247.450554)
			(xy 134.53476 -247.479464) (xy 134.571464 -247.514719) (xy 134.602037 -247.555405) (xy 134.625688 -247.600468)
			(xy 134.641804 -247.648742) (xy 134.649968 -247.698976) (xy 134.65048 -247.724422) (xy 134.649977 -247.749411)
			(xy 134.957294 -247.749411) (xy 134.957294 -247.699433) (xy 134.965113 -247.65007) (xy 134.980557 -247.602538)
			(xy 135.003247 -247.558006) (xy 135.032623 -247.517573) (xy 135.067963 -247.482233) (xy 135.108396 -247.452857)
			(xy 135.152928 -247.430167) (xy 135.20046 -247.414723) (xy 135.249823 -247.406904) (xy 135.299801 -247.406904)
			(xy 135.349164 -247.414723) (xy 135.396696 -247.430167) (xy 135.441228 -247.452857) (xy 135.481661 -247.482233)
			(xy 135.517001 -247.517573) (xy 135.546377 -247.558006) (xy 135.569067 -247.602538) (xy 135.584511 -247.65007)
			(xy 135.59233 -247.699433) (xy 135.59282 -247.724422) (xy 135.898631 -247.724422) (xy 135.902726 -247.673694)
			(xy 135.914905 -247.62428) (xy 135.934853 -247.57746) (xy 135.962054 -247.534446) (xy 135.995802 -247.496352)
			(xy 136.035224 -247.464165) (xy 136.079298 -247.438719) (xy 136.126884 -247.420672) (xy 136.176748 -247.410492)
			(xy 136.2276 -247.408443) (xy 136.278121 -247.414577) (xy 136.327005 -247.428737) (xy 136.372984 -247.450554)
			(xy 136.414868 -247.479464) (xy 136.451572 -247.514719) (xy 136.482145 -247.555405) (xy 136.505796 -247.600468)
			(xy 136.521912 -247.648742) (xy 136.530076 -247.698976) (xy 136.530588 -247.724422) (xy 136.530085 -247.749411)
			(xy 136.837148 -247.749411) (xy 136.837148 -247.699433) (xy 136.844967 -247.65007) (xy 136.860411 -247.602538)
			(xy 136.883101 -247.558006) (xy 136.912477 -247.517573) (xy 136.947817 -247.482233) (xy 136.98825 -247.452857)
			(xy 137.032782 -247.430167) (xy 137.080314 -247.414723) (xy 137.129677 -247.406904) (xy 137.179655 -247.406904)
			(xy 137.229018 -247.414723) (xy 137.27655 -247.430167) (xy 137.321082 -247.452857) (xy 137.361515 -247.482233)
			(xy 137.396855 -247.517573) (xy 137.426231 -247.558006) (xy 137.448921 -247.602538) (xy 137.464365 -247.65007)
			(xy 137.472184 -247.699433) (xy 137.472674 -247.724422) (xy 137.778485 -247.724422) (xy 137.78258 -247.673694)
			(xy 137.794759 -247.62428) (xy 137.814707 -247.57746) (xy 137.841908 -247.534446) (xy 137.875656 -247.496352)
			(xy 137.915078 -247.464165) (xy 137.959152 -247.438719) (xy 138.006738 -247.420672) (xy 138.056602 -247.410492)
			(xy 138.107454 -247.408443) (xy 138.157975 -247.414577) (xy 138.206859 -247.428737) (xy 138.252838 -247.450554)
			(xy 138.294722 -247.479464) (xy 138.331426 -247.514719) (xy 138.361999 -247.555405) (xy 138.38565 -247.600468)
			(xy 138.401766 -247.648742) (xy 138.40993 -247.698976) (xy 138.410442 -247.724422) (xy 138.718539 -247.724422)
			(xy 138.722634 -247.673694) (xy 138.734813 -247.62428) (xy 138.754761 -247.57746) (xy 138.781962 -247.534446)
			(xy 138.81571 -247.496352) (xy 138.855132 -247.464165) (xy 138.899206 -247.438719) (xy 138.946792 -247.420672)
			(xy 138.996656 -247.410492) (xy 139.047508 -247.408443) (xy 139.098029 -247.414577) (xy 139.146913 -247.428737)
			(xy 139.192892 -247.450554) (xy 139.234776 -247.479464) (xy 139.27148 -247.514719) (xy 139.302053 -247.555405)
			(xy 139.325704 -247.600468) (xy 139.34182 -247.648742) (xy 139.349984 -247.698976) (xy 139.350496 -247.724422)
			(xy 139.349993 -247.749411) (xy 139.65731 -247.749411) (xy 139.65731 -247.699433) (xy 139.665129 -247.65007)
			(xy 139.680573 -247.602538) (xy 139.703263 -247.558006) (xy 139.732639 -247.517573) (xy 139.767979 -247.482233)
			(xy 139.808412 -247.452857) (xy 139.852944 -247.430167) (xy 139.900476 -247.414723) (xy 139.949839 -247.406904)
			(xy 139.999817 -247.406904) (xy 140.04918 -247.414723) (xy 140.096712 -247.430167) (xy 140.141244 -247.452857)
			(xy 140.181677 -247.482233) (xy 140.217017 -247.517573) (xy 140.246393 -247.558006) (xy 140.269083 -247.602538)
			(xy 140.284527 -247.65007) (xy 140.292346 -247.699433) (xy 140.292836 -247.724422) (xy 140.598647 -247.724422)
			(xy 140.602742 -247.673694) (xy 140.614921 -247.62428) (xy 140.634869 -247.57746) (xy 140.66207 -247.534446)
			(xy 140.695818 -247.496352) (xy 140.73524 -247.464165) (xy 140.779314 -247.438719) (xy 140.8269 -247.420672)
			(xy 140.876764 -247.410492) (xy 140.927616 -247.408443) (xy 140.978137 -247.414577) (xy 141.027021 -247.428737)
			(xy 141.073 -247.450554) (xy 141.114884 -247.479464) (xy 141.151588 -247.514719) (xy 141.182161 -247.555405)
			(xy 141.205812 -247.600468) (xy 141.221928 -247.648742) (xy 141.230092 -247.698976) (xy 141.230604 -247.724422)
			(xy 141.230101 -247.749411) (xy 141.537164 -247.749411) (xy 141.537164 -247.699433) (xy 141.544983 -247.65007)
			(xy 141.560427 -247.602538) (xy 141.583117 -247.558006) (xy 141.612493 -247.517573) (xy 141.647833 -247.482233)
			(xy 141.688266 -247.452857) (xy 141.732798 -247.430167) (xy 141.78033 -247.414723) (xy 141.829693 -247.406904)
			(xy 141.879671 -247.406904) (xy 141.929034 -247.414723) (xy 141.976566 -247.430167) (xy 142.021098 -247.452857)
			(xy 142.061531 -247.482233) (xy 142.096871 -247.517573) (xy 142.126247 -247.558006) (xy 142.148937 -247.602538)
			(xy 142.164381 -247.65007) (xy 142.1722 -247.699433) (xy 142.17269 -247.724422) (xy 142.478501 -247.724422)
			(xy 142.482596 -247.673694) (xy 142.494775 -247.62428) (xy 142.514723 -247.57746) (xy 142.541924 -247.534446)
			(xy 142.575672 -247.496352) (xy 142.615094 -247.464165) (xy 142.659168 -247.438719) (xy 142.706754 -247.420672)
			(xy 142.756618 -247.410492) (xy 142.80747 -247.408443) (xy 142.857991 -247.414577) (xy 142.906875 -247.428737)
			(xy 142.952854 -247.450554) (xy 142.994738 -247.479464) (xy 143.031442 -247.514719) (xy 143.062015 -247.555405)
			(xy 143.085666 -247.600468) (xy 143.101782 -247.648742) (xy 143.109946 -247.698976) (xy 143.110458 -247.724422)
			(xy 143.109955 -247.749411) (xy 143.417272 -247.749411) (xy 143.417272 -247.699433) (xy 143.425091 -247.65007)
			(xy 143.440535 -247.602538) (xy 143.463225 -247.558006) (xy 143.492601 -247.517573) (xy 143.527941 -247.482233)
			(xy 143.568374 -247.452857) (xy 143.612906 -247.430167) (xy 143.660438 -247.414723) (xy 143.709801 -247.406904)
			(xy 143.759779 -247.406904) (xy 143.809142 -247.414723) (xy 143.856674 -247.430167) (xy 143.901206 -247.452857)
			(xy 143.941639 -247.482233) (xy 143.976979 -247.517573) (xy 144.006355 -247.558006) (xy 144.029045 -247.602538)
			(xy 144.044489 -247.65007) (xy 144.052308 -247.699433) (xy 144.052798 -247.724422) (xy 144.052308 -247.749411)
			(xy 144.044489 -247.798774) (xy 144.029045 -247.846306) (xy 144.006355 -247.890838) (xy 143.976979 -247.931271)
			(xy 143.941639 -247.966611) (xy 143.901206 -247.995987) (xy 143.856674 -248.018677) (xy 143.809142 -248.034121)
			(xy 143.759779 -248.04194) (xy 143.709801 -248.04194) (xy 143.660438 -248.034121) (xy 143.612906 -248.018677)
			(xy 143.568374 -247.995987) (xy 143.527941 -247.966611) (xy 143.492601 -247.931271) (xy 143.463225 -247.890838)
			(xy 143.440535 -247.846306) (xy 143.425091 -247.798774) (xy 143.417272 -247.749411) (xy 143.109955 -247.749411)
			(xy 143.109946 -247.749868) (xy 143.101782 -247.800102) (xy 143.085666 -247.848376) (xy 143.062015 -247.893439)
			(xy 143.031442 -247.934125) (xy 142.994738 -247.96938) (xy 142.952854 -247.99829) (xy 142.906875 -248.020107)
			(xy 142.857991 -248.034267) (xy 142.80747 -248.040401) (xy 142.756618 -248.038352) (xy 142.706754 -248.028172)
			(xy 142.659168 -248.010125) (xy 142.615094 -247.984679) (xy 142.575672 -247.952492) (xy 142.541924 -247.914398)
			(xy 142.514723 -247.871384) (xy 142.494775 -247.824564) (xy 142.482596 -247.77515) (xy 142.478501 -247.724422)
			(xy 142.17269 -247.724422) (xy 142.1722 -247.749411) (xy 142.164381 -247.798774) (xy 142.148937 -247.846306)
			(xy 142.126247 -247.890838) (xy 142.096871 -247.931271) (xy 142.061531 -247.966611) (xy 142.021098 -247.995987)
			(xy 141.976566 -248.018677) (xy 141.929034 -248.034121) (xy 141.879671 -248.04194) (xy 141.829693 -248.04194)
			(xy 141.78033 -248.034121) (xy 141.732798 -248.018677) (xy 141.688266 -247.995987) (xy 141.647833 -247.966611)
			(xy 141.612493 -247.931271) (xy 141.583117 -247.890838) (xy 141.560427 -247.846306) (xy 141.544983 -247.798774)
			(xy 141.537164 -247.749411) (xy 141.230101 -247.749411) (xy 141.230092 -247.749868) (xy 141.221928 -247.800102)
			(xy 141.205812 -247.848376) (xy 141.182161 -247.893439) (xy 141.151588 -247.934125) (xy 141.114884 -247.96938)
			(xy 141.073 -247.99829) (xy 141.027021 -248.020107) (xy 140.978137 -248.034267) (xy 140.927616 -248.040401)
			(xy 140.876764 -248.038352) (xy 140.8269 -248.028172) (xy 140.779314 -248.010125) (xy 140.73524 -247.984679)
			(xy 140.695818 -247.952492) (xy 140.66207 -247.914398) (xy 140.634869 -247.871384) (xy 140.614921 -247.824564)
			(xy 140.602742 -247.77515) (xy 140.598647 -247.724422) (xy 140.292836 -247.724422) (xy 140.292346 -247.749411)
			(xy 140.284527 -247.798774) (xy 140.269083 -247.846306) (xy 140.246393 -247.890838) (xy 140.217017 -247.931271)
			(xy 140.181677 -247.966611) (xy 140.141244 -247.995987) (xy 140.096712 -248.018677) (xy 140.04918 -248.034121)
			(xy 139.999817 -248.04194) (xy 139.949839 -248.04194) (xy 139.900476 -248.034121) (xy 139.852944 -248.018677)
			(xy 139.808412 -247.995987) (xy 139.767979 -247.966611) (xy 139.732639 -247.931271) (xy 139.703263 -247.890838)
			(xy 139.680573 -247.846306) (xy 139.665129 -247.798774) (xy 139.65731 -247.749411) (xy 139.349993 -247.749411)
			(xy 139.349984 -247.749868) (xy 139.34182 -247.800102) (xy 139.325704 -247.848376) (xy 139.302053 -247.893439)
			(xy 139.27148 -247.934125) (xy 139.234776 -247.96938) (xy 139.192892 -247.99829) (xy 139.146913 -248.020107)
			(xy 139.098029 -248.034267) (xy 139.047508 -248.040401) (xy 138.996656 -248.038352) (xy 138.946792 -248.028172)
			(xy 138.899206 -248.010125) (xy 138.855132 -247.984679) (xy 138.81571 -247.952492) (xy 138.781962 -247.914398)
			(xy 138.754761 -247.871384) (xy 138.734813 -247.824564) (xy 138.722634 -247.77515) (xy 138.718539 -247.724422)
			(xy 138.410442 -247.724422) (xy 138.40993 -247.749868) (xy 138.401766 -247.800102) (xy 138.38565 -247.848376)
			(xy 138.361999 -247.893439) (xy 138.331426 -247.934125) (xy 138.294722 -247.96938) (xy 138.252838 -247.99829)
			(xy 138.206859 -248.020107) (xy 138.157975 -248.034267) (xy 138.107454 -248.040401) (xy 138.056602 -248.038352)
			(xy 138.006738 -248.028172) (xy 137.959152 -248.010125) (xy 137.915078 -247.984679) (xy 137.875656 -247.952492)
			(xy 137.841908 -247.914398) (xy 137.814707 -247.871384) (xy 137.794759 -247.824564) (xy 137.78258 -247.77515)
			(xy 137.778485 -247.724422) (xy 137.472674 -247.724422) (xy 137.472184 -247.749411) (xy 137.464365 -247.798774)
			(xy 137.448921 -247.846306) (xy 137.426231 -247.890838) (xy 137.396855 -247.931271) (xy 137.361515 -247.966611)
			(xy 137.321082 -247.995987) (xy 137.27655 -248.018677) (xy 137.229018 -248.034121) (xy 137.179655 -248.04194)
			(xy 137.129677 -248.04194) (xy 137.080314 -248.034121) (xy 137.032782 -248.018677) (xy 136.98825 -247.995987)
			(xy 136.947817 -247.966611) (xy 136.912477 -247.931271) (xy 136.883101 -247.890838) (xy 136.860411 -247.846306)
			(xy 136.844967 -247.798774) (xy 136.837148 -247.749411) (xy 136.530085 -247.749411) (xy 136.530076 -247.749868)
			(xy 136.521912 -247.800102) (xy 136.505796 -247.848376) (xy 136.482145 -247.893439) (xy 136.451572 -247.934125)
			(xy 136.414868 -247.96938) (xy 136.372984 -247.99829) (xy 136.327005 -248.020107) (xy 136.278121 -248.034267)
			(xy 136.2276 -248.040401) (xy 136.176748 -248.038352) (xy 136.126884 -248.028172) (xy 136.079298 -248.010125)
			(xy 136.035224 -247.984679) (xy 135.995802 -247.952492) (xy 135.962054 -247.914398) (xy 135.934853 -247.871384)
			(xy 135.914905 -247.824564) (xy 135.902726 -247.77515) (xy 135.898631 -247.724422) (xy 135.59282 -247.724422)
			(xy 135.59233 -247.749411) (xy 135.584511 -247.798774) (xy 135.569067 -247.846306) (xy 135.546377 -247.890838)
			(xy 135.517001 -247.931271) (xy 135.481661 -247.966611) (xy 135.441228 -247.995987) (xy 135.396696 -248.018677)
			(xy 135.349164 -248.034121) (xy 135.299801 -248.04194) (xy 135.249823 -248.04194) (xy 135.20046 -248.034121)
			(xy 135.152928 -248.018677) (xy 135.108396 -247.995987) (xy 135.067963 -247.966611) (xy 135.032623 -247.931271)
			(xy 135.003247 -247.890838) (xy 134.980557 -247.846306) (xy 134.965113 -247.798774) (xy 134.957294 -247.749411)
			(xy 134.649977 -247.749411) (xy 134.649968 -247.749868) (xy 134.641804 -247.800102) (xy 134.625688 -247.848376)
			(xy 134.602037 -247.893439) (xy 134.571464 -247.934125) (xy 134.53476 -247.96938) (xy 134.492876 -247.99829)
			(xy 134.446897 -248.020107) (xy 134.398013 -248.034267) (xy 134.347492 -248.040401) (xy 134.29664 -248.038352)
			(xy 134.246776 -248.028172) (xy 134.19919 -248.010125) (xy 134.155116 -247.984679) (xy 134.115694 -247.952492)
			(xy 134.081946 -247.914398) (xy 134.054745 -247.871384) (xy 134.034797 -247.824564) (xy 134.022618 -247.77515)
			(xy 134.018523 -247.724422) (xy 133.712712 -247.724422) (xy 133.712222 -247.749411) (xy 133.704403 -247.798774)
			(xy 133.688959 -247.846306) (xy 133.666269 -247.890838) (xy 133.636893 -247.931271) (xy 133.601553 -247.966611)
			(xy 133.56112 -247.995987) (xy 133.516588 -248.018677) (xy 133.469056 -248.034121) (xy 133.419693 -248.04194)
			(xy 133.369715 -248.04194) (xy 133.320352 -248.034121) (xy 133.27282 -248.018677) (xy 133.228288 -247.995987)
			(xy 133.187855 -247.966611) (xy 133.152515 -247.931271) (xy 133.123139 -247.890838) (xy 133.100449 -247.846306)
			(xy 133.085005 -247.798774) (xy 133.077186 -247.749411) (xy 132.769869 -247.749411) (xy 132.76986 -247.749868)
			(xy 132.761696 -247.800102) (xy 132.74558 -247.848376) (xy 132.721929 -247.893439) (xy 132.691356 -247.934125)
			(xy 132.654652 -247.96938) (xy 132.612768 -247.99829) (xy 132.566789 -248.020107) (xy 132.517905 -248.034267)
			(xy 132.467384 -248.040401) (xy 132.416532 -248.038352) (xy 132.366668 -248.028172) (xy 132.319082 -248.010125)
			(xy 132.275008 -247.984679) (xy 132.235586 -247.952492) (xy 132.201838 -247.914398) (xy 132.174637 -247.871384)
			(xy 132.154689 -247.824564) (xy 132.14251 -247.77515) (xy 132.138415 -247.724422) (xy 131.830572 -247.724422)
			(xy 131.83006 -247.749868) (xy 131.821896 -247.800102) (xy 131.80578 -247.848376) (xy 131.782129 -247.893439)
			(xy 131.751556 -247.934125) (xy 131.714852 -247.96938) (xy 131.672968 -247.99829) (xy 131.626989 -248.020107)
			(xy 131.578105 -248.034267) (xy 131.527584 -248.040401) (xy 131.476732 -248.038352) (xy 131.426868 -248.028172)
			(xy 131.379282 -248.010125) (xy 131.335208 -247.984679) (xy 131.295786 -247.952492) (xy 131.262038 -247.914398)
			(xy 131.234837 -247.871384) (xy 131.214889 -247.824564) (xy 131.20271 -247.77515) (xy 131.198615 -247.724422)
			(xy 130.892804 -247.724422) (xy 130.892314 -247.749411) (xy 130.884495 -247.798774) (xy 130.869051 -247.846306)
			(xy 130.846361 -247.890838) (xy 130.816985 -247.931271) (xy 130.781645 -247.966611) (xy 130.741212 -247.995987)
			(xy 130.69668 -248.018677) (xy 130.649148 -248.034121) (xy 130.599785 -248.04194) (xy 130.549807 -248.04194)
			(xy 130.500444 -248.034121) (xy 130.452912 -248.018677) (xy 130.40838 -247.995987) (xy 130.367947 -247.966611)
			(xy 130.332607 -247.931271) (xy 130.303231 -247.890838) (xy 130.280541 -247.846306) (xy 130.265097 -247.798774)
			(xy 130.257278 -247.749411) (xy 129.949961 -247.749411) (xy 129.949952 -247.749868) (xy 129.941788 -247.800102)
			(xy 129.925672 -247.848376) (xy 129.902021 -247.893439) (xy 129.871448 -247.934125) (xy 129.834744 -247.96938)
			(xy 129.79286 -247.99829) (xy 129.746881 -248.020107) (xy 129.697997 -248.034267) (xy 129.647476 -248.040401)
			(xy 129.596624 -248.038352) (xy 129.54676 -248.028172) (xy 129.499174 -248.010125) (xy 129.4551 -247.984679)
			(xy 129.415678 -247.952492) (xy 129.38193 -247.914398) (xy 129.354729 -247.871384) (xy 129.334781 -247.824564)
			(xy 129.322602 -247.77515) (xy 129.318507 -247.724422) (xy 129.012696 -247.724422) (xy 129.012206 -247.749411)
			(xy 129.004387 -247.798774) (xy 128.988943 -247.846306) (xy 128.966253 -247.890838) (xy 128.936877 -247.931271)
			(xy 128.901537 -247.966611) (xy 128.861104 -247.995987) (xy 128.816572 -248.018677) (xy 128.76904 -248.034121)
			(xy 128.719677 -248.04194) (xy 128.669699 -248.04194) (xy 128.620336 -248.034121) (xy 128.572804 -248.018677)
			(xy 128.528272 -247.995987) (xy 128.487839 -247.966611) (xy 128.452499 -247.931271) (xy 128.423123 -247.890838)
			(xy 128.400433 -247.846306) (xy 128.384989 -247.798774) (xy 128.37717 -247.749411) (xy 128.069853 -247.749411)
			(xy 128.069844 -247.749868) (xy 128.06168 -247.800102) (xy 128.045564 -247.848376) (xy 128.021913 -247.893439)
			(xy 127.99134 -247.934125) (xy 127.954636 -247.96938) (xy 127.912752 -247.99829) (xy 127.866773 -248.020107)
			(xy 127.817889 -248.034267) (xy 127.767368 -248.040401) (xy 127.716516 -248.038352) (xy 127.666652 -248.028172)
			(xy 127.619066 -248.010125) (xy 127.574992 -247.984679) (xy 127.53557 -247.952492) (xy 127.501822 -247.914398)
			(xy 127.474621 -247.871384) (xy 127.454673 -247.824564) (xy 127.442494 -247.77515) (xy 127.438399 -247.724422)
			(xy 127.132296 -247.724422) (xy 127.132296 -247.749386) (xy 127.124479 -247.798742) (xy 127.109038 -247.846268)
			(xy 127.086353 -247.890794) (xy 127.056982 -247.931223) (xy 127.021649 -247.96656) (xy 126.981223 -247.995935)
			(xy 126.9367 -248.018625) (xy 126.889175 -248.034071) (xy 126.83982 -248.041893) (xy 126.814834 -248.04243)
			(xy 126.802206 -248.042282) (xy 126.777031 -248.040245) (xy 126.764542 -248.038366) (xy 126.75362 -248.036588)
			(xy 126.74346 -248.039382) (xy 126.738264 -248.041011) (xy 126.72866 -248.046137) (xy 126.72441 -248.049542)
			(xy 126.663958 -248.10085) (xy 126.657447 -248.107748) (xy 126.649486 -248.124948) (xy 126.648464 -248.134378)
			(xy 126.648464 -248.428764) (xy 126.648972 -248.435876) (xy 126.650496 -248.446798) (xy 126.656206 -248.468254)
			(xy 126.662326 -248.512228) (xy 126.662688 -248.534428) (xy 126.662371 -248.556694) (xy 126.661993 -248.559417)
			(xy 126.967216 -248.559417) (xy 126.967216 -248.509439) (xy 126.975035 -248.460076) (xy 126.990479 -248.412544)
			(xy 127.013169 -248.368012) (xy 127.042545 -248.327579) (xy 127.077885 -248.292239) (xy 127.118318 -248.262863)
			(xy 127.16285 -248.240173) (xy 127.210382 -248.224729) (xy 127.259745 -248.21691) (xy 127.309723 -248.21691)
			(xy 127.359086 -248.224729) (xy 127.406618 -248.240173) (xy 127.45115 -248.262863) (xy 127.491583 -248.292239)
			(xy 127.526923 -248.327579) (xy 127.556299 -248.368012) (xy 127.578989 -248.412544) (xy 127.594433 -248.460076)
			(xy 127.602252 -248.509439) (xy 127.602742 -248.534428) (xy 127.908553 -248.534428) (xy 127.912648 -248.4837)
			(xy 127.924827 -248.434286) (xy 127.944775 -248.387466) (xy 127.971976 -248.344452) (xy 128.005724 -248.306358)
			(xy 128.045146 -248.274171) (xy 128.08922 -248.248725) (xy 128.136806 -248.230678) (xy 128.18667 -248.220498)
			(xy 128.237522 -248.218449) (xy 128.288043 -248.224583) (xy 128.336927 -248.238743) (xy 128.382906 -248.26056)
			(xy 128.42479 -248.28947) (xy 128.461494 -248.324725) (xy 128.492067 -248.365411) (xy 128.515718 -248.410474)
			(xy 128.531834 -248.458748) (xy 128.539998 -248.508982) (xy 128.54051 -248.534428) (xy 128.848607 -248.534428)
			(xy 128.852702 -248.4837) (xy 128.864881 -248.434286) (xy 128.884829 -248.387466) (xy 128.91203 -248.344452)
			(xy 128.945778 -248.306358) (xy 128.9852 -248.274171) (xy 129.029274 -248.248725) (xy 129.07686 -248.230678)
			(xy 129.126724 -248.220498) (xy 129.177576 -248.218449) (xy 129.228097 -248.224583) (xy 129.276981 -248.238743)
			(xy 129.32296 -248.26056) (xy 129.364844 -248.28947) (xy 129.401548 -248.324725) (xy 129.432121 -248.365411)
			(xy 129.455772 -248.410474) (xy 129.471888 -248.458748) (xy 129.480052 -248.508982) (xy 129.480564 -248.534428)
			(xy 129.480061 -248.559417) (xy 129.787124 -248.559417) (xy 129.787124 -248.509439) (xy 129.794943 -248.460076)
			(xy 129.810387 -248.412544) (xy 129.833077 -248.368012) (xy 129.862453 -248.327579) (xy 129.897793 -248.292239)
			(xy 129.938226 -248.262863) (xy 129.982758 -248.240173) (xy 130.03029 -248.224729) (xy 130.079653 -248.21691)
			(xy 130.129631 -248.21691) (xy 130.178994 -248.224729) (xy 130.226526 -248.240173) (xy 130.271058 -248.262863)
			(xy 130.311491 -248.292239) (xy 130.346831 -248.327579) (xy 130.376207 -248.368012) (xy 130.398897 -248.412544)
			(xy 130.414341 -248.460076) (xy 130.42216 -248.509439) (xy 130.42265 -248.534428) (xy 130.728461 -248.534428)
			(xy 130.732556 -248.4837) (xy 130.744735 -248.434286) (xy 130.764683 -248.387466) (xy 130.791884 -248.344452)
			(xy 130.825632 -248.306358) (xy 130.865054 -248.274171) (xy 130.909128 -248.248725) (xy 130.956714 -248.230678)
			(xy 131.006578 -248.220498) (xy 131.05743 -248.218449) (xy 131.107951 -248.224583) (xy 131.156835 -248.238743)
			(xy 131.202814 -248.26056) (xy 131.244698 -248.28947) (xy 131.281402 -248.324725) (xy 131.311975 -248.365411)
			(xy 131.335626 -248.410474) (xy 131.351742 -248.458748) (xy 131.359906 -248.508982) (xy 131.360418 -248.534428)
			(xy 131.359915 -248.559417) (xy 131.667232 -248.559417) (xy 131.667232 -248.509439) (xy 131.675051 -248.460076)
			(xy 131.690495 -248.412544) (xy 131.713185 -248.368012) (xy 131.742561 -248.327579) (xy 131.777901 -248.292239)
			(xy 131.818334 -248.262863) (xy 131.862866 -248.240173) (xy 131.910398 -248.224729) (xy 131.959761 -248.21691)
			(xy 132.009739 -248.21691) (xy 132.059102 -248.224729) (xy 132.106634 -248.240173) (xy 132.151166 -248.262863)
			(xy 132.191599 -248.292239) (xy 132.226939 -248.327579) (xy 132.256315 -248.368012) (xy 132.279005 -248.412544)
			(xy 132.294449 -248.460076) (xy 132.302268 -248.509439) (xy 132.302758 -248.534428) (xy 132.608569 -248.534428)
			(xy 132.612664 -248.4837) (xy 132.624843 -248.434286) (xy 132.644791 -248.387466) (xy 132.671992 -248.344452)
			(xy 132.70574 -248.306358) (xy 132.745162 -248.274171) (xy 132.789236 -248.248725) (xy 132.836822 -248.230678)
			(xy 132.886686 -248.220498) (xy 132.937538 -248.218449) (xy 132.988059 -248.224583) (xy 133.036943 -248.238743)
			(xy 133.082922 -248.26056) (xy 133.124806 -248.28947) (xy 133.16151 -248.324725) (xy 133.192083 -248.365411)
			(xy 133.215734 -248.410474) (xy 133.23185 -248.458748) (xy 133.240014 -248.508982) (xy 133.240526 -248.534428)
			(xy 133.240023 -248.559417) (xy 133.54734 -248.559417) (xy 133.54734 -248.509439) (xy 133.555159 -248.460076)
			(xy 133.570603 -248.412544) (xy 133.593293 -248.368012) (xy 133.622669 -248.327579) (xy 133.658009 -248.292239)
			(xy 133.698442 -248.262863) (xy 133.742974 -248.240173) (xy 133.790506 -248.224729) (xy 133.839869 -248.21691)
			(xy 133.889847 -248.21691) (xy 133.93921 -248.224729) (xy 133.986742 -248.240173) (xy 134.031274 -248.262863)
			(xy 134.071707 -248.292239) (xy 134.107047 -248.327579) (xy 134.136423 -248.368012) (xy 134.159113 -248.412544)
			(xy 134.174557 -248.460076) (xy 134.182376 -248.509439) (xy 134.182866 -248.534428) (xy 134.488423 -248.534428)
			(xy 134.492518 -248.4837) (xy 134.504697 -248.434286) (xy 134.524645 -248.387466) (xy 134.551846 -248.344452)
			(xy 134.585594 -248.306358) (xy 134.625016 -248.274171) (xy 134.66909 -248.248725) (xy 134.716676 -248.230678)
			(xy 134.76654 -248.220498) (xy 134.817392 -248.218449) (xy 134.867913 -248.224583) (xy 134.916797 -248.238743)
			(xy 134.962776 -248.26056) (xy 135.00466 -248.28947) (xy 135.041364 -248.324725) (xy 135.071937 -248.365411)
			(xy 135.095588 -248.410474) (xy 135.111704 -248.458748) (xy 135.119868 -248.508982) (xy 135.12038 -248.534428)
			(xy 135.428477 -248.534428) (xy 135.432572 -248.4837) (xy 135.444751 -248.434286) (xy 135.464699 -248.387466)
			(xy 135.4919 -248.344452) (xy 135.525648 -248.306358) (xy 135.56507 -248.274171) (xy 135.609144 -248.248725)
			(xy 135.65673 -248.230678) (xy 135.706594 -248.220498) (xy 135.757446 -248.218449) (xy 135.807967 -248.224583)
			(xy 135.856851 -248.238743) (xy 135.90283 -248.26056) (xy 135.944714 -248.28947) (xy 135.981418 -248.324725)
			(xy 136.011991 -248.365411) (xy 136.035642 -248.410474) (xy 136.051758 -248.458748) (xy 136.059922 -248.508982)
			(xy 136.060434 -248.534428) (xy 136.059931 -248.559417) (xy 136.367248 -248.559417) (xy 136.367248 -248.509439)
			(xy 136.375067 -248.460076) (xy 136.390511 -248.412544) (xy 136.413201 -248.368012) (xy 136.442577 -248.327579)
			(xy 136.477917 -248.292239) (xy 136.51835 -248.262863) (xy 136.562882 -248.240173) (xy 136.610414 -248.224729)
			(xy 136.659777 -248.21691) (xy 136.709755 -248.21691) (xy 136.759118 -248.224729) (xy 136.80665 -248.240173)
			(xy 136.851182 -248.262863) (xy 136.891615 -248.292239) (xy 136.926955 -248.327579) (xy 136.956331 -248.368012)
			(xy 136.979021 -248.412544) (xy 136.994465 -248.460076) (xy 137.002284 -248.509439) (xy 137.002774 -248.534428)
			(xy 137.308585 -248.534428) (xy 137.31268 -248.4837) (xy 137.324859 -248.434286) (xy 137.344807 -248.387466)
			(xy 137.372008 -248.344452) (xy 137.405756 -248.306358) (xy 137.445178 -248.274171) (xy 137.489252 -248.248725)
			(xy 137.536838 -248.230678) (xy 137.586702 -248.220498) (xy 137.637554 -248.218449) (xy 137.688075 -248.224583)
			(xy 137.736959 -248.238743) (xy 137.782938 -248.26056) (xy 137.824822 -248.28947) (xy 137.861526 -248.324725)
			(xy 137.892099 -248.365411) (xy 137.91575 -248.410474) (xy 137.931866 -248.458748) (xy 137.94003 -248.508982)
			(xy 137.940542 -248.534428) (xy 137.940039 -248.559417) (xy 138.247356 -248.559417) (xy 138.247356 -248.509439)
			(xy 138.255175 -248.460076) (xy 138.270619 -248.412544) (xy 138.293309 -248.368012) (xy 138.322685 -248.327579)
			(xy 138.358025 -248.292239) (xy 138.398458 -248.262863) (xy 138.44299 -248.240173) (xy 138.490522 -248.224729)
			(xy 138.539885 -248.21691) (xy 138.589863 -248.21691) (xy 138.639226 -248.224729) (xy 138.686758 -248.240173)
			(xy 138.73129 -248.262863) (xy 138.771723 -248.292239) (xy 138.807063 -248.327579) (xy 138.836439 -248.368012)
			(xy 138.859129 -248.412544) (xy 138.874573 -248.460076) (xy 138.882392 -248.509439) (xy 138.882882 -248.534428)
			(xy 139.188439 -248.534428) (xy 139.192534 -248.4837) (xy 139.204713 -248.434286) (xy 139.224661 -248.387466)
			(xy 139.251862 -248.344452) (xy 139.28561 -248.306358) (xy 139.325032 -248.274171) (xy 139.369106 -248.248725)
			(xy 139.416692 -248.230678) (xy 139.466556 -248.220498) (xy 139.517408 -248.218449) (xy 139.567929 -248.224583)
			(xy 139.616813 -248.238743) (xy 139.662792 -248.26056) (xy 139.704676 -248.28947) (xy 139.74138 -248.324725)
			(xy 139.771953 -248.365411) (xy 139.795604 -248.410474) (xy 139.81172 -248.458748) (xy 139.819884 -248.508982)
			(xy 139.820396 -248.534428) (xy 139.819893 -248.559417) (xy 140.12721 -248.559417) (xy 140.12721 -248.509439)
			(xy 140.135029 -248.460076) (xy 140.150473 -248.412544) (xy 140.173163 -248.368012) (xy 140.202539 -248.327579)
			(xy 140.237879 -248.292239) (xy 140.278312 -248.262863) (xy 140.322844 -248.240173) (xy 140.370376 -248.224729)
			(xy 140.419739 -248.21691) (xy 140.469717 -248.21691) (xy 140.51908 -248.224729) (xy 140.566612 -248.240173)
			(xy 140.611144 -248.262863) (xy 140.651577 -248.292239) (xy 140.686917 -248.327579) (xy 140.716293 -248.368012)
			(xy 140.738983 -248.412544) (xy 140.754427 -248.460076) (xy 140.762246 -248.509439) (xy 140.762736 -248.534428)
			(xy 141.068547 -248.534428) (xy 141.072642 -248.4837) (xy 141.084821 -248.434286) (xy 141.104769 -248.387466)
			(xy 141.13197 -248.344452) (xy 141.165718 -248.306358) (xy 141.20514 -248.274171) (xy 141.249214 -248.248725)
			(xy 141.2968 -248.230678) (xy 141.346664 -248.220498) (xy 141.397516 -248.218449) (xy 141.448037 -248.224583)
			(xy 141.496921 -248.238743) (xy 141.5429 -248.26056) (xy 141.584784 -248.28947) (xy 141.621488 -248.324725)
			(xy 141.652061 -248.365411) (xy 141.675712 -248.410474) (xy 141.691828 -248.458748) (xy 141.699992 -248.508982)
			(xy 141.700504 -248.534428) (xy 142.008601 -248.534428) (xy 142.012696 -248.4837) (xy 142.024875 -248.434286)
			(xy 142.044823 -248.387466) (xy 142.072024 -248.344452) (xy 142.105772 -248.306358) (xy 142.145194 -248.274171)
			(xy 142.189268 -248.248725) (xy 142.236854 -248.230678) (xy 142.286718 -248.220498) (xy 142.33757 -248.218449)
			(xy 142.388091 -248.224583) (xy 142.436975 -248.238743) (xy 142.482954 -248.26056) (xy 142.524838 -248.28947)
			(xy 142.561542 -248.324725) (xy 142.592115 -248.365411) (xy 142.615766 -248.410474) (xy 142.631882 -248.458748)
			(xy 142.640046 -248.508982) (xy 142.640558 -248.534428) (xy 142.640055 -248.559417) (xy 142.947118 -248.559417)
			(xy 142.947118 -248.509439) (xy 142.954937 -248.460076) (xy 142.970381 -248.412544) (xy 142.993071 -248.368012)
			(xy 143.022447 -248.327579) (xy 143.057787 -248.292239) (xy 143.09822 -248.262863) (xy 143.142752 -248.240173)
			(xy 143.190284 -248.224729) (xy 143.239647 -248.21691) (xy 143.289625 -248.21691) (xy 143.338988 -248.224729)
			(xy 143.38652 -248.240173) (xy 143.431052 -248.262863) (xy 143.471485 -248.292239) (xy 143.506825 -248.327579)
			(xy 143.536201 -248.368012) (xy 143.558891 -248.412544) (xy 143.574335 -248.460076) (xy 143.582154 -248.509439)
			(xy 143.582644 -248.534428) (xy 143.582154 -248.559417) (xy 143.574335 -248.60878) (xy 143.558891 -248.656312)
			(xy 143.536201 -248.700844) (xy 143.506825 -248.741277) (xy 143.471485 -248.776617) (xy 143.431052 -248.805993)
			(xy 143.38652 -248.828683) (xy 143.338988 -248.844127) (xy 143.289625 -248.851946) (xy 143.239647 -248.851946)
			(xy 143.190284 -248.844127) (xy 143.142752 -248.828683) (xy 143.09822 -248.805993) (xy 143.057787 -248.776617)
			(xy 143.022447 -248.741277) (xy 142.993071 -248.700844) (xy 142.970381 -248.656312) (xy 142.954937 -248.60878)
			(xy 142.947118 -248.559417) (xy 142.640055 -248.559417) (xy 142.640046 -248.559874) (xy 142.631882 -248.610108)
			(xy 142.615766 -248.658382) (xy 142.592115 -248.703445) (xy 142.561542 -248.744131) (xy 142.524838 -248.779386)
			(xy 142.482954 -248.808296) (xy 142.436975 -248.830113) (xy 142.388091 -248.844273) (xy 142.33757 -248.850407)
			(xy 142.286718 -248.848358) (xy 142.236854 -248.838178) (xy 142.189268 -248.820131) (xy 142.145194 -248.794685)
			(xy 142.105772 -248.762498) (xy 142.072024 -248.724404) (xy 142.044823 -248.68139) (xy 142.024875 -248.63457)
			(xy 142.012696 -248.585156) (xy 142.008601 -248.534428) (xy 141.700504 -248.534428) (xy 141.699992 -248.559874)
			(xy 141.691828 -248.610108) (xy 141.675712 -248.658382) (xy 141.652061 -248.703445) (xy 141.621488 -248.744131)
			(xy 141.584784 -248.779386) (xy 141.5429 -248.808296) (xy 141.496921 -248.830113) (xy 141.448037 -248.844273)
			(xy 141.397516 -248.850407) (xy 141.346664 -248.848358) (xy 141.2968 -248.838178) (xy 141.249214 -248.820131)
			(xy 141.20514 -248.794685) (xy 141.165718 -248.762498) (xy 141.13197 -248.724404) (xy 141.104769 -248.68139)
			(xy 141.084821 -248.63457) (xy 141.072642 -248.585156) (xy 141.068547 -248.534428) (xy 140.762736 -248.534428)
			(xy 140.762246 -248.559417) (xy 140.754427 -248.60878) (xy 140.738983 -248.656312) (xy 140.716293 -248.700844)
			(xy 140.686917 -248.741277) (xy 140.651577 -248.776617) (xy 140.611144 -248.805993) (xy 140.566612 -248.828683)
			(xy 140.51908 -248.844127) (xy 140.469717 -248.851946) (xy 140.419739 -248.851946) (xy 140.370376 -248.844127)
			(xy 140.322844 -248.828683) (xy 140.278312 -248.805993) (xy 140.237879 -248.776617) (xy 140.202539 -248.741277)
			(xy 140.173163 -248.700844) (xy 140.150473 -248.656312) (xy 140.135029 -248.60878) (xy 140.12721 -248.559417)
			(xy 139.819893 -248.559417) (xy 139.819884 -248.559874) (xy 139.81172 -248.610108) (xy 139.795604 -248.658382)
			(xy 139.771953 -248.703445) (xy 139.74138 -248.744131) (xy 139.704676 -248.779386) (xy 139.662792 -248.808296)
			(xy 139.616813 -248.830113) (xy 139.567929 -248.844273) (xy 139.517408 -248.850407) (xy 139.466556 -248.848358)
			(xy 139.416692 -248.838178) (xy 139.369106 -248.820131) (xy 139.325032 -248.794685) (xy 139.28561 -248.762498)
			(xy 139.251862 -248.724404) (xy 139.224661 -248.68139) (xy 139.204713 -248.63457) (xy 139.192534 -248.585156)
			(xy 139.188439 -248.534428) (xy 138.882882 -248.534428) (xy 138.882392 -248.559417) (xy 138.874573 -248.60878)
			(xy 138.859129 -248.656312) (xy 138.836439 -248.700844) (xy 138.807063 -248.741277) (xy 138.771723 -248.776617)
			(xy 138.73129 -248.805993) (xy 138.686758 -248.828683) (xy 138.639226 -248.844127) (xy 138.589863 -248.851946)
			(xy 138.539885 -248.851946) (xy 138.490522 -248.844127) (xy 138.44299 -248.828683) (xy 138.398458 -248.805993)
			(xy 138.358025 -248.776617) (xy 138.322685 -248.741277) (xy 138.293309 -248.700844) (xy 138.270619 -248.656312)
			(xy 138.255175 -248.60878) (xy 138.247356 -248.559417) (xy 137.940039 -248.559417) (xy 137.94003 -248.559874)
			(xy 137.931866 -248.610108) (xy 137.91575 -248.658382) (xy 137.892099 -248.703445) (xy 137.861526 -248.744131)
			(xy 137.824822 -248.779386) (xy 137.782938 -248.808296) (xy 137.736959 -248.830113) (xy 137.688075 -248.844273)
			(xy 137.637554 -248.850407) (xy 137.586702 -248.848358) (xy 137.536838 -248.838178) (xy 137.489252 -248.820131)
			(xy 137.445178 -248.794685) (xy 137.405756 -248.762498) (xy 137.372008 -248.724404) (xy 137.344807 -248.68139)
			(xy 137.324859 -248.63457) (xy 137.31268 -248.585156) (xy 137.308585 -248.534428) (xy 137.002774 -248.534428)
			(xy 137.002284 -248.559417) (xy 136.994465 -248.60878) (xy 136.979021 -248.656312) (xy 136.956331 -248.700844)
			(xy 136.926955 -248.741277) (xy 136.891615 -248.776617) (xy 136.851182 -248.805993) (xy 136.80665 -248.828683)
			(xy 136.759118 -248.844127) (xy 136.709755 -248.851946) (xy 136.659777 -248.851946) (xy 136.610414 -248.844127)
			(xy 136.562882 -248.828683) (xy 136.51835 -248.805993) (xy 136.477917 -248.776617) (xy 136.442577 -248.741277)
			(xy 136.413201 -248.700844) (xy 136.390511 -248.656312) (xy 136.375067 -248.60878) (xy 136.367248 -248.559417)
			(xy 136.059931 -248.559417) (xy 136.059922 -248.559874) (xy 136.051758 -248.610108) (xy 136.035642 -248.658382)
			(xy 136.011991 -248.703445) (xy 135.981418 -248.744131) (xy 135.944714 -248.779386) (xy 135.90283 -248.808296)
			(xy 135.856851 -248.830113) (xy 135.807967 -248.844273) (xy 135.757446 -248.850407) (xy 135.706594 -248.848358)
			(xy 135.65673 -248.838178) (xy 135.609144 -248.820131) (xy 135.56507 -248.794685) (xy 135.525648 -248.762498)
			(xy 135.4919 -248.724404) (xy 135.464699 -248.68139) (xy 135.444751 -248.63457) (xy 135.432572 -248.585156)
			(xy 135.428477 -248.534428) (xy 135.12038 -248.534428) (xy 135.119868 -248.559874) (xy 135.111704 -248.610108)
			(xy 135.095588 -248.658382) (xy 135.071937 -248.703445) (xy 135.041364 -248.744131) (xy 135.00466 -248.779386)
			(xy 134.962776 -248.808296) (xy 134.916797 -248.830113) (xy 134.867913 -248.844273) (xy 134.817392 -248.850407)
			(xy 134.76654 -248.848358) (xy 134.716676 -248.838178) (xy 134.66909 -248.820131) (xy 134.625016 -248.794685)
			(xy 134.585594 -248.762498) (xy 134.551846 -248.724404) (xy 134.524645 -248.68139) (xy 134.504697 -248.63457)
			(xy 134.492518 -248.585156) (xy 134.488423 -248.534428) (xy 134.182866 -248.534428) (xy 134.182376 -248.559417)
			(xy 134.174557 -248.60878) (xy 134.159113 -248.656312) (xy 134.136423 -248.700844) (xy 134.107047 -248.741277)
			(xy 134.071707 -248.776617) (xy 134.031274 -248.805993) (xy 133.986742 -248.828683) (xy 133.93921 -248.844127)
			(xy 133.889847 -248.851946) (xy 133.839869 -248.851946) (xy 133.790506 -248.844127) (xy 133.742974 -248.828683)
			(xy 133.698442 -248.805993) (xy 133.658009 -248.776617) (xy 133.622669 -248.741277) (xy 133.593293 -248.700844)
			(xy 133.570603 -248.656312) (xy 133.555159 -248.60878) (xy 133.54734 -248.559417) (xy 133.240023 -248.559417)
			(xy 133.240014 -248.559874) (xy 133.23185 -248.610108) (xy 133.215734 -248.658382) (xy 133.192083 -248.703445)
			(xy 133.16151 -248.744131) (xy 133.124806 -248.779386) (xy 133.082922 -248.808296) (xy 133.036943 -248.830113)
			(xy 132.988059 -248.844273) (xy 132.937538 -248.850407) (xy 132.886686 -248.848358) (xy 132.836822 -248.838178)
			(xy 132.789236 -248.820131) (xy 132.745162 -248.794685) (xy 132.70574 -248.762498) (xy 132.671992 -248.724404)
			(xy 132.644791 -248.68139) (xy 132.624843 -248.63457) (xy 132.612664 -248.585156) (xy 132.608569 -248.534428)
			(xy 132.302758 -248.534428) (xy 132.302268 -248.559417) (xy 132.294449 -248.60878) (xy 132.279005 -248.656312)
			(xy 132.256315 -248.700844) (xy 132.226939 -248.741277) (xy 132.191599 -248.776617) (xy 132.151166 -248.805993)
			(xy 132.106634 -248.828683) (xy 132.059102 -248.844127) (xy 132.009739 -248.851946) (xy 131.959761 -248.851946)
			(xy 131.910398 -248.844127) (xy 131.862866 -248.828683) (xy 131.818334 -248.805993) (xy 131.777901 -248.776617)
			(xy 131.742561 -248.741277) (xy 131.713185 -248.700844) (xy 131.690495 -248.656312) (xy 131.675051 -248.60878)
			(xy 131.667232 -248.559417) (xy 131.359915 -248.559417) (xy 131.359906 -248.559874) (xy 131.351742 -248.610108)
			(xy 131.335626 -248.658382) (xy 131.311975 -248.703445) (xy 131.281402 -248.744131) (xy 131.244698 -248.779386)
			(xy 131.202814 -248.808296) (xy 131.156835 -248.830113) (xy 131.107951 -248.844273) (xy 131.05743 -248.850407)
			(xy 131.006578 -248.848358) (xy 130.956714 -248.838178) (xy 130.909128 -248.820131) (xy 130.865054 -248.794685)
			(xy 130.825632 -248.762498) (xy 130.791884 -248.724404) (xy 130.764683 -248.68139) (xy 130.744735 -248.63457)
			(xy 130.732556 -248.585156) (xy 130.728461 -248.534428) (xy 130.42265 -248.534428) (xy 130.42216 -248.559417)
			(xy 130.414341 -248.60878) (xy 130.398897 -248.656312) (xy 130.376207 -248.700844) (xy 130.346831 -248.741277)
			(xy 130.311491 -248.776617) (xy 130.271058 -248.805993) (xy 130.226526 -248.828683) (xy 130.178994 -248.844127)
			(xy 130.129631 -248.851946) (xy 130.079653 -248.851946) (xy 130.03029 -248.844127) (xy 129.982758 -248.828683)
			(xy 129.938226 -248.805993) (xy 129.897793 -248.776617) (xy 129.862453 -248.741277) (xy 129.833077 -248.700844)
			(xy 129.810387 -248.656312) (xy 129.794943 -248.60878) (xy 129.787124 -248.559417) (xy 129.480061 -248.559417)
			(xy 129.480052 -248.559874) (xy 129.471888 -248.610108) (xy 129.455772 -248.658382) (xy 129.432121 -248.703445)
			(xy 129.401548 -248.744131) (xy 129.364844 -248.779386) (xy 129.32296 -248.808296) (xy 129.276981 -248.830113)
			(xy 129.228097 -248.844273) (xy 129.177576 -248.850407) (xy 129.126724 -248.848358) (xy 129.07686 -248.838178)
			(xy 129.029274 -248.820131) (xy 128.9852 -248.794685) (xy 128.945778 -248.762498) (xy 128.91203 -248.724404)
			(xy 128.884829 -248.68139) (xy 128.864881 -248.63457) (xy 128.852702 -248.585156) (xy 128.848607 -248.534428)
			(xy 128.54051 -248.534428) (xy 128.539998 -248.559874) (xy 128.531834 -248.610108) (xy 128.515718 -248.658382)
			(xy 128.492067 -248.703445) (xy 128.461494 -248.744131) (xy 128.42479 -248.779386) (xy 128.382906 -248.808296)
			(xy 128.336927 -248.830113) (xy 128.288043 -248.844273) (xy 128.237522 -248.850407) (xy 128.18667 -248.848358)
			(xy 128.136806 -248.838178) (xy 128.08922 -248.820131) (xy 128.045146 -248.794685) (xy 128.005724 -248.762498)
			(xy 127.971976 -248.724404) (xy 127.944775 -248.68139) (xy 127.924827 -248.63457) (xy 127.912648 -248.585156)
			(xy 127.908553 -248.534428) (xy 127.602742 -248.534428) (xy 127.602252 -248.559417) (xy 127.594433 -248.60878)
			(xy 127.578989 -248.656312) (xy 127.556299 -248.700844) (xy 127.526923 -248.741277) (xy 127.491583 -248.776617)
			(xy 127.45115 -248.805993) (xy 127.406618 -248.828683) (xy 127.359086 -248.844127) (xy 127.309723 -248.851946)
			(xy 127.259745 -248.851946) (xy 127.210382 -248.844127) (xy 127.16285 -248.828683) (xy 127.118318 -248.805993)
			(xy 127.077885 -248.776617) (xy 127.042545 -248.741277) (xy 127.013169 -248.700844) (xy 126.990479 -248.656312)
			(xy 126.975035 -248.60878) (xy 126.967216 -248.559417) (xy 126.661993 -248.559417) (xy 126.656255 -248.600802)
			(xy 126.650496 -248.622312) (xy 126.648464 -248.62917) (xy 126.648464 -248.93143) (xy 126.648464 -248.934478)
			(xy 126.649418 -248.943927) (xy 126.657383 -248.961152) (xy 126.663958 -248.968006) (xy 126.72441 -249.019314)
			(xy 126.728649 -249.022734) (xy 126.738257 -249.027861) (xy 126.74346 -249.029474) (xy 126.75362 -249.032268)
			(xy 126.764542 -249.03049) (xy 126.777028 -249.02859) (xy 126.802205 -249.026553) (xy 126.814834 -249.026426)
			(xy 126.839819 -249.026919) (xy 126.889172 -249.03474) (xy 126.936695 -249.050186) (xy 126.981217 -249.072875)
			(xy 127.021641 -249.102249) (xy 127.056973 -249.137585) (xy 127.086343 -249.178012) (xy 127.109027 -249.222536)
			(xy 127.124467 -249.270061) (xy 127.132284 -249.319415) (xy 127.132284 -249.344434) (xy 127.438399 -249.344434)
			(xy 127.442494 -249.293706) (xy 127.454673 -249.244292) (xy 127.474621 -249.197472) (xy 127.501822 -249.154458)
			(xy 127.53557 -249.116364) (xy 127.574992 -249.084177) (xy 127.619066 -249.058731) (xy 127.666652 -249.040684)
			(xy 127.716516 -249.030504) (xy 127.767368 -249.028455) (xy 127.817889 -249.034589) (xy 127.866773 -249.048749)
			(xy 127.912752 -249.070566) (xy 127.954636 -249.099476) (xy 127.99134 -249.134731) (xy 128.021913 -249.175417)
			(xy 128.045564 -249.22048) (xy 128.06168 -249.268754) (xy 128.069844 -249.318988) (xy 128.070356 -249.344434)
			(xy 128.069853 -249.369423) (xy 128.37717 -249.369423) (xy 128.37717 -249.319445) (xy 128.384989 -249.270082)
			(xy 128.400433 -249.22255) (xy 128.423123 -249.178018) (xy 128.452499 -249.137585) (xy 128.487839 -249.102245)
			(xy 128.528272 -249.072869) (xy 128.572804 -249.050179) (xy 128.620336 -249.034735) (xy 128.669699 -249.026916)
			(xy 128.719677 -249.026916) (xy 128.76904 -249.034735) (xy 128.816572 -249.050179) (xy 128.861104 -249.072869)
			(xy 128.901537 -249.102245) (xy 128.936877 -249.137585) (xy 128.966253 -249.178018) (xy 128.988943 -249.22255)
			(xy 129.004387 -249.270082) (xy 129.012206 -249.319445) (xy 129.012696 -249.344434) (xy 129.012206 -249.369423)
			(xy 129.317224 -249.369423) (xy 129.317224 -249.319445) (xy 129.325043 -249.270082) (xy 129.340487 -249.22255)
			(xy 129.363177 -249.178018) (xy 129.392553 -249.137585) (xy 129.427893 -249.102245) (xy 129.468326 -249.072869)
			(xy 129.512858 -249.050179) (xy 129.56039 -249.034735) (xy 129.609753 -249.026916) (xy 129.659731 -249.026916)
			(xy 129.709094 -249.034735) (xy 129.756626 -249.050179) (xy 129.801158 -249.072869) (xy 129.841591 -249.102245)
			(xy 129.876931 -249.137585) (xy 129.906307 -249.178018) (xy 129.928997 -249.22255) (xy 129.944441 -249.270082)
			(xy 129.95226 -249.319445) (xy 129.95275 -249.344434) (xy 131.198615 -249.344434) (xy 131.20271 -249.293706)
			(xy 131.214889 -249.244292) (xy 131.234837 -249.197472) (xy 131.262038 -249.154458) (xy 131.295786 -249.116364)
			(xy 131.335208 -249.084177) (xy 131.379282 -249.058731) (xy 131.426868 -249.040684) (xy 131.476732 -249.030504)
			(xy 131.527584 -249.028455) (xy 131.578105 -249.034589) (xy 131.626989 -249.048749) (xy 131.672968 -249.070566)
			(xy 131.714852 -249.099476) (xy 131.751556 -249.134731) (xy 131.782129 -249.175417) (xy 131.80578 -249.22048)
			(xy 131.821896 -249.268754) (xy 131.83006 -249.318988) (xy 131.830572 -249.344434) (xy 131.830069 -249.369423)
			(xy 132.137132 -249.369423) (xy 132.137132 -249.319445) (xy 132.144951 -249.270082) (xy 132.160395 -249.22255)
			(xy 132.183085 -249.178018) (xy 132.212461 -249.137585) (xy 132.247801 -249.102245) (xy 132.288234 -249.072869)
			(xy 132.332766 -249.050179) (xy 132.380298 -249.034735) (xy 132.429661 -249.026916) (xy 132.479639 -249.026916)
			(xy 132.529002 -249.034735) (xy 132.576534 -249.050179) (xy 132.621066 -249.072869) (xy 132.661499 -249.102245)
			(xy 132.696839 -249.137585) (xy 132.726215 -249.178018) (xy 132.748905 -249.22255) (xy 132.764349 -249.270082)
			(xy 132.772168 -249.319445) (xy 132.772658 -249.344434) (xy 132.772168 -249.369423) (xy 133.077186 -249.369423)
			(xy 133.077186 -249.319445) (xy 133.085005 -249.270082) (xy 133.100449 -249.22255) (xy 133.123139 -249.178018)
			(xy 133.152515 -249.137585) (xy 133.187855 -249.102245) (xy 133.228288 -249.072869) (xy 133.27282 -249.050179)
			(xy 133.320352 -249.034735) (xy 133.369715 -249.026916) (xy 133.419693 -249.026916) (xy 133.469056 -249.034735)
			(xy 133.516588 -249.050179) (xy 133.56112 -249.072869) (xy 133.601553 -249.102245) (xy 133.636893 -249.137585)
			(xy 133.666269 -249.178018) (xy 133.688959 -249.22255) (xy 133.704403 -249.270082) (xy 133.712222 -249.319445)
			(xy 133.712712 -249.344434) (xy 134.018523 -249.344434) (xy 134.022618 -249.293706) (xy 134.034797 -249.244292)
			(xy 134.054745 -249.197472) (xy 134.081946 -249.154458) (xy 134.115694 -249.116364) (xy 134.155116 -249.084177)
			(xy 134.19919 -249.058731) (xy 134.246776 -249.040684) (xy 134.29664 -249.030504) (xy 134.347492 -249.028455)
			(xy 134.398013 -249.034589) (xy 134.446897 -249.048749) (xy 134.492876 -249.070566) (xy 134.53476 -249.099476)
			(xy 134.571464 -249.134731) (xy 134.602037 -249.175417) (xy 134.625688 -249.22048) (xy 134.641804 -249.268754)
			(xy 134.649968 -249.318988) (xy 134.65048 -249.344434) (xy 134.649977 -249.369423) (xy 134.957294 -249.369423)
			(xy 134.957294 -249.319445) (xy 134.965113 -249.270082) (xy 134.980557 -249.22255) (xy 135.003247 -249.178018)
			(xy 135.032623 -249.137585) (xy 135.067963 -249.102245) (xy 135.108396 -249.072869) (xy 135.152928 -249.050179)
			(xy 135.20046 -249.034735) (xy 135.249823 -249.026916) (xy 135.299801 -249.026916) (xy 135.349164 -249.034735)
			(xy 135.396696 -249.050179) (xy 135.441228 -249.072869) (xy 135.481661 -249.102245) (xy 135.517001 -249.137585)
			(xy 135.546377 -249.178018) (xy 135.569067 -249.22255) (xy 135.584511 -249.270082) (xy 135.59233 -249.319445)
			(xy 135.59282 -249.344434) (xy 135.59233 -249.369423) (xy 135.897348 -249.369423) (xy 135.897348 -249.319445)
			(xy 135.905167 -249.270082) (xy 135.920611 -249.22255) (xy 135.943301 -249.178018) (xy 135.972677 -249.137585)
			(xy 136.008017 -249.102245) (xy 136.04845 -249.072869) (xy 136.092982 -249.050179) (xy 136.140514 -249.034735)
			(xy 136.189877 -249.026916) (xy 136.239855 -249.026916) (xy 136.289218 -249.034735) (xy 136.33675 -249.050179)
			(xy 136.381282 -249.072869) (xy 136.421715 -249.102245) (xy 136.457055 -249.137585) (xy 136.486431 -249.178018)
			(xy 136.509121 -249.22255) (xy 136.524565 -249.270082) (xy 136.532384 -249.319445) (xy 136.532874 -249.344434)
			(xy 137.778485 -249.344434) (xy 137.78258 -249.293706) (xy 137.794759 -249.244292) (xy 137.814707 -249.197472)
			(xy 137.841908 -249.154458) (xy 137.875656 -249.116364) (xy 137.915078 -249.084177) (xy 137.959152 -249.058731)
			(xy 138.006738 -249.040684) (xy 138.056602 -249.030504) (xy 138.107454 -249.028455) (xy 138.157975 -249.034589)
			(xy 138.206859 -249.048749) (xy 138.252838 -249.070566) (xy 138.294722 -249.099476) (xy 138.331426 -249.134731)
			(xy 138.361999 -249.175417) (xy 138.38565 -249.22048) (xy 138.401766 -249.268754) (xy 138.40993 -249.318988)
			(xy 138.410442 -249.344434) (xy 138.409939 -249.369423) (xy 138.717256 -249.369423) (xy 138.717256 -249.319445)
			(xy 138.725075 -249.270082) (xy 138.740519 -249.22255) (xy 138.763209 -249.178018) (xy 138.792585 -249.137585)
			(xy 138.827925 -249.102245) (xy 138.868358 -249.072869) (xy 138.91289 -249.050179) (xy 138.960422 -249.034735)
			(xy 139.009785 -249.026916) (xy 139.059763 -249.026916) (xy 139.109126 -249.034735) (xy 139.156658 -249.050179)
			(xy 139.20119 -249.072869) (xy 139.241623 -249.102245) (xy 139.276963 -249.137585) (xy 139.306339 -249.178018)
			(xy 139.329029 -249.22255) (xy 139.344473 -249.270082) (xy 139.352292 -249.319445) (xy 139.352782 -249.344434)
			(xy 139.352292 -249.369423) (xy 139.65731 -249.369423) (xy 139.65731 -249.319445) (xy 139.665129 -249.270082)
			(xy 139.680573 -249.22255) (xy 139.703263 -249.178018) (xy 139.732639 -249.137585) (xy 139.767979 -249.102245)
			(xy 139.808412 -249.072869) (xy 139.852944 -249.050179) (xy 139.900476 -249.034735) (xy 139.949839 -249.026916)
			(xy 139.999817 -249.026916) (xy 140.04918 -249.034735) (xy 140.096712 -249.050179) (xy 140.141244 -249.072869)
			(xy 140.181677 -249.102245) (xy 140.217017 -249.137585) (xy 140.246393 -249.178018) (xy 140.269083 -249.22255)
			(xy 140.284527 -249.270082) (xy 140.292346 -249.319445) (xy 140.292836 -249.344434) (xy 140.598647 -249.344434)
			(xy 140.602742 -249.293706) (xy 140.614921 -249.244292) (xy 140.634869 -249.197472) (xy 140.66207 -249.154458)
			(xy 140.695818 -249.116364) (xy 140.73524 -249.084177) (xy 140.779314 -249.058731) (xy 140.8269 -249.040684)
			(xy 140.876764 -249.030504) (xy 140.927616 -249.028455) (xy 140.978137 -249.034589) (xy 141.027021 -249.048749)
			(xy 141.073 -249.070566) (xy 141.114884 -249.099476) (xy 141.151588 -249.134731) (xy 141.182161 -249.175417)
			(xy 141.205812 -249.22048) (xy 141.221928 -249.268754) (xy 141.230092 -249.318988) (xy 141.230604 -249.344434)
			(xy 141.230101 -249.369423) (xy 141.537164 -249.369423) (xy 141.537164 -249.319445) (xy 141.544983 -249.270082)
			(xy 141.560427 -249.22255) (xy 141.583117 -249.178018) (xy 141.612493 -249.137585) (xy 141.647833 -249.102245)
			(xy 141.688266 -249.072869) (xy 141.732798 -249.050179) (xy 141.78033 -249.034735) (xy 141.829693 -249.026916)
			(xy 141.879671 -249.026916) (xy 141.929034 -249.034735) (xy 141.976566 -249.050179) (xy 142.021098 -249.072869)
			(xy 142.061531 -249.102245) (xy 142.096871 -249.137585) (xy 142.126247 -249.178018) (xy 142.148937 -249.22255)
			(xy 142.164381 -249.270082) (xy 142.1722 -249.319445) (xy 142.17269 -249.344434) (xy 142.1722 -249.369423)
			(xy 142.477218 -249.369423) (xy 142.477218 -249.319445) (xy 142.485037 -249.270082) (xy 142.500481 -249.22255)
			(xy 142.523171 -249.178018) (xy 142.552547 -249.137585) (xy 142.587887 -249.102245) (xy 142.62832 -249.072869)
			(xy 142.672852 -249.050179) (xy 142.720384 -249.034735) (xy 142.769747 -249.026916) (xy 142.819725 -249.026916)
			(xy 142.869088 -249.034735) (xy 142.91662 -249.050179) (xy 142.961152 -249.072869) (xy 143.001585 -249.102245)
			(xy 143.036925 -249.137585) (xy 143.066301 -249.178018) (xy 143.088991 -249.22255) (xy 143.104435 -249.270082)
			(xy 143.112254 -249.319445) (xy 143.112744 -249.344434) (xy 143.112254 -249.369423) (xy 143.104435 -249.418786)
			(xy 143.088991 -249.466318) (xy 143.066301 -249.51085) (xy 143.036925 -249.551283) (xy 143.001585 -249.586623)
			(xy 142.961152 -249.615999) (xy 142.91662 -249.638689) (xy 142.869088 -249.654133) (xy 142.819725 -249.661952)
			(xy 142.769747 -249.661952) (xy 142.720384 -249.654133) (xy 142.672852 -249.638689) (xy 142.62832 -249.615999)
			(xy 142.587887 -249.586623) (xy 142.552547 -249.551283) (xy 142.523171 -249.51085) (xy 142.500481 -249.466318)
			(xy 142.485037 -249.418786) (xy 142.477218 -249.369423) (xy 142.1722 -249.369423) (xy 142.164381 -249.418786)
			(xy 142.148937 -249.466318) (xy 142.126247 -249.51085) (xy 142.096871 -249.551283) (xy 142.061531 -249.586623)
			(xy 142.021098 -249.615999) (xy 141.976566 -249.638689) (xy 141.929034 -249.654133) (xy 141.879671 -249.661952)
			(xy 141.829693 -249.661952) (xy 141.78033 -249.654133) (xy 141.732798 -249.638689) (xy 141.688266 -249.615999)
			(xy 141.647833 -249.586623) (xy 141.612493 -249.551283) (xy 141.583117 -249.51085) (xy 141.560427 -249.466318)
			(xy 141.544983 -249.418786) (xy 141.537164 -249.369423) (xy 141.230101 -249.369423) (xy 141.230092 -249.36988)
			(xy 141.221928 -249.420114) (xy 141.205812 -249.468388) (xy 141.182161 -249.513451) (xy 141.151588 -249.554137)
			(xy 141.114884 -249.589392) (xy 141.073 -249.618302) (xy 141.027021 -249.640119) (xy 140.978137 -249.654279)
			(xy 140.927616 -249.660413) (xy 140.876764 -249.658364) (xy 140.8269 -249.648184) (xy 140.779314 -249.630137)
			(xy 140.73524 -249.604691) (xy 140.695818 -249.572504) (xy 140.66207 -249.53441) (xy 140.634869 -249.491396)
			(xy 140.614921 -249.444576) (xy 140.602742 -249.395162) (xy 140.598647 -249.344434) (xy 140.292836 -249.344434)
			(xy 140.292346 -249.369423) (xy 140.284527 -249.418786) (xy 140.269083 -249.466318) (xy 140.246393 -249.51085)
			(xy 140.217017 -249.551283) (xy 140.181677 -249.586623) (xy 140.141244 -249.615999) (xy 140.096712 -249.638689)
			(xy 140.04918 -249.654133) (xy 139.999817 -249.661952) (xy 139.949839 -249.661952) (xy 139.900476 -249.654133)
			(xy 139.852944 -249.638689) (xy 139.808412 -249.615999) (xy 139.767979 -249.586623) (xy 139.732639 -249.551283)
			(xy 139.703263 -249.51085) (xy 139.680573 -249.466318) (xy 139.665129 -249.418786) (xy 139.65731 -249.369423)
			(xy 139.352292 -249.369423) (xy 139.344473 -249.418786) (xy 139.329029 -249.466318) (xy 139.306339 -249.51085)
			(xy 139.276963 -249.551283) (xy 139.241623 -249.586623) (xy 139.20119 -249.615999) (xy 139.156658 -249.638689)
			(xy 139.109126 -249.654133) (xy 139.059763 -249.661952) (xy 139.009785 -249.661952) (xy 138.960422 -249.654133)
			(xy 138.91289 -249.638689) (xy 138.868358 -249.615999) (xy 138.827925 -249.586623) (xy 138.792585 -249.551283)
			(xy 138.763209 -249.51085) (xy 138.740519 -249.466318) (xy 138.725075 -249.418786) (xy 138.717256 -249.369423)
			(xy 138.409939 -249.369423) (xy 138.40993 -249.36988) (xy 138.401766 -249.420114) (xy 138.38565 -249.468388)
			(xy 138.361999 -249.513451) (xy 138.331426 -249.554137) (xy 138.294722 -249.589392) (xy 138.252838 -249.618302)
			(xy 138.206859 -249.640119) (xy 138.157975 -249.654279) (xy 138.107454 -249.660413) (xy 138.056602 -249.658364)
			(xy 138.006738 -249.648184) (xy 137.959152 -249.630137) (xy 137.915078 -249.604691) (xy 137.875656 -249.572504)
			(xy 137.841908 -249.53441) (xy 137.814707 -249.491396) (xy 137.794759 -249.444576) (xy 137.78258 -249.395162)
			(xy 137.778485 -249.344434) (xy 136.532874 -249.344434) (xy 136.532384 -249.369423) (xy 136.524565 -249.418786)
			(xy 136.509121 -249.466318) (xy 136.486431 -249.51085) (xy 136.457055 -249.551283) (xy 136.421715 -249.586623)
			(xy 136.381282 -249.615999) (xy 136.33675 -249.638689) (xy 136.289218 -249.654133) (xy 136.239855 -249.661952)
			(xy 136.189877 -249.661952) (xy 136.140514 -249.654133) (xy 136.092982 -249.638689) (xy 136.04845 -249.615999)
			(xy 136.008017 -249.586623) (xy 135.972677 -249.551283) (xy 135.943301 -249.51085) (xy 135.920611 -249.466318)
			(xy 135.905167 -249.418786) (xy 135.897348 -249.369423) (xy 135.59233 -249.369423) (xy 135.584511 -249.418786)
			(xy 135.569067 -249.466318) (xy 135.546377 -249.51085) (xy 135.517001 -249.551283) (xy 135.481661 -249.586623)
			(xy 135.441228 -249.615999) (xy 135.396696 -249.638689) (xy 135.349164 -249.654133) (xy 135.299801 -249.661952)
			(xy 135.249823 -249.661952) (xy 135.20046 -249.654133) (xy 135.152928 -249.638689) (xy 135.108396 -249.615999)
			(xy 135.067963 -249.586623) (xy 135.032623 -249.551283) (xy 135.003247 -249.51085) (xy 134.980557 -249.466318)
			(xy 134.965113 -249.418786) (xy 134.957294 -249.369423) (xy 134.649977 -249.369423) (xy 134.649968 -249.36988)
			(xy 134.641804 -249.420114) (xy 134.625688 -249.468388) (xy 134.602037 -249.513451) (xy 134.571464 -249.554137)
			(xy 134.53476 -249.589392) (xy 134.492876 -249.618302) (xy 134.446897 -249.640119) (xy 134.398013 -249.654279)
			(xy 134.347492 -249.660413) (xy 134.29664 -249.658364) (xy 134.246776 -249.648184) (xy 134.19919 -249.630137)
			(xy 134.155116 -249.604691) (xy 134.115694 -249.572504) (xy 134.081946 -249.53441) (xy 134.054745 -249.491396)
			(xy 134.034797 -249.444576) (xy 134.022618 -249.395162) (xy 134.018523 -249.344434) (xy 133.712712 -249.344434)
			(xy 133.712222 -249.369423) (xy 133.704403 -249.418786) (xy 133.688959 -249.466318) (xy 133.666269 -249.51085)
			(xy 133.636893 -249.551283) (xy 133.601553 -249.586623) (xy 133.56112 -249.615999) (xy 133.516588 -249.638689)
			(xy 133.469056 -249.654133) (xy 133.419693 -249.661952) (xy 133.369715 -249.661952) (xy 133.320352 -249.654133)
			(xy 133.27282 -249.638689) (xy 133.228288 -249.615999) (xy 133.187855 -249.586623) (xy 133.152515 -249.551283)
			(xy 133.123139 -249.51085) (xy 133.100449 -249.466318) (xy 133.085005 -249.418786) (xy 133.077186 -249.369423)
			(xy 132.772168 -249.369423) (xy 132.764349 -249.418786) (xy 132.748905 -249.466318) (xy 132.726215 -249.51085)
			(xy 132.696839 -249.551283) (xy 132.661499 -249.586623) (xy 132.621066 -249.615999) (xy 132.576534 -249.638689)
			(xy 132.529002 -249.654133) (xy 132.479639 -249.661952) (xy 132.429661 -249.661952) (xy 132.380298 -249.654133)
			(xy 132.332766 -249.638689) (xy 132.288234 -249.615999) (xy 132.247801 -249.586623) (xy 132.212461 -249.551283)
			(xy 132.183085 -249.51085) (xy 132.160395 -249.466318) (xy 132.144951 -249.418786) (xy 132.137132 -249.369423)
			(xy 131.830069 -249.369423) (xy 131.83006 -249.36988) (xy 131.821896 -249.420114) (xy 131.80578 -249.468388)
			(xy 131.782129 -249.513451) (xy 131.751556 -249.554137) (xy 131.714852 -249.589392) (xy 131.672968 -249.618302)
			(xy 131.626989 -249.640119) (xy 131.578105 -249.654279) (xy 131.527584 -249.660413) (xy 131.476732 -249.658364)
			(xy 131.426868 -249.648184) (xy 131.379282 -249.630137) (xy 131.335208 -249.604691) (xy 131.295786 -249.572504)
			(xy 131.262038 -249.53441) (xy 131.234837 -249.491396) (xy 131.214889 -249.444576) (xy 131.20271 -249.395162)
			(xy 131.198615 -249.344434) (xy 129.95275 -249.344434) (xy 129.95226 -249.369423) (xy 129.944441 -249.418786)
			(xy 129.928997 -249.466318) (xy 129.906307 -249.51085) (xy 129.876931 -249.551283) (xy 129.841591 -249.586623)
			(xy 129.801158 -249.615999) (xy 129.756626 -249.638689) (xy 129.709094 -249.654133) (xy 129.659731 -249.661952)
			(xy 129.609753 -249.661952) (xy 129.56039 -249.654133) (xy 129.512858 -249.638689) (xy 129.468326 -249.615999)
			(xy 129.427893 -249.586623) (xy 129.392553 -249.551283) (xy 129.363177 -249.51085) (xy 129.340487 -249.466318)
			(xy 129.325043 -249.418786) (xy 129.317224 -249.369423) (xy 129.012206 -249.369423) (xy 129.004387 -249.418786)
			(xy 128.988943 -249.466318) (xy 128.966253 -249.51085) (xy 128.936877 -249.551283) (xy 128.901537 -249.586623)
			(xy 128.861104 -249.615999) (xy 128.816572 -249.638689) (xy 128.76904 -249.654133) (xy 128.719677 -249.661952)
			(xy 128.669699 -249.661952) (xy 128.620336 -249.654133) (xy 128.572804 -249.638689) (xy 128.528272 -249.615999)
			(xy 128.487839 -249.586623) (xy 128.452499 -249.551283) (xy 128.423123 -249.51085) (xy 128.400433 -249.466318)
			(xy 128.384989 -249.418786) (xy 128.37717 -249.369423) (xy 128.069853 -249.369423) (xy 128.069844 -249.36988)
			(xy 128.06168 -249.420114) (xy 128.045564 -249.468388) (xy 128.021913 -249.513451) (xy 127.99134 -249.554137)
			(xy 127.954636 -249.589392) (xy 127.912752 -249.618302) (xy 127.866773 -249.640119) (xy 127.817889 -249.654279)
			(xy 127.767368 -249.660413) (xy 127.716516 -249.658364) (xy 127.666652 -249.648184) (xy 127.619066 -249.630137)
			(xy 127.574992 -249.604691) (xy 127.53557 -249.572504) (xy 127.501822 -249.53441) (xy 127.474621 -249.491396)
			(xy 127.454673 -249.444576) (xy 127.442494 -249.395162) (xy 127.438399 -249.344434) (xy 127.132284 -249.344434)
			(xy 127.132284 -249.369385) (xy 127.124467 -249.418739) (xy 127.109027 -249.466264) (xy 127.086343 -249.510788)
			(xy 127.056973 -249.551215) (xy 127.021641 -249.586551) (xy 126.981217 -249.615925) (xy 126.936695 -249.638614)
			(xy 126.889172 -249.65406) (xy 126.839819 -249.661881) (xy 126.814834 -249.662442) (xy 126.8024 -249.662344)
			(xy 126.777607 -249.660434) (xy 126.765304 -249.658632) (xy 126.763526 -249.658378) (xy 126.75616 -249.65787)
			(xy 126.747781 -249.658297) (xy 126.731969 -249.663872) (xy 126.725172 -249.668792) (xy 126.706122 -249.684794)
			(xy 126.705614 -249.685302) (xy 126.666244 -249.719084) (xy 126.658713 -249.726151) (xy 126.649528 -249.744627)
			(xy 126.648464 -249.754898) (xy 126.648464 -250.052332) (xy 126.648972 -250.055888) (xy 126.650496 -250.06681)
			(xy 126.651004 -250.068842) (xy 126.651512 -250.070366) (xy 126.656771 -250.090984) (xy 126.662373 -250.133164)
			(xy 126.662688 -250.15444) (xy 127.908553 -250.15444) (xy 127.912648 -250.103712) (xy 127.924827 -250.054298)
			(xy 127.944775 -250.007478) (xy 127.971976 -249.964464) (xy 128.005724 -249.92637) (xy 128.045146 -249.894183)
			(xy 128.08922 -249.868737) (xy 128.136806 -249.85069) (xy 128.18667 -249.84051) (xy 128.237522 -249.838461)
			(xy 128.288043 -249.844595) (xy 128.336927 -249.858755) (xy 128.382906 -249.880572) (xy 128.42479 -249.909482)
			(xy 128.461494 -249.944737) (xy 128.492067 -249.985423) (xy 128.515718 -250.030486) (xy 128.531834 -250.07876)
			(xy 128.539998 -250.128994) (xy 128.54051 -250.15444) (xy 128.540007 -250.179429) (xy 128.847324 -250.179429)
			(xy 128.847324 -250.129451) (xy 128.855143 -250.080088) (xy 128.870587 -250.032556) (xy 128.893277 -249.988024)
			(xy 128.922653 -249.947591) (xy 128.957993 -249.912251) (xy 128.998426 -249.882875) (xy 129.042958 -249.860185)
			(xy 129.09049 -249.844741) (xy 129.139853 -249.836922) (xy 129.189831 -249.836922) (xy 129.239194 -249.844741)
			(xy 129.286726 -249.860185) (xy 129.331258 -249.882875) (xy 129.371691 -249.912251) (xy 129.407031 -249.947591)
			(xy 129.436407 -249.988024) (xy 129.459097 -250.032556) (xy 129.474541 -250.080088) (xy 129.48236 -250.129451)
			(xy 129.48285 -250.15444) (xy 129.48236 -250.179429) (xy 129.787124 -250.179429) (xy 129.787124 -250.129451)
			(xy 129.794943 -250.080088) (xy 129.810387 -250.032556) (xy 129.833077 -249.988024) (xy 129.862453 -249.947591)
			(xy 129.897793 -249.912251) (xy 129.938226 -249.882875) (xy 129.982758 -249.860185) (xy 130.03029 -249.844741)
			(xy 130.079653 -249.836922) (xy 130.129631 -249.836922) (xy 130.178994 -249.844741) (xy 130.226526 -249.860185)
			(xy 130.271058 -249.882875) (xy 130.311491 -249.912251) (xy 130.346831 -249.947591) (xy 130.376207 -249.988024)
			(xy 130.398897 -250.032556) (xy 130.414341 -250.080088) (xy 130.42216 -250.129451) (xy 130.42265 -250.15444)
			(xy 130.728461 -250.15444) (xy 130.732556 -250.103712) (xy 130.744735 -250.054298) (xy 130.764683 -250.007478)
			(xy 130.791884 -249.964464) (xy 130.825632 -249.92637) (xy 130.865054 -249.894183) (xy 130.909128 -249.868737)
			(xy 130.956714 -249.85069) (xy 131.006578 -249.84051) (xy 131.05743 -249.838461) (xy 131.107951 -249.844595)
			(xy 131.156835 -249.858755) (xy 131.202814 -249.880572) (xy 131.244698 -249.909482) (xy 131.281402 -249.944737)
			(xy 131.311975 -249.985423) (xy 131.335626 -250.030486) (xy 131.351742 -250.07876) (xy 131.359906 -250.128994)
			(xy 131.360418 -250.15444) (xy 131.359915 -250.179429) (xy 131.667232 -250.179429) (xy 131.667232 -250.129451)
			(xy 131.675051 -250.080088) (xy 131.690495 -250.032556) (xy 131.713185 -249.988024) (xy 131.742561 -249.947591)
			(xy 131.777901 -249.912251) (xy 131.818334 -249.882875) (xy 131.862866 -249.860185) (xy 131.910398 -249.844741)
			(xy 131.959761 -249.836922) (xy 132.009739 -249.836922) (xy 132.059102 -249.844741) (xy 132.106634 -249.860185)
			(xy 132.151166 -249.882875) (xy 132.191599 -249.912251) (xy 132.226939 -249.947591) (xy 132.256315 -249.988024)
			(xy 132.279005 -250.032556) (xy 132.294449 -250.080088) (xy 132.302268 -250.129451) (xy 132.302758 -250.15444)
			(xy 132.302268 -250.179429) (xy 132.607286 -250.179429) (xy 132.607286 -250.129451) (xy 132.615105 -250.080088)
			(xy 132.630549 -250.032556) (xy 132.653239 -249.988024) (xy 132.682615 -249.947591) (xy 132.717955 -249.912251)
			(xy 132.758388 -249.882875) (xy 132.80292 -249.860185) (xy 132.850452 -249.844741) (xy 132.899815 -249.836922)
			(xy 132.949793 -249.836922) (xy 132.999156 -249.844741) (xy 133.046688 -249.860185) (xy 133.09122 -249.882875)
			(xy 133.131653 -249.912251) (xy 133.166993 -249.947591) (xy 133.196369 -249.988024) (xy 133.219059 -250.032556)
			(xy 133.234503 -250.080088) (xy 133.242322 -250.129451) (xy 133.242812 -250.15444) (xy 133.242322 -250.179429)
			(xy 133.54734 -250.179429) (xy 133.54734 -250.129451) (xy 133.555159 -250.080088) (xy 133.570603 -250.032556)
			(xy 133.593293 -249.988024) (xy 133.622669 -249.947591) (xy 133.658009 -249.912251) (xy 133.698442 -249.882875)
			(xy 133.742974 -249.860185) (xy 133.790506 -249.844741) (xy 133.839869 -249.836922) (xy 133.889847 -249.836922)
			(xy 133.93921 -249.844741) (xy 133.986742 -249.860185) (xy 134.031274 -249.882875) (xy 134.071707 -249.912251)
			(xy 134.107047 -249.947591) (xy 134.136423 -249.988024) (xy 134.159113 -250.032556) (xy 134.174557 -250.080088)
			(xy 134.182376 -250.129451) (xy 134.182866 -250.15444) (xy 134.488423 -250.15444) (xy 134.492518 -250.103712)
			(xy 134.504697 -250.054298) (xy 134.524645 -250.007478) (xy 134.551846 -249.964464) (xy 134.585594 -249.92637)
			(xy 134.625016 -249.894183) (xy 134.66909 -249.868737) (xy 134.716676 -249.85069) (xy 134.76654 -249.84051)
			(xy 134.817392 -249.838461) (xy 134.867913 -249.844595) (xy 134.916797 -249.858755) (xy 134.962776 -249.880572)
			(xy 135.00466 -249.909482) (xy 135.041364 -249.944737) (xy 135.071937 -249.985423) (xy 135.095588 -250.030486)
			(xy 135.111704 -250.07876) (xy 135.119868 -250.128994) (xy 135.12038 -250.15444) (xy 135.119877 -250.179429)
			(xy 135.427194 -250.179429) (xy 135.427194 -250.129451) (xy 135.435013 -250.080088) (xy 135.450457 -250.032556)
			(xy 135.473147 -249.988024) (xy 135.502523 -249.947591) (xy 135.537863 -249.912251) (xy 135.578296 -249.882875)
			(xy 135.622828 -249.860185) (xy 135.67036 -249.844741) (xy 135.719723 -249.836922) (xy 135.769701 -249.836922)
			(xy 135.819064 -249.844741) (xy 135.866596 -249.860185) (xy 135.911128 -249.882875) (xy 135.951561 -249.912251)
			(xy 135.986901 -249.947591) (xy 136.016277 -249.988024) (xy 136.038967 -250.032556) (xy 136.054411 -250.080088)
			(xy 136.06223 -250.129451) (xy 136.06272 -250.15444) (xy 136.06223 -250.179429) (xy 136.367248 -250.179429)
			(xy 136.367248 -250.129451) (xy 136.375067 -250.080088) (xy 136.390511 -250.032556) (xy 136.413201 -249.988024)
			(xy 136.442577 -249.947591) (xy 136.477917 -249.912251) (xy 136.51835 -249.882875) (xy 136.562882 -249.860185)
			(xy 136.610414 -249.844741) (xy 136.659777 -249.836922) (xy 136.709755 -249.836922) (xy 136.759118 -249.844741)
			(xy 136.80665 -249.860185) (xy 136.851182 -249.882875) (xy 136.891615 -249.912251) (xy 136.926955 -249.947591)
			(xy 136.956331 -249.988024) (xy 136.979021 -250.032556) (xy 136.994465 -250.080088) (xy 137.002284 -250.129451)
			(xy 137.002774 -250.15444) (xy 137.308585 -250.15444) (xy 137.31268 -250.103712) (xy 137.324859 -250.054298)
			(xy 137.344807 -250.007478) (xy 137.372008 -249.964464) (xy 137.405756 -249.92637) (xy 137.445178 -249.894183)
			(xy 137.489252 -249.868737) (xy 137.536838 -249.85069) (xy 137.586702 -249.84051) (xy 137.637554 -249.838461)
			(xy 137.688075 -249.844595) (xy 137.736959 -249.858755) (xy 137.782938 -249.880572) (xy 137.824822 -249.909482)
			(xy 137.861526 -249.944737) (xy 137.892099 -249.985423) (xy 137.91575 -250.030486) (xy 137.931866 -250.07876)
			(xy 137.94003 -250.128994) (xy 137.940542 -250.15444) (xy 137.940039 -250.179429) (xy 138.247356 -250.179429)
			(xy 138.247356 -250.129451) (xy 138.255175 -250.080088) (xy 138.270619 -250.032556) (xy 138.293309 -249.988024)
			(xy 138.322685 -249.947591) (xy 138.358025 -249.912251) (xy 138.398458 -249.882875) (xy 138.44299 -249.860185)
			(xy 138.490522 -249.844741) (xy 138.539885 -249.836922) (xy 138.589863 -249.836922) (xy 138.639226 -249.844741)
			(xy 138.686758 -249.860185) (xy 138.73129 -249.882875) (xy 138.771723 -249.912251) (xy 138.807063 -249.947591)
			(xy 138.836439 -249.988024) (xy 138.859129 -250.032556) (xy 138.874573 -250.080088) (xy 138.882392 -250.129451)
			(xy 138.882882 -250.15444) (xy 138.882392 -250.179429) (xy 139.187156 -250.179429) (xy 139.187156 -250.129451)
			(xy 139.194975 -250.080088) (xy 139.210419 -250.032556) (xy 139.233109 -249.988024) (xy 139.262485 -249.947591)
			(xy 139.297825 -249.912251) (xy 139.338258 -249.882875) (xy 139.38279 -249.860185) (xy 139.430322 -249.844741)
			(xy 139.479685 -249.836922) (xy 139.529663 -249.836922) (xy 139.579026 -249.844741) (xy 139.626558 -249.860185)
			(xy 139.67109 -249.882875) (xy 139.711523 -249.912251) (xy 139.746863 -249.947591) (xy 139.776239 -249.988024)
			(xy 139.798929 -250.032556) (xy 139.814373 -250.080088) (xy 139.822192 -250.129451) (xy 139.822682 -250.15444)
			(xy 139.822192 -250.179429) (xy 140.12721 -250.179429) (xy 140.12721 -250.129451) (xy 140.135029 -250.080088)
			(xy 140.150473 -250.032556) (xy 140.173163 -249.988024) (xy 140.202539 -249.947591) (xy 140.237879 -249.912251)
			(xy 140.278312 -249.882875) (xy 140.322844 -249.860185) (xy 140.370376 -249.844741) (xy 140.419739 -249.836922)
			(xy 140.469717 -249.836922) (xy 140.51908 -249.844741) (xy 140.566612 -249.860185) (xy 140.611144 -249.882875)
			(xy 140.651577 -249.912251) (xy 140.686917 -249.947591) (xy 140.716293 -249.988024) (xy 140.738983 -250.032556)
			(xy 140.754427 -250.080088) (xy 140.762246 -250.129451) (xy 140.762736 -250.15444) (xy 141.068547 -250.15444)
			(xy 141.072642 -250.103712) (xy 141.084821 -250.054298) (xy 141.104769 -250.007478) (xy 141.13197 -249.964464)
			(xy 141.165718 -249.92637) (xy 141.20514 -249.894183) (xy 141.249214 -249.868737) (xy 141.2968 -249.85069)
			(xy 141.346664 -249.84051) (xy 141.397516 -249.838461) (xy 141.448037 -249.844595) (xy 141.496921 -249.858755)
			(xy 141.5429 -249.880572) (xy 141.584784 -249.909482) (xy 141.621488 -249.944737) (xy 141.652061 -249.985423)
			(xy 141.675712 -250.030486) (xy 141.691828 -250.07876) (xy 141.699992 -250.128994) (xy 141.700504 -250.15444)
			(xy 141.700001 -250.179429) (xy 142.007318 -250.179429) (xy 142.007318 -250.129451) (xy 142.015137 -250.080088)
			(xy 142.030581 -250.032556) (xy 142.053271 -249.988024) (xy 142.082647 -249.947591) (xy 142.117987 -249.912251)
			(xy 142.15842 -249.882875) (xy 142.202952 -249.860185) (xy 142.250484 -249.844741) (xy 142.299847 -249.836922)
			(xy 142.349825 -249.836922) (xy 142.399188 -249.844741) (xy 142.44672 -249.860185) (xy 142.491252 -249.882875)
			(xy 142.531685 -249.912251) (xy 142.567025 -249.947591) (xy 142.596401 -249.988024) (xy 142.619091 -250.032556)
			(xy 142.634535 -250.080088) (xy 142.642354 -250.129451) (xy 142.642844 -250.15444) (xy 142.642354 -250.179429)
			(xy 142.947118 -250.179429) (xy 142.947118 -250.129451) (xy 142.954937 -250.080088) (xy 142.970381 -250.032556)
			(xy 142.993071 -249.988024) (xy 143.022447 -249.947591) (xy 143.057787 -249.912251) (xy 143.09822 -249.882875)
			(xy 143.142752 -249.860185) (xy 143.190284 -249.844741) (xy 143.239647 -249.836922) (xy 143.289625 -249.836922)
			(xy 143.338988 -249.844741) (xy 143.38652 -249.860185) (xy 143.431052 -249.882875) (xy 143.471485 -249.912251)
			(xy 143.506825 -249.947591) (xy 143.536201 -249.988024) (xy 143.558891 -250.032556) (xy 143.574335 -250.080088)
			(xy 143.582154 -250.129451) (xy 143.582644 -250.15444) (xy 143.582154 -250.179429) (xy 143.887172 -250.179429)
			(xy 143.887172 -250.129451) (xy 143.894991 -250.080088) (xy 143.910435 -250.032556) (xy 143.933125 -249.988024)
			(xy 143.962501 -249.947591) (xy 143.997841 -249.912251) (xy 144.038274 -249.882875) (xy 144.082806 -249.860185)
			(xy 144.130338 -249.844741) (xy 144.179701 -249.836922) (xy 144.229679 -249.836922) (xy 144.279042 -249.844741)
			(xy 144.326574 -249.860185) (xy 144.371106 -249.882875) (xy 144.411539 -249.912251) (xy 144.446879 -249.947591)
			(xy 144.476255 -249.988024) (xy 144.498945 -250.032556) (xy 144.514389 -250.080088) (xy 144.522208 -250.129451)
			(xy 144.522698 -250.15444) (xy 144.522208 -250.179429) (xy 144.514389 -250.228792) (xy 144.498945 -250.276324)
			(xy 144.476255 -250.320856) (xy 144.446879 -250.361289) (xy 144.411539 -250.396629) (xy 144.371106 -250.426005)
			(xy 144.326574 -250.448695) (xy 144.279042 -250.464139) (xy 144.229679 -250.471958) (xy 144.179701 -250.471958)
			(xy 144.130338 -250.464139) (xy 144.082806 -250.448695) (xy 144.038274 -250.426005) (xy 143.997841 -250.396629)
			(xy 143.962501 -250.361289) (xy 143.933125 -250.320856) (xy 143.910435 -250.276324) (xy 143.894991 -250.228792)
			(xy 143.887172 -250.179429) (xy 143.582154 -250.179429) (xy 143.574335 -250.228792) (xy 143.558891 -250.276324)
			(xy 143.536201 -250.320856) (xy 143.506825 -250.361289) (xy 143.471485 -250.396629) (xy 143.431052 -250.426005)
			(xy 143.38652 -250.448695) (xy 143.338988 -250.464139) (xy 143.289625 -250.471958) (xy 143.239647 -250.471958)
			(xy 143.190284 -250.464139) (xy 143.142752 -250.448695) (xy 143.09822 -250.426005) (xy 143.057787 -250.396629)
			(xy 143.022447 -250.361289) (xy 142.993071 -250.320856) (xy 142.970381 -250.276324) (xy 142.954937 -250.228792)
			(xy 142.947118 -250.179429) (xy 142.642354 -250.179429) (xy 142.634535 -250.228792) (xy 142.619091 -250.276324)
			(xy 142.596401 -250.320856) (xy 142.567025 -250.361289) (xy 142.531685 -250.396629) (xy 142.491252 -250.426005)
			(xy 142.44672 -250.448695) (xy 142.399188 -250.464139) (xy 142.349825 -250.471958) (xy 142.299847 -250.471958)
			(xy 142.250484 -250.464139) (xy 142.202952 -250.448695) (xy 142.15842 -250.426005) (xy 142.117987 -250.396629)
			(xy 142.082647 -250.361289) (xy 142.053271 -250.320856) (xy 142.030581 -250.276324) (xy 142.015137 -250.228792)
			(xy 142.007318 -250.179429) (xy 141.700001 -250.179429) (xy 141.699992 -250.179886) (xy 141.691828 -250.23012)
			(xy 141.675712 -250.278394) (xy 141.652061 -250.323457) (xy 141.621488 -250.364143) (xy 141.584784 -250.399398)
			(xy 141.5429 -250.428308) (xy 141.496921 -250.450125) (xy 141.448037 -250.464285) (xy 141.397516 -250.470419)
			(xy 141.346664 -250.46837) (xy 141.2968 -250.45819) (xy 141.249214 -250.440143) (xy 141.20514 -250.414697)
			(xy 141.165718 -250.38251) (xy 141.13197 -250.344416) (xy 141.104769 -250.301402) (xy 141.084821 -250.254582)
			(xy 141.072642 -250.205168) (xy 141.068547 -250.15444) (xy 140.762736 -250.15444) (xy 140.762246 -250.179429)
			(xy 140.754427 -250.228792) (xy 140.738983 -250.276324) (xy 140.716293 -250.320856) (xy 140.686917 -250.361289)
			(xy 140.651577 -250.396629) (xy 140.611144 -250.426005) (xy 140.566612 -250.448695) (xy 140.51908 -250.464139)
			(xy 140.469717 -250.471958) (xy 140.419739 -250.471958) (xy 140.370376 -250.464139) (xy 140.322844 -250.448695)
			(xy 140.278312 -250.426005) (xy 140.237879 -250.396629) (xy 140.202539 -250.361289) (xy 140.173163 -250.320856)
			(xy 140.150473 -250.276324) (xy 140.135029 -250.228792) (xy 140.12721 -250.179429) (xy 139.822192 -250.179429)
			(xy 139.814373 -250.228792) (xy 139.798929 -250.276324) (xy 139.776239 -250.320856) (xy 139.746863 -250.361289)
			(xy 139.711523 -250.396629) (xy 139.67109 -250.426005) (xy 139.626558 -250.448695) (xy 139.579026 -250.464139)
			(xy 139.529663 -250.471958) (xy 139.479685 -250.471958) (xy 139.430322 -250.464139) (xy 139.38279 -250.448695)
			(xy 139.338258 -250.426005) (xy 139.297825 -250.396629) (xy 139.262485 -250.361289) (xy 139.233109 -250.320856)
			(xy 139.210419 -250.276324) (xy 139.194975 -250.228792) (xy 139.187156 -250.179429) (xy 138.882392 -250.179429)
			(xy 138.874573 -250.228792) (xy 138.859129 -250.276324) (xy 138.836439 -250.320856) (xy 138.807063 -250.361289)
			(xy 138.771723 -250.396629) (xy 138.73129 -250.426005) (xy 138.686758 -250.448695) (xy 138.639226 -250.464139)
			(xy 138.589863 -250.471958) (xy 138.539885 -250.471958) (xy 138.490522 -250.464139) (xy 138.44299 -250.448695)
			(xy 138.398458 -250.426005) (xy 138.358025 -250.396629) (xy 138.322685 -250.361289) (xy 138.293309 -250.320856)
			(xy 138.270619 -250.276324) (xy 138.255175 -250.228792) (xy 138.247356 -250.179429) (xy 137.940039 -250.179429)
			(xy 137.94003 -250.179886) (xy 137.931866 -250.23012) (xy 137.91575 -250.278394) (xy 137.892099 -250.323457)
			(xy 137.861526 -250.364143) (xy 137.824822 -250.399398) (xy 137.782938 -250.428308) (xy 137.736959 -250.450125)
			(xy 137.688075 -250.464285) (xy 137.637554 -250.470419) (xy 137.586702 -250.46837) (xy 137.536838 -250.45819)
			(xy 137.489252 -250.440143) (xy 137.445178 -250.414697) (xy 137.405756 -250.38251) (xy 137.372008 -250.344416)
			(xy 137.344807 -250.301402) (xy 137.324859 -250.254582) (xy 137.31268 -250.205168) (xy 137.308585 -250.15444)
			(xy 137.002774 -250.15444) (xy 137.002284 -250.179429) (xy 136.994465 -250.228792) (xy 136.979021 -250.276324)
			(xy 136.956331 -250.320856) (xy 136.926955 -250.361289) (xy 136.891615 -250.396629) (xy 136.851182 -250.426005)
			(xy 136.80665 -250.448695) (xy 136.759118 -250.464139) (xy 136.709755 -250.471958) (xy 136.659777 -250.471958)
			(xy 136.610414 -250.464139) (xy 136.562882 -250.448695) (xy 136.51835 -250.426005) (xy 136.477917 -250.396629)
			(xy 136.442577 -250.361289) (xy 136.413201 -250.320856) (xy 136.390511 -250.276324) (xy 136.375067 -250.228792)
			(xy 136.367248 -250.179429) (xy 136.06223 -250.179429) (xy 136.054411 -250.228792) (xy 136.038967 -250.276324)
			(xy 136.016277 -250.320856) (xy 135.986901 -250.361289) (xy 135.951561 -250.396629) (xy 135.911128 -250.426005)
			(xy 135.866596 -250.448695) (xy 135.819064 -250.464139) (xy 135.769701 -250.471958) (xy 135.719723 -250.471958)
			(xy 135.67036 -250.464139) (xy 135.622828 -250.448695) (xy 135.578296 -250.426005) (xy 135.537863 -250.396629)
			(xy 135.502523 -250.361289) (xy 135.473147 -250.320856) (xy 135.450457 -250.276324) (xy 135.435013 -250.228792)
			(xy 135.427194 -250.179429) (xy 135.119877 -250.179429) (xy 135.119868 -250.179886) (xy 135.111704 -250.23012)
			(xy 135.095588 -250.278394) (xy 135.071937 -250.323457) (xy 135.041364 -250.364143) (xy 135.00466 -250.399398)
			(xy 134.962776 -250.428308) (xy 134.916797 -250.450125) (xy 134.867913 -250.464285) (xy 134.817392 -250.470419)
			(xy 134.76654 -250.46837) (xy 134.716676 -250.45819) (xy 134.66909 -250.440143) (xy 134.625016 -250.414697)
			(xy 134.585594 -250.38251) (xy 134.551846 -250.344416) (xy 134.524645 -250.301402) (xy 134.504697 -250.254582)
			(xy 134.492518 -250.205168) (xy 134.488423 -250.15444) (xy 134.182866 -250.15444) (xy 134.182376 -250.179429)
			(xy 134.174557 -250.228792) (xy 134.159113 -250.276324) (xy 134.136423 -250.320856) (xy 134.107047 -250.361289)
			(xy 134.071707 -250.396629) (xy 134.031274 -250.426005) (xy 133.986742 -250.448695) (xy 133.93921 -250.464139)
			(xy 133.889847 -250.471958) (xy 133.839869 -250.471958) (xy 133.790506 -250.464139) (xy 133.742974 -250.448695)
			(xy 133.698442 -250.426005) (xy 133.658009 -250.396629) (xy 133.622669 -250.361289) (xy 133.593293 -250.320856)
			(xy 133.570603 -250.276324) (xy 133.555159 -250.228792) (xy 133.54734 -250.179429) (xy 133.242322 -250.179429)
			(xy 133.234503 -250.228792) (xy 133.219059 -250.276324) (xy 133.196369 -250.320856) (xy 133.166993 -250.361289)
			(xy 133.131653 -250.396629) (xy 133.09122 -250.426005) (xy 133.046688 -250.448695) (xy 132.999156 -250.464139)
			(xy 132.949793 -250.471958) (xy 132.899815 -250.471958) (xy 132.850452 -250.464139) (xy 132.80292 -250.448695)
			(xy 132.758388 -250.426005) (xy 132.717955 -250.396629) (xy 132.682615 -250.361289) (xy 132.653239 -250.320856)
			(xy 132.630549 -250.276324) (xy 132.615105 -250.228792) (xy 132.607286 -250.179429) (xy 132.302268 -250.179429)
			(xy 132.294449 -250.228792) (xy 132.279005 -250.276324) (xy 132.256315 -250.320856) (xy 132.226939 -250.361289)
			(xy 132.191599 -250.396629) (xy 132.151166 -250.426005) (xy 132.106634 -250.448695) (xy 132.059102 -250.464139)
			(xy 132.009739 -250.471958) (xy 131.959761 -250.471958) (xy 131.910398 -250.464139) (xy 131.862866 -250.448695)
			(xy 131.818334 -250.426005) (xy 131.777901 -250.396629) (xy 131.742561 -250.361289) (xy 131.713185 -250.320856)
			(xy 131.690495 -250.276324) (xy 131.675051 -250.228792) (xy 131.667232 -250.179429) (xy 131.359915 -250.179429)
			(xy 131.359906 -250.179886) (xy 131.351742 -250.23012) (xy 131.335626 -250.278394) (xy 131.311975 -250.323457)
			(xy 131.281402 -250.364143) (xy 131.244698 -250.399398) (xy 131.202814 -250.428308) (xy 131.156835 -250.450125)
			(xy 131.107951 -250.464285) (xy 131.05743 -250.470419) (xy 131.006578 -250.46837) (xy 130.956714 -250.45819)
			(xy 130.909128 -250.440143) (xy 130.865054 -250.414697) (xy 130.825632 -250.38251) (xy 130.791884 -250.344416)
			(xy 130.764683 -250.301402) (xy 130.744735 -250.254582) (xy 130.732556 -250.205168) (xy 130.728461 -250.15444)
			(xy 130.42265 -250.15444) (xy 130.42216 -250.179429) (xy 130.414341 -250.228792) (xy 130.398897 -250.276324)
			(xy 130.376207 -250.320856) (xy 130.346831 -250.361289) (xy 130.311491 -250.396629) (xy 130.271058 -250.426005)
			(xy 130.226526 -250.448695) (xy 130.178994 -250.464139) (xy 130.129631 -250.471958) (xy 130.079653 -250.471958)
			(xy 130.03029 -250.464139) (xy 129.982758 -250.448695) (xy 129.938226 -250.426005) (xy 129.897793 -250.396629)
			(xy 129.862453 -250.361289) (xy 129.833077 -250.320856) (xy 129.810387 -250.276324) (xy 129.794943 -250.228792)
			(xy 129.787124 -250.179429) (xy 129.48236 -250.179429) (xy 129.474541 -250.228792) (xy 129.459097 -250.276324)
			(xy 129.436407 -250.320856) (xy 129.407031 -250.361289) (xy 129.371691 -250.396629) (xy 129.331258 -250.426005)
			(xy 129.286726 -250.448695) (xy 129.239194 -250.464139) (xy 129.189831 -250.471958) (xy 129.139853 -250.471958)
			(xy 129.09049 -250.464139) (xy 129.042958 -250.448695) (xy 128.998426 -250.426005) (xy 128.957993 -250.396629)
			(xy 128.922653 -250.361289) (xy 128.893277 -250.320856) (xy 128.870587 -250.276324) (xy 128.855143 -250.228792)
			(xy 128.847324 -250.179429) (xy 128.540007 -250.179429) (xy 128.539998 -250.179886) (xy 128.531834 -250.23012)
			(xy 128.515718 -250.278394) (xy 128.492067 -250.323457) (xy 128.461494 -250.364143) (xy 128.42479 -250.399398)
			(xy 128.382906 -250.428308) (xy 128.336927 -250.450125) (xy 128.288043 -250.464285) (xy 128.237522 -250.470419)
			(xy 128.18667 -250.46837) (xy 128.136806 -250.45819) (xy 128.08922 -250.440143) (xy 128.045146 -250.414697)
			(xy 128.005724 -250.38251) (xy 127.971976 -250.344416) (xy 127.944775 -250.301402) (xy 127.924827 -250.254582)
			(xy 127.912648 -250.205168) (xy 127.908553 -250.15444) (xy 126.662688 -250.15444) (xy 126.662434 -250.168156)
			(xy 126.661375 -250.186958) (xy 126.655396 -250.224141) (xy 126.650496 -250.242324) (xy 126.648464 -250.249182)
			(xy 126.648464 -250.49099) (xy 126.647926 -250.500827) (xy 126.640341 -250.518989) (xy 126.633732 -250.526296)
			(xy 126.536196 -250.623832) (xy 126.528957 -250.630544) (xy 126.510753 -250.638138) (xy 126.50089 -250.638564)
			(xy 125.653038 -250.638564) (xy 125.643199 -250.639098) (xy 125.625033 -250.646679) (xy 125.617732 -250.653296)
			(xy 125.520196 -250.750832) (xy 125.513485 -250.758071) (xy 125.505897 -250.776276) (xy 125.505464 -250.786138)
			(xy 125.505464 -250.989435) (xy 126.497316 -250.989435) (xy 126.497316 -250.939457) (xy 126.505135 -250.890094)
			(xy 126.520579 -250.842562) (xy 126.543269 -250.79803) (xy 126.572645 -250.757597) (xy 126.607985 -250.722257)
			(xy 126.648418 -250.692881) (xy 126.69295 -250.670191) (xy 126.740482 -250.654747) (xy 126.789845 -250.646928)
			(xy 126.839823 -250.646928) (xy 126.889186 -250.654747) (xy 126.936718 -250.670191) (xy 126.98125 -250.692881)
			(xy 127.021683 -250.722257) (xy 127.057023 -250.757597) (xy 127.086399 -250.79803) (xy 127.109089 -250.842562)
			(xy 127.124533 -250.890094) (xy 127.132352 -250.939457) (xy 127.132842 -250.964446) (xy 127.438399 -250.964446)
			(xy 127.442494 -250.913718) (xy 127.454673 -250.864304) (xy 127.474621 -250.817484) (xy 127.501822 -250.77447)
			(xy 127.53557 -250.736376) (xy 127.574992 -250.704189) (xy 127.619066 -250.678743) (xy 127.666652 -250.660696)
			(xy 127.716516 -250.650516) (xy 127.767368 -250.648467) (xy 127.817889 -250.654601) (xy 127.866773 -250.668761)
			(xy 127.912752 -250.690578) (xy 127.954636 -250.719488) (xy 127.99134 -250.754743) (xy 128.021913 -250.795429)
			(xy 128.045564 -250.840492) (xy 128.06168 -250.888766) (xy 128.069844 -250.939) (xy 128.070356 -250.964446)
			(xy 128.069853 -250.989435) (xy 128.37717 -250.989435) (xy 128.37717 -250.939457) (xy 128.384989 -250.890094)
			(xy 128.400433 -250.842562) (xy 128.423123 -250.79803) (xy 128.452499 -250.757597) (xy 128.487839 -250.722257)
			(xy 128.528272 -250.692881) (xy 128.572804 -250.670191) (xy 128.620336 -250.654747) (xy 128.669699 -250.646928)
			(xy 128.719677 -250.646928) (xy 128.76904 -250.654747) (xy 128.816572 -250.670191) (xy 128.861104 -250.692881)
			(xy 128.901537 -250.722257) (xy 128.936877 -250.757597) (xy 128.966253 -250.79803) (xy 128.988943 -250.842562)
			(xy 129.004387 -250.890094) (xy 129.012206 -250.939457) (xy 129.012696 -250.964446) (xy 129.318507 -250.964446)
			(xy 129.322602 -250.913718) (xy 129.334781 -250.864304) (xy 129.354729 -250.817484) (xy 129.38193 -250.77447)
			(xy 129.415678 -250.736376) (xy 129.4551 -250.704189) (xy 129.499174 -250.678743) (xy 129.54676 -250.660696)
			(xy 129.596624 -250.650516) (xy 129.647476 -250.648467) (xy 129.697997 -250.654601) (xy 129.746881 -250.668761)
			(xy 129.79286 -250.690578) (xy 129.834744 -250.719488) (xy 129.871448 -250.754743) (xy 129.902021 -250.795429)
			(xy 129.925672 -250.840492) (xy 129.941788 -250.888766) (xy 129.949952 -250.939) (xy 129.950464 -250.964446)
			(xy 129.949961 -250.989435) (xy 130.257278 -250.989435) (xy 130.257278 -250.939457) (xy 130.265097 -250.890094)
			(xy 130.280541 -250.842562) (xy 130.303231 -250.79803) (xy 130.332607 -250.757597) (xy 130.367947 -250.722257)
			(xy 130.40838 -250.692881) (xy 130.452912 -250.670191) (xy 130.500444 -250.654747) (xy 130.549807 -250.646928)
			(xy 130.599785 -250.646928) (xy 130.649148 -250.654747) (xy 130.69668 -250.670191) (xy 130.741212 -250.692881)
			(xy 130.781645 -250.722257) (xy 130.816985 -250.757597) (xy 130.846361 -250.79803) (xy 130.869051 -250.842562)
			(xy 130.884495 -250.890094) (xy 130.892314 -250.939457) (xy 130.892804 -250.964446) (xy 131.198615 -250.964446)
			(xy 131.20271 -250.913718) (xy 131.214889 -250.864304) (xy 131.234837 -250.817484) (xy 131.262038 -250.77447)
			(xy 131.295786 -250.736376) (xy 131.335208 -250.704189) (xy 131.379282 -250.678743) (xy 131.426868 -250.660696)
			(xy 131.476732 -250.650516) (xy 131.527584 -250.648467) (xy 131.578105 -250.654601) (xy 131.626989 -250.668761)
			(xy 131.672968 -250.690578) (xy 131.714852 -250.719488) (xy 131.751556 -250.754743) (xy 131.782129 -250.795429)
			(xy 131.80578 -250.840492) (xy 131.821896 -250.888766) (xy 131.83006 -250.939) (xy 131.830572 -250.964446)
			(xy 132.138415 -250.964446) (xy 132.14251 -250.913718) (xy 132.154689 -250.864304) (xy 132.174637 -250.817484)
			(xy 132.201838 -250.77447) (xy 132.235586 -250.736376) (xy 132.275008 -250.704189) (xy 132.319082 -250.678743)
			(xy 132.366668 -250.660696) (xy 132.416532 -250.650516) (xy 132.467384 -250.648467) (xy 132.517905 -250.654601)
			(xy 132.566789 -250.668761) (xy 132.612768 -250.690578) (xy 132.654652 -250.719488) (xy 132.691356 -250.754743)
			(xy 132.721929 -250.795429) (xy 132.74558 -250.840492) (xy 132.761696 -250.888766) (xy 132.76986 -250.939)
			(xy 132.770372 -250.964446) (xy 132.769869 -250.989435) (xy 133.077186 -250.989435) (xy 133.077186 -250.939457)
			(xy 133.085005 -250.890094) (xy 133.100449 -250.842562) (xy 133.123139 -250.79803) (xy 133.152515 -250.757597)
			(xy 133.187855 -250.722257) (xy 133.228288 -250.692881) (xy 133.27282 -250.670191) (xy 133.320352 -250.654747)
			(xy 133.369715 -250.646928) (xy 133.419693 -250.646928) (xy 133.469056 -250.654747) (xy 133.516588 -250.670191)
			(xy 133.56112 -250.692881) (xy 133.601553 -250.722257) (xy 133.636893 -250.757597) (xy 133.666269 -250.79803)
			(xy 133.688959 -250.842562) (xy 133.704403 -250.890094) (xy 133.712222 -250.939457) (xy 133.712712 -250.964446)
			(xy 134.018523 -250.964446) (xy 134.022618 -250.913718) (xy 134.034797 -250.864304) (xy 134.054745 -250.817484)
			(xy 134.081946 -250.77447) (xy 134.115694 -250.736376) (xy 134.155116 -250.704189) (xy 134.19919 -250.678743)
			(xy 134.246776 -250.660696) (xy 134.29664 -250.650516) (xy 134.347492 -250.648467) (xy 134.398013 -250.654601)
			(xy 134.446897 -250.668761) (xy 134.492876 -250.690578) (xy 134.53476 -250.719488) (xy 134.571464 -250.754743)
			(xy 134.602037 -250.795429) (xy 134.625688 -250.840492) (xy 134.641804 -250.888766) (xy 134.649968 -250.939)
			(xy 134.65048 -250.964446) (xy 134.649977 -250.989435) (xy 134.957294 -250.989435) (xy 134.957294 -250.939457)
			(xy 134.965113 -250.890094) (xy 134.980557 -250.842562) (xy 135.003247 -250.79803) (xy 135.032623 -250.757597)
			(xy 135.067963 -250.722257) (xy 135.108396 -250.692881) (xy 135.152928 -250.670191) (xy 135.20046 -250.654747)
			(xy 135.249823 -250.646928) (xy 135.299801 -250.646928) (xy 135.349164 -250.654747) (xy 135.396696 -250.670191)
			(xy 135.441228 -250.692881) (xy 135.481661 -250.722257) (xy 135.517001 -250.757597) (xy 135.546377 -250.79803)
			(xy 135.569067 -250.842562) (xy 135.584511 -250.890094) (xy 135.59233 -250.939457) (xy 135.59282 -250.964446)
			(xy 135.898631 -250.964446) (xy 135.902726 -250.913718) (xy 135.914905 -250.864304) (xy 135.934853 -250.817484)
			(xy 135.962054 -250.77447) (xy 135.995802 -250.736376) (xy 136.035224 -250.704189) (xy 136.079298 -250.678743)
			(xy 136.126884 -250.660696) (xy 136.176748 -250.650516) (xy 136.2276 -250.648467) (xy 136.278121 -250.654601)
			(xy 136.327005 -250.668761) (xy 136.372984 -250.690578) (xy 136.414868 -250.719488) (xy 136.451572 -250.754743)
			(xy 136.482145 -250.795429) (xy 136.505796 -250.840492) (xy 136.521912 -250.888766) (xy 136.530076 -250.939)
			(xy 136.530588 -250.964446) (xy 136.530085 -250.989435) (xy 136.837148 -250.989435) (xy 136.837148 -250.939457)
			(xy 136.844967 -250.890094) (xy 136.860411 -250.842562) (xy 136.883101 -250.79803) (xy 136.912477 -250.757597)
			(xy 136.947817 -250.722257) (xy 136.98825 -250.692881) (xy 137.032782 -250.670191) (xy 137.080314 -250.654747)
			(xy 137.129677 -250.646928) (xy 137.179655 -250.646928) (xy 137.229018 -250.654747) (xy 137.27655 -250.670191)
			(xy 137.321082 -250.692881) (xy 137.361515 -250.722257) (xy 137.396855 -250.757597) (xy 137.426231 -250.79803)
			(xy 137.448921 -250.842562) (xy 137.464365 -250.890094) (xy 137.472184 -250.939457) (xy 137.472674 -250.964446)
			(xy 137.778485 -250.964446) (xy 137.78258 -250.913718) (xy 137.794759 -250.864304) (xy 137.814707 -250.817484)
			(xy 137.841908 -250.77447) (xy 137.875656 -250.736376) (xy 137.915078 -250.704189) (xy 137.959152 -250.678743)
			(xy 138.006738 -250.660696) (xy 138.056602 -250.650516) (xy 138.107454 -250.648467) (xy 138.157975 -250.654601)
			(xy 138.206859 -250.668761) (xy 138.252838 -250.690578) (xy 138.294722 -250.719488) (xy 138.331426 -250.754743)
			(xy 138.361999 -250.795429) (xy 138.38565 -250.840492) (xy 138.401766 -250.888766) (xy 138.40993 -250.939)
			(xy 138.410442 -250.964446) (xy 138.718539 -250.964446) (xy 138.722634 -250.913718) (xy 138.734813 -250.864304)
			(xy 138.754761 -250.817484) (xy 138.781962 -250.77447) (xy 138.81571 -250.736376) (xy 138.855132 -250.704189)
			(xy 138.899206 -250.678743) (xy 138.946792 -250.660696) (xy 138.996656 -250.650516) (xy 139.047508 -250.648467)
			(xy 139.098029 -250.654601) (xy 139.146913 -250.668761) (xy 139.192892 -250.690578) (xy 139.234776 -250.719488)
			(xy 139.27148 -250.754743) (xy 139.302053 -250.795429) (xy 139.325704 -250.840492) (xy 139.34182 -250.888766)
			(xy 139.349984 -250.939) (xy 139.350496 -250.964446) (xy 139.349993 -250.989435) (xy 139.65731 -250.989435)
			(xy 139.65731 -250.939457) (xy 139.665129 -250.890094) (xy 139.680573 -250.842562) (xy 139.703263 -250.79803)
			(xy 139.732639 -250.757597) (xy 139.767979 -250.722257) (xy 139.808412 -250.692881) (xy 139.852944 -250.670191)
			(xy 139.900476 -250.654747) (xy 139.949839 -250.646928) (xy 139.999817 -250.646928) (xy 140.04918 -250.654747)
			(xy 140.096712 -250.670191) (xy 140.141244 -250.692881) (xy 140.181677 -250.722257) (xy 140.217017 -250.757597)
			(xy 140.246393 -250.79803) (xy 140.269083 -250.842562) (xy 140.284527 -250.890094) (xy 140.292346 -250.939457)
			(xy 140.292836 -250.964446) (xy 140.598647 -250.964446) (xy 140.602742 -250.913718) (xy 140.614921 -250.864304)
			(xy 140.634869 -250.817484) (xy 140.66207 -250.77447) (xy 140.695818 -250.736376) (xy 140.73524 -250.704189)
			(xy 140.779314 -250.678743) (xy 140.8269 -250.660696) (xy 140.876764 -250.650516) (xy 140.927616 -250.648467)
			(xy 140.978137 -250.654601) (xy 141.027021 -250.668761) (xy 141.073 -250.690578) (xy 141.114884 -250.719488)
			(xy 141.151588 -250.754743) (xy 141.182161 -250.795429) (xy 141.205812 -250.840492) (xy 141.221928 -250.888766)
			(xy 141.230092 -250.939) (xy 141.230604 -250.964446) (xy 141.230101 -250.989435) (xy 141.537164 -250.989435)
			(xy 141.537164 -250.939457) (xy 141.544983 -250.890094) (xy 141.560427 -250.842562) (xy 141.583117 -250.79803)
			(xy 141.612493 -250.757597) (xy 141.647833 -250.722257) (xy 141.688266 -250.692881) (xy 141.732798 -250.670191)
			(xy 141.78033 -250.654747) (xy 141.829693 -250.646928) (xy 141.879671 -250.646928) (xy 141.929034 -250.654747)
			(xy 141.976566 -250.670191) (xy 142.021098 -250.692881) (xy 142.061531 -250.722257) (xy 142.096871 -250.757597)
			(xy 142.126247 -250.79803) (xy 142.148937 -250.842562) (xy 142.164381 -250.890094) (xy 142.1722 -250.939457)
			(xy 142.17269 -250.964446) (xy 142.478501 -250.964446) (xy 142.482596 -250.913718) (xy 142.494775 -250.864304)
			(xy 142.514723 -250.817484) (xy 142.541924 -250.77447) (xy 142.575672 -250.736376) (xy 142.615094 -250.704189)
			(xy 142.659168 -250.678743) (xy 142.706754 -250.660696) (xy 142.756618 -250.650516) (xy 142.80747 -250.648467)
			(xy 142.857991 -250.654601) (xy 142.906875 -250.668761) (xy 142.952854 -250.690578) (xy 142.994738 -250.719488)
			(xy 143.031442 -250.754743) (xy 143.062015 -250.795429) (xy 143.085666 -250.840492) (xy 143.101782 -250.888766)
			(xy 143.109946 -250.939) (xy 143.110458 -250.964446) (xy 143.109955 -250.989435) (xy 143.417272 -250.989435)
			(xy 143.417272 -250.939457) (xy 143.425091 -250.890094) (xy 143.440535 -250.842562) (xy 143.463225 -250.79803)
			(xy 143.492601 -250.757597) (xy 143.527941 -250.722257) (xy 143.568374 -250.692881) (xy 143.612906 -250.670191)
			(xy 143.660438 -250.654747) (xy 143.709801 -250.646928) (xy 143.759779 -250.646928) (xy 143.809142 -250.654747)
			(xy 143.856674 -250.670191) (xy 143.901206 -250.692881) (xy 143.941639 -250.722257) (xy 143.976979 -250.757597)
			(xy 144.006355 -250.79803) (xy 144.029045 -250.842562) (xy 144.044489 -250.890094) (xy 144.052308 -250.939457)
			(xy 144.052798 -250.964446) (xy 144.052308 -250.989435) (xy 144.044489 -251.038798) (xy 144.029045 -251.08633)
			(xy 144.006355 -251.130862) (xy 143.976979 -251.171295) (xy 143.941639 -251.206635) (xy 143.901206 -251.236011)
			(xy 143.856674 -251.258701) (xy 143.809142 -251.274145) (xy 143.759779 -251.281964) (xy 143.709801 -251.281964)
			(xy 143.660438 -251.274145) (xy 143.612906 -251.258701) (xy 143.568374 -251.236011) (xy 143.527941 -251.206635)
			(xy 143.492601 -251.171295) (xy 143.463225 -251.130862) (xy 143.440535 -251.08633) (xy 143.425091 -251.038798)
			(xy 143.417272 -250.989435) (xy 143.109955 -250.989435) (xy 143.109946 -250.989892) (xy 143.101782 -251.040126)
			(xy 143.085666 -251.0884) (xy 143.062015 -251.133463) (xy 143.031442 -251.174149) (xy 142.994738 -251.209404)
			(xy 142.952854 -251.238314) (xy 142.906875 -251.260131) (xy 142.857991 -251.274291) (xy 142.80747 -251.280425)
			(xy 142.756618 -251.278376) (xy 142.706754 -251.268196) (xy 142.659168 -251.250149) (xy 142.615094 -251.224703)
			(xy 142.575672 -251.192516) (xy 142.541924 -251.154422) (xy 142.514723 -251.111408) (xy 142.494775 -251.064588)
			(xy 142.482596 -251.015174) (xy 142.478501 -250.964446) (xy 142.17269 -250.964446) (xy 142.1722 -250.989435)
			(xy 142.164381 -251.038798) (xy 142.148937 -251.08633) (xy 142.126247 -251.130862) (xy 142.096871 -251.171295)
			(xy 142.061531 -251.206635) (xy 142.021098 -251.236011) (xy 141.976566 -251.258701) (xy 141.929034 -251.274145)
			(xy 141.879671 -251.281964) (xy 141.829693 -251.281964) (xy 141.78033 -251.274145) (xy 141.732798 -251.258701)
			(xy 141.688266 -251.236011) (xy 141.647833 -251.206635) (xy 141.612493 -251.171295) (xy 141.583117 -251.130862)
			(xy 141.560427 -251.08633) (xy 141.544983 -251.038798) (xy 141.537164 -250.989435) (xy 141.230101 -250.989435)
			(xy 141.230092 -250.989892) (xy 141.221928 -251.040126) (xy 141.205812 -251.0884) (xy 141.182161 -251.133463)
			(xy 141.151588 -251.174149) (xy 141.114884 -251.209404) (xy 141.073 -251.238314) (xy 141.027021 -251.260131)
			(xy 140.978137 -251.274291) (xy 140.927616 -251.280425) (xy 140.876764 -251.278376) (xy 140.8269 -251.268196)
			(xy 140.779314 -251.250149) (xy 140.73524 -251.224703) (xy 140.695818 -251.192516) (xy 140.66207 -251.154422)
			(xy 140.634869 -251.111408) (xy 140.614921 -251.064588) (xy 140.602742 -251.015174) (xy 140.598647 -250.964446)
			(xy 140.292836 -250.964446) (xy 140.292346 -250.989435) (xy 140.284527 -251.038798) (xy 140.269083 -251.08633)
			(xy 140.246393 -251.130862) (xy 140.217017 -251.171295) (xy 140.181677 -251.206635) (xy 140.141244 -251.236011)
			(xy 140.096712 -251.258701) (xy 140.04918 -251.274145) (xy 139.999817 -251.281964) (xy 139.949839 -251.281964)
			(xy 139.900476 -251.274145) (xy 139.852944 -251.258701) (xy 139.808412 -251.236011) (xy 139.767979 -251.206635)
			(xy 139.732639 -251.171295) (xy 139.703263 -251.130862) (xy 139.680573 -251.08633) (xy 139.665129 -251.038798)
			(xy 139.65731 -250.989435) (xy 139.349993 -250.989435) (xy 139.349984 -250.989892) (xy 139.34182 -251.040126)
			(xy 139.325704 -251.0884) (xy 139.302053 -251.133463) (xy 139.27148 -251.174149) (xy 139.234776 -251.209404)
			(xy 139.192892 -251.238314) (xy 139.146913 -251.260131) (xy 139.098029 -251.274291) (xy 139.047508 -251.280425)
			(xy 138.996656 -251.278376) (xy 138.946792 -251.268196) (xy 138.899206 -251.250149) (xy 138.855132 -251.224703)
			(xy 138.81571 -251.192516) (xy 138.781962 -251.154422) (xy 138.754761 -251.111408) (xy 138.734813 -251.064588)
			(xy 138.722634 -251.015174) (xy 138.718539 -250.964446) (xy 138.410442 -250.964446) (xy 138.40993 -250.989892)
			(xy 138.401766 -251.040126) (xy 138.38565 -251.0884) (xy 138.361999 -251.133463) (xy 138.331426 -251.174149)
			(xy 138.294722 -251.209404) (xy 138.252838 -251.238314) (xy 138.206859 -251.260131) (xy 138.157975 -251.274291)
			(xy 138.107454 -251.280425) (xy 138.056602 -251.278376) (xy 138.006738 -251.268196) (xy 137.959152 -251.250149)
			(xy 137.915078 -251.224703) (xy 137.875656 -251.192516) (xy 137.841908 -251.154422) (xy 137.814707 -251.111408)
			(xy 137.794759 -251.064588) (xy 137.78258 -251.015174) (xy 137.778485 -250.964446) (xy 137.472674 -250.964446)
			(xy 137.472184 -250.989435) (xy 137.464365 -251.038798) (xy 137.448921 -251.08633) (xy 137.426231 -251.130862)
			(xy 137.396855 -251.171295) (xy 137.361515 -251.206635) (xy 137.321082 -251.236011) (xy 137.27655 -251.258701)
			(xy 137.229018 -251.274145) (xy 137.179655 -251.281964) (xy 137.129677 -251.281964) (xy 137.080314 -251.274145)
			(xy 137.032782 -251.258701) (xy 136.98825 -251.236011) (xy 136.947817 -251.206635) (xy 136.912477 -251.171295)
			(xy 136.883101 -251.130862) (xy 136.860411 -251.08633) (xy 136.844967 -251.038798) (xy 136.837148 -250.989435)
			(xy 136.530085 -250.989435) (xy 136.530076 -250.989892) (xy 136.521912 -251.040126) (xy 136.505796 -251.0884)
			(xy 136.482145 -251.133463) (xy 136.451572 -251.174149) (xy 136.414868 -251.209404) (xy 136.372984 -251.238314)
			(xy 136.327005 -251.260131) (xy 136.278121 -251.274291) (xy 136.2276 -251.280425) (xy 136.176748 -251.278376)
			(xy 136.126884 -251.268196) (xy 136.079298 -251.250149) (xy 136.035224 -251.224703) (xy 135.995802 -251.192516)
			(xy 135.962054 -251.154422) (xy 135.934853 -251.111408) (xy 135.914905 -251.064588) (xy 135.902726 -251.015174)
			(xy 135.898631 -250.964446) (xy 135.59282 -250.964446) (xy 135.59233 -250.989435) (xy 135.584511 -251.038798)
			(xy 135.569067 -251.08633) (xy 135.546377 -251.130862) (xy 135.517001 -251.171295) (xy 135.481661 -251.206635)
			(xy 135.441228 -251.236011) (xy 135.396696 -251.258701) (xy 135.349164 -251.274145) (xy 135.299801 -251.281964)
			(xy 135.249823 -251.281964) (xy 135.20046 -251.274145) (xy 135.152928 -251.258701) (xy 135.108396 -251.236011)
			(xy 135.067963 -251.206635) (xy 135.032623 -251.171295) (xy 135.003247 -251.130862) (xy 134.980557 -251.08633)
			(xy 134.965113 -251.038798) (xy 134.957294 -250.989435) (xy 134.649977 -250.989435) (xy 134.649968 -250.989892)
			(xy 134.641804 -251.040126) (xy 134.625688 -251.0884) (xy 134.602037 -251.133463) (xy 134.571464 -251.174149)
			(xy 134.53476 -251.209404) (xy 134.492876 -251.238314) (xy 134.446897 -251.260131) (xy 134.398013 -251.274291)
			(xy 134.347492 -251.280425) (xy 134.29664 -251.278376) (xy 134.246776 -251.268196) (xy 134.19919 -251.250149)
			(xy 134.155116 -251.224703) (xy 134.115694 -251.192516) (xy 134.081946 -251.154422) (xy 134.054745 -251.111408)
			(xy 134.034797 -251.064588) (xy 134.022618 -251.015174) (xy 134.018523 -250.964446) (xy 133.712712 -250.964446)
			(xy 133.712222 -250.989435) (xy 133.704403 -251.038798) (xy 133.688959 -251.08633) (xy 133.666269 -251.130862)
			(xy 133.636893 -251.171295) (xy 133.601553 -251.206635) (xy 133.56112 -251.236011) (xy 133.516588 -251.258701)
			(xy 133.469056 -251.274145) (xy 133.419693 -251.281964) (xy 133.369715 -251.281964) (xy 133.320352 -251.274145)
			(xy 133.27282 -251.258701) (xy 133.228288 -251.236011) (xy 133.187855 -251.206635) (xy 133.152515 -251.171295)
			(xy 133.123139 -251.130862) (xy 133.100449 -251.08633) (xy 133.085005 -251.038798) (xy 133.077186 -250.989435)
			(xy 132.769869 -250.989435) (xy 132.76986 -250.989892) (xy 132.761696 -251.040126) (xy 132.74558 -251.0884)
			(xy 132.721929 -251.133463) (xy 132.691356 -251.174149) (xy 132.654652 -251.209404) (xy 132.612768 -251.238314)
			(xy 132.566789 -251.260131) (xy 132.517905 -251.274291) (xy 132.467384 -251.280425) (xy 132.416532 -251.278376)
			(xy 132.366668 -251.268196) (xy 132.319082 -251.250149) (xy 132.275008 -251.224703) (xy 132.235586 -251.192516)
			(xy 132.201838 -251.154422) (xy 132.174637 -251.111408) (xy 132.154689 -251.064588) (xy 132.14251 -251.015174)
			(xy 132.138415 -250.964446) (xy 131.830572 -250.964446) (xy 131.83006 -250.989892) (xy 131.821896 -251.040126)
			(xy 131.80578 -251.0884) (xy 131.782129 -251.133463) (xy 131.751556 -251.174149) (xy 131.714852 -251.209404)
			(xy 131.672968 -251.238314) (xy 131.626989 -251.260131) (xy 131.578105 -251.274291) (xy 131.527584 -251.280425)
			(xy 131.476732 -251.278376) (xy 131.426868 -251.268196) (xy 131.379282 -251.250149) (xy 131.335208 -251.224703)
			(xy 131.295786 -251.192516) (xy 131.262038 -251.154422) (xy 131.234837 -251.111408) (xy 131.214889 -251.064588)
			(xy 131.20271 -251.015174) (xy 131.198615 -250.964446) (xy 130.892804 -250.964446) (xy 130.892314 -250.989435)
			(xy 130.884495 -251.038798) (xy 130.869051 -251.08633) (xy 130.846361 -251.130862) (xy 130.816985 -251.171295)
			(xy 130.781645 -251.206635) (xy 130.741212 -251.236011) (xy 130.69668 -251.258701) (xy 130.649148 -251.274145)
			(xy 130.599785 -251.281964) (xy 130.549807 -251.281964) (xy 130.500444 -251.274145) (xy 130.452912 -251.258701)
			(xy 130.40838 -251.236011) (xy 130.367947 -251.206635) (xy 130.332607 -251.171295) (xy 130.303231 -251.130862)
			(xy 130.280541 -251.08633) (xy 130.265097 -251.038798) (xy 130.257278 -250.989435) (xy 129.949961 -250.989435)
			(xy 129.949952 -250.989892) (xy 129.941788 -251.040126) (xy 129.925672 -251.0884) (xy 129.902021 -251.133463)
			(xy 129.871448 -251.174149) (xy 129.834744 -251.209404) (xy 129.79286 -251.238314) (xy 129.746881 -251.260131)
			(xy 129.697997 -251.274291) (xy 129.647476 -251.280425) (xy 129.596624 -251.278376) (xy 129.54676 -251.268196)
			(xy 129.499174 -251.250149) (xy 129.4551 -251.224703) (xy 129.415678 -251.192516) (xy 129.38193 -251.154422)
			(xy 129.354729 -251.111408) (xy 129.334781 -251.064588) (xy 129.322602 -251.015174) (xy 129.318507 -250.964446)
			(xy 129.012696 -250.964446) (xy 129.012206 -250.989435) (xy 129.004387 -251.038798) (xy 128.988943 -251.08633)
			(xy 128.966253 -251.130862) (xy 128.936877 -251.171295) (xy 128.901537 -251.206635) (xy 128.861104 -251.236011)
			(xy 128.816572 -251.258701) (xy 128.76904 -251.274145) (xy 128.719677 -251.281964) (xy 128.669699 -251.281964)
			(xy 128.620336 -251.274145) (xy 128.572804 -251.258701) (xy 128.528272 -251.236011) (xy 128.487839 -251.206635)
			(xy 128.452499 -251.171295) (xy 128.423123 -251.130862) (xy 128.400433 -251.08633) (xy 128.384989 -251.038798)
			(xy 128.37717 -250.989435) (xy 128.069853 -250.989435) (xy 128.069844 -250.989892) (xy 128.06168 -251.040126)
			(xy 128.045564 -251.0884) (xy 128.021913 -251.133463) (xy 127.99134 -251.174149) (xy 127.954636 -251.209404)
			(xy 127.912752 -251.238314) (xy 127.866773 -251.260131) (xy 127.817889 -251.274291) (xy 127.767368 -251.280425)
			(xy 127.716516 -251.278376) (xy 127.666652 -251.268196) (xy 127.619066 -251.250149) (xy 127.574992 -251.224703)
			(xy 127.53557 -251.192516) (xy 127.501822 -251.154422) (xy 127.474621 -251.111408) (xy 127.454673 -251.064588)
			(xy 127.442494 -251.015174) (xy 127.438399 -250.964446) (xy 127.132842 -250.964446) (xy 127.132352 -250.989435)
			(xy 127.124533 -251.038798) (xy 127.109089 -251.08633) (xy 127.086399 -251.130862) (xy 127.057023 -251.171295)
			(xy 127.021683 -251.206635) (xy 126.98125 -251.236011) (xy 126.936718 -251.258701) (xy 126.889186 -251.274145)
			(xy 126.839823 -251.281964) (xy 126.789845 -251.281964) (xy 126.740482 -251.274145) (xy 126.69295 -251.258701)
			(xy 126.648418 -251.236011) (xy 126.607985 -251.206635) (xy 126.572645 -251.171295) (xy 126.543269 -251.130862)
			(xy 126.520579 -251.08633) (xy 126.505135 -251.038798) (xy 126.497316 -250.989435) (xy 125.505464 -250.989435)
			(xy 125.505464 -251.37999) (xy 125.504926 -251.389827) (xy 125.497341 -251.407989) (xy 125.490732 -251.415296)
			(xy 125.393196 -251.512832) (xy 125.385957 -251.519544) (xy 125.367753 -251.527138) (xy 125.35789 -251.527564)
			(xy 124.856748 -251.527564) (xy 124.854716 -251.527564) (xy 124.843644 -251.52857) (xy 124.823889 -251.538714)
			(xy 124.816616 -251.547122) (xy 124.76861 -251.616464) (xy 124.764911 -251.622199) (xy 124.760408 -251.635075)
			(xy 124.75972 -251.641864) (xy 124.758958 -251.652786) (xy 124.761752 -251.660406) (xy 124.765562 -251.671074)
			(xy 124.773595 -251.696097) (xy 124.782283 -251.747924) (xy 124.782834 -251.774198) (xy 124.782834 -251.774452)
			(xy 124.782344 -251.799441) (xy 126.027162 -251.799441) (xy 126.027162 -251.749463) (xy 126.034981 -251.7001)
			(xy 126.050425 -251.652568) (xy 126.073115 -251.608036) (xy 126.102491 -251.567603) (xy 126.137831 -251.532263)
			(xy 126.178264 -251.502887) (xy 126.222796 -251.480197) (xy 126.270328 -251.464753) (xy 126.319691 -251.456934)
			(xy 126.369669 -251.456934) (xy 126.419032 -251.464753) (xy 126.466564 -251.480197) (xy 126.511096 -251.502887)
			(xy 126.551529 -251.532263) (xy 126.586869 -251.567603) (xy 126.616245 -251.608036) (xy 126.638935 -251.652568)
			(xy 126.654379 -251.7001) (xy 126.662198 -251.749463) (xy 126.662688 -251.774452) (xy 127.908553 -251.774452)
			(xy 127.912648 -251.723724) (xy 127.924827 -251.67431) (xy 127.944775 -251.62749) (xy 127.971976 -251.584476)
			(xy 128.005724 -251.546382) (xy 128.045146 -251.514195) (xy 128.08922 -251.488749) (xy 128.136806 -251.470702)
			(xy 128.18667 -251.460522) (xy 128.237522 -251.458473) (xy 128.288043 -251.464607) (xy 128.336927 -251.478767)
			(xy 128.382906 -251.500584) (xy 128.42479 -251.529494) (xy 128.461494 -251.564749) (xy 128.492067 -251.605435)
			(xy 128.515718 -251.650498) (xy 128.531834 -251.698772) (xy 128.539998 -251.749006) (xy 128.54051 -251.774452)
			(xy 128.540007 -251.799441) (xy 128.847324 -251.799441) (xy 128.847324 -251.749463) (xy 128.855143 -251.7001)
			(xy 128.870587 -251.652568) (xy 128.893277 -251.608036) (xy 128.922653 -251.567603) (xy 128.957993 -251.532263)
			(xy 128.998426 -251.502887) (xy 129.042958 -251.480197) (xy 129.09049 -251.464753) (xy 129.139853 -251.456934)
			(xy 129.189831 -251.456934) (xy 129.239194 -251.464753) (xy 129.286726 -251.480197) (xy 129.331258 -251.502887)
			(xy 129.371691 -251.532263) (xy 129.407031 -251.567603) (xy 129.436407 -251.608036) (xy 129.459097 -251.652568)
			(xy 129.474541 -251.7001) (xy 129.48236 -251.749463) (xy 129.48285 -251.774452) (xy 130.728461 -251.774452)
			(xy 130.732556 -251.723724) (xy 130.744735 -251.67431) (xy 130.764683 -251.62749) (xy 130.791884 -251.584476)
			(xy 130.825632 -251.546382) (xy 130.865054 -251.514195) (xy 130.909128 -251.488749) (xy 130.956714 -251.470702)
			(xy 131.006578 -251.460522) (xy 131.05743 -251.458473) (xy 131.107951 -251.464607) (xy 131.156835 -251.478767)
			(xy 131.202814 -251.500584) (xy 131.244698 -251.529494) (xy 131.281402 -251.564749) (xy 131.311975 -251.605435)
			(xy 131.335626 -251.650498) (xy 131.351742 -251.698772) (xy 131.359906 -251.749006) (xy 131.360418 -251.774452)
			(xy 131.359915 -251.799441) (xy 131.667232 -251.799441) (xy 131.667232 -251.749463) (xy 131.675051 -251.7001)
			(xy 131.690495 -251.652568) (xy 131.713185 -251.608036) (xy 131.742561 -251.567603) (xy 131.777901 -251.532263)
			(xy 131.818334 -251.502887) (xy 131.862866 -251.480197) (xy 131.910398 -251.464753) (xy 131.959761 -251.456934)
			(xy 132.009739 -251.456934) (xy 132.059102 -251.464753) (xy 132.106634 -251.480197) (xy 132.151166 -251.502887)
			(xy 132.191599 -251.532263) (xy 132.226939 -251.567603) (xy 132.256315 -251.608036) (xy 132.279005 -251.652568)
			(xy 132.294449 -251.7001) (xy 132.302268 -251.749463) (xy 132.302758 -251.774452) (xy 132.302268 -251.799441)
			(xy 132.607286 -251.799441) (xy 132.607286 -251.749463) (xy 132.615105 -251.7001) (xy 132.630549 -251.652568)
			(xy 132.653239 -251.608036) (xy 132.682615 -251.567603) (xy 132.717955 -251.532263) (xy 132.758388 -251.502887)
			(xy 132.80292 -251.480197) (xy 132.850452 -251.464753) (xy 132.899815 -251.456934) (xy 132.949793 -251.456934)
			(xy 132.999156 -251.464753) (xy 133.046688 -251.480197) (xy 133.09122 -251.502887) (xy 133.131653 -251.532263)
			(xy 133.166993 -251.567603) (xy 133.196369 -251.608036) (xy 133.219059 -251.652568) (xy 133.234503 -251.7001)
			(xy 133.242322 -251.749463) (xy 133.242812 -251.774452) (xy 133.242322 -251.799441) (xy 133.54734 -251.799441)
			(xy 133.54734 -251.749463) (xy 133.555159 -251.7001) (xy 133.570603 -251.652568) (xy 133.593293 -251.608036)
			(xy 133.622669 -251.567603) (xy 133.658009 -251.532263) (xy 133.698442 -251.502887) (xy 133.742974 -251.480197)
			(xy 133.790506 -251.464753) (xy 133.839869 -251.456934) (xy 133.889847 -251.456934) (xy 133.93921 -251.464753)
			(xy 133.986742 -251.480197) (xy 134.031274 -251.502887) (xy 134.071707 -251.532263) (xy 134.107047 -251.567603)
			(xy 134.136423 -251.608036) (xy 134.159113 -251.652568) (xy 134.174557 -251.7001) (xy 134.182376 -251.749463)
			(xy 134.182866 -251.774452) (xy 134.488423 -251.774452) (xy 134.492518 -251.723724) (xy 134.504697 -251.67431)
			(xy 134.524645 -251.62749) (xy 134.551846 -251.584476) (xy 134.585594 -251.546382) (xy 134.625016 -251.514195)
			(xy 134.66909 -251.488749) (xy 134.716676 -251.470702) (xy 134.76654 -251.460522) (xy 134.817392 -251.458473)
			(xy 134.867913 -251.464607) (xy 134.916797 -251.478767) (xy 134.962776 -251.500584) (xy 135.00466 -251.529494)
			(xy 135.041364 -251.564749) (xy 135.071937 -251.605435) (xy 135.095588 -251.650498) (xy 135.111704 -251.698772)
			(xy 135.119868 -251.749006) (xy 135.12038 -251.774452) (xy 135.119877 -251.799441) (xy 135.427194 -251.799441)
			(xy 135.427194 -251.749463) (xy 135.435013 -251.7001) (xy 135.450457 -251.652568) (xy 135.473147 -251.608036)
			(xy 135.502523 -251.567603) (xy 135.537863 -251.532263) (xy 135.578296 -251.502887) (xy 135.622828 -251.480197)
			(xy 135.67036 -251.464753) (xy 135.719723 -251.456934) (xy 135.769701 -251.456934) (xy 135.819064 -251.464753)
			(xy 135.866596 -251.480197) (xy 135.911128 -251.502887) (xy 135.951561 -251.532263) (xy 135.986901 -251.567603)
			(xy 136.016277 -251.608036) (xy 136.038967 -251.652568) (xy 136.054411 -251.7001) (xy 136.06223 -251.749463)
			(xy 136.06272 -251.774452) (xy 137.308585 -251.774452) (xy 137.31268 -251.723724) (xy 137.324859 -251.67431)
			(xy 137.344807 -251.62749) (xy 137.372008 -251.584476) (xy 137.405756 -251.546382) (xy 137.445178 -251.514195)
			(xy 137.489252 -251.488749) (xy 137.536838 -251.470702) (xy 137.586702 -251.460522) (xy 137.637554 -251.458473)
			(xy 137.688075 -251.464607) (xy 137.736959 -251.478767) (xy 137.782938 -251.500584) (xy 137.824822 -251.529494)
			(xy 137.861526 -251.564749) (xy 137.892099 -251.605435) (xy 137.91575 -251.650498) (xy 137.931866 -251.698772)
			(xy 137.94003 -251.749006) (xy 137.940542 -251.774452) (xy 137.940039 -251.799441) (xy 138.247356 -251.799441)
			(xy 138.247356 -251.749463) (xy 138.255175 -251.7001) (xy 138.270619 -251.652568) (xy 138.293309 -251.608036)
			(xy 138.322685 -251.567603) (xy 138.358025 -251.532263) (xy 138.398458 -251.502887) (xy 138.44299 -251.480197)
			(xy 138.490522 -251.464753) (xy 138.539885 -251.456934) (xy 138.589863 -251.456934) (xy 138.639226 -251.464753)
			(xy 138.686758 -251.480197) (xy 138.73129 -251.502887) (xy 138.771723 -251.532263) (xy 138.807063 -251.567603)
			(xy 138.836439 -251.608036) (xy 138.859129 -251.652568) (xy 138.874573 -251.7001) (xy 138.882392 -251.749463)
			(xy 138.882882 -251.774452) (xy 138.882392 -251.799441) (xy 139.187156 -251.799441) (xy 139.187156 -251.749463)
			(xy 139.194975 -251.7001) (xy 139.210419 -251.652568) (xy 139.233109 -251.608036) (xy 139.262485 -251.567603)
			(xy 139.297825 -251.532263) (xy 139.338258 -251.502887) (xy 139.38279 -251.480197) (xy 139.430322 -251.464753)
			(xy 139.479685 -251.456934) (xy 139.529663 -251.456934) (xy 139.579026 -251.464753) (xy 139.626558 -251.480197)
			(xy 139.67109 -251.502887) (xy 139.711523 -251.532263) (xy 139.746863 -251.567603) (xy 139.776239 -251.608036)
			(xy 139.798929 -251.652568) (xy 139.814373 -251.7001) (xy 139.822192 -251.749463) (xy 139.822682 -251.774452)
			(xy 139.822192 -251.799441) (xy 140.12721 -251.799441) (xy 140.12721 -251.749463) (xy 140.135029 -251.7001)
			(xy 140.150473 -251.652568) (xy 140.173163 -251.608036) (xy 140.202539 -251.567603) (xy 140.237879 -251.532263)
			(xy 140.278312 -251.502887) (xy 140.322844 -251.480197) (xy 140.370376 -251.464753) (xy 140.419739 -251.456934)
			(xy 140.469717 -251.456934) (xy 140.51908 -251.464753) (xy 140.566612 -251.480197) (xy 140.611144 -251.502887)
			(xy 140.651577 -251.532263) (xy 140.686917 -251.567603) (xy 140.716293 -251.608036) (xy 140.738983 -251.652568)
			(xy 140.754427 -251.7001) (xy 140.762246 -251.749463) (xy 140.762736 -251.774452) (xy 141.068547 -251.774452)
			(xy 141.072642 -251.723724) (xy 141.084821 -251.67431) (xy 141.104769 -251.62749) (xy 141.13197 -251.584476)
			(xy 141.165718 -251.546382) (xy 141.20514 -251.514195) (xy 141.249214 -251.488749) (xy 141.2968 -251.470702)
			(xy 141.346664 -251.460522) (xy 141.397516 -251.458473) (xy 141.448037 -251.464607) (xy 141.496921 -251.478767)
			(xy 141.5429 -251.500584) (xy 141.584784 -251.529494) (xy 141.621488 -251.564749) (xy 141.652061 -251.605435)
			(xy 141.675712 -251.650498) (xy 141.691828 -251.698772) (xy 141.699992 -251.749006) (xy 141.700504 -251.774452)
			(xy 141.700001 -251.799441) (xy 142.007318 -251.799441) (xy 142.007318 -251.749463) (xy 142.015137 -251.7001)
			(xy 142.030581 -251.652568) (xy 142.053271 -251.608036) (xy 142.082647 -251.567603) (xy 142.117987 -251.532263)
			(xy 142.15842 -251.502887) (xy 142.202952 -251.480197) (xy 142.250484 -251.464753) (xy 142.299847 -251.456934)
			(xy 142.349825 -251.456934) (xy 142.399188 -251.464753) (xy 142.44672 -251.480197) (xy 142.491252 -251.502887)
			(xy 142.531685 -251.532263) (xy 142.567025 -251.567603) (xy 142.596401 -251.608036) (xy 142.619091 -251.652568)
			(xy 142.634535 -251.7001) (xy 142.642354 -251.749463) (xy 142.642844 -251.774452) (xy 142.642354 -251.799441)
			(xy 142.634535 -251.848804) (xy 142.619091 -251.896336) (xy 142.596401 -251.940868) (xy 142.567025 -251.981301)
			(xy 142.531685 -252.016641) (xy 142.491252 -252.046017) (xy 142.44672 -252.068707) (xy 142.399188 -252.084151)
			(xy 142.349825 -252.09197) (xy 142.299847 -252.09197) (xy 142.250484 -252.084151) (xy 142.202952 -252.068707)
			(xy 142.15842 -252.046017) (xy 142.117987 -252.016641) (xy 142.082647 -251.981301) (xy 142.053271 -251.940868)
			(xy 142.030581 -251.896336) (xy 142.015137 -251.848804) (xy 142.007318 -251.799441) (xy 141.700001 -251.799441)
			(xy 141.699992 -251.799898) (xy 141.691828 -251.850132) (xy 141.675712 -251.898406) (xy 141.652061 -251.943469)
			(xy 141.621488 -251.984155) (xy 141.584784 -252.01941) (xy 141.5429 -252.04832) (xy 141.496921 -252.070137)
			(xy 141.448037 -252.084297) (xy 141.397516 -252.090431) (xy 141.346664 -252.088382) (xy 141.2968 -252.078202)
			(xy 141.249214 -252.060155) (xy 141.20514 -252.034709) (xy 141.165718 -252.002522) (xy 141.13197 -251.964428)
			(xy 141.104769 -251.921414) (xy 141.084821 -251.874594) (xy 141.072642 -251.82518) (xy 141.068547 -251.774452)
			(xy 140.762736 -251.774452) (xy 140.762246 -251.799441) (xy 140.754427 -251.848804) (xy 140.738983 -251.896336)
			(xy 140.716293 -251.940868) (xy 140.686917 -251.981301) (xy 140.651577 -252.016641) (xy 140.611144 -252.046017)
			(xy 140.566612 -252.068707) (xy 140.51908 -252.084151) (xy 140.469717 -252.09197) (xy 140.419739 -252.09197)
			(xy 140.370376 -252.084151) (xy 140.322844 -252.068707) (xy 140.278312 -252.046017) (xy 140.237879 -252.016641)
			(xy 140.202539 -251.981301) (xy 140.173163 -251.940868) (xy 140.150473 -251.896336) (xy 140.135029 -251.848804)
			(xy 140.12721 -251.799441) (xy 139.822192 -251.799441) (xy 139.814373 -251.848804) (xy 139.798929 -251.896336)
			(xy 139.776239 -251.940868) (xy 139.746863 -251.981301) (xy 139.711523 -252.016641) (xy 139.67109 -252.046017)
			(xy 139.626558 -252.068707) (xy 139.579026 -252.084151) (xy 139.529663 -252.09197) (xy 139.479685 -252.09197)
			(xy 139.430322 -252.084151) (xy 139.38279 -252.068707) (xy 139.338258 -252.046017) (xy 139.297825 -252.016641)
			(xy 139.262485 -251.981301) (xy 139.233109 -251.940868) (xy 139.210419 -251.896336) (xy 139.194975 -251.848804)
			(xy 139.187156 -251.799441) (xy 138.882392 -251.799441) (xy 138.874573 -251.848804) (xy 138.859129 -251.896336)
			(xy 138.836439 -251.940868) (xy 138.807063 -251.981301) (xy 138.771723 -252.016641) (xy 138.73129 -252.046017)
			(xy 138.686758 -252.068707) (xy 138.639226 -252.084151) (xy 138.589863 -252.09197) (xy 138.539885 -252.09197)
			(xy 138.490522 -252.084151) (xy 138.44299 -252.068707) (xy 138.398458 -252.046017) (xy 138.358025 -252.016641)
			(xy 138.322685 -251.981301) (xy 138.293309 -251.940868) (xy 138.270619 -251.896336) (xy 138.255175 -251.848804)
			(xy 138.247356 -251.799441) (xy 137.940039 -251.799441) (xy 137.94003 -251.799898) (xy 137.931866 -251.850132)
			(xy 137.91575 -251.898406) (xy 137.892099 -251.943469) (xy 137.861526 -251.984155) (xy 137.824822 -252.01941)
			(xy 137.782938 -252.04832) (xy 137.736959 -252.070137) (xy 137.688075 -252.084297) (xy 137.637554 -252.090431)
			(xy 137.586702 -252.088382) (xy 137.536838 -252.078202) (xy 137.489252 -252.060155) (xy 137.445178 -252.034709)
			(xy 137.405756 -252.002522) (xy 137.372008 -251.964428) (xy 137.344807 -251.921414) (xy 137.324859 -251.874594)
			(xy 137.31268 -251.82518) (xy 137.308585 -251.774452) (xy 136.06272 -251.774452) (xy 136.06223 -251.799441)
			(xy 136.054411 -251.848804) (xy 136.038967 -251.896336) (xy 136.016277 -251.940868) (xy 135.986901 -251.981301)
			(xy 135.951561 -252.016641) (xy 135.911128 -252.046017) (xy 135.866596 -252.068707) (xy 135.819064 -252.084151)
			(xy 135.769701 -252.09197) (xy 135.719723 -252.09197) (xy 135.67036 -252.084151) (xy 135.622828 -252.068707)
			(xy 135.578296 -252.046017) (xy 135.537863 -252.016641) (xy 135.502523 -251.981301) (xy 135.473147 -251.940868)
			(xy 135.450457 -251.896336) (xy 135.435013 -251.848804) (xy 135.427194 -251.799441) (xy 135.119877 -251.799441)
			(xy 135.119868 -251.799898) (xy 135.111704 -251.850132) (xy 135.095588 -251.898406) (xy 135.071937 -251.943469)
			(xy 135.041364 -251.984155) (xy 135.00466 -252.01941) (xy 134.962776 -252.04832) (xy 134.916797 -252.070137)
			(xy 134.867913 -252.084297) (xy 134.817392 -252.090431) (xy 134.76654 -252.088382) (xy 134.716676 -252.078202)
			(xy 134.66909 -252.060155) (xy 134.625016 -252.034709) (xy 134.585594 -252.002522) (xy 134.551846 -251.964428)
			(xy 134.524645 -251.921414) (xy 134.504697 -251.874594) (xy 134.492518 -251.82518) (xy 134.488423 -251.774452)
			(xy 134.182866 -251.774452) (xy 134.182376 -251.799441) (xy 134.174557 -251.848804) (xy 134.159113 -251.896336)
			(xy 134.136423 -251.940868) (xy 134.107047 -251.981301) (xy 134.071707 -252.016641) (xy 134.031274 -252.046017)
			(xy 133.986742 -252.068707) (xy 133.93921 -252.084151) (xy 133.889847 -252.09197) (xy 133.839869 -252.09197)
			(xy 133.790506 -252.084151) (xy 133.742974 -252.068707) (xy 133.698442 -252.046017) (xy 133.658009 -252.016641)
			(xy 133.622669 -251.981301) (xy 133.593293 -251.940868) (xy 133.570603 -251.896336) (xy 133.555159 -251.848804)
			(xy 133.54734 -251.799441) (xy 133.242322 -251.799441) (xy 133.234503 -251.848804) (xy 133.219059 -251.896336)
			(xy 133.196369 -251.940868) (xy 133.166993 -251.981301) (xy 133.131653 -252.016641) (xy 133.09122 -252.046017)
			(xy 133.046688 -252.068707) (xy 132.999156 -252.084151) (xy 132.949793 -252.09197) (xy 132.899815 -252.09197)
			(xy 132.850452 -252.084151) (xy 132.80292 -252.068707) (xy 132.758388 -252.046017) (xy 132.717955 -252.016641)
			(xy 132.682615 -251.981301) (xy 132.653239 -251.940868) (xy 132.630549 -251.896336) (xy 132.615105 -251.848804)
			(xy 132.607286 -251.799441) (xy 132.302268 -251.799441) (xy 132.294449 -251.848804) (xy 132.279005 -251.896336)
			(xy 132.256315 -251.940868) (xy 132.226939 -251.981301) (xy 132.191599 -252.016641) (xy 132.151166 -252.046017)
			(xy 132.106634 -252.068707) (xy 132.059102 -252.084151) (xy 132.009739 -252.09197) (xy 131.959761 -252.09197)
			(xy 131.910398 -252.084151) (xy 131.862866 -252.068707) (xy 131.818334 -252.046017) (xy 131.777901 -252.016641)
			(xy 131.742561 -251.981301) (xy 131.713185 -251.940868) (xy 131.690495 -251.896336) (xy 131.675051 -251.848804)
			(xy 131.667232 -251.799441) (xy 131.359915 -251.799441) (xy 131.359906 -251.799898) (xy 131.351742 -251.850132)
			(xy 131.335626 -251.898406) (xy 131.311975 -251.943469) (xy 131.281402 -251.984155) (xy 131.244698 -252.01941)
			(xy 131.202814 -252.04832) (xy 131.156835 -252.070137) (xy 131.107951 -252.084297) (xy 131.05743 -252.090431)
			(xy 131.006578 -252.088382) (xy 130.956714 -252.078202) (xy 130.909128 -252.060155) (xy 130.865054 -252.034709)
			(xy 130.825632 -252.002522) (xy 130.791884 -251.964428) (xy 130.764683 -251.921414) (xy 130.744735 -251.874594)
			(xy 130.732556 -251.82518) (xy 130.728461 -251.774452) (xy 129.48285 -251.774452) (xy 129.48236 -251.799441)
			(xy 129.474541 -251.848804) (xy 129.459097 -251.896336) (xy 129.436407 -251.940868) (xy 129.407031 -251.981301)
			(xy 129.371691 -252.016641) (xy 129.331258 -252.046017) (xy 129.286726 -252.068707) (xy 129.239194 -252.084151)
			(xy 129.189831 -252.09197) (xy 129.139853 -252.09197) (xy 129.09049 -252.084151) (xy 129.042958 -252.068707)
			(xy 128.998426 -252.046017) (xy 128.957993 -252.016641) (xy 128.922653 -251.981301) (xy 128.893277 -251.940868)
			(xy 128.870587 -251.896336) (xy 128.855143 -251.848804) (xy 128.847324 -251.799441) (xy 128.540007 -251.799441)
			(xy 128.539998 -251.799898) (xy 128.531834 -251.850132) (xy 128.515718 -251.898406) (xy 128.492067 -251.943469)
			(xy 128.461494 -251.984155) (xy 128.42479 -252.01941) (xy 128.382906 -252.04832) (xy 128.336927 -252.070137)
			(xy 128.288043 -252.084297) (xy 128.237522 -252.090431) (xy 128.18667 -252.088382) (xy 128.136806 -252.078202)
			(xy 128.08922 -252.060155) (xy 128.045146 -252.034709) (xy 128.005724 -252.002522) (xy 127.971976 -251.964428)
			(xy 127.944775 -251.921414) (xy 127.924827 -251.874594) (xy 127.912648 -251.82518) (xy 127.908553 -251.774452)
			(xy 126.662688 -251.774452) (xy 126.662198 -251.799441) (xy 126.654379 -251.848804) (xy 126.638935 -251.896336)
			(xy 126.616245 -251.940868) (xy 126.586869 -251.981301) (xy 126.551529 -252.016641) (xy 126.511096 -252.046017)
			(xy 126.466564 -252.068707) (xy 126.419032 -252.084151) (xy 126.369669 -252.09197) (xy 126.319691 -252.09197)
			(xy 126.270328 -252.084151) (xy 126.222796 -252.068707) (xy 126.178264 -252.046017) (xy 126.137831 -252.016641)
			(xy 126.102491 -251.981301) (xy 126.073115 -251.940868) (xy 126.050425 -251.896336) (xy 126.034981 -251.848804)
			(xy 126.027162 -251.799441) (xy 124.782344 -251.799441) (xy 124.774525 -251.848804) (xy 124.759081 -251.896336)
			(xy 124.736391 -251.940868) (xy 124.707015 -251.981301) (xy 124.671675 -252.016641) (xy 124.631242 -252.046017)
			(xy 124.58671 -252.068707) (xy 124.539178 -252.084151) (xy 124.489815 -252.09197) (xy 124.439837 -252.09197)
			(xy 124.390474 -252.084151) (xy 124.342942 -252.068707) (xy 124.29841 -252.046017) (xy 124.257977 -252.016641)
			(xy 124.222637 -251.981301) (xy 124.193261 -251.940868) (xy 124.170571 -251.896336) (xy 124.155127 -251.848804)
			(xy 124.147308 -251.799441) (xy 124.146818 -251.774452) (xy 124.146818 -251.774198) (xy 124.147406 -251.74556)
			(xy 124.157637 -251.689207) (xy 124.167138 -251.662184) (xy 124.167138 -251.66193) (xy 124.16917 -251.656596)
			(xy 124.170694 -251.644404) (xy 124.169932 -251.639324) (xy 124.168966 -251.633345) (xy 124.164595 -251.622052)
			(xy 124.161296 -251.616972) (xy 124.11456 -251.549408) (xy 124.114306 -251.549154) (xy 124.106732 -251.539568)
			(xy 124.0851 -251.528296) (xy 124.072904 -251.527564) (xy 122.97664 -251.527564) (xy 122.974608 -251.527564)
			(xy 122.963537 -251.528572) (xy 122.943785 -251.538717) (xy 122.936508 -251.547122) (xy 122.888502 -251.616464)
			(xy 122.884804 -251.622199) (xy 122.880301 -251.635075) (xy 122.879612 -251.641864) (xy 122.87885 -251.652786)
			(xy 122.881644 -251.660406) (xy 122.885454 -251.671074) (xy 122.893488 -251.696097) (xy 122.902175 -251.747923)
			(xy 122.902726 -251.774198) (xy 122.902726 -251.774452) (xy 122.902236 -251.799441) (xy 122.894417 -251.848804)
			(xy 122.878973 -251.896336) (xy 122.856283 -251.940868) (xy 122.826907 -251.981301) (xy 122.791567 -252.016641)
			(xy 122.751134 -252.046017) (xy 122.706602 -252.068707) (xy 122.65907 -252.084151) (xy 122.609707 -252.09197)
			(xy 122.559729 -252.09197) (xy 122.510366 -252.084151) (xy 122.462834 -252.068707) (xy 122.418302 -252.046017)
			(xy 122.377869 -252.016641) (xy 122.342529 -251.981301) (xy 122.313153 -251.940868) (xy 122.290463 -251.896336)
			(xy 122.275019 -251.848804) (xy 122.2672 -251.799441) (xy 122.26671 -251.774452) (xy 122.267203 -251.749478)
			(xy 122.275019 -251.700147) (xy 122.290453 -251.652644) (xy 122.313123 -251.608138) (xy 122.342473 -251.567724)
			(xy 122.37778 -251.532395) (xy 122.418177 -251.503021) (xy 122.46267 -251.480325) (xy 122.510164 -251.464863)
			(xy 122.559491 -251.457018) (xy 122.584464 -251.456444) (xy 122.585226 -251.456444) (xy 122.604784 -251.456952)
			(xy 122.605292 -251.456952) (xy 122.620786 -251.455428) (xy 122.62475 -251.454322) (xy 122.632277 -251.450997)
			(xy 122.635772 -251.448824) (xy 122.642884 -251.443236) (xy 122.695716 -251.393706) (xy 122.702804 -251.386338)
			(xy 122.710922 -251.367594) (xy 122.711464 -251.357384) (xy 122.711464 -250.786646) (xy 122.711109 -250.777958)
			(xy 122.705252 -250.761599) (xy 122.700034 -250.754642) (xy 122.696732 -250.750832) (xy 122.599196 -250.653296)
			(xy 122.595466 -250.649773) (xy 122.586893 -250.644141) (xy 122.582178 -250.64212) (xy 122.573542 -250.638564)
			(xy 121.970038 -250.638564) (xy 121.960199 -250.639098) (xy 121.942033 -250.646679) (xy 121.934732 -250.653296)
			(xy 121.710704 -250.877324) (xy 121.704148 -250.884572) (xy 121.696687 -250.902614) (xy 121.696226 -250.912376)
			(xy 121.696226 -251.197364) (xy 121.695464 -251.197364) (xy 121.695464 -251.37999) (xy 121.694926 -251.389827)
			(xy 121.687341 -251.407989) (xy 121.680732 -251.415296) (xy 121.583196 -251.512832) (xy 121.575957 -251.519544)
			(xy 121.557753 -251.527138) (xy 121.54789 -251.527564) (xy 121.096532 -251.527564) (xy 121.0945 -251.527564)
			(xy 121.08343 -251.528573) (xy 121.06368 -251.53872) (xy 121.0564 -251.547122) (xy 121.008394 -251.616464)
			(xy 121.004696 -251.622199) (xy 121.000194 -251.635075) (xy 120.999504 -251.641864) (xy 120.998742 -251.652786)
			(xy 121.001536 -251.660406) (xy 121.005346 -251.671074) (xy 121.01338 -251.696097) (xy 121.022068 -251.747923)
			(xy 121.022618 -251.774198) (xy 121.022618 -251.774452) (xy 121.022128 -251.799441) (xy 121.014309 -251.848804)
			(xy 120.998865 -251.896336) (xy 120.976175 -251.940868) (xy 120.946799 -251.981301) (xy 120.911459 -252.016641)
			(xy 120.871026 -252.046017) (xy 120.826494 -252.068707) (xy 120.778962 -252.084151) (xy 120.729599 -252.09197)
			(xy 120.679621 -252.09197) (xy 120.630258 -252.084151) (xy 120.582726 -252.068707) (xy 120.538194 -252.046017)
			(xy 120.497761 -252.016641) (xy 120.462421 -251.981301) (xy 120.433045 -251.940868) (xy 120.410355 -251.896336)
			(xy 120.394911 -251.848804) (xy 120.387092 -251.799441) (xy 120.386602 -251.774452) (xy 120.386602 -251.774198)
			(xy 120.387189 -251.74556) (xy 120.397421 -251.689207) (xy 120.406922 -251.662184) (xy 120.406922 -251.66193)
			(xy 120.408954 -251.656596) (xy 120.410478 -251.644404) (xy 120.409716 -251.639324) (xy 120.408749 -251.633345)
			(xy 120.404377 -251.622053) (xy 120.40108 -251.616972) (xy 120.354344 -251.549408) (xy 120.35409 -251.549154)
			(xy 120.346515 -251.539571) (xy 120.324883 -251.528305) (xy 120.312688 -251.527564) (xy 119.33301 -251.527564)
			(xy 119.323191 -251.528095) (xy 119.305076 -251.535691) (xy 119.291227 -251.549621) (xy 119.283737 -251.56778)
			(xy 119.283226 -251.577602) (xy 119.283226 -252.03912) (xy 119.282972 -252.04166) (xy 119.282972 -252.056646)
			(xy 119.253254 -252.086364) (xy 119.067834 -252.086364) (xy 119.058653 -252.086822) (xy 119.041537 -252.093486)
			(xy 119.027939 -252.105833) (xy 119.01966 -252.122229) (xy 119.018304 -252.131322) (xy 119.018304 -252.146308)
			(xy 118.763288 -252.146308) (xy 118.743391 -252.145829) (xy 118.704298 -252.138388) (xy 118.667256 -252.123841)
			(xy 118.633547 -252.10269) (xy 118.604335 -252.075666) (xy 118.580629 -252.043702) (xy 118.563248 -252.007903)
			(xy 118.552793 -251.969505) (xy 118.55069 -251.949712) (xy 118.550182 -251.944378) (xy 118.544594 -251.925328)
			(xy 118.542308 -251.92101) (xy 118.531094 -251.89827) (xy 118.515232 -251.850117) (xy 118.507215 -251.800056)
			(xy 118.506748 -251.774706) (xy 118.506748 -251.769118) (xy 118.507663 -251.743991) (xy 118.516437 -251.694485)
			(xy 118.532884 -251.646974) (xy 118.54434 -251.624592) (xy 118.546626 -251.62002) (xy 118.551452 -251.604018)
			(xy 118.55196 -251.600208) (xy 118.55558 -251.578697) (xy 118.570394 -251.537676) (xy 118.593207 -251.500503)
			(xy 118.623074 -251.468719) (xy 118.658757 -251.443641) (xy 118.698779 -251.426306) (xy 118.741481 -251.417434)
			(xy 118.763288 -251.41682) (xy 118.851426 -251.41682) (xy 118.861247 -251.416341) (xy 118.879401 -251.408838)
			(xy 118.89332 -251.394977) (xy 118.900899 -251.376855) (xy 118.901464 -251.367036) (xy 118.901464 -250.786646)
			(xy 118.901109 -250.777958) (xy 118.895252 -250.761599) (xy 118.890034 -250.754642) (xy 118.886732 -250.750832)
			(xy 118.789196 -250.653296) (xy 118.785466 -250.649773) (xy 118.776893 -250.644141) (xy 118.772178 -250.64212)
			(xy 118.763542 -250.638564) (xy 118.160038 -250.638564) (xy 118.150199 -250.639098) (xy 118.132033 -250.646679)
			(xy 118.124732 -250.653296) (xy 118.027196 -250.750832) (xy 118.020485 -250.758071) (xy 118.012897 -250.776276)
			(xy 118.012464 -250.786138) (xy 118.012464 -251.12599) (xy 118.011926 -251.135827) (xy 118.004341 -251.153989)
			(xy 117.997732 -251.161296) (xy 117.773196 -251.385832) (xy 117.765957 -251.392544) (xy 117.747753 -251.400138)
			(xy 117.73789 -251.400564) (xy 117.42801 -251.400564) (xy 117.418191 -251.401095) (xy 117.400076 -251.408691)
			(xy 117.386227 -251.422621) (xy 117.378737 -251.44078) (xy 117.378226 -251.450602) (xy 117.378226 -252.03912)
			(xy 117.377972 -252.04166) (xy 117.377972 -252.056646) (xy 117.348254 -252.086364) (xy 117.162834 -252.086364)
			(xy 117.153653 -252.086822) (xy 117.136537 -252.093486) (xy 117.122939 -252.105833) (xy 117.11466 -252.122229)
			(xy 117.113304 -252.131322) (xy 117.113304 -252.146308) (xy 116.858288 -252.146308) (xy 116.837026 -252.145817)
			(xy 116.795335 -252.13744) (xy 116.756126 -252.12098) (xy 116.720949 -252.097088) (xy 116.691194 -252.066708)
			(xy 116.668039 -252.031041) (xy 116.652398 -251.991498) (xy 116.64489 -251.949642) (xy 116.644928 -251.928376)
			(xy 116.644928 -251.881132) (xy 116.642388 -251.873258) (xy 116.63503 -251.849223) (xy 116.627124 -251.799586)
			(xy 116.627131 -251.749323) (xy 116.635052 -251.699688) (xy 116.642388 -251.675646) (xy 116.644928 -251.667772)
			(xy 116.644928 -251.636022) (xy 116.644928 -251.635006) (xy 116.644883 -251.618129) (xy 116.649472 -251.584695)
			(xy 116.654072 -251.568458) (xy 116.65458 -251.567442) (xy 116.654834 -251.566172) (xy 116.66855 -251.52223)
			(xy 116.668385 -251.514711) (xy 116.664248 -251.500258) (xy 116.660422 -251.493782) (xy 116.64188 -251.46508)
			(xy 116.614956 -251.423678) (xy 116.607481 -251.413419) (xy 116.585212 -251.401305) (xy 116.572538 -251.400564)
			(xy 115.65001 -251.400564) (xy 115.640191 -251.401095) (xy 115.622076 -251.408691) (xy 115.608227 -251.422621)
			(xy 115.600737 -251.44078) (xy 115.600226 -251.450602) (xy 115.600226 -252.03912) (xy 115.599972 -252.04166)
			(xy 115.599972 -252.056646) (xy 115.570254 -252.086364) (xy 115.384834 -252.086364) (xy 115.375653 -252.086822)
			(xy 115.358537 -252.093486) (xy 115.344939 -252.105833) (xy 115.33666 -252.122229) (xy 115.335304 -252.131322)
			(xy 115.335304 -252.146308) (xy 115.080288 -252.146308) (xy 115.060267 -252.145868) (xy 115.020923 -252.138423)
			(xy 114.983663 -252.123758) (xy 114.949799 -252.10239) (xy 114.920522 -252.075073) (xy 114.90833 -252.059186)
			(xy 114.90706 -252.057408) (xy 114.901472 -252.051058) (xy 114.891566 -252.041152) (xy 114.887502 -252.038358)
			(xy 114.866226 -252.023466) (xy 114.828379 -251.98791) (xy 114.796821 -251.94667) (xy 114.772392 -251.900846)
			(xy 114.755743 -251.851658) (xy 114.747319 -251.800417) (xy 114.746786 -251.774452) (xy 114.747214 -251.750522)
			(xy 114.754378 -251.703202) (xy 114.768552 -251.65749) (xy 114.789416 -251.614418) (xy 114.816498 -251.574958)
			(xy 114.849188 -251.540002) (xy 114.886747 -251.51034) (xy 114.907314 -251.4981) (xy 114.908838 -251.497338)
			(xy 114.910616 -251.496322) (xy 114.922046 -251.487178) (xy 114.923824 -251.4854) (xy 114.92484 -251.48413)
			(xy 114.933562 -251.475087) (xy 114.952791 -251.458917) (xy 114.963194 -251.451872) (xy 114.96675 -251.449586)
			(xy 114.967004 -251.449586) (xy 114.967512 -251.449332) (xy 114.972097 -251.44624) (xy 114.979917 -251.438425)
			(xy 114.983006 -251.433838) (xy 114.986054 -251.429012) (xy 114.989864 -251.418344) (xy 114.999516 -251.334016)
			(xy 114.99985 -251.322925) (xy 114.992228 -251.30211) (xy 114.984784 -251.293884) (xy 114.979196 -251.288296)
			(xy 114.972481 -251.281059) (xy 114.964883 -251.262854) (xy 114.964464 -251.25299) (xy 114.964464 -250.913646)
			(xy 114.964109 -250.904958) (xy 114.958252 -250.888599) (xy 114.953034 -250.881642) (xy 114.949732 -250.877832)
			(xy 114.852196 -250.780296) (xy 114.848466 -250.776773) (xy 114.839893 -250.771141) (xy 114.835178 -250.76912)
			(xy 114.826542 -250.765564) (xy 114.06124 -250.765564) (xy 114.054429 -250.765777) (xy 114.041292 -250.769374)
			(xy 114.035332 -250.772676) (xy 114.031628 -250.774957) (xy 114.024989 -250.780578) (xy 114.022124 -250.783852)
			(xy 113.973356 -250.84659) (xy 113.969963 -250.851216) (xy 113.965092 -250.861598) (xy 113.963704 -250.867164)
			(xy 113.961418 -250.878086) (xy 113.965228 -250.89485) (xy 113.965228 -250.895104) (xy 113.968749 -250.912031)
			(xy 113.972563 -250.946397) (xy 113.972848 -250.963684) (xy 113.972848 -250.964446) (xy 113.972358 -250.989435)
			(xy 113.964539 -251.038798) (xy 113.949095 -251.08633) (xy 113.926405 -251.130862) (xy 113.897029 -251.171295)
			(xy 113.861689 -251.206635) (xy 113.821256 -251.236011) (xy 113.776724 -251.258701) (xy 113.729192 -251.274145)
			(xy 113.679829 -251.281964) (xy 113.629851 -251.281964) (xy 113.580488 -251.274145) (xy 113.532956 -251.258701)
			(xy 113.488424 -251.236011) (xy 113.447991 -251.206635) (xy 113.412651 -251.171295) (xy 113.383275 -251.130862)
			(xy 113.360585 -251.08633) (xy 113.345141 -251.038798) (xy 113.337322 -250.989435) (xy 113.336832 -250.964446)
			(xy 113.336832 -250.963684) (xy 113.337088 -250.946395) (xy 113.34091 -250.912028) (xy 113.344452 -250.895104)
			(xy 113.344452 -250.89485) (xy 113.348262 -250.878086) (xy 113.345976 -250.867164) (xy 113.344629 -250.861584)
			(xy 113.339754 -250.851194) (xy 113.336324 -250.84659) (xy 113.287556 -250.783852) (xy 113.284698 -250.78057)
			(xy 113.278061 -250.774945) (xy 113.274348 -250.772676) (xy 113.26838 -250.769393) (xy 113.255248 -250.765791)
			(xy 113.24844 -250.765564) (xy 109.778038 -250.765564) (xy 109.768199 -250.766098) (xy 109.750033 -250.773679)
			(xy 109.742732 -250.780296) (xy 109.010196 -251.512832) (xy 109.002957 -251.519544) (xy 108.984753 -251.527138)
			(xy 108.97489 -251.527564) (xy 108.15701 -251.527564) (xy 108.147191 -251.528095) (xy 108.129076 -251.535691)
			(xy 108.115227 -251.549621) (xy 108.107737 -251.56778) (xy 108.107226 -251.577602) (xy 108.107226 -251.774452)
			(xy 109.113066 -251.774452) (xy 109.113584 -251.749529) (xy 109.121391 -251.700296) (xy 109.13676 -251.652877)
			(xy 109.14761 -251.630434) (xy 109.149658 -251.626046) (xy 109.152219 -251.616711) (xy 109.15269 -251.611892)
			(xy 109.15484 -251.592185) (xy 109.16547 -251.553999) (xy 109.182965 -251.518431) (xy 109.206722 -251.486703)
			(xy 109.235927 -251.459903) (xy 109.269576 -251.438953) (xy 109.306513 -251.424573) (xy 109.345469 -251.417256)
			(xy 109.365288 -251.41682) (xy 109.620304 -251.41682) (xy 109.620304 -251.425964) (xy 109.620749 -251.435983)
			(xy 109.628408 -251.4545) (xy 109.642573 -251.468674) (xy 109.661085 -251.476344) (xy 109.671104 -251.476764)
			(xy 109.834172 -251.476764) (xy 109.844173 -251.47731) (xy 109.862658 -251.484954) (xy 109.876811 -251.499088)
			(xy 109.884477 -251.517563) (xy 109.884972 -251.527564) (xy 109.884972 -251.654564) (xy 111.8108 -251.654564)
			(xy 111.8108 -251.146564) (xy 111.811259 -251.136554) (xy 111.81893 -251.118061) (xy 111.833092 -251.10391)
			(xy 111.85159 -251.096251) (xy 111.8616 -251.095764) (xy 112.075468 -251.095764) (xy 112.075468 -251.08662)
			(xy 112.076004 -251.076618) (xy 112.083651 -251.058132) (xy 112.097789 -251.04398) (xy 112.116266 -251.036314)
			(xy 112.126268 -251.03582) (xy 112.330484 -251.03582) (xy 112.350556 -251.03624) (xy 112.38999 -251.043767)
			(xy 112.427318 -251.058539) (xy 112.461224 -251.080035) (xy 112.490509 -251.107494) (xy 112.502696 -251.12345)
			(xy 112.510316 -251.131832) (xy 112.530823 -251.150448) (xy 112.566469 -251.192833) (xy 112.595127 -251.240224)
			(xy 112.616105 -251.291479) (xy 112.628899 -251.345362) (xy 112.633201 -251.400576) (xy 112.628907 -251.455791)
			(xy 112.61612 -251.509676) (xy 112.595148 -251.560934) (xy 112.566497 -251.608328) (xy 112.530857 -251.650718)
			(xy 112.510316 -251.669296) (xy 112.502696 -251.677678) (xy 112.490525 -251.693639) (xy 112.461211 -251.721056)
			(xy 112.427297 -251.742522) (xy 112.389974 -251.757285) (xy 112.350552 -251.764825) (xy 112.330484 -251.765308)
			(xy 112.075468 -251.765308) (xy 112.075468 -251.756164) (xy 112.075041 -251.74615) (xy 112.067363 -251.727651)
			(xy 112.053191 -251.713499) (xy 112.034683 -251.705846) (xy 112.024668 -251.705364) (xy 111.8616 -251.705364)
			(xy 111.851574 -251.70498) (xy 111.83305 -251.697303) (xy 111.818877 -251.683119) (xy 111.811213 -251.66459)
			(xy 111.8108 -251.654564) (xy 109.884972 -251.654564) (xy 109.884972 -251.774452) (xy 112.866678 -251.774452)
			(xy 112.867132 -251.75076) (xy 112.874139 -251.703898) (xy 112.888019 -251.658593) (xy 112.908467 -251.615849)
			(xy 112.935028 -251.576611) (xy 112.967117 -251.541747) (xy 112.985296 -251.526548) (xy 112.988425 -251.523953)
			(xy 112.993913 -251.517958) (xy 112.996218 -251.51461) (xy 113.008165 -251.496975) (xy 113.037867 -251.466452)
			(xy 113.07303 -251.442422) (xy 113.112257 -251.425836) (xy 113.153994 -251.417354) (xy 113.175288 -251.41682)
			(xy 113.430304 -251.41682) (xy 113.430304 -251.425964) (xy 113.430749 -251.435983) (xy 113.438408 -251.4545)
			(xy 113.452573 -251.468674) (xy 113.471085 -251.476344) (xy 113.481104 -251.476764) (xy 113.644172 -251.476764)
			(xy 113.654173 -251.47731) (xy 113.672658 -251.484954) (xy 113.686811 -251.499088) (xy 113.694477 -251.517563)
			(xy 113.694972 -251.527564) (xy 113.694972 -252.035564) (xy 113.69455 -252.045586) (xy 113.686887 -252.064108)
			(xy 113.672715 -252.078282) (xy 113.654194 -252.085949) (xy 113.644172 -252.086364) (xy 113.430304 -252.086364)
			(xy 113.430304 -252.095508) (xy 113.429818 -252.105516) (xy 113.422157 -252.124007) (xy 113.408003 -252.138159)
			(xy 113.389512 -252.145819) (xy 113.379504 -252.146308) (xy 113.175288 -252.146308) (xy 113.15541 -252.145828)
			(xy 113.116341 -252.138467) (xy 113.07931 -252.124001) (xy 113.045596 -252.102931) (xy 113.016365 -252.075985)
			(xy 112.992626 -252.044094) (xy 112.983518 -252.02642) (xy 112.981278 -252.022076) (xy 112.975394 -252.014275)
			(xy 112.971834 -252.010926) (xy 112.95238 -251.992676) (xy 112.919281 -251.95085) (xy 112.893613 -251.904094)
			(xy 112.876095 -251.853715) (xy 112.867215 -251.801121) (xy 112.866678 -251.774452) (xy 109.884972 -251.774452)
			(xy 109.884972 -252.035564) (xy 109.88455 -252.045586) (xy 109.876887 -252.064108) (xy 109.862715 -252.078282)
			(xy 109.844194 -252.085949) (xy 109.834172 -252.086364) (xy 109.620304 -252.086364) (xy 109.620304 -252.095508)
			(xy 109.619818 -252.105516) (xy 109.612157 -252.124007) (xy 109.598003 -252.138159) (xy 109.579512 -252.145819)
			(xy 109.569504 -252.146308) (xy 109.365288 -252.146308) (xy 109.344206 -252.145887) (xy 109.302861 -252.137615)
			(xy 109.263942 -252.121394) (xy 109.22896 -252.097855) (xy 109.199274 -252.067912) (xy 109.176038 -252.032728)
			(xy 109.160153 -251.99367) (xy 109.152239 -251.952256) (xy 109.151928 -251.93117) (xy 109.151928 -251.927106)
			(xy 109.139699 -251.903539) (xy 109.122362 -251.853358) (xy 109.113584 -251.800998) (xy 109.113066 -251.774452)
			(xy 108.107226 -251.774452) (xy 108.107226 -252.03912) (xy 108.106972 -252.04166) (xy 108.106972 -252.056646)
			(xy 108.077254 -252.086364) (xy 107.891834 -252.086364) (xy 107.882653 -252.086822) (xy 107.865537 -252.093486)
			(xy 107.851939 -252.105833) (xy 107.84366 -252.122229) (xy 107.842304 -252.131322) (xy 107.842304 -252.146308)
			(xy 107.587034 -252.146308) (xy 107.564567 -252.145735) (xy 107.520632 -252.136306) (xy 107.47964 -252.1179)
			(xy 107.443401 -252.09133) (xy 107.42803 -252.074934) (xy 107.42549 -252.071886) (xy 107.425236 -252.071632)
			(xy 107.41025 -252.059694) (xy 107.405932 -252.057408) (xy 107.405424 -252.057154) (xy 107.383515 -252.045329)
			(xy 107.343347 -252.015919) (xy 107.30825 -251.980612) (xy 107.27908 -251.94027) (xy 107.256549 -251.895877)
			(xy 107.241208 -251.848516) (xy 107.23343 -251.799344) (xy 107.232958 -251.774452) (xy 107.232958 -251.771404)
			(xy 107.233821 -251.743742) (xy 107.243912 -251.689332) (xy 107.253024 -251.6632) (xy 107.253278 -251.662692)
			(xy 107.255244 -251.656874) (xy 107.256646 -251.644677) (xy 107.256072 -251.638562) (xy 107.254548 -251.626878)
			(xy 107.2007 -251.549408) (xy 107.200446 -251.549154) (xy 107.192874 -251.539561) (xy 107.171243 -251.528272)
			(xy 107.159044 -251.527564) (xy 106.25201 -251.527564) (xy 106.242191 -251.528095) (xy 106.224076 -251.535691)
			(xy 106.210227 -251.549621) (xy 106.202737 -251.56778) (xy 106.202226 -251.577602) (xy 106.202226 -252.03912)
			(xy 106.201972 -252.04166) (xy 106.201972 -252.056646) (xy 106.172254 -252.086364) (xy 105.986834 -252.086364)
			(xy 105.977653 -252.086822) (xy 105.960537 -252.093486) (xy 105.946939 -252.105833) (xy 105.93866 -252.122229)
			(xy 105.937304 -252.131322) (xy 105.937304 -252.146308) (xy 105.682034 -252.146308) (xy 105.661339 -252.145759)
			(xy 105.620744 -252.137676) (xy 105.582459 -252.12194) (xy 105.547914 -252.099139) (xy 105.518395 -252.070122)
			(xy 105.506266 -252.053344) (xy 105.503726 -252.049534) (xy 105.491026 -252.03658) (xy 105.48747 -252.03404)
			(xy 105.467192 -252.01911) (xy 105.431176 -251.983918) (xy 105.401153 -251.943492) (xy 105.377873 -251.898841)
			(xy 105.361917 -251.851081) (xy 105.353684 -251.801404) (xy 105.353104 -251.77623) (xy 105.353104 -251.774198)
			(xy 105.353748 -251.74583) (xy 105.363836 -251.689996) (xy 105.37317 -251.6632) (xy 105.373424 -251.662692)
			(xy 105.375407 -251.656878) (xy 105.376811 -251.644677) (xy 105.376218 -251.638562) (xy 105.374694 -251.626878)
			(xy 105.320846 -251.549408) (xy 105.320592 -251.549154) (xy 105.313017 -251.53957) (xy 105.291385 -251.528304)
			(xy 105.27919 -251.527564) (xy 104.34701 -251.527564) (xy 104.337191 -251.528095) (xy 104.319076 -251.535691)
			(xy 104.305227 -251.549621) (xy 104.297737 -251.56778) (xy 104.297226 -251.577602) (xy 104.297226 -252.03912)
			(xy 104.296972 -252.04166) (xy 104.296972 -252.056646) (xy 104.267254 -252.086364) (xy 104.081834 -252.086364)
			(xy 104.072653 -252.086822) (xy 104.055537 -252.093486) (xy 104.041939 -252.105833) (xy 104.03366 -252.122229)
			(xy 104.032304 -252.131322) (xy 104.032304 -252.146308) (xy 103.777034 -252.146308) (xy 103.757009 -252.145801)
			(xy 103.717679 -252.138229) (xy 103.680449 -252.123458) (xy 103.646626 -252.102005) (xy 103.617396 -252.074623)
			(xy 103.593783 -252.042271) (xy 103.584756 -252.024388) (xy 103.58247 -252.019816) (xy 103.57104 -252.004322)
			(xy 103.5685 -252.001782) (xy 103.550757 -251.983726) (xy 103.520655 -251.943028) (xy 103.497386 -251.898072)
			(xy 103.481538 -251.849996) (xy 103.473512 -251.800016) (xy 103.472996 -251.774706) (xy 103.472996 -251.771404)
			(xy 103.473859 -251.743742) (xy 103.483951 -251.689333) (xy 103.493062 -251.6632) (xy 103.493316 -251.662692)
			(xy 103.495299 -251.656878) (xy 103.496703 -251.644677) (xy 103.49611 -251.638562) (xy 103.494586 -251.626878)
			(xy 103.440738 -251.549408) (xy 103.440484 -251.549154) (xy 103.432908 -251.539572) (xy 103.411276 -251.528309)
			(xy 103.399082 -251.527564) (xy 102.40391 -251.527564) (xy 102.388674 -251.528072) (xy 102.359556 -251.537056)
			(xy 102.334383 -251.554228) (xy 102.315393 -251.57806) (xy 102.304277 -251.606433) (xy 102.302023 -251.636822)
			(xy 102.308832 -251.666524) (xy 102.316026 -251.679964) (xy 102.36835 -251.770388) (xy 102.369112 -251.771912)
			(xy 102.370128 -251.773182) (xy 102.371144 -251.77496) (xy 102.373176 -251.77877) (xy 102.37851 -251.787914)
			(xy 102.367334 -251.828554) (xy 102.36708 -251.828808) (xy 102.366826 -251.829062) (xy 102.361492 -251.849128)
			(xy 102.359416 -251.858875) (xy 102.362034 -251.87861) (xy 102.366572 -251.887482) (xy 102.448614 -252.029214)
			(xy 102.449884 -252.031246) (xy 102.450392 -252.032516) (xy 102.458774 -252.047248) (xy 102.448106 -252.087888)
			(xy 102.447852 -252.087888) (xy 102.439216 -252.092968) (xy 102.43185 -252.097286) (xy 102.430326 -252.098048)
			(xy 101.908102 -252.399546) (xy 101.898687 -252.405873) (xy 101.88614 -252.424735) (xy 101.883972 -252.435868)
			(xy 101.883464 -252.44298) (xy 101.883464 -252.670564) (xy 111.791496 -252.670564) (xy 111.791496 -252.162564)
			(xy 111.791958 -252.152555) (xy 111.799629 -252.134063) (xy 111.81379 -252.119911) (xy 111.832286 -252.112252)
			(xy 111.842296 -252.111764) (xy 112.056672 -252.111764) (xy 112.056672 -252.10262) (xy 112.057204 -252.092617)
			(xy 112.064851 -252.074131) (xy 112.078991 -252.059978) (xy 112.09747 -252.052313) (xy 112.107472 -252.05182)
			(xy 112.311434 -252.05182) (xy 112.331505 -252.052276) (xy 112.370936 -252.059794) (xy 112.408264 -252.074557)
			(xy 112.442171 -252.096045) (xy 112.471457 -252.123497) (xy 112.483646 -252.13945) (xy 112.491266 -252.147832)
			(xy 112.511771 -252.16645) (xy 112.547412 -252.208837) (xy 112.576065 -252.256228) (xy 112.597041 -252.307482)
			(xy 112.609833 -252.361364) (xy 112.614134 -252.416576) (xy 112.60984 -252.471789) (xy 112.597055 -252.525673)
			(xy 112.576087 -252.57693) (xy 112.571537 -252.584458) (xy 120.856756 -252.584458) (xy 120.857272 -252.558242)
			(xy 120.865878 -252.506521) (xy 120.882835 -252.456906) (xy 120.907685 -252.410736) (xy 120.939757 -252.369257)
			(xy 120.95861 -252.351032) (xy 120.963314 -252.346371) (xy 120.970392 -252.335184) (xy 120.97258 -252.328934)
			(xy 120.978779 -252.310593) (xy 120.996766 -252.276316) (xy 121.020628 -252.245836) (xy 121.049586 -252.220147)
			(xy 121.082693 -252.200088) (xy 121.11887 -252.186314) (xy 121.156934 -252.179275) (xy 121.176288 -252.17882)
			(xy 121.431304 -252.17882) (xy 121.431304 -252.187964) (xy 121.431749 -252.197983) (xy 121.439408 -252.2165)
			(xy 121.453573 -252.230674) (xy 121.472085 -252.238344) (xy 121.482104 -252.238764) (xy 121.645172 -252.238764)
			(xy 121.655173 -252.23931) (xy 121.673658 -252.246954) (xy 121.687811 -252.261088) (xy 121.695477 -252.279563)
			(xy 121.695972 -252.289564) (xy 121.695972 -252.584458) (xy 122.73661 -252.584458) (xy 122.737098 -252.559239)
			(xy 122.745046 -252.509431) (xy 122.760766 -252.461506) (xy 122.783864 -252.416668) (xy 122.81376 -252.376045)
			(xy 122.8497 -252.340658) (xy 122.86996 -252.325632) (xy 122.875297 -252.321536) (xy 122.883796 -252.311115)
			(xy 122.886724 -252.305058) (xy 122.895532 -252.286597) (xy 122.919038 -252.25313) (xy 122.948482 -252.224747)
			(xy 122.982787 -252.202483) (xy 123.020702 -252.187151) (xy 123.06084 -252.179313) (xy 123.081288 -252.17882)
			(xy 123.336304 -252.17882) (xy 123.336304 -252.187964) (xy 123.336749 -252.197983) (xy 123.344408 -252.2165)
			(xy 123.358573 -252.230674) (xy 123.377085 -252.238344) (xy 123.387104 -252.238764) (xy 123.550172 -252.238764)
			(xy 123.560173 -252.23931) (xy 123.578658 -252.246954) (xy 123.592811 -252.261088) (xy 123.600477 -252.279563)
			(xy 123.600972 -252.289564) (xy 123.600972 -252.584458) (xy 124.616718 -252.584458) (xy 124.61712 -252.56318)
			(xy 124.622841 -252.521009) (xy 124.634123 -252.479975) (xy 124.642118 -252.460252) (xy 124.645928 -252.4506)
			(xy 124.645928 -252.39345) (xy 124.646288 -252.372402) (xy 124.654288 -252.331077) (xy 124.670224 -252.292118)
			(xy 124.69348 -252.257034) (xy 124.723156 -252.227183) (xy 124.758102 -252.203719) (xy 124.796965 -252.187553)
			(xy 124.838242 -252.179309) (xy 124.859288 -252.17882) (xy 125.114304 -252.17882) (xy 125.114304 -252.187964)
			(xy 125.114749 -252.197983) (xy 125.122408 -252.2165) (xy 125.136573 -252.230674) (xy 125.155085 -252.238344)
			(xy 125.165104 -252.238764) (xy 125.328172 -252.238764) (xy 125.338173 -252.23931) (xy 125.356658 -252.246954)
			(xy 125.370811 -252.261088) (xy 125.378477 -252.279563) (xy 125.378972 -252.289564) (xy 125.378972 -252.609447)
			(xy 126.497316 -252.609447) (xy 126.497316 -252.559469) (xy 126.505135 -252.510106) (xy 126.520579 -252.462574)
			(xy 126.543269 -252.418042) (xy 126.572645 -252.377609) (xy 126.607985 -252.342269) (xy 126.648418 -252.312893)
			(xy 126.69295 -252.290203) (xy 126.740482 -252.274759) (xy 126.789845 -252.26694) (xy 126.839823 -252.26694)
			(xy 126.889186 -252.274759) (xy 126.936718 -252.290203) (xy 126.98125 -252.312893) (xy 127.021683 -252.342269)
			(xy 127.057023 -252.377609) (xy 127.086399 -252.418042) (xy 127.109089 -252.462574) (xy 127.124533 -252.510106)
			(xy 127.132352 -252.559469) (xy 127.132842 -252.584458) (xy 127.132352 -252.609447) (xy 127.437116 -252.609447)
			(xy 127.437116 -252.559469) (xy 127.444935 -252.510106) (xy 127.460379 -252.462574) (xy 127.483069 -252.418042)
			(xy 127.512445 -252.377609) (xy 127.547785 -252.342269) (xy 127.588218 -252.312893) (xy 127.63275 -252.290203)
			(xy 127.680282 -252.274759) (xy 127.729645 -252.26694) (xy 127.779623 -252.26694) (xy 127.828986 -252.274759)
			(xy 127.876518 -252.290203) (xy 127.92105 -252.312893) (xy 127.961483 -252.342269) (xy 127.996823 -252.377609)
			(xy 128.026199 -252.418042) (xy 128.048889 -252.462574) (xy 128.064333 -252.510106) (xy 128.072152 -252.559469)
			(xy 128.072642 -252.584458) (xy 128.072152 -252.609447) (xy 128.37717 -252.609447) (xy 128.37717 -252.559469)
			(xy 128.384989 -252.510106) (xy 128.400433 -252.462574) (xy 128.423123 -252.418042) (xy 128.452499 -252.377609)
			(xy 128.487839 -252.342269) (xy 128.528272 -252.312893) (xy 128.572804 -252.290203) (xy 128.620336 -252.274759)
			(xy 128.669699 -252.26694) (xy 128.719677 -252.26694) (xy 128.76904 -252.274759) (xy 128.816572 -252.290203)
			(xy 128.861104 -252.312893) (xy 128.901537 -252.342269) (xy 128.936877 -252.377609) (xy 128.966253 -252.418042)
			(xy 128.988943 -252.462574) (xy 129.004387 -252.510106) (xy 129.012206 -252.559469) (xy 129.012696 -252.584458)
			(xy 129.318507 -252.584458) (xy 129.322602 -252.53373) (xy 129.334781 -252.484316) (xy 129.354729 -252.437496)
			(xy 129.38193 -252.394482) (xy 129.415678 -252.356388) (xy 129.4551 -252.324201) (xy 129.499174 -252.298755)
			(xy 129.54676 -252.280708) (xy 129.596624 -252.270528) (xy 129.647476 -252.268479) (xy 129.697997 -252.274613)
			(xy 129.746881 -252.288773) (xy 129.79286 -252.31059) (xy 129.834744 -252.3395) (xy 129.871448 -252.374755)
			(xy 129.902021 -252.415441) (xy 129.925672 -252.460504) (xy 129.941788 -252.508778) (xy 129.949952 -252.559012)
			(xy 129.950464 -252.584458) (xy 129.949961 -252.609447) (xy 130.257278 -252.609447) (xy 130.257278 -252.559469)
			(xy 130.265097 -252.510106) (xy 130.280541 -252.462574) (xy 130.303231 -252.418042) (xy 130.332607 -252.377609)
			(xy 130.367947 -252.342269) (xy 130.40838 -252.312893) (xy 130.452912 -252.290203) (xy 130.500444 -252.274759)
			(xy 130.549807 -252.26694) (xy 130.599785 -252.26694) (xy 130.649148 -252.274759) (xy 130.69668 -252.290203)
			(xy 130.741212 -252.312893) (xy 130.781645 -252.342269) (xy 130.816985 -252.377609) (xy 130.846361 -252.418042)
			(xy 130.869051 -252.462574) (xy 130.884495 -252.510106) (xy 130.892314 -252.559469) (xy 130.892804 -252.584458)
			(xy 130.892314 -252.609447) (xy 131.197332 -252.609447) (xy 131.197332 -252.559469) (xy 131.205151 -252.510106)
			(xy 131.220595 -252.462574) (xy 131.243285 -252.418042) (xy 131.272661 -252.377609) (xy 131.308001 -252.342269)
			(xy 131.348434 -252.312893) (xy 131.392966 -252.290203) (xy 131.440498 -252.274759) (xy 131.489861 -252.26694)
			(xy 131.539839 -252.26694) (xy 131.589202 -252.274759) (xy 131.636734 -252.290203) (xy 131.681266 -252.312893)
			(xy 131.721699 -252.342269) (xy 131.757039 -252.377609) (xy 131.786415 -252.418042) (xy 131.809105 -252.462574)
			(xy 131.824549 -252.510106) (xy 131.832368 -252.559469) (xy 131.832858 -252.584458) (xy 132.138415 -252.584458)
			(xy 132.14251 -252.53373) (xy 132.154689 -252.484316) (xy 132.174637 -252.437496) (xy 132.201838 -252.394482)
			(xy 132.235586 -252.356388) (xy 132.275008 -252.324201) (xy 132.319082 -252.298755) (xy 132.366668 -252.280708)
			(xy 132.416532 -252.270528) (xy 132.467384 -252.268479) (xy 132.517905 -252.274613) (xy 132.566789 -252.288773)
			(xy 132.612768 -252.31059) (xy 132.654652 -252.3395) (xy 132.691356 -252.374755) (xy 132.721929 -252.415441)
			(xy 132.74558 -252.460504) (xy 132.761696 -252.508778) (xy 132.76986 -252.559012) (xy 132.770372 -252.584458)
			(xy 132.769869 -252.609447) (xy 133.077186 -252.609447) (xy 133.077186 -252.559469) (xy 133.085005 -252.510106)
			(xy 133.100449 -252.462574) (xy 133.123139 -252.418042) (xy 133.152515 -252.377609) (xy 133.187855 -252.342269)
			(xy 133.228288 -252.312893) (xy 133.27282 -252.290203) (xy 133.320352 -252.274759) (xy 133.369715 -252.26694)
			(xy 133.419693 -252.26694) (xy 133.469056 -252.274759) (xy 133.516588 -252.290203) (xy 133.56112 -252.312893)
			(xy 133.601553 -252.342269) (xy 133.636893 -252.377609) (xy 133.666269 -252.418042) (xy 133.688959 -252.462574)
			(xy 133.704403 -252.510106) (xy 133.712222 -252.559469) (xy 133.712712 -252.584458) (xy 133.712222 -252.609447)
			(xy 134.01724 -252.609447) (xy 134.01724 -252.559469) (xy 134.025059 -252.510106) (xy 134.040503 -252.462574)
			(xy 134.063193 -252.418042) (xy 134.092569 -252.377609) (xy 134.127909 -252.342269) (xy 134.168342 -252.312893)
			(xy 134.212874 -252.290203) (xy 134.260406 -252.274759) (xy 134.309769 -252.26694) (xy 134.359747 -252.26694)
			(xy 134.40911 -252.274759) (xy 134.456642 -252.290203) (xy 134.501174 -252.312893) (xy 134.541607 -252.342269)
			(xy 134.576947 -252.377609) (xy 134.606323 -252.418042) (xy 134.629013 -252.462574) (xy 134.644457 -252.510106)
			(xy 134.652276 -252.559469) (xy 134.652766 -252.584458) (xy 134.652276 -252.609447) (xy 134.957294 -252.609447)
			(xy 134.957294 -252.559469) (xy 134.965113 -252.510106) (xy 134.980557 -252.462574) (xy 135.003247 -252.418042)
			(xy 135.032623 -252.377609) (xy 135.067963 -252.342269) (xy 135.108396 -252.312893) (xy 135.152928 -252.290203)
			(xy 135.20046 -252.274759) (xy 135.249823 -252.26694) (xy 135.299801 -252.26694) (xy 135.349164 -252.274759)
			(xy 135.396696 -252.290203) (xy 135.441228 -252.312893) (xy 135.481661 -252.342269) (xy 135.517001 -252.377609)
			(xy 135.546377 -252.418042) (xy 135.569067 -252.462574) (xy 135.584511 -252.510106) (xy 135.59233 -252.559469)
			(xy 135.59282 -252.584458) (xy 135.898631 -252.584458) (xy 135.902726 -252.53373) (xy 135.914905 -252.484316)
			(xy 135.934853 -252.437496) (xy 135.962054 -252.394482) (xy 135.995802 -252.356388) (xy 136.035224 -252.324201)
			(xy 136.079298 -252.298755) (xy 136.126884 -252.280708) (xy 136.176748 -252.270528) (xy 136.2276 -252.268479)
			(xy 136.278121 -252.274613) (xy 136.327005 -252.288773) (xy 136.372984 -252.31059) (xy 136.414868 -252.3395)
			(xy 136.451572 -252.374755) (xy 136.482145 -252.415441) (xy 136.505796 -252.460504) (xy 136.521912 -252.508778)
			(xy 136.530076 -252.559012) (xy 136.530588 -252.584458) (xy 136.530085 -252.609447) (xy 136.837148 -252.609447)
			(xy 136.837148 -252.559469) (xy 136.844967 -252.510106) (xy 136.860411 -252.462574) (xy 136.883101 -252.418042)
			(xy 136.912477 -252.377609) (xy 136.947817 -252.342269) (xy 136.98825 -252.312893) (xy 137.032782 -252.290203)
			(xy 137.080314 -252.274759) (xy 137.129677 -252.26694) (xy 137.179655 -252.26694) (xy 137.229018 -252.274759)
			(xy 137.27655 -252.290203) (xy 137.321082 -252.312893) (xy 137.361515 -252.342269) (xy 137.396855 -252.377609)
			(xy 137.426231 -252.418042) (xy 137.448921 -252.462574) (xy 137.464365 -252.510106) (xy 137.472184 -252.559469)
			(xy 137.472674 -252.584458) (xy 137.472184 -252.609447) (xy 137.777202 -252.609447) (xy 137.777202 -252.559469)
			(xy 137.785021 -252.510106) (xy 137.800465 -252.462574) (xy 137.823155 -252.418042) (xy 137.852531 -252.377609)
			(xy 137.887871 -252.342269) (xy 137.928304 -252.312893) (xy 137.972836 -252.290203) (xy 138.020368 -252.274759)
			(xy 138.069731 -252.26694) (xy 138.119709 -252.26694) (xy 138.169072 -252.274759) (xy 138.216604 -252.290203)
			(xy 138.261136 -252.312893) (xy 138.301569 -252.342269) (xy 138.336909 -252.377609) (xy 138.366285 -252.418042)
			(xy 138.388975 -252.462574) (xy 138.404419 -252.510106) (xy 138.412238 -252.559469) (xy 138.412728 -252.584458)
			(xy 138.718539 -252.584458) (xy 138.722634 -252.53373) (xy 138.734813 -252.484316) (xy 138.754761 -252.437496)
			(xy 138.781962 -252.394482) (xy 138.81571 -252.356388) (xy 138.855132 -252.324201) (xy 138.899206 -252.298755)
			(xy 138.946792 -252.280708) (xy 138.996656 -252.270528) (xy 139.047508 -252.268479) (xy 139.098029 -252.274613)
			(xy 139.146913 -252.288773) (xy 139.192892 -252.31059) (xy 139.234776 -252.3395) (xy 139.27148 -252.374755)
			(xy 139.302053 -252.415441) (xy 139.325704 -252.460504) (xy 139.34182 -252.508778) (xy 139.349984 -252.559012)
			(xy 139.350496 -252.584458) (xy 139.349993 -252.609447) (xy 139.65731 -252.609447) (xy 139.65731 -252.559469)
			(xy 139.665129 -252.510106) (xy 139.680573 -252.462574) (xy 139.703263 -252.418042) (xy 139.732639 -252.377609)
			(xy 139.767979 -252.342269) (xy 139.808412 -252.312893) (xy 139.852944 -252.290203) (xy 139.900476 -252.274759)
			(xy 139.949839 -252.26694) (xy 139.999817 -252.26694) (xy 140.04918 -252.274759) (xy 140.096712 -252.290203)
			(xy 140.141244 -252.312893) (xy 140.181677 -252.342269) (xy 140.217017 -252.377609) (xy 140.246393 -252.418042)
			(xy 140.269083 -252.462574) (xy 140.284527 -252.510106) (xy 140.292346 -252.559469) (xy 140.292836 -252.584458)
			(xy 140.292346 -252.609447) (xy 140.59711 -252.609447) (xy 140.59711 -252.559469) (xy 140.604929 -252.510106)
			(xy 140.620373 -252.462574) (xy 140.643063 -252.418042) (xy 140.672439 -252.377609) (xy 140.707779 -252.342269)
			(xy 140.748212 -252.312893) (xy 140.792744 -252.290203) (xy 140.840276 -252.274759) (xy 140.889639 -252.26694)
			(xy 140.939617 -252.26694) (xy 140.98898 -252.274759) (xy 141.036512 -252.290203) (xy 141.081044 -252.312893)
			(xy 141.121477 -252.342269) (xy 141.156817 -252.377609) (xy 141.186193 -252.418042) (xy 141.208883 -252.462574)
			(xy 141.224327 -252.510106) (xy 141.232146 -252.559469) (xy 141.232636 -252.584458) (xy 141.232146 -252.609447)
			(xy 141.537164 -252.609447) (xy 141.537164 -252.559469) (xy 141.544983 -252.510106) (xy 141.560427 -252.462574)
			(xy 141.583117 -252.418042) (xy 141.612493 -252.377609) (xy 141.647833 -252.342269) (xy 141.688266 -252.312893)
			(xy 141.732798 -252.290203) (xy 141.78033 -252.274759) (xy 141.829693 -252.26694) (xy 141.879671 -252.26694)
			(xy 141.929034 -252.274759) (xy 141.976566 -252.290203) (xy 142.021098 -252.312893) (xy 142.061531 -252.342269)
			(xy 142.096871 -252.377609) (xy 142.126247 -252.418042) (xy 142.148937 -252.462574) (xy 142.164381 -252.510106)
			(xy 142.1722 -252.559469) (xy 142.17269 -252.584458) (xy 142.478501 -252.584458) (xy 142.482596 -252.53373)
			(xy 142.494775 -252.484316) (xy 142.514723 -252.437496) (xy 142.541924 -252.394482) (xy 142.575672 -252.356388)
			(xy 142.615094 -252.324201) (xy 142.659168 -252.298755) (xy 142.706754 -252.280708) (xy 142.756618 -252.270528)
			(xy 142.80747 -252.268479) (xy 142.857991 -252.274613) (xy 142.906875 -252.288773) (xy 142.952854 -252.31059)
			(xy 142.994738 -252.3395) (xy 143.031442 -252.374755) (xy 143.062015 -252.415441) (xy 143.085666 -252.460504)
			(xy 143.101782 -252.508778) (xy 143.109946 -252.559012) (xy 143.110458 -252.584458) (xy 143.109955 -252.609447)
			(xy 143.417272 -252.609447) (xy 143.417272 -252.559469) (xy 143.425091 -252.510106) (xy 143.440535 -252.462574)
			(xy 143.463225 -252.418042) (xy 143.492601 -252.377609) (xy 143.527941 -252.342269) (xy 143.568374 -252.312893)
			(xy 143.612906 -252.290203) (xy 143.660438 -252.274759) (xy 143.709801 -252.26694) (xy 143.759779 -252.26694)
			(xy 143.809142 -252.274759) (xy 143.856674 -252.290203) (xy 143.901206 -252.312893) (xy 143.941639 -252.342269)
			(xy 143.976979 -252.377609) (xy 144.006355 -252.418042) (xy 144.029045 -252.462574) (xy 144.044489 -252.510106)
			(xy 144.052308 -252.559469) (xy 144.052798 -252.584458) (xy 144.052308 -252.609447) (xy 144.044489 -252.65881)
			(xy 144.029045 -252.706342) (xy 144.006355 -252.750874) (xy 143.976979 -252.791307) (xy 143.941639 -252.826647)
			(xy 143.901206 -252.856023) (xy 143.856674 -252.878713) (xy 143.809142 -252.894157) (xy 143.759779 -252.901976)
			(xy 143.709801 -252.901976) (xy 143.660438 -252.894157) (xy 143.612906 -252.878713) (xy 143.568374 -252.856023)
			(xy 143.527941 -252.826647) (xy 143.492601 -252.791307) (xy 143.463225 -252.750874) (xy 143.440535 -252.706342)
			(xy 143.425091 -252.65881) (xy 143.417272 -252.609447) (xy 143.109955 -252.609447) (xy 143.109946 -252.609904)
			(xy 143.101782 -252.660138) (xy 143.085666 -252.708412) (xy 143.062015 -252.753475) (xy 143.031442 -252.794161)
			(xy 142.994738 -252.829416) (xy 142.952854 -252.858326) (xy 142.906875 -252.880143) (xy 142.857991 -252.894303)
			(xy 142.80747 -252.900437) (xy 142.756618 -252.898388) (xy 142.706754 -252.888208) (xy 142.659168 -252.870161)
			(xy 142.615094 -252.844715) (xy 142.575672 -252.812528) (xy 142.541924 -252.774434) (xy 142.514723 -252.73142)
			(xy 142.494775 -252.6846) (xy 142.482596 -252.635186) (xy 142.478501 -252.584458) (xy 142.17269 -252.584458)
			(xy 142.1722 -252.609447) (xy 142.164381 -252.65881) (xy 142.148937 -252.706342) (xy 142.126247 -252.750874)
			(xy 142.096871 -252.791307) (xy 142.061531 -252.826647) (xy 142.021098 -252.856023) (xy 141.976566 -252.878713)
			(xy 141.929034 -252.894157) (xy 141.879671 -252.901976) (xy 141.829693 -252.901976) (xy 141.78033 -252.894157)
			(xy 141.732798 -252.878713) (xy 141.688266 -252.856023) (xy 141.647833 -252.826647) (xy 141.612493 -252.791307)
			(xy 141.583117 -252.750874) (xy 141.560427 -252.706342) (xy 141.544983 -252.65881) (xy 141.537164 -252.609447)
			(xy 141.232146 -252.609447) (xy 141.224327 -252.65881) (xy 141.208883 -252.706342) (xy 141.186193 -252.750874)
			(xy 141.156817 -252.791307) (xy 141.121477 -252.826647) (xy 141.081044 -252.856023) (xy 141.036512 -252.878713)
			(xy 140.98898 -252.894157) (xy 140.939617 -252.901976) (xy 140.889639 -252.901976) (xy 140.840276 -252.894157)
			(xy 140.792744 -252.878713) (xy 140.748212 -252.856023) (xy 140.707779 -252.826647) (xy 140.672439 -252.791307)
			(xy 140.643063 -252.750874) (xy 140.620373 -252.706342) (xy 140.604929 -252.65881) (xy 140.59711 -252.609447)
			(xy 140.292346 -252.609447) (xy 140.284527 -252.65881) (xy 140.269083 -252.706342) (xy 140.246393 -252.750874)
			(xy 140.217017 -252.791307) (xy 140.181677 -252.826647) (xy 140.141244 -252.856023) (xy 140.096712 -252.878713)
			(xy 140.04918 -252.894157) (xy 139.999817 -252.901976) (xy 139.949839 -252.901976) (xy 139.900476 -252.894157)
			(xy 139.852944 -252.878713) (xy 139.808412 -252.856023) (xy 139.767979 -252.826647) (xy 139.732639 -252.791307)
			(xy 139.703263 -252.750874) (xy 139.680573 -252.706342) (xy 139.665129 -252.65881) (xy 139.65731 -252.609447)
			(xy 139.349993 -252.609447) (xy 139.349984 -252.609904) (xy 139.34182 -252.660138) (xy 139.325704 -252.708412)
			(xy 139.302053 -252.753475) (xy 139.27148 -252.794161) (xy 139.234776 -252.829416) (xy 139.192892 -252.858326)
			(xy 139.146913 -252.880143) (xy 139.098029 -252.894303) (xy 139.047508 -252.900437) (xy 138.996656 -252.898388)
			(xy 138.946792 -252.888208) (xy 138.899206 -252.870161) (xy 138.855132 -252.844715) (xy 138.81571 -252.812528)
			(xy 138.781962 -252.774434) (xy 138.754761 -252.73142) (xy 138.734813 -252.6846) (xy 138.722634 -252.635186)
			(xy 138.718539 -252.584458) (xy 138.412728 -252.584458) (xy 138.412238 -252.609447) (xy 138.404419 -252.65881)
			(xy 138.388975 -252.706342) (xy 138.366285 -252.750874) (xy 138.336909 -252.791307) (xy 138.301569 -252.826647)
			(xy 138.261136 -252.856023) (xy 138.216604 -252.878713) (xy 138.169072 -252.894157) (xy 138.119709 -252.901976)
			(xy 138.069731 -252.901976) (xy 138.020368 -252.894157) (xy 137.972836 -252.878713) (xy 137.928304 -252.856023)
			(xy 137.887871 -252.826647) (xy 137.852531 -252.791307) (xy 137.823155 -252.750874) (xy 137.800465 -252.706342)
			(xy 137.785021 -252.65881) (xy 137.777202 -252.609447) (xy 137.472184 -252.609447) (xy 137.464365 -252.65881)
			(xy 137.448921 -252.706342) (xy 137.426231 -252.750874) (xy 137.396855 -252.791307) (xy 137.361515 -252.826647)
			(xy 137.321082 -252.856023) (xy 137.27655 -252.878713) (xy 137.229018 -252.894157) (xy 137.179655 -252.901976)
			(xy 137.129677 -252.901976) (xy 137.080314 -252.894157) (xy 137.032782 -252.878713) (xy 136.98825 -252.856023)
			(xy 136.947817 -252.826647) (xy 136.912477 -252.791307) (xy 136.883101 -252.750874) (xy 136.860411 -252.706342)
			(xy 136.844967 -252.65881) (xy 136.837148 -252.609447) (xy 136.530085 -252.609447) (xy 136.530076 -252.609904)
			(xy 136.521912 -252.660138) (xy 136.505796 -252.708412) (xy 136.482145 -252.753475) (xy 136.451572 -252.794161)
			(xy 136.414868 -252.829416) (xy 136.372984 -252.858326) (xy 136.327005 -252.880143) (xy 136.278121 -252.894303)
			(xy 136.2276 -252.900437) (xy 136.176748 -252.898388) (xy 136.126884 -252.888208) (xy 136.079298 -252.870161)
			(xy 136.035224 -252.844715) (xy 135.995802 -252.812528) (xy 135.962054 -252.774434) (xy 135.934853 -252.73142)
			(xy 135.914905 -252.6846) (xy 135.902726 -252.635186) (xy 135.898631 -252.584458) (xy 135.59282 -252.584458)
			(xy 135.59233 -252.609447) (xy 135.584511 -252.65881) (xy 135.569067 -252.706342) (xy 135.546377 -252.750874)
			(xy 135.517001 -252.791307) (xy 135.481661 -252.826647) (xy 135.441228 -252.856023) (xy 135.396696 -252.878713)
			(xy 135.349164 -252.894157) (xy 135.299801 -252.901976) (xy 135.249823 -252.901976) (xy 135.20046 -252.894157)
			(xy 135.152928 -252.878713) (xy 135.108396 -252.856023) (xy 135.067963 -252.826647) (xy 135.032623 -252.791307)
			(xy 135.003247 -252.750874) (xy 134.980557 -252.706342) (xy 134.965113 -252.65881) (xy 134.957294 -252.609447)
			(xy 134.652276 -252.609447) (xy 134.644457 -252.65881) (xy 134.629013 -252.706342) (xy 134.606323 -252.750874)
			(xy 134.576947 -252.791307) (xy 134.541607 -252.826647) (xy 134.501174 -252.856023) (xy 134.456642 -252.878713)
			(xy 134.40911 -252.894157) (xy 134.359747 -252.901976) (xy 134.309769 -252.901976) (xy 134.260406 -252.894157)
			(xy 134.212874 -252.878713) (xy 134.168342 -252.856023) (xy 134.127909 -252.826647) (xy 134.092569 -252.791307)
			(xy 134.063193 -252.750874) (xy 134.040503 -252.706342) (xy 134.025059 -252.65881) (xy 134.01724 -252.609447)
			(xy 133.712222 -252.609447) (xy 133.704403 -252.65881) (xy 133.688959 -252.706342) (xy 133.666269 -252.750874)
			(xy 133.636893 -252.791307) (xy 133.601553 -252.826647) (xy 133.56112 -252.856023) (xy 133.516588 -252.878713)
			(xy 133.469056 -252.894157) (xy 133.419693 -252.901976) (xy 133.369715 -252.901976) (xy 133.320352 -252.894157)
			(xy 133.27282 -252.878713) (xy 133.228288 -252.856023) (xy 133.187855 -252.826647) (xy 133.152515 -252.791307)
			(xy 133.123139 -252.750874) (xy 133.100449 -252.706342) (xy 133.085005 -252.65881) (xy 133.077186 -252.609447)
			(xy 132.769869 -252.609447) (xy 132.76986 -252.609904) (xy 132.761696 -252.660138) (xy 132.74558 -252.708412)
			(xy 132.721929 -252.753475) (xy 132.691356 -252.794161) (xy 132.654652 -252.829416) (xy 132.612768 -252.858326)
			(xy 132.566789 -252.880143) (xy 132.517905 -252.894303) (xy 132.467384 -252.900437) (xy 132.416532 -252.898388)
			(xy 132.366668 -252.888208) (xy 132.319082 -252.870161) (xy 132.275008 -252.844715) (xy 132.235586 -252.812528)
			(xy 132.201838 -252.774434) (xy 132.174637 -252.73142) (xy 132.154689 -252.6846) (xy 132.14251 -252.635186)
			(xy 132.138415 -252.584458) (xy 131.832858 -252.584458) (xy 131.832368 -252.609447) (xy 131.824549 -252.65881)
			(xy 131.809105 -252.706342) (xy 131.786415 -252.750874) (xy 131.757039 -252.791307) (xy 131.721699 -252.826647)
			(xy 131.681266 -252.856023) (xy 131.636734 -252.878713) (xy 131.589202 -252.894157) (xy 131.539839 -252.901976)
			(xy 131.489861 -252.901976) (xy 131.440498 -252.894157) (xy 131.392966 -252.878713) (xy 131.348434 -252.856023)
			(xy 131.308001 -252.826647) (xy 131.272661 -252.791307) (xy 131.243285 -252.750874) (xy 131.220595 -252.706342)
			(xy 131.205151 -252.65881) (xy 131.197332 -252.609447) (xy 130.892314 -252.609447) (xy 130.884495 -252.65881)
			(xy 130.869051 -252.706342) (xy 130.846361 -252.750874) (xy 130.816985 -252.791307) (xy 130.781645 -252.826647)
			(xy 130.741212 -252.856023) (xy 130.69668 -252.878713) (xy 130.649148 -252.894157) (xy 130.599785 -252.901976)
			(xy 130.549807 -252.901976) (xy 130.500444 -252.894157) (xy 130.452912 -252.878713) (xy 130.40838 -252.856023)
			(xy 130.367947 -252.826647) (xy 130.332607 -252.791307) (xy 130.303231 -252.750874) (xy 130.280541 -252.706342)
			(xy 130.265097 -252.65881) (xy 130.257278 -252.609447) (xy 129.949961 -252.609447) (xy 129.949952 -252.609904)
			(xy 129.941788 -252.660138) (xy 129.925672 -252.708412) (xy 129.902021 -252.753475) (xy 129.871448 -252.794161)
			(xy 129.834744 -252.829416) (xy 129.79286 -252.858326) (xy 129.746881 -252.880143) (xy 129.697997 -252.894303)
			(xy 129.647476 -252.900437) (xy 129.596624 -252.898388) (xy 129.54676 -252.888208) (xy 129.499174 -252.870161)
			(xy 129.4551 -252.844715) (xy 129.415678 -252.812528) (xy 129.38193 -252.774434) (xy 129.354729 -252.73142)
			(xy 129.334781 -252.6846) (xy 129.322602 -252.635186) (xy 129.318507 -252.584458) (xy 129.012696 -252.584458)
			(xy 129.012206 -252.609447) (xy 129.004387 -252.65881) (xy 128.988943 -252.706342) (xy 128.966253 -252.750874)
			(xy 128.936877 -252.791307) (xy 128.901537 -252.826647) (xy 128.861104 -252.856023) (xy 128.816572 -252.878713)
			(xy 128.76904 -252.894157) (xy 128.719677 -252.901976) (xy 128.669699 -252.901976) (xy 128.620336 -252.894157)
			(xy 128.572804 -252.878713) (xy 128.528272 -252.856023) (xy 128.487839 -252.826647) (xy 128.452499 -252.791307)
			(xy 128.423123 -252.750874) (xy 128.400433 -252.706342) (xy 128.384989 -252.65881) (xy 128.37717 -252.609447)
			(xy 128.072152 -252.609447) (xy 128.064333 -252.65881) (xy 128.048889 -252.706342) (xy 128.026199 -252.750874)
			(xy 127.996823 -252.791307) (xy 127.961483 -252.826647) (xy 127.92105 -252.856023) (xy 127.876518 -252.878713)
			(xy 127.828986 -252.894157) (xy 127.779623 -252.901976) (xy 127.729645 -252.901976) (xy 127.680282 -252.894157)
			(xy 127.63275 -252.878713) (xy 127.588218 -252.856023) (xy 127.547785 -252.826647) (xy 127.512445 -252.791307)
			(xy 127.483069 -252.750874) (xy 127.460379 -252.706342) (xy 127.444935 -252.65881) (xy 127.437116 -252.609447)
			(xy 127.132352 -252.609447) (xy 127.124533 -252.65881) (xy 127.109089 -252.706342) (xy 127.086399 -252.750874)
			(xy 127.057023 -252.791307) (xy 127.021683 -252.826647) (xy 126.98125 -252.856023) (xy 126.936718 -252.878713)
			(xy 126.889186 -252.894157) (xy 126.839823 -252.901976) (xy 126.789845 -252.901976) (xy 126.740482 -252.894157)
			(xy 126.69295 -252.878713) (xy 126.648418 -252.856023) (xy 126.607985 -252.826647) (xy 126.572645 -252.791307)
			(xy 126.543269 -252.750874) (xy 126.520579 -252.706342) (xy 126.505135 -252.65881) (xy 126.497316 -252.609447)
			(xy 125.378972 -252.609447) (xy 125.378972 -252.797564) (xy 125.37855 -252.807586) (xy 125.370887 -252.826108)
			(xy 125.356715 -252.840282) (xy 125.338194 -252.847949) (xy 125.328172 -252.848364) (xy 125.114304 -252.848364)
			(xy 125.114304 -252.857508) (xy 125.113818 -252.867516) (xy 125.106157 -252.886007) (xy 125.092003 -252.900159)
			(xy 125.073512 -252.907819) (xy 125.063504 -252.908308) (xy 124.859288 -252.908308) (xy 124.837712 -252.907778)
			(xy 124.795447 -252.899075) (xy 124.755789 -252.882065) (xy 124.720352 -252.857441) (xy 124.690579 -252.826205)
			(xy 124.667681 -252.789629) (xy 124.652591 -252.749201) (xy 124.648722 -252.727968) (xy 124.644658 -252.715014)
			(xy 124.635799 -252.694405) (xy 124.623345 -252.651308) (xy 124.61708 -252.606888) (xy 124.616718 -252.584458)
			(xy 123.600972 -252.584458) (xy 123.600972 -252.797564) (xy 123.60055 -252.807586) (xy 123.592887 -252.826108)
			(xy 123.578715 -252.840282) (xy 123.560194 -252.847949) (xy 123.550172 -252.848364) (xy 123.336304 -252.848364)
			(xy 123.336304 -252.857508) (xy 123.335818 -252.867516) (xy 123.328157 -252.886007) (xy 123.314003 -252.900159)
			(xy 123.295512 -252.907819) (xy 123.285504 -252.908308) (xy 123.081288 -252.908308) (xy 123.068718 -252.908061)
			(xy 123.043761 -252.90501) (xy 123.031504 -252.902212) (xy 123.024392 -252.901196) (xy 122.998465 -252.898218)
			(xy 122.948028 -252.88482) (xy 122.900453 -252.863372) (xy 122.857016 -252.834448) (xy 122.818881 -252.798823)
			(xy 122.78707 -252.757454) (xy 122.762436 -252.711448) (xy 122.74564 -252.662039) (xy 122.737131 -252.610551)
			(xy 122.73661 -252.584458) (xy 121.695972 -252.584458) (xy 121.695972 -252.797564) (xy 121.69555 -252.807586)
			(xy 121.687887 -252.826108) (xy 121.673715 -252.840282) (xy 121.655194 -252.847949) (xy 121.645172 -252.848364)
			(xy 121.431304 -252.848364) (xy 121.431304 -252.857508) (xy 121.430818 -252.867516) (xy 121.423157 -252.886007)
			(xy 121.409003 -252.900159) (xy 121.390512 -252.907819) (xy 121.380504 -252.908308) (xy 121.176288 -252.908308)
			(xy 121.156585 -252.907832) (xy 121.117857 -252.900541) (xy 121.099326 -252.89383) (xy 121.093992 -252.892052)
			(xy 121.068865 -252.884861) (xy 121.02117 -252.8635) (xy 120.977609 -252.834629) (xy 120.939354 -252.799025)
			(xy 120.907434 -252.757647) (xy 120.882708 -252.711606) (xy 120.865842 -252.662143) (xy 120.857289 -252.610588)
			(xy 120.856756 -252.584458) (xy 112.571537 -252.584458) (xy 112.547439 -252.624325) (xy 112.511804 -252.666716)
			(xy 112.491266 -252.685296) (xy 112.483646 -252.693678) (xy 112.471446 -252.709616) (xy 112.442139 -252.737034)
			(xy 112.408233 -252.758504) (xy 112.370916 -252.773273) (xy 112.3315 -252.780821) (xy 112.311434 -252.781308)
			(xy 112.056672 -252.781308) (xy 112.056672 -252.772164) (xy 112.056241 -252.762151) (xy 112.048564 -252.743653)
			(xy 112.034394 -252.7295) (xy 112.015886 -252.721847) (xy 112.005872 -252.721364) (xy 111.842296 -252.721364)
			(xy 111.83227 -252.720983) (xy 111.813746 -252.713305) (xy 111.799573 -252.69912) (xy 111.791909 -252.68059)
			(xy 111.791496 -252.670564) (xy 101.883464 -252.670564) (xy 101.883464 -253.007114) (xy 101.883909 -253.016661)
			(xy 101.890947 -253.034415) (xy 101.89718 -253.041658) (xy 101.911404 -253.056898) (xy 101.911912 -253.05766)
			(xy 101.913182 -253.058676) (xy 101.916198 -253.061491) (xy 101.92296 -253.066216) (xy 101.926644 -253.068074)
			(xy 101.94798 -253.078234) (xy 101.955854 -253.079504) (xy 101.956108 -253.079504) (xy 101.981043 -253.083579)
			(xy 102.029288 -253.098578) (xy 102.074559 -253.12101) (xy 102.115717 -253.150311) (xy 102.151731 -253.185745)
			(xy 102.181696 -253.226422) (xy 102.204859 -253.271322) (xy 102.22064 -253.319317) (xy 102.228642 -253.369203)
			(xy 102.229116 -253.392432) (xy 103.469948 -253.392432) (xy 103.470461 -253.365662) (xy 103.479444 -253.31288)
			(xy 103.497146 -253.26235) (xy 103.523064 -253.215501) (xy 103.556467 -253.173657) (xy 103.596409 -253.138003)
			(xy 103.641761 -253.109546) (xy 103.66629 -253.098808) (xy 103.672132 -253.096014) (xy 103.688256 -253.087222)
			(xy 103.722773 -253.07469) (xy 103.758929 -253.068267) (xy 103.777288 -253.06782) (xy 104.032304 -253.06782)
			(xy 104.032304 -253.076964) (xy 104.032749 -253.086983) (xy 104.040408 -253.1055) (xy 104.054573 -253.119674)
			(xy 104.073085 -253.127344) (xy 104.083104 -253.127764) (xy 104.246172 -253.127764) (xy 104.256173 -253.12831)
			(xy 104.274658 -253.135954) (xy 104.288811 -253.150088) (xy 104.296477 -253.168563) (xy 104.296972 -253.178564)
			(xy 104.296972 -253.392432) (xy 105.349802 -253.392432) (xy 105.350313 -253.367788) (xy 105.357934 -253.319094)
			(xy 105.372969 -253.272155) (xy 105.395059 -253.228095) (xy 105.423675 -253.187965) (xy 105.458134 -253.152725)
			(xy 105.497612 -253.123216) (xy 105.541166 -253.100144) (xy 105.587756 -253.08406) (xy 105.61193 -253.07925)
			(xy 105.61828 -253.077726) (xy 105.633883 -253.07313) (xy 105.666026 -253.068149) (xy 105.682288 -253.06782)
			(xy 105.937304 -253.06782) (xy 105.937304 -253.076964) (xy 105.937749 -253.086983) (xy 105.945408 -253.1055)
			(xy 105.959573 -253.119674) (xy 105.978085 -253.127344) (xy 105.988104 -253.127764) (xy 106.151172 -253.127764)
			(xy 106.161173 -253.12831) (xy 106.179658 -253.135954) (xy 106.193811 -253.150088) (xy 106.201477 -253.168563)
			(xy 106.201972 -253.178564) (xy 106.201972 -253.392432) (xy 107.22991 -253.392432) (xy 107.230348 -253.368357)
			(xy 107.237602 -253.320756) (xy 107.25195 -253.274793) (xy 107.273064 -253.231519) (xy 107.30046 -253.191922)
			(xy 107.333514 -253.156909) (xy 107.371468 -253.127279) (xy 107.413455 -253.10371) (xy 107.458516 -253.08674)
			(xy 107.50562 -253.076758) (xy 107.52963 -253.074932) (xy 107.53852 -253.073662) (xy 107.550533 -253.070968)
			(xy 107.574979 -253.068038) (xy 107.587288 -253.06782) (xy 107.842304 -253.06782) (xy 107.842304 -253.076964)
			(xy 107.842749 -253.086983) (xy 107.850408 -253.1055) (xy 107.864573 -253.119674) (xy 107.883085 -253.127344)
			(xy 107.893104 -253.127764) (xy 108.056172 -253.127764) (xy 108.066173 -253.12831) (xy 108.084658 -253.135954)
			(xy 108.098811 -253.150088) (xy 108.106477 -253.168563) (xy 108.106972 -253.178564) (xy 108.106972 -253.392432)
			(xy 109.110018 -253.392432) (xy 109.110407 -253.370312) (xy 109.116574 -253.326504) (xy 109.12874 -253.28397)
			(xy 109.14667 -253.243526) (xy 109.158024 -253.224538) (xy 109.163104 -253.21387) (xy 109.17064 -253.192958)
			(xy 109.193065 -253.154587) (xy 109.222936 -253.121679) (xy 109.258964 -253.095656) (xy 109.299592 -253.077641)
			(xy 109.343067 -253.068412) (xy 109.365288 -253.06782) (xy 109.620304 -253.06782) (xy 109.620304 -253.076964)
			(xy 109.620749 -253.086983) (xy 109.628408 -253.1055) (xy 109.642573 -253.119674) (xy 109.661085 -253.127344)
			(xy 109.671104 -253.127764) (xy 109.834172 -253.127764) (xy 109.844173 -253.12831) (xy 109.862658 -253.135954)
			(xy 109.876811 -253.150088) (xy 109.884477 -253.168563) (xy 109.884972 -253.178564) (xy 109.884972 -253.686564)
			(xy 111.791496 -253.686564) (xy 111.791496 -253.178564) (xy 111.791958 -253.168555) (xy 111.799629 -253.150063)
			(xy 111.81379 -253.135911) (xy 111.832286 -253.128252) (xy 111.842296 -253.127764) (xy 112.056672 -253.127764)
			(xy 112.056672 -253.11862) (xy 112.057204 -253.108617) (xy 112.064851 -253.090131) (xy 112.078991 -253.075978)
			(xy 112.09747 -253.068313) (xy 112.107472 -253.06782) (xy 112.311434 -253.06782) (xy 112.331505 -253.068276)
			(xy 112.370936 -253.075794) (xy 112.408264 -253.090557) (xy 112.442171 -253.112045) (xy 112.471457 -253.139497)
			(xy 112.483646 -253.15545) (xy 112.491266 -253.163832) (xy 112.511771 -253.18245) (xy 112.547412 -253.224837)
			(xy 112.576065 -253.272228) (xy 112.597041 -253.323482) (xy 112.609833 -253.377364) (xy 112.611007 -253.392432)
			(xy 112.86998 -253.392432) (xy 112.870539 -253.366165) (xy 112.879189 -253.314349) (xy 112.896228 -253.264655)
			(xy 112.921192 -253.218432) (xy 112.953405 -253.176934) (xy 112.991993 -253.141286) (xy 113.035909 -253.112455)
			(xy 113.059718 -253.101348) (xy 113.06556 -253.0983) (xy 113.082251 -253.088746) (xy 113.118233 -253.075177)
			(xy 113.156061 -253.068253) (xy 113.175288 -253.06782) (xy 113.430304 -253.06782) (xy 113.430304 -253.076964)
			(xy 113.430749 -253.086983) (xy 113.438408 -253.1055) (xy 113.452573 -253.119674) (xy 113.471085 -253.127344)
			(xy 113.481104 -253.127764) (xy 113.644172 -253.127764) (xy 113.654173 -253.12831) (xy 113.672658 -253.135954)
			(xy 113.686811 -253.150088) (xy 113.694477 -253.168563) (xy 113.694972 -253.178564) (xy 113.694972 -253.392432)
			(xy 114.749834 -253.392432) (xy 114.750306 -253.368017) (xy 114.757788 -253.319763) (xy 114.77255 -253.273217)
			(xy 114.794247 -253.229471) (xy 114.82237 -253.189552) (xy 114.856258 -253.154395) (xy 114.895118 -253.124825)
			(xy 114.938037 -253.101535) (xy 114.984009 -253.085073) (xy 115.007898 -253.080012) (xy 115.014248 -253.078488)
			(xy 115.030307 -253.073529) (xy 115.063485 -253.068172) (xy 115.080288 -253.06782) (xy 115.335304 -253.06782)
			(xy 115.335304 -253.076964) (xy 115.335749 -253.086983) (xy 115.343408 -253.1055) (xy 115.357573 -253.119674)
			(xy 115.376085 -253.127344) (xy 115.386104 -253.127764) (xy 115.549172 -253.127764) (xy 115.559173 -253.12831)
			(xy 115.577658 -253.135954) (xy 115.591811 -253.150088) (xy 115.599477 -253.168563) (xy 115.599972 -253.178564)
			(xy 115.599972 -253.392432) (xy 116.629942 -253.392432) (xy 116.630298 -253.369567) (xy 116.636807 -253.324304)
			(xy 116.642896 -253.302262) (xy 116.644928 -253.295404) (xy 116.644928 -253.282704) (xy 116.645266 -253.261639)
			(xy 116.653229 -253.220275) (xy 116.669142 -253.181273) (xy 116.69239 -253.146145) (xy 116.72207 -253.116253)
			(xy 116.757031 -253.092757) (xy 116.79592 -253.076567) (xy 116.837226 -253.068311) (xy 116.858288 -253.06782)
			(xy 117.062504 -253.06782) (xy 117.072528 -253.068217) (xy 117.091049 -253.075892) (xy 117.105222 -253.090071)
			(xy 117.112888 -253.108596) (xy 117.113304 -253.11862) (xy 117.113304 -253.120652) (xy 117.12448 -253.127764)
			(xy 117.327172 -253.127764) (xy 117.337173 -253.12831) (xy 117.355658 -253.135954) (xy 117.369811 -253.150088)
			(xy 117.377477 -253.168563) (xy 117.377972 -253.178564) (xy 117.377972 -253.392432) (xy 118.509796 -253.392432)
			(xy 118.510437 -253.363974) (xy 118.520569 -253.307967) (xy 118.540497 -253.254654) (xy 118.5545 -253.229872)
			(xy 118.55958 -253.218696) (xy 118.565641 -253.200257) (xy 118.583522 -253.165811) (xy 118.607338 -253.135166)
			(xy 118.636302 -253.109332) (xy 118.66946 -253.089162) (xy 118.705719 -253.075321) (xy 118.743883 -253.068265)
			(xy 118.763288 -253.06782) (xy 119.018304 -253.06782) (xy 119.018304 -253.076964) (xy 119.018749 -253.086983)
			(xy 119.026408 -253.1055) (xy 119.040573 -253.119674) (xy 119.059085 -253.127344) (xy 119.069104 -253.127764)
			(xy 119.232172 -253.127764) (xy 119.242173 -253.12831) (xy 119.260658 -253.135954) (xy 119.274811 -253.150088)
			(xy 119.282477 -253.168563) (xy 119.282972 -253.178564) (xy 119.282972 -253.419453) (xy 122.2672 -253.419453)
			(xy 122.2672 -253.369475) (xy 122.275019 -253.320112) (xy 122.290463 -253.27258) (xy 122.313153 -253.228048)
			(xy 122.342529 -253.187615) (xy 122.377869 -253.152275) (xy 122.418302 -253.122899) (xy 122.462834 -253.100209)
			(xy 122.510366 -253.084765) (xy 122.559729 -253.076946) (xy 122.609707 -253.076946) (xy 122.65907 -253.084765)
			(xy 122.706602 -253.100209) (xy 122.751134 -253.122899) (xy 122.791567 -253.152275) (xy 122.826907 -253.187615)
			(xy 122.856283 -253.228048) (xy 122.878973 -253.27258) (xy 122.894417 -253.320112) (xy 122.902236 -253.369475)
			(xy 122.902726 -253.394464) (xy 122.902236 -253.419453) (xy 124.147308 -253.419453) (xy 124.147308 -253.369475)
			(xy 124.155127 -253.320112) (xy 124.170571 -253.27258) (xy 124.193261 -253.228048) (xy 124.222637 -253.187615)
			(xy 124.257977 -253.152275) (xy 124.29841 -253.122899) (xy 124.342942 -253.100209) (xy 124.390474 -253.084765)
			(xy 124.439837 -253.076946) (xy 124.489815 -253.076946) (xy 124.539178 -253.084765) (xy 124.58671 -253.100209)
			(xy 124.631242 -253.122899) (xy 124.671675 -253.152275) (xy 124.707015 -253.187615) (xy 124.736391 -253.228048)
			(xy 124.759081 -253.27258) (xy 124.774525 -253.320112) (xy 124.782344 -253.369475) (xy 124.782834 -253.394464)
			(xy 124.782344 -253.419453) (xy 126.027162 -253.419453) (xy 126.027162 -253.369475) (xy 126.034981 -253.320112)
			(xy 126.050425 -253.27258) (xy 126.073115 -253.228048) (xy 126.102491 -253.187615) (xy 126.137831 -253.152275)
			(xy 126.178264 -253.122899) (xy 126.222796 -253.100209) (xy 126.270328 -253.084765) (xy 126.319691 -253.076946)
			(xy 126.369669 -253.076946) (xy 126.419032 -253.084765) (xy 126.466564 -253.100209) (xy 126.511096 -253.122899)
			(xy 126.551529 -253.152275) (xy 126.586869 -253.187615) (xy 126.616245 -253.228048) (xy 126.638935 -253.27258)
			(xy 126.654379 -253.320112) (xy 126.662198 -253.369475) (xy 126.662688 -253.394464) (xy 127.908553 -253.394464)
			(xy 127.912648 -253.343736) (xy 127.924827 -253.294322) (xy 127.944775 -253.247502) (xy 127.971976 -253.204488)
			(xy 128.005724 -253.166394) (xy 128.045146 -253.134207) (xy 128.08922 -253.108761) (xy 128.136806 -253.090714)
			(xy 128.18667 -253.080534) (xy 128.237522 -253.078485) (xy 128.288043 -253.084619) (xy 128.336927 -253.098779)
			(xy 128.382906 -253.120596) (xy 128.42479 -253.149506) (xy 128.461494 -253.184761) (xy 128.492067 -253.225447)
			(xy 128.515718 -253.27051) (xy 128.531834 -253.318784) (xy 128.539998 -253.369018) (xy 128.54051 -253.394464)
			(xy 128.848607 -253.394464) (xy 128.852702 -253.343736) (xy 128.864881 -253.294322) (xy 128.884829 -253.247502)
			(xy 128.91203 -253.204488) (xy 128.945778 -253.166394) (xy 128.9852 -253.134207) (xy 129.029274 -253.108761)
			(xy 129.07686 -253.090714) (xy 129.126724 -253.080534) (xy 129.177576 -253.078485) (xy 129.228097 -253.084619)
			(xy 129.276981 -253.098779) (xy 129.32296 -253.120596) (xy 129.364844 -253.149506) (xy 129.401548 -253.184761)
			(xy 129.432121 -253.225447) (xy 129.455772 -253.27051) (xy 129.471888 -253.318784) (xy 129.480052 -253.369018)
			(xy 129.480564 -253.394464) (xy 129.480061 -253.419453) (xy 129.787124 -253.419453) (xy 129.787124 -253.369475)
			(xy 129.794943 -253.320112) (xy 129.810387 -253.27258) (xy 129.833077 -253.228048) (xy 129.862453 -253.187615)
			(xy 129.897793 -253.152275) (xy 129.938226 -253.122899) (xy 129.982758 -253.100209) (xy 130.03029 -253.084765)
			(xy 130.079653 -253.076946) (xy 130.129631 -253.076946) (xy 130.178994 -253.084765) (xy 130.226526 -253.100209)
			(xy 130.271058 -253.122899) (xy 130.311491 -253.152275) (xy 130.346831 -253.187615) (xy 130.376207 -253.228048)
			(xy 130.398897 -253.27258) (xy 130.414341 -253.320112) (xy 130.42216 -253.369475) (xy 130.42265 -253.394464)
			(xy 130.728461 -253.394464) (xy 130.732556 -253.343736) (xy 130.744735 -253.294322) (xy 130.764683 -253.247502)
			(xy 130.791884 -253.204488) (xy 130.825632 -253.166394) (xy 130.865054 -253.134207) (xy 130.909128 -253.108761)
			(xy 130.956714 -253.090714) (xy 131.006578 -253.080534) (xy 131.05743 -253.078485) (xy 131.107951 -253.084619)
			(xy 131.156835 -253.098779) (xy 131.202814 -253.120596) (xy 131.244698 -253.149506) (xy 131.281402 -253.184761)
			(xy 131.311975 -253.225447) (xy 131.335626 -253.27051) (xy 131.351742 -253.318784) (xy 131.359906 -253.369018)
			(xy 131.360418 -253.394464) (xy 131.359915 -253.419453) (xy 131.667232 -253.419453) (xy 131.667232 -253.369475)
			(xy 131.675051 -253.320112) (xy 131.690495 -253.27258) (xy 131.713185 -253.228048) (xy 131.742561 -253.187615)
			(xy 131.777901 -253.152275) (xy 131.818334 -253.122899) (xy 131.862866 -253.100209) (xy 131.910398 -253.084765)
			(xy 131.959761 -253.076946) (xy 132.009739 -253.076946) (xy 132.059102 -253.084765) (xy 132.106634 -253.100209)
			(xy 132.151166 -253.122899) (xy 132.191599 -253.152275) (xy 132.226939 -253.187615) (xy 132.256315 -253.228048)
			(xy 132.279005 -253.27258) (xy 132.294449 -253.320112) (xy 132.302268 -253.369475) (xy 132.302758 -253.394464)
			(xy 132.608569 -253.394464) (xy 132.612664 -253.343736) (xy 132.624843 -253.294322) (xy 132.644791 -253.247502)
			(xy 132.671992 -253.204488) (xy 132.70574 -253.166394) (xy 132.745162 -253.134207) (xy 132.789236 -253.108761)
			(xy 132.836822 -253.090714) (xy 132.886686 -253.080534) (xy 132.937538 -253.078485) (xy 132.988059 -253.084619)
			(xy 133.036943 -253.098779) (xy 133.082922 -253.120596) (xy 133.124806 -253.149506) (xy 133.16151 -253.184761)
			(xy 133.192083 -253.225447) (xy 133.215734 -253.27051) (xy 133.23185 -253.318784) (xy 133.240014 -253.369018)
			(xy 133.240526 -253.394464) (xy 133.240023 -253.419453) (xy 133.54734 -253.419453) (xy 133.54734 -253.369475)
			(xy 133.555159 -253.320112) (xy 133.570603 -253.27258) (xy 133.593293 -253.228048) (xy 133.622669 -253.187615)
			(xy 133.658009 -253.152275) (xy 133.698442 -253.122899) (xy 133.742974 -253.100209) (xy 133.790506 -253.084765)
			(xy 133.839869 -253.076946) (xy 133.889847 -253.076946) (xy 133.93921 -253.084765) (xy 133.986742 -253.100209)
			(xy 134.031274 -253.122899) (xy 134.071707 -253.152275) (xy 134.107047 -253.187615) (xy 134.136423 -253.228048)
			(xy 134.159113 -253.27258) (xy 134.174557 -253.320112) (xy 134.182376 -253.369475) (xy 134.182866 -253.394464)
			(xy 134.488423 -253.394464) (xy 134.492518 -253.343736) (xy 134.504697 -253.294322) (xy 134.524645 -253.247502)
			(xy 134.551846 -253.204488) (xy 134.585594 -253.166394) (xy 134.625016 -253.134207) (xy 134.66909 -253.108761)
			(xy 134.716676 -253.090714) (xy 134.76654 -253.080534) (xy 134.817392 -253.078485) (xy 134.867913 -253.084619)
			(xy 134.916797 -253.098779) (xy 134.962776 -253.120596) (xy 135.00466 -253.149506) (xy 135.041364 -253.184761)
			(xy 135.071937 -253.225447) (xy 135.095588 -253.27051) (xy 135.111704 -253.318784) (xy 135.119868 -253.369018)
			(xy 135.12038 -253.394464) (xy 135.428477 -253.394464) (xy 135.432572 -253.343736) (xy 135.444751 -253.294322)
			(xy 135.464699 -253.247502) (xy 135.4919 -253.204488) (xy 135.525648 -253.166394) (xy 135.56507 -253.134207)
			(xy 135.609144 -253.108761) (xy 135.65673 -253.090714) (xy 135.706594 -253.080534) (xy 135.757446 -253.078485)
			(xy 135.807967 -253.084619) (xy 135.856851 -253.098779) (xy 135.90283 -253.120596) (xy 135.944714 -253.149506)
			(xy 135.981418 -253.184761) (xy 136.011991 -253.225447) (xy 136.035642 -253.27051) (xy 136.051758 -253.318784)
			(xy 136.059922 -253.369018) (xy 136.060434 -253.394464) (xy 136.059931 -253.419453) (xy 136.367248 -253.419453)
			(xy 136.367248 -253.369475) (xy 136.375067 -253.320112) (xy 136.390511 -253.27258) (xy 136.413201 -253.228048)
			(xy 136.442577 -253.187615) (xy 136.477917 -253.152275) (xy 136.51835 -253.122899) (xy 136.562882 -253.100209)
			(xy 136.610414 -253.084765) (xy 136.659777 -253.076946) (xy 136.709755 -253.076946) (xy 136.759118 -253.084765)
			(xy 136.80665 -253.100209) (xy 136.851182 -253.122899) (xy 136.891615 -253.152275) (xy 136.926955 -253.187615)
			(xy 136.956331 -253.228048) (xy 136.979021 -253.27258) (xy 136.994465 -253.320112) (xy 137.002284 -253.369475)
			(xy 137.002774 -253.394464) (xy 137.308585 -253.394464) (xy 137.31268 -253.343736) (xy 137.324859 -253.294322)
			(xy 137.344807 -253.247502) (xy 137.372008 -253.204488) (xy 137.405756 -253.166394) (xy 137.445178 -253.134207)
			(xy 137.489252 -253.108761) (xy 137.536838 -253.090714) (xy 137.586702 -253.080534) (xy 137.637554 -253.078485)
			(xy 137.688075 -253.084619) (xy 137.736959 -253.098779) (xy 137.782938 -253.120596) (xy 137.824822 -253.149506)
			(xy 137.861526 -253.184761) (xy 137.892099 -253.225447) (xy 137.91575 -253.27051) (xy 137.931866 -253.318784)
			(xy 137.94003 -253.369018) (xy 137.940542 -253.394464) (xy 137.940039 -253.419453) (xy 138.247356 -253.419453)
			(xy 138.247356 -253.369475) (xy 138.255175 -253.320112) (xy 138.270619 -253.27258) (xy 138.293309 -253.228048)
			(xy 138.322685 -253.187615) (xy 138.358025 -253.152275) (xy 138.398458 -253.122899) (xy 138.44299 -253.100209)
			(xy 138.490522 -253.084765) (xy 138.539885 -253.076946) (xy 138.589863 -253.076946) (xy 138.639226 -253.084765)
			(xy 138.686758 -253.100209) (xy 138.73129 -253.122899) (xy 138.771723 -253.152275) (xy 138.807063 -253.187615)
			(xy 138.836439 -253.228048) (xy 138.859129 -253.27258) (xy 138.874573 -253.320112) (xy 138.882392 -253.369475)
			(xy 138.882882 -253.394464) (xy 139.188439 -253.394464) (xy 139.192534 -253.343736) (xy 139.204713 -253.294322)
			(xy 139.224661 -253.247502) (xy 139.251862 -253.204488) (xy 139.28561 -253.166394) (xy 139.325032 -253.134207)
			(xy 139.369106 -253.108761) (xy 139.416692 -253.090714) (xy 139.466556 -253.080534) (xy 139.517408 -253.078485)
			(xy 139.567929 -253.084619) (xy 139.616813 -253.098779) (xy 139.662792 -253.120596) (xy 139.704676 -253.149506)
			(xy 139.74138 -253.184761) (xy 139.771953 -253.225447) (xy 139.795604 -253.27051) (xy 139.81172 -253.318784)
			(xy 139.819884 -253.369018) (xy 139.820396 -253.394464) (xy 139.819893 -253.419453) (xy 140.12721 -253.419453)
			(xy 140.12721 -253.369475) (xy 140.135029 -253.320112) (xy 140.150473 -253.27258) (xy 140.173163 -253.228048)
			(xy 140.202539 -253.187615) (xy 140.237879 -253.152275) (xy 140.278312 -253.122899) (xy 140.322844 -253.100209)
			(xy 140.370376 -253.084765) (xy 140.419739 -253.076946) (xy 140.469717 -253.076946) (xy 140.51908 -253.084765)
			(xy 140.566612 -253.100209) (xy 140.611144 -253.122899) (xy 140.651577 -253.152275) (xy 140.686917 -253.187615)
			(xy 140.716293 -253.228048) (xy 140.738983 -253.27258) (xy 140.754427 -253.320112) (xy 140.762246 -253.369475)
			(xy 140.762736 -253.394464) (xy 141.068547 -253.394464) (xy 141.072642 -253.343736) (xy 141.084821 -253.294322)
			(xy 141.104769 -253.247502) (xy 141.13197 -253.204488) (xy 141.165718 -253.166394) (xy 141.20514 -253.134207)
			(xy 141.249214 -253.108761) (xy 141.2968 -253.090714) (xy 141.346664 -253.080534) (xy 141.397516 -253.078485)
			(xy 141.448037 -253.084619) (xy 141.496921 -253.098779) (xy 141.5429 -253.120596) (xy 141.584784 -253.149506)
			(xy 141.621488 -253.184761) (xy 141.652061 -253.225447) (xy 141.675712 -253.27051) (xy 141.691828 -253.318784)
			(xy 141.699992 -253.369018) (xy 141.700504 -253.394464) (xy 142.008601 -253.394464) (xy 142.012696 -253.343736)
			(xy 142.024875 -253.294322) (xy 142.044823 -253.247502) (xy 142.072024 -253.204488) (xy 142.105772 -253.166394)
			(xy 142.145194 -253.134207) (xy 142.189268 -253.108761) (xy 142.236854 -253.090714) (xy 142.286718 -253.080534)
			(xy 142.33757 -253.078485) (xy 142.388091 -253.084619) (xy 142.436975 -253.098779) (xy 142.482954 -253.120596)
			(xy 142.524838 -253.149506) (xy 142.561542 -253.184761) (xy 142.592115 -253.225447) (xy 142.615766 -253.27051)
			(xy 142.631882 -253.318784) (xy 142.640046 -253.369018) (xy 142.640558 -253.394464) (xy 142.640055 -253.419453)
			(xy 142.947118 -253.419453) (xy 142.947118 -253.369475) (xy 142.954937 -253.320112) (xy 142.970381 -253.27258)
			(xy 142.993071 -253.228048) (xy 143.022447 -253.187615) (xy 143.057787 -253.152275) (xy 143.09822 -253.122899)
			(xy 143.142752 -253.100209) (xy 143.190284 -253.084765) (xy 143.239647 -253.076946) (xy 143.289625 -253.076946)
			(xy 143.338988 -253.084765) (xy 143.38652 -253.100209) (xy 143.431052 -253.122899) (xy 143.471485 -253.152275)
			(xy 143.506825 -253.187615) (xy 143.536201 -253.228048) (xy 143.558891 -253.27258) (xy 143.574335 -253.320112)
			(xy 143.582154 -253.369475) (xy 143.582644 -253.394464) (xy 143.582154 -253.419453) (xy 143.574335 -253.468816)
			(xy 143.558891 -253.516348) (xy 143.536201 -253.56088) (xy 143.506825 -253.601313) (xy 143.471485 -253.636653)
			(xy 143.431052 -253.666029) (xy 143.38652 -253.688719) (xy 143.338988 -253.704163) (xy 143.289625 -253.711982)
			(xy 143.239647 -253.711982) (xy 143.190284 -253.704163) (xy 143.142752 -253.688719) (xy 143.09822 -253.666029)
			(xy 143.057787 -253.636653) (xy 143.022447 -253.601313) (xy 142.993071 -253.56088) (xy 142.970381 -253.516348)
			(xy 142.954937 -253.468816) (xy 142.947118 -253.419453) (xy 142.640055 -253.419453) (xy 142.640046 -253.41991)
			(xy 142.631882 -253.470144) (xy 142.615766 -253.518418) (xy 142.592115 -253.563481) (xy 142.561542 -253.604167)
			(xy 142.524838 -253.639422) (xy 142.482954 -253.668332) (xy 142.436975 -253.690149) (xy 142.388091 -253.704309)
			(xy 142.33757 -253.710443) (xy 142.286718 -253.708394) (xy 142.236854 -253.698214) (xy 142.189268 -253.680167)
			(xy 142.145194 -253.654721) (xy 142.105772 -253.622534) (xy 142.072024 -253.58444) (xy 142.044823 -253.541426)
			(xy 142.024875 -253.494606) (xy 142.012696 -253.445192) (xy 142.008601 -253.394464) (xy 141.700504 -253.394464)
			(xy 141.699992 -253.41991) (xy 141.691828 -253.470144) (xy 141.675712 -253.518418) (xy 141.652061 -253.563481)
			(xy 141.621488 -253.604167) (xy 141.584784 -253.639422) (xy 141.5429 -253.668332) (xy 141.496921 -253.690149)
			(xy 141.448037 -253.704309) (xy 141.397516 -253.710443) (xy 141.346664 -253.708394) (xy 141.2968 -253.698214)
			(xy 141.249214 -253.680167) (xy 141.20514 -253.654721) (xy 141.165718 -253.622534) (xy 141.13197 -253.58444)
			(xy 141.104769 -253.541426) (xy 141.084821 -253.494606) (xy 141.072642 -253.445192) (xy 141.068547 -253.394464)
			(xy 140.762736 -253.394464) (xy 140.762246 -253.419453) (xy 140.754427 -253.468816) (xy 140.738983 -253.516348)
			(xy 140.716293 -253.56088) (xy 140.686917 -253.601313) (xy 140.651577 -253.636653) (xy 140.611144 -253.666029)
			(xy 140.566612 -253.688719) (xy 140.51908 -253.704163) (xy 140.469717 -253.711982) (xy 140.419739 -253.711982)
			(xy 140.370376 -253.704163) (xy 140.322844 -253.688719) (xy 140.278312 -253.666029) (xy 140.237879 -253.636653)
			(xy 140.202539 -253.601313) (xy 140.173163 -253.56088) (xy 140.150473 -253.516348) (xy 140.135029 -253.468816)
			(xy 140.12721 -253.419453) (xy 139.819893 -253.419453) (xy 139.819884 -253.41991) (xy 139.81172 -253.470144)
			(xy 139.795604 -253.518418) (xy 139.771953 -253.563481) (xy 139.74138 -253.604167) (xy 139.704676 -253.639422)
			(xy 139.662792 -253.668332) (xy 139.616813 -253.690149) (xy 139.567929 -253.704309) (xy 139.517408 -253.710443)
			(xy 139.466556 -253.708394) (xy 139.416692 -253.698214) (xy 139.369106 -253.680167) (xy 139.325032 -253.654721)
			(xy 139.28561 -253.622534) (xy 139.251862 -253.58444) (xy 139.224661 -253.541426) (xy 139.204713 -253.494606)
			(xy 139.192534 -253.445192) (xy 139.188439 -253.394464) (xy 138.882882 -253.394464) (xy 138.882392 -253.419453)
			(xy 138.874573 -253.468816) (xy 138.859129 -253.516348) (xy 138.836439 -253.56088) (xy 138.807063 -253.601313)
			(xy 138.771723 -253.636653) (xy 138.73129 -253.666029) (xy 138.686758 -253.688719) (xy 138.639226 -253.704163)
			(xy 138.589863 -253.711982) (xy 138.539885 -253.711982) (xy 138.490522 -253.704163) (xy 138.44299 -253.688719)
			(xy 138.398458 -253.666029) (xy 138.358025 -253.636653) (xy 138.322685 -253.601313) (xy 138.293309 -253.56088)
			(xy 138.270619 -253.516348) (xy 138.255175 -253.468816) (xy 138.247356 -253.419453) (xy 137.940039 -253.419453)
			(xy 137.94003 -253.41991) (xy 137.931866 -253.470144) (xy 137.91575 -253.518418) (xy 137.892099 -253.563481)
			(xy 137.861526 -253.604167) (xy 137.824822 -253.639422) (xy 137.782938 -253.668332) (xy 137.736959 -253.690149)
			(xy 137.688075 -253.704309) (xy 137.637554 -253.710443) (xy 137.586702 -253.708394) (xy 137.536838 -253.698214)
			(xy 137.489252 -253.680167) (xy 137.445178 -253.654721) (xy 137.405756 -253.622534) (xy 137.372008 -253.58444)
			(xy 137.344807 -253.541426) (xy 137.324859 -253.494606) (xy 137.31268 -253.445192) (xy 137.308585 -253.394464)
			(xy 137.002774 -253.394464) (xy 137.002284 -253.419453) (xy 136.994465 -253.468816) (xy 136.979021 -253.516348)
			(xy 136.956331 -253.56088) (xy 136.926955 -253.601313) (xy 136.891615 -253.636653) (xy 136.851182 -253.666029)
			(xy 136.80665 -253.688719) (xy 136.759118 -253.704163) (xy 136.709755 -253.711982) (xy 136.659777 -253.711982)
			(xy 136.610414 -253.704163) (xy 136.562882 -253.688719) (xy 136.51835 -253.666029) (xy 136.477917 -253.636653)
			(xy 136.442577 -253.601313) (xy 136.413201 -253.56088) (xy 136.390511 -253.516348) (xy 136.375067 -253.468816)
			(xy 136.367248 -253.419453) (xy 136.059931 -253.419453) (xy 136.059922 -253.41991) (xy 136.051758 -253.470144)
			(xy 136.035642 -253.518418) (xy 136.011991 -253.563481) (xy 135.981418 -253.604167) (xy 135.944714 -253.639422)
			(xy 135.90283 -253.668332) (xy 135.856851 -253.690149) (xy 135.807967 -253.704309) (xy 135.757446 -253.710443)
			(xy 135.706594 -253.708394) (xy 135.65673 -253.698214) (xy 135.609144 -253.680167) (xy 135.56507 -253.654721)
			(xy 135.525648 -253.622534) (xy 135.4919 -253.58444) (xy 135.464699 -253.541426) (xy 135.444751 -253.494606)
			(xy 135.432572 -253.445192) (xy 135.428477 -253.394464) (xy 135.12038 -253.394464) (xy 135.119868 -253.41991)
			(xy 135.111704 -253.470144) (xy 135.095588 -253.518418) (xy 135.071937 -253.563481) (xy 135.041364 -253.604167)
			(xy 135.00466 -253.639422) (xy 134.962776 -253.668332) (xy 134.916797 -253.690149) (xy 134.867913 -253.704309)
			(xy 134.817392 -253.710443) (xy 134.76654 -253.708394) (xy 134.716676 -253.698214) (xy 134.66909 -253.680167)
			(xy 134.625016 -253.654721) (xy 134.585594 -253.622534) (xy 134.551846 -253.58444) (xy 134.524645 -253.541426)
			(xy 134.504697 -253.494606) (xy 134.492518 -253.445192) (xy 134.488423 -253.394464) (xy 134.182866 -253.394464)
			(xy 134.182376 -253.419453) (xy 134.174557 -253.468816) (xy 134.159113 -253.516348) (xy 134.136423 -253.56088)
			(xy 134.107047 -253.601313) (xy 134.071707 -253.636653) (xy 134.031274 -253.666029) (xy 133.986742 -253.688719)
			(xy 133.93921 -253.704163) (xy 133.889847 -253.711982) (xy 133.839869 -253.711982) (xy 133.790506 -253.704163)
			(xy 133.742974 -253.688719) (xy 133.698442 -253.666029) (xy 133.658009 -253.636653) (xy 133.622669 -253.601313)
			(xy 133.593293 -253.56088) (xy 133.570603 -253.516348) (xy 133.555159 -253.468816) (xy 133.54734 -253.419453)
			(xy 133.240023 -253.419453) (xy 133.240014 -253.41991) (xy 133.23185 -253.470144) (xy 133.215734 -253.518418)
			(xy 133.192083 -253.563481) (xy 133.16151 -253.604167) (xy 133.124806 -253.639422) (xy 133.082922 -253.668332)
			(xy 133.036943 -253.690149) (xy 132.988059 -253.704309) (xy 132.937538 -253.710443) (xy 132.886686 -253.708394)
			(xy 132.836822 -253.698214) (xy 132.789236 -253.680167) (xy 132.745162 -253.654721) (xy 132.70574 -253.622534)
			(xy 132.671992 -253.58444) (xy 132.644791 -253.541426) (xy 132.624843 -253.494606) (xy 132.612664 -253.445192)
			(xy 132.608569 -253.394464) (xy 132.302758 -253.394464) (xy 132.302268 -253.419453) (xy 132.294449 -253.468816)
			(xy 132.279005 -253.516348) (xy 132.256315 -253.56088) (xy 132.226939 -253.601313) (xy 132.191599 -253.636653)
			(xy 132.151166 -253.666029) (xy 132.106634 -253.688719) (xy 132.059102 -253.704163) (xy 132.009739 -253.711982)
			(xy 131.959761 -253.711982) (xy 131.910398 -253.704163) (xy 131.862866 -253.688719) (xy 131.818334 -253.666029)
			(xy 131.777901 -253.636653) (xy 131.742561 -253.601313) (xy 131.713185 -253.56088) (xy 131.690495 -253.516348)
			(xy 131.675051 -253.468816) (xy 131.667232 -253.419453) (xy 131.359915 -253.419453) (xy 131.359906 -253.41991)
			(xy 131.351742 -253.470144) (xy 131.335626 -253.518418) (xy 131.311975 -253.563481) (xy 131.281402 -253.604167)
			(xy 131.244698 -253.639422) (xy 131.202814 -253.668332) (xy 131.156835 -253.690149) (xy 131.107951 -253.704309)
			(xy 131.05743 -253.710443) (xy 131.006578 -253.708394) (xy 130.956714 -253.698214) (xy 130.909128 -253.680167)
			(xy 130.865054 -253.654721) (xy 130.825632 -253.622534) (xy 130.791884 -253.58444) (xy 130.764683 -253.541426)
			(xy 130.744735 -253.494606) (xy 130.732556 -253.445192) (xy 130.728461 -253.394464) (xy 130.42265 -253.394464)
			(xy 130.42216 -253.419453) (xy 130.414341 -253.468816) (xy 130.398897 -253.516348) (xy 130.376207 -253.56088)
			(xy 130.346831 -253.601313) (xy 130.311491 -253.636653) (xy 130.271058 -253.666029) (xy 130.226526 -253.688719)
			(xy 130.178994 -253.704163) (xy 130.129631 -253.711982) (xy 130.079653 -253.711982) (xy 130.03029 -253.704163)
			(xy 129.982758 -253.688719) (xy 129.938226 -253.666029) (xy 129.897793 -253.636653) (xy 129.862453 -253.601313)
			(xy 129.833077 -253.56088) (xy 129.810387 -253.516348) (xy 129.794943 -253.468816) (xy 129.787124 -253.419453)
			(xy 129.480061 -253.419453) (xy 129.480052 -253.41991) (xy 129.471888 -253.470144) (xy 129.455772 -253.518418)
			(xy 129.432121 -253.563481) (xy 129.401548 -253.604167) (xy 129.364844 -253.639422) (xy 129.32296 -253.668332)
			(xy 129.276981 -253.690149) (xy 129.228097 -253.704309) (xy 129.177576 -253.710443) (xy 129.126724 -253.708394)
			(xy 129.07686 -253.698214) (xy 129.029274 -253.680167) (xy 128.9852 -253.654721) (xy 128.945778 -253.622534)
			(xy 128.91203 -253.58444) (xy 128.884829 -253.541426) (xy 128.864881 -253.494606) (xy 128.852702 -253.445192)
			(xy 128.848607 -253.394464) (xy 128.54051 -253.394464) (xy 128.539998 -253.41991) (xy 128.531834 -253.470144)
			(xy 128.515718 -253.518418) (xy 128.492067 -253.563481) (xy 128.461494 -253.604167) (xy 128.42479 -253.639422)
			(xy 128.382906 -253.668332) (xy 128.336927 -253.690149) (xy 128.288043 -253.704309) (xy 128.237522 -253.710443)
			(xy 128.18667 -253.708394) (xy 128.136806 -253.698214) (xy 128.08922 -253.680167) (xy 128.045146 -253.654721)
			(xy 128.005724 -253.622534) (xy 127.971976 -253.58444) (xy 127.944775 -253.541426) (xy 127.924827 -253.494606)
			(xy 127.912648 -253.445192) (xy 127.908553 -253.394464) (xy 126.662688 -253.394464) (xy 126.662198 -253.419453)
			(xy 126.654379 -253.468816) (xy 126.638935 -253.516348) (xy 126.616245 -253.56088) (xy 126.586869 -253.601313)
			(xy 126.551529 -253.636653) (xy 126.511096 -253.666029) (xy 126.466564 -253.688719) (xy 126.419032 -253.704163)
			(xy 126.369669 -253.711982) (xy 126.319691 -253.711982) (xy 126.270328 -253.704163) (xy 126.222796 -253.688719)
			(xy 126.178264 -253.666029) (xy 126.137831 -253.636653) (xy 126.102491 -253.601313) (xy 126.073115 -253.56088)
			(xy 126.050425 -253.516348) (xy 126.034981 -253.468816) (xy 126.027162 -253.419453) (xy 124.782344 -253.419453)
			(xy 124.774525 -253.468816) (xy 124.759081 -253.516348) (xy 124.736391 -253.56088) (xy 124.707015 -253.601313)
			(xy 124.671675 -253.636653) (xy 124.631242 -253.666029) (xy 124.58671 -253.688719) (xy 124.539178 -253.704163)
			(xy 124.489815 -253.711982) (xy 124.439837 -253.711982) (xy 124.390474 -253.704163) (xy 124.342942 -253.688719)
			(xy 124.29841 -253.666029) (xy 124.257977 -253.636653) (xy 124.222637 -253.601313) (xy 124.193261 -253.56088)
			(xy 124.170571 -253.516348) (xy 124.155127 -253.468816) (xy 124.147308 -253.419453) (xy 122.902236 -253.419453)
			(xy 122.894417 -253.468816) (xy 122.878973 -253.516348) (xy 122.856283 -253.56088) (xy 122.826907 -253.601313)
			(xy 122.791567 -253.636653) (xy 122.751134 -253.666029) (xy 122.706602 -253.688719) (xy 122.65907 -253.704163)
			(xy 122.609707 -253.711982) (xy 122.559729 -253.711982) (xy 122.510366 -253.704163) (xy 122.462834 -253.688719)
			(xy 122.418302 -253.666029) (xy 122.377869 -253.636653) (xy 122.342529 -253.601313) (xy 122.313153 -253.56088)
			(xy 122.290463 -253.516348) (xy 122.275019 -253.468816) (xy 122.2672 -253.419453) (xy 119.282972 -253.419453)
			(xy 119.282972 -253.686564) (xy 119.28255 -253.696586) (xy 119.274887 -253.715108) (xy 119.260715 -253.729282)
			(xy 119.242194 -253.736949) (xy 119.232172 -253.737364) (xy 119.018304 -253.737364) (xy 119.018304 -253.746508)
			(xy 119.017818 -253.756516) (xy 119.010157 -253.775007) (xy 118.996003 -253.789159) (xy 118.977512 -253.796819)
			(xy 118.967504 -253.797308) (xy 118.763288 -253.797308) (xy 118.742244 -253.796787) (xy 118.700972 -253.788544)
			(xy 118.662111 -253.772381) (xy 118.627168 -253.748922) (xy 118.597494 -253.719075) (xy 118.574237 -253.683997)
			(xy 118.558299 -253.645044) (xy 118.550295 -253.603724) (xy 118.549928 -253.582678) (xy 118.549928 -253.58217)
			(xy 118.549928 -253.553722) (xy 118.547388 -253.542546) (xy 118.544848 -253.537466) (xy 118.54434 -253.536704)
			(xy 118.533472 -253.514222) (xy 118.518087 -253.466718) (xy 118.510289 -253.417398) (xy 118.509796 -253.392432)
			(xy 117.377972 -253.392432) (xy 117.377972 -253.686564) (xy 117.37755 -253.696586) (xy 117.369887 -253.715108)
			(xy 117.355715 -253.729282) (xy 117.337194 -253.736949) (xy 117.327172 -253.737364) (xy 117.113304 -253.737364)
			(xy 117.113304 -253.746508) (xy 117.112818 -253.756516) (xy 117.105157 -253.775007) (xy 117.091003 -253.789159)
			(xy 117.072512 -253.796819) (xy 117.062504 -253.797308) (xy 116.858288 -253.797308) (xy 116.837244 -253.796787)
			(xy 116.795972 -253.788544) (xy 116.757111 -253.772381) (xy 116.722168 -253.748922) (xy 116.692494 -253.719075)
			(xy 116.669237 -253.683997) (xy 116.653299 -253.645044) (xy 116.645295 -253.603724) (xy 116.644928 -253.582678)
			(xy 116.644928 -253.58217) (xy 116.644928 -253.48946) (xy 116.642896 -253.482602) (xy 116.636826 -253.460556)
			(xy 116.630323 -253.415295) (xy 116.629942 -253.392432) (xy 115.599972 -253.392432) (xy 115.599972 -253.686564)
			(xy 115.59955 -253.696586) (xy 115.591887 -253.715108) (xy 115.577715 -253.729282) (xy 115.559194 -253.736949)
			(xy 115.549172 -253.737364) (xy 115.335304 -253.737364) (xy 115.335304 -253.746508) (xy 115.334818 -253.756516)
			(xy 115.327157 -253.775007) (xy 115.313003 -253.789159) (xy 115.294512 -253.796819) (xy 115.284504 -253.797308)
			(xy 115.080288 -253.797308) (xy 115.058745 -253.796805) (xy 115.016535 -253.788152) (xy 114.976915 -253.771219)
			(xy 114.941489 -253.746693) (xy 114.911695 -253.715567) (xy 114.888739 -253.679104) (xy 114.880644 -253.659132)
			(xy 114.87812 -253.652987) (xy 114.870393 -253.642185) (xy 114.865404 -253.637796) (xy 114.847668 -253.622589)
			(xy 114.816384 -253.58789) (xy 114.790509 -253.548991) (xy 114.7706 -253.506728) (xy 114.757082 -253.462007)
			(xy 114.750248 -253.415791) (xy 114.749834 -253.392432) (xy 113.694972 -253.392432) (xy 113.694972 -253.686564)
			(xy 113.69455 -253.696586) (xy 113.686887 -253.715108) (xy 113.672715 -253.729282) (xy 113.654194 -253.736949)
			(xy 113.644172 -253.737364) (xy 113.430304 -253.737364) (xy 113.430304 -253.746508) (xy 113.429818 -253.756516)
			(xy 113.422157 -253.775007) (xy 113.408003 -253.789159) (xy 113.389512 -253.796819) (xy 113.379504 -253.797308)
			(xy 113.175288 -253.797308) (xy 113.154829 -253.796817) (xy 113.114659 -253.789023) (xy 113.076708 -253.773723)
			(xy 113.042366 -253.751475) (xy 113.012888 -253.723095) (xy 112.989354 -253.689622) (xy 112.972625 -253.652279)
			(xy 112.967516 -253.632462) (xy 112.96586 -253.626049) (xy 112.959682 -253.614337) (xy 112.955324 -253.609348)
			(xy 112.939367 -253.59158) (xy 112.912415 -253.552157) (xy 112.891653 -253.509152) (xy 112.877545 -253.463528)
			(xy 112.870409 -253.416309) (xy 112.86998 -253.392432) (xy 112.611007 -253.392432) (xy 112.614134 -253.432576)
			(xy 112.60984 -253.487789) (xy 112.597055 -253.541673) (xy 112.576087 -253.59293) (xy 112.547439 -253.640325)
			(xy 112.511804 -253.682716) (xy 112.491266 -253.701296) (xy 112.483646 -253.709678) (xy 112.471446 -253.725616)
			(xy 112.442139 -253.753034) (xy 112.408233 -253.774504) (xy 112.370916 -253.789273) (xy 112.3315 -253.796821)
			(xy 112.311434 -253.797308) (xy 112.056672 -253.797308) (xy 112.056672 -253.788164) (xy 112.056241 -253.778151)
			(xy 112.048564 -253.759653) (xy 112.034394 -253.7455) (xy 112.015886 -253.737847) (xy 112.005872 -253.737364)
			(xy 111.842296 -253.737364) (xy 111.83227 -253.736983) (xy 111.813746 -253.729305) (xy 111.799573 -253.71512)
			(xy 111.791909 -253.69659) (xy 111.791496 -253.686564) (xy 109.884972 -253.686564) (xy 109.88455 -253.696586)
			(xy 109.876887 -253.715108) (xy 109.862715 -253.729282) (xy 109.844194 -253.736949) (xy 109.834172 -253.737364)
			(xy 109.620304 -253.737364) (xy 109.620304 -253.746508) (xy 109.619818 -253.756516) (xy 109.612157 -253.775007)
			(xy 109.598003 -253.789159) (xy 109.579512 -253.796819) (xy 109.569504 -253.797308) (xy 109.365288 -253.797308)
			(xy 109.344244 -253.796787) (xy 109.302972 -253.788544) (xy 109.264111 -253.772381) (xy 109.229168 -253.748922)
			(xy 109.199494 -253.719075) (xy 109.176237 -253.683997) (xy 109.160299 -253.645044) (xy 109.152295 -253.603724)
			(xy 109.151928 -253.582678) (xy 109.151928 -253.58217) (xy 109.151928 -253.562866) (xy 109.151742 -253.557002)
			(xy 109.149053 -253.545586) (xy 109.146594 -253.54026) (xy 109.146086 -253.539244) (xy 109.13476 -253.516443)
			(xy 109.118695 -253.468136) (xy 109.11054 -253.417886) (xy 109.110018 -253.392432) (xy 108.106972 -253.392432)
			(xy 108.106972 -253.686564) (xy 108.10655 -253.696586) (xy 108.098887 -253.715108) (xy 108.084715 -253.729282)
			(xy 108.066194 -253.736949) (xy 108.056172 -253.737364) (xy 107.842304 -253.737364) (xy 107.842304 -253.746508)
			(xy 107.841818 -253.756516) (xy 107.834157 -253.775007) (xy 107.820003 -253.789159) (xy 107.801512 -253.796819)
			(xy 107.791504 -253.797308) (xy 107.587288 -253.797308) (xy 107.567842 -253.796848) (xy 107.529602 -253.78975)
			(xy 107.493273 -253.775863) (xy 107.460049 -253.755643) (xy 107.431022 -253.729755) (xy 107.407149 -253.699051)
			(xy 107.397804 -253.681992) (xy 107.394548 -253.676028) (xy 107.385398 -253.665989) (xy 107.37977 -253.66218)
			(xy 107.357226 -253.647549) (xy 107.317028 -253.611883) (xy 107.283403 -253.569961) (xy 107.257312 -253.52298)
			(xy 107.239497 -253.472278) (xy 107.230466 -253.419302) (xy 107.22991 -253.392432) (xy 106.201972 -253.392432)
			(xy 106.201972 -253.686564) (xy 106.20155 -253.696586) (xy 106.193887 -253.715108) (xy 106.179715 -253.729282)
			(xy 106.161194 -253.736949) (xy 106.151172 -253.737364) (xy 105.937304 -253.737364) (xy 105.937304 -253.746508)
			(xy 105.936818 -253.756516) (xy 105.929157 -253.775007) (xy 105.915003 -253.789159) (xy 105.896512 -253.796819)
			(xy 105.886504 -253.797308) (xy 105.682288 -253.797308) (xy 105.660947 -253.796769) (xy 105.619126 -253.788236)
			(xy 105.579831 -253.771572) (xy 105.544625 -253.747439) (xy 105.51491 -253.716799) (xy 105.491868 -253.680871)
			(xy 105.48366 -253.661164) (xy 105.481086 -253.655051) (xy 105.473224 -253.644374) (xy 105.468166 -253.640082)
			(xy 105.450034 -253.624876) (xy 105.418019 -253.59003) (xy 105.391516 -253.550828) (xy 105.371109 -253.508134)
			(xy 105.357248 -253.46289) (xy 105.350237 -253.416092) (xy 105.349802 -253.392432) (xy 104.296972 -253.392432)
			(xy 104.296972 -253.686564) (xy 104.29655 -253.696586) (xy 104.288887 -253.715108) (xy 104.274715 -253.729282)
			(xy 104.256194 -253.736949) (xy 104.246172 -253.737364) (xy 104.032304 -253.737364) (xy 104.032304 -253.746508)
			(xy 104.031818 -253.756516) (xy 104.024157 -253.775007) (xy 104.010003 -253.789159) (xy 103.991512 -253.796819)
			(xy 103.981504 -253.797308) (xy 103.777288 -253.797308) (xy 103.757011 -253.796847) (xy 103.717192 -253.78915)
			(xy 103.679543 -253.774074) (xy 103.645418 -253.75216) (xy 103.616043 -253.724197) (xy 103.592477 -253.691192)
			(xy 103.575566 -253.65433) (xy 103.570278 -253.634748) (xy 103.568483 -253.628311) (xy 103.562041 -253.616608)
			(xy 103.557578 -253.611634) (xy 103.541244 -253.593776) (xy 103.513576 -253.554071) (xy 103.492244 -253.510633)
			(xy 103.477742 -253.464463) (xy 103.470403 -253.416629) (xy 103.469948 -253.392432) (xy 102.229116 -253.392432)
			(xy 102.229158 -253.394464) (xy 102.228696 -253.419456) (xy 102.220881 -253.468824) (xy 102.205438 -253.516362)
			(xy 102.182748 -253.560898) (xy 102.153369 -253.601335) (xy 102.118024 -253.636678) (xy 102.077586 -253.666055)
			(xy 102.033049 -253.688743) (xy 101.98551 -253.704184) (xy 101.936142 -253.711997) (xy 101.91115 -253.712472)
			(xy 101.885848 -253.711979) (xy 101.835883 -253.703959) (xy 101.787819 -253.688129) (xy 101.742868 -253.664888)
			(xy 101.702163 -253.634822) (xy 101.666733 -253.598691) (xy 101.63747 -253.557406) (xy 101.615113 -253.512008)
			(xy 101.600226 -253.463643) (xy 101.59619 -253.43866) (xy 101.595936 -253.435866) (xy 101.595682 -253.434342)
			(xy 101.595428 -253.43358) (xy 101.594158 -253.42469) (xy 101.592888 -253.394718) (xy 101.592888 -253.39421)
			(xy 101.593173 -253.375098) (xy 101.597762 -253.33715) (xy 101.602032 -253.318518) (xy 101.604064 -253.31039)
			(xy 101.605334 -253.306072) (xy 101.607929 -253.294622) (xy 101.603553 -253.271585) (xy 101.596952 -253.261876)
			(xy 101.549454 -253.198884) (xy 101.541849 -253.189781) (xy 101.520659 -253.179188) (xy 101.508814 -253.178564)
			(xy 100.888038 -253.178564) (xy 100.878199 -253.179098) (xy 100.860033 -253.186679) (xy 100.852732 -253.193296)
			(xy 100.755196 -253.290832) (xy 100.748485 -253.298071) (xy 100.740897 -253.316276) (xy 100.740464 -253.326138)
			(xy 100.740464 -253.71298) (xy 100.740993 -253.7228) (xy 100.748587 -253.740919) (xy 100.762518 -253.754771)
			(xy 100.780679 -253.762263) (xy 100.790502 -253.762764) (xy 100.890324 -253.762764) (xy 100.890324 -253.761748)
			(xy 101.096572 -253.761748) (xy 101.106478 -253.760732) (xy 101.113638 -253.759029) (xy 101.126668 -253.7522)
			(xy 101.132132 -253.74727) (xy 101.132386 -253.747016) (xy 101.148896 -253.730252) (xy 101.156516 -253.711964)
			(xy 101.156516 -253.70282) (xy 101.18725 -253.70282) (xy 101.19106 -253.702312) (xy 101.19868 -253.701804)
			(xy 101.411532 -253.701804) (xy 101.432671 -253.702314) (xy 101.474124 -253.710627) (xy 101.513152 -253.726886)
			(xy 101.548246 -253.750463) (xy 101.578052 -253.780448) (xy 101.601419 -253.815682) (xy 101.617444 -253.854806)
			(xy 101.625509 -253.896308) (xy 101.625908 -253.91745) (xy 101.625908 -253.920752) (xy 101.626177 -253.927638)
			(xy 101.629917 -253.940895) (xy 101.633274 -253.946914) (xy 101.63429 -253.948946) (xy 101.64064 -253.956566)
			(xy 101.642672 -253.958598) (xy 101.660527 -253.973781) (xy 101.692012 -254.0085) (xy 101.718061 -254.047463)
			(xy 101.738108 -254.089827) (xy 101.751721 -254.134675) (xy 101.758605 -254.181036) (xy 101.759004 -254.20447)
			(xy 101.758542 -254.229463) (xy 101.750727 -254.278833) (xy 101.735284 -254.326373) (xy 101.712594 -254.370912)
			(xy 101.683215 -254.411352) (xy 101.647872 -254.446698) (xy 101.607434 -254.47608) (xy 101.562897 -254.498774)
			(xy 101.515358 -254.51422) (xy 101.465989 -254.52204) (xy 101.440996 -254.522478) (xy 101.440742 -254.522478)
			(xy 101.413332 -254.521878) (xy 101.359329 -254.512442) (xy 101.307736 -254.493911) (xy 101.260071 -254.466829)
			(xy 101.238558 -254.449834) (xy 101.231954 -254.444246) (xy 101.21138 -254.436626) (xy 101.207092 -254.435107)
			(xy 101.198148 -254.433449) (xy 101.1936 -254.433324) (xy 101.185218 -254.433324) (xy 101.183948 -254.432308)
			(xy 101.156516 -254.404876) (xy 101.156516 -254.395732) (xy 101.153722 -254.389636) (xy 101.14153 -254.381762)
			(xy 101.135198 -254.377906) (xy 101.121 -254.373663) (xy 101.11359 -254.37338) (xy 100.890324 -254.37338)
			(xy 100.890324 -254.372364) (xy 100.803456 -254.372364) (xy 100.792534 -254.374904) (xy 100.773738 -254.384556)
			(xy 100.768404 -254.387858) (xy 100.76053 -254.394716) (xy 100.760276 -254.39497) (xy 100.755665 -254.399149)
			(xy 100.748474 -254.409303) (xy 100.746052 -254.415036) (xy 100.742496 -254.42545) (xy 100.741529 -254.428991)
			(xy 100.740507 -254.436258) (xy 100.740464 -254.439928) (xy 100.740464 -255.014476) (xy 101.593142 -255.014476)
			(xy 101.593587 -254.990924) (xy 101.600535 -254.944334) (xy 101.614263 -254.899273) (xy 101.634471 -254.856723)
			(xy 101.647244 -254.83693) (xy 101.653594 -254.823976) (xy 101.657238 -254.812873) (xy 101.666663 -254.79149)
			(xy 101.67239 -254.781304) (xy 101.79939 -254.561086) (xy 101.807518 -254.565658) (xy 101.816412 -254.570253)
			(xy 101.83624 -254.572867) (xy 101.85556 -254.567697) (xy 101.871433 -254.555529) (xy 101.87686 -254.547116)
			(xy 101.958648 -254.405384) (xy 101.964081 -254.396977) (xy 101.979951 -254.384814) (xy 101.999266 -254.379647)
			(xy 102.019089 -254.382263) (xy 102.02799 -254.386842) (xy 102.467918 -254.640842) (xy 102.47632 -254.646281)
			(xy 102.488483 -254.662149) (xy 102.493651 -254.681462) (xy 102.491037 -254.701284) (xy 102.490379 -254.702564)
			(xy 111.791496 -254.702564) (xy 111.791496 -254.194564) (xy 111.791958 -254.184555) (xy 111.799629 -254.166063)
			(xy 111.81379 -254.151911) (xy 111.832286 -254.144252) (xy 111.842296 -254.143764) (xy 112.056672 -254.143764)
			(xy 112.056672 -254.13462) (xy 112.057204 -254.124617) (xy 112.064851 -254.106131) (xy 112.078991 -254.091978)
			(xy 112.09747 -254.084313) (xy 112.107472 -254.08382) (xy 112.311434 -254.08382) (xy 112.331505 -254.084276)
			(xy 112.370936 -254.091794) (xy 112.408264 -254.106557) (xy 112.442171 -254.128045) (xy 112.471457 -254.155497)
			(xy 112.483646 -254.17145) (xy 112.491266 -254.179832) (xy 112.511771 -254.19845) (xy 112.516833 -254.20447)
			(xy 120.856756 -254.20447) (xy 120.85716 -254.180658) (xy 120.864259 -254.133567) (xy 120.878308 -254.088064)
			(xy 120.898992 -254.045167) (xy 120.925848 -254.005839) (xy 120.958274 -253.97096) (xy 120.976644 -253.955804)
			(xy 120.980446 -253.952562) (xy 120.986844 -253.94489) (xy 120.989344 -253.940564) (xy 120.998898 -253.924128)
			(xy 121.022813 -253.894584) (xy 121.051574 -253.869731) (xy 121.084274 -253.850353) (xy 121.119884 -253.83706)
			(xy 121.157283 -253.830269) (xy 121.176288 -253.82982) (xy 121.431304 -253.82982) (xy 121.431304 -253.838964)
			(xy 121.431749 -253.848983) (xy 121.439408 -253.8675) (xy 121.453573 -253.881674) (xy 121.472085 -253.889344)
			(xy 121.482104 -253.889764) (xy 121.645172 -253.889764) (xy 121.655173 -253.89031) (xy 121.673658 -253.897954)
			(xy 121.687811 -253.912088) (xy 121.695477 -253.930563) (xy 121.695972 -253.940564) (xy 121.695972 -254.20447)
			(xy 122.73661 -254.20447) (xy 122.73709 -254.180704) (xy 122.74417 -254.133702) (xy 122.758153 -254.088272)
			(xy 122.778729 -254.045424) (xy 122.805441 -254.006107) (xy 122.837698 -253.971195) (xy 122.874782 -253.941461)
			(xy 122.895106 -253.929134) (xy 122.899494 -253.926484) (xy 122.907177 -253.919701) (xy 122.910346 -253.915672)
			(xy 122.922589 -253.900044) (xy 122.951804 -253.873171) (xy 122.985473 -253.852144) (xy 123.022441 -253.837687)
			(xy 123.061441 -253.830293) (xy 123.081288 -253.82982) (xy 123.336304 -253.82982) (xy 123.336304 -253.838964)
			(xy 123.336749 -253.848983) (xy 123.344408 -253.8675) (xy 123.358573 -253.881674) (xy 123.377085 -253.889344)
			(xy 123.387104 -253.889764) (xy 123.550172 -253.889764) (xy 123.560173 -253.89031) (xy 123.578658 -253.897954)
			(xy 123.592811 -253.912088) (xy 123.600477 -253.930563) (xy 123.600972 -253.940564) (xy 123.600972 -254.204978)
			(xy 124.616718 -254.204978) (xy 124.616718 -254.20447) (xy 124.617091 -254.183191) (xy 124.622824 -254.141019)
			(xy 124.634117 -254.099985) (xy 124.642118 -254.080264) (xy 124.645928 -254.070612) (xy 124.645928 -254.04445)
			(xy 124.646288 -254.023402) (xy 124.654288 -253.982077) (xy 124.670224 -253.943118) (xy 124.69348 -253.908034)
			(xy 124.723156 -253.878183) (xy 124.758102 -253.854719) (xy 124.796965 -253.838553) (xy 124.838242 -253.830309)
			(xy 124.859288 -253.82982) (xy 125.114304 -253.82982) (xy 125.114304 -253.838964) (xy 125.114749 -253.848983)
			(xy 125.122408 -253.8675) (xy 125.136573 -253.881674) (xy 125.155085 -253.889344) (xy 125.165104 -253.889764)
			(xy 125.328172 -253.889764) (xy 125.338173 -253.89031) (xy 125.356658 -253.897954) (xy 125.370811 -253.912088)
			(xy 125.378477 -253.930563) (xy 125.378972 -253.940564) (xy 125.378972 -254.229459) (xy 126.497316 -254.229459)
			(xy 126.497316 -254.179481) (xy 126.505135 -254.130118) (xy 126.520579 -254.082586) (xy 126.543269 -254.038054)
			(xy 126.572645 -253.997621) (xy 126.607985 -253.962281) (xy 126.648418 -253.932905) (xy 126.69295 -253.910215)
			(xy 126.740482 -253.894771) (xy 126.789845 -253.886952) (xy 126.839823 -253.886952) (xy 126.889186 -253.894771)
			(xy 126.936718 -253.910215) (xy 126.98125 -253.932905) (xy 127.021683 -253.962281) (xy 127.057023 -253.997621)
			(xy 127.086399 -254.038054) (xy 127.109089 -254.082586) (xy 127.124533 -254.130118) (xy 127.132352 -254.179481)
			(xy 127.132842 -254.20447) (xy 127.438399 -254.20447) (xy 127.442494 -254.153742) (xy 127.454673 -254.104328)
			(xy 127.474621 -254.057508) (xy 127.501822 -254.014494) (xy 127.53557 -253.9764) (xy 127.574992 -253.944213)
			(xy 127.619066 -253.918767) (xy 127.666652 -253.90072) (xy 127.716516 -253.89054) (xy 127.767368 -253.888491)
			(xy 127.817889 -253.894625) (xy 127.866773 -253.908785) (xy 127.912752 -253.930602) (xy 127.954636 -253.959512)
			(xy 127.99134 -253.994767) (xy 128.021913 -254.035453) (xy 128.045564 -254.080516) (xy 128.06168 -254.12879)
			(xy 128.069844 -254.179024) (xy 128.070356 -254.20447) (xy 128.069853 -254.229459) (xy 128.37717 -254.229459)
			(xy 128.37717 -254.179481) (xy 128.384989 -254.130118) (xy 128.400433 -254.082586) (xy 128.423123 -254.038054)
			(xy 128.452499 -253.997621) (xy 128.487839 -253.962281) (xy 128.528272 -253.932905) (xy 128.572804 -253.910215)
			(xy 128.620336 -253.894771) (xy 128.669699 -253.886952) (xy 128.719677 -253.886952) (xy 128.76904 -253.894771)
			(xy 128.816572 -253.910215) (xy 128.861104 -253.932905) (xy 128.901537 -253.962281) (xy 128.936877 -253.997621)
			(xy 128.966253 -254.038054) (xy 128.988943 -254.082586) (xy 129.004387 -254.130118) (xy 129.012206 -254.179481)
			(xy 129.012696 -254.20447) (xy 129.318507 -254.20447) (xy 129.322602 -254.153742) (xy 129.334781 -254.104328)
			(xy 129.354729 -254.057508) (xy 129.38193 -254.014494) (xy 129.415678 -253.9764) (xy 129.4551 -253.944213)
			(xy 129.499174 -253.918767) (xy 129.54676 -253.90072) (xy 129.596624 -253.89054) (xy 129.647476 -253.888491)
			(xy 129.697997 -253.894625) (xy 129.746881 -253.908785) (xy 129.79286 -253.930602) (xy 129.834744 -253.959512)
			(xy 129.871448 -253.994767) (xy 129.902021 -254.035453) (xy 129.925672 -254.080516) (xy 129.941788 -254.12879)
			(xy 129.949952 -254.179024) (xy 129.950464 -254.20447) (xy 131.198615 -254.20447) (xy 131.20271 -254.153742)
			(xy 131.214889 -254.104328) (xy 131.234837 -254.057508) (xy 131.262038 -254.014494) (xy 131.295786 -253.9764)
			(xy 131.335208 -253.944213) (xy 131.379282 -253.918767) (xy 131.426868 -253.90072) (xy 131.476732 -253.89054)
			(xy 131.527584 -253.888491) (xy 131.578105 -253.894625) (xy 131.626989 -253.908785) (xy 131.672968 -253.930602)
			(xy 131.714852 -253.959512) (xy 131.751556 -253.994767) (xy 131.782129 -254.035453) (xy 131.80578 -254.080516)
			(xy 131.821896 -254.12879) (xy 131.83006 -254.179024) (xy 131.830572 -254.20447) (xy 132.138415 -254.20447)
			(xy 132.14251 -254.153742) (xy 132.154689 -254.104328) (xy 132.174637 -254.057508) (xy 132.201838 -254.014494)
			(xy 132.235586 -253.9764) (xy 132.275008 -253.944213) (xy 132.319082 -253.918767) (xy 132.366668 -253.90072)
			(xy 132.416532 -253.89054) (xy 132.467384 -253.888491) (xy 132.517905 -253.894625) (xy 132.566789 -253.908785)
			(xy 132.612768 -253.930602) (xy 132.654652 -253.959512) (xy 132.691356 -253.994767) (xy 132.721929 -254.035453)
			(xy 132.74558 -254.080516) (xy 132.761696 -254.12879) (xy 132.76986 -254.179024) (xy 132.770372 -254.20447)
			(xy 132.769869 -254.229459) (xy 133.077186 -254.229459) (xy 133.077186 -254.179481) (xy 133.085005 -254.130118)
			(xy 133.100449 -254.082586) (xy 133.123139 -254.038054) (xy 133.152515 -253.997621) (xy 133.187855 -253.962281)
			(xy 133.228288 -253.932905) (xy 133.27282 -253.910215) (xy 133.320352 -253.894771) (xy 133.369715 -253.886952)
			(xy 133.419693 -253.886952) (xy 133.469056 -253.894771) (xy 133.516588 -253.910215) (xy 133.56112 -253.932905)
			(xy 133.601553 -253.962281) (xy 133.636893 -253.997621) (xy 133.666269 -254.038054) (xy 133.688959 -254.082586)
			(xy 133.704403 -254.130118) (xy 133.712222 -254.179481) (xy 133.712712 -254.20447) (xy 134.018523 -254.20447)
			(xy 134.022618 -254.153742) (xy 134.034797 -254.104328) (xy 134.054745 -254.057508) (xy 134.081946 -254.014494)
			(xy 134.115694 -253.9764) (xy 134.155116 -253.944213) (xy 134.19919 -253.918767) (xy 134.246776 -253.90072)
			(xy 134.29664 -253.89054) (xy 134.347492 -253.888491) (xy 134.398013 -253.894625) (xy 134.446897 -253.908785)
			(xy 134.492876 -253.930602) (xy 134.53476 -253.959512) (xy 134.571464 -253.994767) (xy 134.602037 -254.035453)
			(xy 134.625688 -254.080516) (xy 134.641804 -254.12879) (xy 134.649968 -254.179024) (xy 134.65048 -254.20447)
			(xy 134.649977 -254.229459) (xy 134.957294 -254.229459) (xy 134.957294 -254.179481) (xy 134.965113 -254.130118)
			(xy 134.980557 -254.082586) (xy 135.003247 -254.038054) (xy 135.032623 -253.997621) (xy 135.067963 -253.962281)
			(xy 135.108396 -253.932905) (xy 135.152928 -253.910215) (xy 135.20046 -253.894771) (xy 135.249823 -253.886952)
			(xy 135.299801 -253.886952) (xy 135.349164 -253.894771) (xy 135.396696 -253.910215) (xy 135.441228 -253.932905)
			(xy 135.481661 -253.962281) (xy 135.517001 -253.997621) (xy 135.546377 -254.038054) (xy 135.569067 -254.082586)
			(xy 135.584511 -254.130118) (xy 135.59233 -254.179481) (xy 135.59282 -254.20447) (xy 135.898631 -254.20447)
			(xy 135.902726 -254.153742) (xy 135.914905 -254.104328) (xy 135.934853 -254.057508) (xy 135.962054 -254.014494)
			(xy 135.995802 -253.9764) (xy 136.035224 -253.944213) (xy 136.079298 -253.918767) (xy 136.126884 -253.90072)
			(xy 136.176748 -253.89054) (xy 136.2276 -253.888491) (xy 136.278121 -253.894625) (xy 136.327005 -253.908785)
			(xy 136.372984 -253.930602) (xy 136.414868 -253.959512) (xy 136.451572 -253.994767) (xy 136.482145 -254.035453)
			(xy 136.505796 -254.080516) (xy 136.521912 -254.12879) (xy 136.530076 -254.179024) (xy 136.530588 -254.20447)
			(xy 137.778485 -254.20447) (xy 137.78258 -254.153742) (xy 137.794759 -254.104328) (xy 137.814707 -254.057508)
			(xy 137.841908 -254.014494) (xy 137.875656 -253.9764) (xy 137.915078 -253.944213) (xy 137.959152 -253.918767)
			(xy 138.006738 -253.90072) (xy 138.056602 -253.89054) (xy 138.107454 -253.888491) (xy 138.157975 -253.894625)
			(xy 138.206859 -253.908785) (xy 138.252838 -253.930602) (xy 138.294722 -253.959512) (xy 138.331426 -253.994767)
			(xy 138.361999 -254.035453) (xy 138.38565 -254.080516) (xy 138.401766 -254.12879) (xy 138.40993 -254.179024)
			(xy 138.410442 -254.20447) (xy 138.718539 -254.20447) (xy 138.722634 -254.153742) (xy 138.734813 -254.104328)
			(xy 138.754761 -254.057508) (xy 138.781962 -254.014494) (xy 138.81571 -253.9764) (xy 138.855132 -253.944213)
			(xy 138.899206 -253.918767) (xy 138.946792 -253.90072) (xy 138.996656 -253.89054) (xy 139.047508 -253.888491)
			(xy 139.098029 -253.894625) (xy 139.146913 -253.908785) (xy 139.192892 -253.930602) (xy 139.234776 -253.959512)
			(xy 139.27148 -253.994767) (xy 139.302053 -254.035453) (xy 139.325704 -254.080516) (xy 139.34182 -254.12879)
			(xy 139.349984 -254.179024) (xy 139.350496 -254.20447) (xy 139.349993 -254.229459) (xy 139.65731 -254.229459)
			(xy 139.65731 -254.179481) (xy 139.665129 -254.130118) (xy 139.680573 -254.082586) (xy 139.703263 -254.038054)
			(xy 139.732639 -253.997621) (xy 139.767979 -253.962281) (xy 139.808412 -253.932905) (xy 139.852944 -253.910215)
			(xy 139.900476 -253.894771) (xy 139.949839 -253.886952) (xy 139.999817 -253.886952) (xy 140.04918 -253.894771)
			(xy 140.096712 -253.910215) (xy 140.141244 -253.932905) (xy 140.181677 -253.962281) (xy 140.217017 -253.997621)
			(xy 140.246393 -254.038054) (xy 140.269083 -254.082586) (xy 140.284527 -254.130118) (xy 140.292346 -254.179481)
			(xy 140.292836 -254.20447) (xy 140.598647 -254.20447) (xy 140.602742 -254.153742) (xy 140.614921 -254.104328)
			(xy 140.634869 -254.057508) (xy 140.66207 -254.014494) (xy 140.695818 -253.9764) (xy 140.73524 -253.944213)
			(xy 140.779314 -253.918767) (xy 140.8269 -253.90072) (xy 140.876764 -253.89054) (xy 140.927616 -253.888491)
			(xy 140.978137 -253.894625) (xy 141.027021 -253.908785) (xy 141.073 -253.930602) (xy 141.114884 -253.959512)
			(xy 141.151588 -253.994767) (xy 141.182161 -254.035453) (xy 141.205812 -254.080516) (xy 141.221928 -254.12879)
			(xy 141.230092 -254.179024) (xy 141.230604 -254.20447) (xy 141.230101 -254.229459) (xy 141.537164 -254.229459)
			(xy 141.537164 -254.179481) (xy 141.544983 -254.130118) (xy 141.560427 -254.082586) (xy 141.583117 -254.038054)
			(xy 141.612493 -253.997621) (xy 141.647833 -253.962281) (xy 141.688266 -253.932905) (xy 141.732798 -253.910215)
			(xy 141.78033 -253.894771) (xy 141.829693 -253.886952) (xy 141.879671 -253.886952) (xy 141.929034 -253.894771)
			(xy 141.976566 -253.910215) (xy 142.021098 -253.932905) (xy 142.061531 -253.962281) (xy 142.096871 -253.997621)
			(xy 142.126247 -254.038054) (xy 142.148937 -254.082586) (xy 142.164381 -254.130118) (xy 142.1722 -254.179481)
			(xy 142.17269 -254.20447) (xy 142.478501 -254.20447) (xy 142.482596 -254.153742) (xy 142.494775 -254.104328)
			(xy 142.514723 -254.057508) (xy 142.541924 -254.014494) (xy 142.575672 -253.9764) (xy 142.615094 -253.944213)
			(xy 142.659168 -253.918767) (xy 142.706754 -253.90072) (xy 142.756618 -253.89054) (xy 142.80747 -253.888491)
			(xy 142.857991 -253.894625) (xy 142.906875 -253.908785) (xy 142.952854 -253.930602) (xy 142.994738 -253.959512)
			(xy 143.031442 -253.994767) (xy 143.062015 -254.035453) (xy 143.085666 -254.080516) (xy 143.101782 -254.12879)
			(xy 143.109946 -254.179024) (xy 143.110458 -254.20447) (xy 143.109946 -254.229916) (xy 143.101782 -254.28015)
			(xy 143.085666 -254.328424) (xy 143.062015 -254.373487) (xy 143.031442 -254.414173) (xy 142.994738 -254.449428)
			(xy 142.952854 -254.478338) (xy 142.906875 -254.500155) (xy 142.857991 -254.514315) (xy 142.80747 -254.520449)
			(xy 142.756618 -254.5184) (xy 142.706754 -254.50822) (xy 142.659168 -254.490173) (xy 142.615094 -254.464727)
			(xy 142.575672 -254.43254) (xy 142.541924 -254.394446) (xy 142.514723 -254.351432) (xy 142.494775 -254.304612)
			(xy 142.482596 -254.255198) (xy 142.478501 -254.20447) (xy 142.17269 -254.20447) (xy 142.1722 -254.229459)
			(xy 142.164381 -254.278822) (xy 142.148937 -254.326354) (xy 142.126247 -254.370886) (xy 142.096871 -254.411319)
			(xy 142.061531 -254.446659) (xy 142.021098 -254.476035) (xy 141.976566 -254.498725) (xy 141.929034 -254.514169)
			(xy 141.879671 -254.521988) (xy 141.829693 -254.521988) (xy 141.78033 -254.514169) (xy 141.732798 -254.498725)
			(xy 141.688266 -254.476035) (xy 141.647833 -254.446659) (xy 141.612493 -254.411319) (xy 141.583117 -254.370886)
			(xy 141.560427 -254.326354) (xy 141.544983 -254.278822) (xy 141.537164 -254.229459) (xy 141.230101 -254.229459)
			(xy 141.230092 -254.229916) (xy 141.221928 -254.28015) (xy 141.205812 -254.328424) (xy 141.182161 -254.373487)
			(xy 141.151588 -254.414173) (xy 141.114884 -254.449428) (xy 141.073 -254.478338) (xy 141.027021 -254.500155)
			(xy 140.978137 -254.514315) (xy 140.927616 -254.520449) (xy 140.876764 -254.5184) (xy 140.8269 -254.50822)
			(xy 140.779314 -254.490173) (xy 140.73524 -254.464727) (xy 140.695818 -254.43254) (xy 140.66207 -254.394446)
			(xy 140.634869 -254.351432) (xy 140.614921 -254.304612) (xy 140.602742 -254.255198) (xy 140.598647 -254.20447)
			(xy 140.292836 -254.20447) (xy 140.292346 -254.229459) (xy 140.284527 -254.278822) (xy 140.269083 -254.326354)
			(xy 140.246393 -254.370886) (xy 140.217017 -254.411319) (xy 140.181677 -254.446659) (xy 140.141244 -254.476035)
			(xy 140.096712 -254.498725) (xy 140.04918 -254.514169) (xy 139.999817 -254.521988) (xy 139.949839 -254.521988)
			(xy 139.900476 -254.514169) (xy 139.852944 -254.498725) (xy 139.808412 -254.476035) (xy 139.767979 -254.446659)
			(xy 139.732639 -254.411319) (xy 139.703263 -254.370886) (xy 139.680573 -254.326354) (xy 139.665129 -254.278822)
			(xy 139.65731 -254.229459) (xy 139.349993 -254.229459) (xy 139.349984 -254.229916) (xy 139.34182 -254.28015)
			(xy 139.325704 -254.328424) (xy 139.302053 -254.373487) (xy 139.27148 -254.414173) (xy 139.234776 -254.449428)
			(xy 139.192892 -254.478338) (xy 139.146913 -254.500155) (xy 139.098029 -254.514315) (xy 139.047508 -254.520449)
			(xy 138.996656 -254.5184) (xy 138.946792 -254.50822) (xy 138.899206 -254.490173) (xy 138.855132 -254.464727)
			(xy 138.81571 -254.43254) (xy 138.781962 -254.394446) (xy 138.754761 -254.351432) (xy 138.734813 -254.304612)
			(xy 138.722634 -254.255198) (xy 138.718539 -254.20447) (xy 138.410442 -254.20447) (xy 138.40993 -254.229916)
			(xy 138.401766 -254.28015) (xy 138.38565 -254.328424) (xy 138.361999 -254.373487) (xy 138.331426 -254.414173)
			(xy 138.294722 -254.449428) (xy 138.252838 -254.478338) (xy 138.206859 -254.500155) (xy 138.157975 -254.514315)
			(xy 138.107454 -254.520449) (xy 138.056602 -254.5184) (xy 138.006738 -254.50822) (xy 137.959152 -254.490173)
			(xy 137.915078 -254.464727) (xy 137.875656 -254.43254) (xy 137.841908 -254.394446) (xy 137.814707 -254.351432)
			(xy 137.794759 -254.304612) (xy 137.78258 -254.255198) (xy 137.778485 -254.20447) (xy 136.530588 -254.20447)
			(xy 136.530076 -254.229916) (xy 136.521912 -254.28015) (xy 136.505796 -254.328424) (xy 136.482145 -254.373487)
			(xy 136.451572 -254.414173) (xy 136.414868 -254.449428) (xy 136.372984 -254.478338) (xy 136.327005 -254.500155)
			(xy 136.278121 -254.514315) (xy 136.2276 -254.520449) (xy 136.176748 -254.5184) (xy 136.126884 -254.50822)
			(xy 136.079298 -254.490173) (xy 136.035224 -254.464727) (xy 135.995802 -254.43254) (xy 135.962054 -254.394446)
			(xy 135.934853 -254.351432) (xy 135.914905 -254.304612) (xy 135.902726 -254.255198) (xy 135.898631 -254.20447)
			(xy 135.59282 -254.20447) (xy 135.59233 -254.229459) (xy 135.584511 -254.278822) (xy 135.569067 -254.326354)
			(xy 135.546377 -254.370886) (xy 135.517001 -254.411319) (xy 135.481661 -254.446659) (xy 135.441228 -254.476035)
			(xy 135.396696 -254.498725) (xy 135.349164 -254.514169) (xy 135.299801 -254.521988) (xy 135.249823 -254.521988)
			(xy 135.20046 -254.514169) (xy 135.152928 -254.498725) (xy 135.108396 -254.476035) (xy 135.067963 -254.446659)
			(xy 135.032623 -254.411319) (xy 135.003247 -254.370886) (xy 134.980557 -254.326354) (xy 134.965113 -254.278822)
			(xy 134.957294 -254.229459) (xy 134.649977 -254.229459) (xy 134.649968 -254.229916) (xy 134.641804 -254.28015)
			(xy 134.625688 -254.328424) (xy 134.602037 -254.373487) (xy 134.571464 -254.414173) (xy 134.53476 -254.449428)
			(xy 134.492876 -254.478338) (xy 134.446897 -254.500155) (xy 134.398013 -254.514315) (xy 134.347492 -254.520449)
			(xy 134.29664 -254.5184) (xy 134.246776 -254.50822) (xy 134.19919 -254.490173) (xy 134.155116 -254.464727)
			(xy 134.115694 -254.43254) (xy 134.081946 -254.394446) (xy 134.054745 -254.351432) (xy 134.034797 -254.304612)
			(xy 134.022618 -254.255198) (xy 134.018523 -254.20447) (xy 133.712712 -254.20447) (xy 133.712222 -254.229459)
			(xy 133.704403 -254.278822) (xy 133.688959 -254.326354) (xy 133.666269 -254.370886) (xy 133.636893 -254.411319)
			(xy 133.601553 -254.446659) (xy 133.56112 -254.476035) (xy 133.516588 -254.498725) (xy 133.469056 -254.514169)
			(xy 133.419693 -254.521988) (xy 133.369715 -254.521988) (xy 133.320352 -254.514169) (xy 133.27282 -254.498725)
			(xy 133.228288 -254.476035) (xy 133.187855 -254.446659) (xy 133.152515 -254.411319) (xy 133.123139 -254.370886)
			(xy 133.100449 -254.326354) (xy 133.085005 -254.278822) (xy 133.077186 -254.229459) (xy 132.769869 -254.229459)
			(xy 132.76986 -254.229916) (xy 132.761696 -254.28015) (xy 132.74558 -254.328424) (xy 132.721929 -254.373487)
			(xy 132.691356 -254.414173) (xy 132.654652 -254.449428) (xy 132.612768 -254.478338) (xy 132.566789 -254.500155)
			(xy 132.517905 -254.514315) (xy 132.467384 -254.520449) (xy 132.416532 -254.5184) (xy 132.366668 -254.50822)
			(xy 132.319082 -254.490173) (xy 132.275008 -254.464727) (xy 132.235586 -254.43254) (xy 132.201838 -254.394446)
			(xy 132.174637 -254.351432) (xy 132.154689 -254.304612) (xy 132.14251 -254.255198) (xy 132.138415 -254.20447)
			(xy 131.830572 -254.20447) (xy 131.83006 -254.229916) (xy 131.821896 -254.28015) (xy 131.80578 -254.328424)
			(xy 131.782129 -254.373487) (xy 131.751556 -254.414173) (xy 131.714852 -254.449428) (xy 131.672968 -254.478338)
			(xy 131.626989 -254.500155) (xy 131.578105 -254.514315) (xy 131.527584 -254.520449) (xy 131.476732 -254.5184)
			(xy 131.426868 -254.50822) (xy 131.379282 -254.490173) (xy 131.335208 -254.464727) (xy 131.295786 -254.43254)
			(xy 131.262038 -254.394446) (xy 131.234837 -254.351432) (xy 131.214889 -254.304612) (xy 131.20271 -254.255198)
			(xy 131.198615 -254.20447) (xy 129.950464 -254.20447) (xy 129.949952 -254.229916) (xy 129.941788 -254.28015)
			(xy 129.925672 -254.328424) (xy 129.902021 -254.373487) (xy 129.871448 -254.414173) (xy 129.834744 -254.449428)
			(xy 129.79286 -254.478338) (xy 129.746881 -254.500155) (xy 129.697997 -254.514315) (xy 129.647476 -254.520449)
			(xy 129.596624 -254.5184) (xy 129.54676 -254.50822) (xy 129.499174 -254.490173) (xy 129.4551 -254.464727)
			(xy 129.415678 -254.43254) (xy 129.38193 -254.394446) (xy 129.354729 -254.351432) (xy 129.334781 -254.304612)
			(xy 129.322602 -254.255198) (xy 129.318507 -254.20447) (xy 129.012696 -254.20447) (xy 129.012206 -254.229459)
			(xy 129.004387 -254.278822) (xy 128.988943 -254.326354) (xy 128.966253 -254.370886) (xy 128.936877 -254.411319)
			(xy 128.901537 -254.446659) (xy 128.861104 -254.476035) (xy 128.816572 -254.498725) (xy 128.76904 -254.514169)
			(xy 128.719677 -254.521988) (xy 128.669699 -254.521988) (xy 128.620336 -254.514169) (xy 128.572804 -254.498725)
			(xy 128.528272 -254.476035) (xy 128.487839 -254.446659) (xy 128.452499 -254.411319) (xy 128.423123 -254.370886)
			(xy 128.400433 -254.326354) (xy 128.384989 -254.278822) (xy 128.37717 -254.229459) (xy 128.069853 -254.229459)
			(xy 128.069844 -254.229916) (xy 128.06168 -254.28015) (xy 128.045564 -254.328424) (xy 128.021913 -254.373487)
			(xy 127.99134 -254.414173) (xy 127.954636 -254.449428) (xy 127.912752 -254.478338) (xy 127.866773 -254.500155)
			(xy 127.817889 -254.514315) (xy 127.767368 -254.520449) (xy 127.716516 -254.5184) (xy 127.666652 -254.50822)
			(xy 127.619066 -254.490173) (xy 127.574992 -254.464727) (xy 127.53557 -254.43254) (xy 127.501822 -254.394446)
			(xy 127.474621 -254.351432) (xy 127.454673 -254.304612) (xy 127.442494 -254.255198) (xy 127.438399 -254.20447)
			(xy 127.132842 -254.20447) (xy 127.132352 -254.229459) (xy 127.124533 -254.278822) (xy 127.109089 -254.326354)
			(xy 127.086399 -254.370886) (xy 127.057023 -254.411319) (xy 127.021683 -254.446659) (xy 126.98125 -254.476035)
			(xy 126.936718 -254.498725) (xy 126.889186 -254.514169) (xy 126.839823 -254.521988) (xy 126.789845 -254.521988)
			(xy 126.740482 -254.514169) (xy 126.69295 -254.498725) (xy 126.648418 -254.476035) (xy 126.607985 -254.446659)
			(xy 126.572645 -254.411319) (xy 126.543269 -254.370886) (xy 126.520579 -254.326354) (xy 126.505135 -254.278822)
			(xy 126.497316 -254.229459) (xy 125.378972 -254.229459) (xy 125.378972 -254.448564) (xy 125.37855 -254.458586)
			(xy 125.370887 -254.477108) (xy 125.356715 -254.491282) (xy 125.338194 -254.498949) (xy 125.328172 -254.499364)
			(xy 125.114304 -254.499364) (xy 125.114304 -254.508508) (xy 125.113818 -254.518516) (xy 125.106157 -254.537007)
			(xy 125.092003 -254.551159) (xy 125.073512 -254.558819) (xy 125.063504 -254.559308) (xy 124.859288 -254.559308)
			(xy 124.838206 -254.558887) (xy 124.796861 -254.550615) (xy 124.757942 -254.534394) (xy 124.72296 -254.510855)
			(xy 124.693274 -254.480912) (xy 124.670038 -254.445728) (xy 124.654153 -254.40667) (xy 124.646239 -254.365256)
			(xy 124.645928 -254.34417) (xy 124.645928 -254.33782) (xy 124.636701 -254.316904) (xy 124.623706 -254.273075)
			(xy 124.617128 -254.227835) (xy 124.616718 -254.204978) (xy 123.600972 -254.204978) (xy 123.600972 -254.448564)
			(xy 123.60055 -254.458586) (xy 123.592887 -254.477108) (xy 123.578715 -254.491282) (xy 123.560194 -254.498949)
			(xy 123.550172 -254.499364) (xy 123.336304 -254.499364) (xy 123.336304 -254.508508) (xy 123.335818 -254.518516)
			(xy 123.328157 -254.537007) (xy 123.314003 -254.551159) (xy 123.295512 -254.558819) (xy 123.285504 -254.559308)
			(xy 123.081288 -254.559308) (xy 123.061543 -254.558881) (xy 123.022731 -254.551591) (xy 122.985925 -254.537281)
			(xy 122.952381 -254.516441) (xy 122.937524 -254.503428) (xy 122.934491 -254.500738) (xy 122.927725 -254.496274)
			(xy 122.924062 -254.494538) (xy 122.900492 -254.483334) (xy 122.857048 -254.454424) (xy 122.818906 -254.418811)
			(xy 122.787088 -254.377451) (xy 122.762447 -254.331451) (xy 122.745645 -254.282046) (xy 122.737133 -254.230562)
			(xy 122.73661 -254.20447) (xy 121.695972 -254.20447) (xy 121.695972 -254.448564) (xy 121.69555 -254.458586)
			(xy 121.687887 -254.477108) (xy 121.673715 -254.491282) (xy 121.655194 -254.498949) (xy 121.645172 -254.499364)
			(xy 121.431304 -254.499364) (xy 121.431304 -254.508508) (xy 121.430818 -254.518516) (xy 121.423157 -254.537007)
			(xy 121.409003 -254.551159) (xy 121.390512 -254.558819) (xy 121.380504 -254.559308) (xy 121.176288 -254.559308)
			(xy 121.1573 -254.558828) (xy 121.119932 -254.552042) (xy 121.084352 -254.538759) (xy 121.051681 -254.519395)
			(xy 121.022947 -254.494561) (xy 121.01068 -254.48006) (xy 121.008179 -254.477089) (xy 121.002442 -254.471857)
			(xy 120.99925 -254.469646) (xy 120.977733 -254.454779) (xy 120.939431 -254.419171) (xy 120.907472 -254.377776)
			(xy 120.882718 -254.331708) (xy 120.865837 -254.282211) (xy 120.857284 -254.230618) (xy 120.856756 -254.20447)
			(xy 112.516833 -254.20447) (xy 112.547412 -254.240837) (xy 112.576065 -254.288228) (xy 112.597041 -254.339482)
			(xy 112.609833 -254.393364) (xy 112.614134 -254.448576) (xy 112.60984 -254.503789) (xy 112.597055 -254.557673)
			(xy 112.576087 -254.60893) (xy 112.547439 -254.656325) (xy 112.511804 -254.698716) (xy 112.491266 -254.717296)
			(xy 112.483646 -254.725678) (xy 112.471446 -254.741616) (xy 112.442139 -254.769034) (xy 112.408233 -254.790504)
			(xy 112.370916 -254.805273) (xy 112.3315 -254.812821) (xy 112.311434 -254.813308) (xy 112.056672 -254.813308)
			(xy 112.056672 -254.804164) (xy 112.056241 -254.794151) (xy 112.048564 -254.775653) (xy 112.034394 -254.7615)
			(xy 112.015886 -254.753847) (xy 112.005872 -254.753364) (xy 111.842296 -254.753364) (xy 111.83227 -254.752983)
			(xy 111.813746 -254.745305) (xy 111.799573 -254.73112) (xy 111.791909 -254.71259) (xy 111.791496 -254.702564)
			(xy 102.490379 -254.702564) (xy 102.48646 -254.710184) (xy 102.379272 -254.89535) (xy 102.387146 -254.899922)
			(xy 102.395664 -254.905243) (xy 102.407964 -254.9211) (xy 102.413214 -254.94047) (xy 102.410604 -254.960368)
			(xy 102.405942 -254.969264) (xy 102.365395 -255.039465) (xy 122.2672 -255.039465) (xy 122.2672 -254.989487)
			(xy 122.275019 -254.940124) (xy 122.290463 -254.892592) (xy 122.313153 -254.84806) (xy 122.342529 -254.807627)
			(xy 122.377869 -254.772287) (xy 122.418302 -254.742911) (xy 122.462834 -254.720221) (xy 122.510366 -254.704777)
			(xy 122.559729 -254.696958) (xy 122.609707 -254.696958) (xy 122.65907 -254.704777) (xy 122.706602 -254.720221)
			(xy 122.751134 -254.742911) (xy 122.791567 -254.772287) (xy 122.826907 -254.807627) (xy 122.856283 -254.84806)
			(xy 122.878973 -254.892592) (xy 122.894417 -254.940124) (xy 122.902236 -254.989487) (xy 122.902726 -255.014476)
			(xy 122.902236 -255.039465) (xy 124.147308 -255.039465) (xy 124.147308 -254.989487) (xy 124.155127 -254.940124)
			(xy 124.170571 -254.892592) (xy 124.193261 -254.84806) (xy 124.222637 -254.807627) (xy 124.257977 -254.772287)
			(xy 124.29841 -254.742911) (xy 124.342942 -254.720221) (xy 124.390474 -254.704777) (xy 124.439837 -254.696958)
			(xy 124.489815 -254.696958) (xy 124.539178 -254.704777) (xy 124.58671 -254.720221) (xy 124.631242 -254.742911)
			(xy 124.671675 -254.772287) (xy 124.707015 -254.807627) (xy 124.736391 -254.84806) (xy 124.759081 -254.892592)
			(xy 124.774525 -254.940124) (xy 124.782344 -254.989487) (xy 124.782834 -255.014476) (xy 124.782344 -255.039465)
			(xy 126.027162 -255.039465) (xy 126.027162 -254.989487) (xy 126.034981 -254.940124) (xy 126.050425 -254.892592)
			(xy 126.073115 -254.84806) (xy 126.102491 -254.807627) (xy 126.137831 -254.772287) (xy 126.178264 -254.742911)
			(xy 126.222796 -254.720221) (xy 126.270328 -254.704777) (xy 126.319691 -254.696958) (xy 126.369669 -254.696958)
			(xy 126.419032 -254.704777) (xy 126.466564 -254.720221) (xy 126.511096 -254.742911) (xy 126.551529 -254.772287)
			(xy 126.586869 -254.807627) (xy 126.616245 -254.84806) (xy 126.638935 -254.892592) (xy 126.654379 -254.940124)
			(xy 126.662198 -254.989487) (xy 126.662688 -255.014476) (xy 127.908553 -255.014476) (xy 127.912648 -254.963748)
			(xy 127.924827 -254.914334) (xy 127.944775 -254.867514) (xy 127.971976 -254.8245) (xy 128.005724 -254.786406)
			(xy 128.045146 -254.754219) (xy 128.08922 -254.728773) (xy 128.136806 -254.710726) (xy 128.18667 -254.700546)
			(xy 128.237522 -254.698497) (xy 128.288043 -254.704631) (xy 128.336927 -254.718791) (xy 128.382906 -254.740608)
			(xy 128.42479 -254.769518) (xy 128.461494 -254.804773) (xy 128.492067 -254.845459) (xy 128.515718 -254.890522)
			(xy 128.531834 -254.938796) (xy 128.539998 -254.98903) (xy 128.54051 -255.014476) (xy 128.848607 -255.014476)
			(xy 128.852702 -254.963748) (xy 128.864881 -254.914334) (xy 128.884829 -254.867514) (xy 128.91203 -254.8245)
			(xy 128.945778 -254.786406) (xy 128.9852 -254.754219) (xy 129.029274 -254.728773) (xy 129.07686 -254.710726)
			(xy 129.126724 -254.700546) (xy 129.177576 -254.698497) (xy 129.228097 -254.704631) (xy 129.276981 -254.718791)
			(xy 129.32296 -254.740608) (xy 129.364844 -254.769518) (xy 129.401548 -254.804773) (xy 129.432121 -254.845459)
			(xy 129.455772 -254.890522) (xy 129.471888 -254.938796) (xy 129.480052 -254.98903) (xy 129.480564 -255.014476)
			(xy 129.480061 -255.039465) (xy 129.787124 -255.039465) (xy 129.787124 -254.989487) (xy 129.794943 -254.940124)
			(xy 129.810387 -254.892592) (xy 129.833077 -254.84806) (xy 129.862453 -254.807627) (xy 129.897793 -254.772287)
			(xy 129.938226 -254.742911) (xy 129.982758 -254.720221) (xy 130.03029 -254.704777) (xy 130.079653 -254.696958)
			(xy 130.129631 -254.696958) (xy 130.178994 -254.704777) (xy 130.226526 -254.720221) (xy 130.271058 -254.742911)
			(xy 130.311491 -254.772287) (xy 130.346831 -254.807627) (xy 130.376207 -254.84806) (xy 130.398897 -254.892592)
			(xy 130.414341 -254.940124) (xy 130.42216 -254.989487) (xy 130.42265 -255.014476) (xy 130.728461 -255.014476)
			(xy 130.732556 -254.963748) (xy 130.744735 -254.914334) (xy 130.764683 -254.867514) (xy 130.791884 -254.8245)
			(xy 130.825632 -254.786406) (xy 130.865054 -254.754219) (xy 130.909128 -254.728773) (xy 130.956714 -254.710726)
			(xy 131.006578 -254.700546) (xy 131.05743 -254.698497) (xy 131.107951 -254.704631) (xy 131.156835 -254.718791)
			(xy 131.202814 -254.740608) (xy 131.244698 -254.769518) (xy 131.281402 -254.804773) (xy 131.311975 -254.845459)
			(xy 131.335626 -254.890522) (xy 131.351742 -254.938796) (xy 131.359906 -254.98903) (xy 131.360418 -255.014476)
			(xy 131.359915 -255.039465) (xy 131.667232 -255.039465) (xy 131.667232 -254.989487) (xy 131.675051 -254.940124)
			(xy 131.690495 -254.892592) (xy 131.713185 -254.84806) (xy 131.742561 -254.807627) (xy 131.777901 -254.772287)
			(xy 131.818334 -254.742911) (xy 131.862866 -254.720221) (xy 131.910398 -254.704777) (xy 131.959761 -254.696958)
			(xy 132.009739 -254.696958) (xy 132.059102 -254.704777) (xy 132.106634 -254.720221) (xy 132.151166 -254.742911)
			(xy 132.191599 -254.772287) (xy 132.226939 -254.807627) (xy 132.256315 -254.84806) (xy 132.279005 -254.892592)
			(xy 132.294449 -254.940124) (xy 132.302268 -254.989487) (xy 132.302758 -255.014476) (xy 132.608569 -255.014476)
			(xy 132.612664 -254.963748) (xy 132.624843 -254.914334) (xy 132.644791 -254.867514) (xy 132.671992 -254.8245)
			(xy 132.70574 -254.786406) (xy 132.745162 -254.754219) (xy 132.789236 -254.728773) (xy 132.836822 -254.710726)
			(xy 132.886686 -254.700546) (xy 132.937538 -254.698497) (xy 132.988059 -254.704631) (xy 133.036943 -254.718791)
			(xy 133.082922 -254.740608) (xy 133.124806 -254.769518) (xy 133.16151 -254.804773) (xy 133.192083 -254.845459)
			(xy 133.215734 -254.890522) (xy 133.23185 -254.938796) (xy 133.240014 -254.98903) (xy 133.240526 -255.014476)
			(xy 133.240023 -255.039465) (xy 133.54734 -255.039465) (xy 133.54734 -254.989487) (xy 133.555159 -254.940124)
			(xy 133.570603 -254.892592) (xy 133.593293 -254.84806) (xy 133.622669 -254.807627) (xy 133.658009 -254.772287)
			(xy 133.698442 -254.742911) (xy 133.742974 -254.720221) (xy 133.790506 -254.704777) (xy 133.839869 -254.696958)
			(xy 133.889847 -254.696958) (xy 133.93921 -254.704777) (xy 133.986742 -254.720221) (xy 134.031274 -254.742911)
			(xy 134.071707 -254.772287) (xy 134.107047 -254.807627) (xy 134.136423 -254.84806) (xy 134.159113 -254.892592)
			(xy 134.174557 -254.940124) (xy 134.182376 -254.989487) (xy 134.182866 -255.014476) (xy 134.488423 -255.014476)
			(xy 134.492518 -254.963748) (xy 134.504697 -254.914334) (xy 134.524645 -254.867514) (xy 134.551846 -254.8245)
			(xy 134.585594 -254.786406) (xy 134.625016 -254.754219) (xy 134.66909 -254.728773) (xy 134.716676 -254.710726)
			(xy 134.76654 -254.700546) (xy 134.817392 -254.698497) (xy 134.867913 -254.704631) (xy 134.916797 -254.718791)
			(xy 134.962776 -254.740608) (xy 135.00466 -254.769518) (xy 135.041364 -254.804773) (xy 135.071937 -254.845459)
			(xy 135.095588 -254.890522) (xy 135.111704 -254.938796) (xy 135.119868 -254.98903) (xy 135.12038 -255.014476)
			(xy 135.428477 -255.014476) (xy 135.432572 -254.963748) (xy 135.444751 -254.914334) (xy 135.464699 -254.867514)
			(xy 135.4919 -254.8245) (xy 135.525648 -254.786406) (xy 135.56507 -254.754219) (xy 135.609144 -254.728773)
			(xy 135.65673 -254.710726) (xy 135.706594 -254.700546) (xy 135.757446 -254.698497) (xy 135.807967 -254.704631)
			(xy 135.856851 -254.718791) (xy 135.90283 -254.740608) (xy 135.944714 -254.769518) (xy 135.981418 -254.804773)
			(xy 136.011991 -254.845459) (xy 136.035642 -254.890522) (xy 136.051758 -254.938796) (xy 136.059922 -254.98903)
			(xy 136.060434 -255.014476) (xy 136.059931 -255.039465) (xy 136.367248 -255.039465) (xy 136.367248 -254.989487)
			(xy 136.375067 -254.940124) (xy 136.390511 -254.892592) (xy 136.413201 -254.84806) (xy 136.442577 -254.807627)
			(xy 136.477917 -254.772287) (xy 136.51835 -254.742911) (xy 136.562882 -254.720221) (xy 136.610414 -254.704777)
			(xy 136.659777 -254.696958) (xy 136.709755 -254.696958) (xy 136.759118 -254.704777) (xy 136.80665 -254.720221)
			(xy 136.851182 -254.742911) (xy 136.891615 -254.772287) (xy 136.926955 -254.807627) (xy 136.956331 -254.84806)
			(xy 136.979021 -254.892592) (xy 136.994465 -254.940124) (xy 137.002284 -254.989487) (xy 137.002774 -255.014476)
			(xy 137.308585 -255.014476) (xy 137.31268 -254.963748) (xy 137.324859 -254.914334) (xy 137.344807 -254.867514)
			(xy 137.372008 -254.8245) (xy 137.405756 -254.786406) (xy 137.445178 -254.754219) (xy 137.489252 -254.728773)
			(xy 137.536838 -254.710726) (xy 137.586702 -254.700546) (xy 137.637554 -254.698497) (xy 137.688075 -254.704631)
			(xy 137.736959 -254.718791) (xy 137.782938 -254.740608) (xy 137.824822 -254.769518) (xy 137.861526 -254.804773)
			(xy 137.892099 -254.845459) (xy 137.91575 -254.890522) (xy 137.931866 -254.938796) (xy 137.94003 -254.98903)
			(xy 137.940542 -255.014476) (xy 137.940039 -255.039465) (xy 138.247356 -255.039465) (xy 138.247356 -254.989487)
			(xy 138.255175 -254.940124) (xy 138.270619 -254.892592) (xy 138.293309 -254.84806) (xy 138.322685 -254.807627)
			(xy 138.358025 -254.772287) (xy 138.398458 -254.742911) (xy 138.44299 -254.720221) (xy 138.490522 -254.704777)
			(xy 138.539885 -254.696958) (xy 138.589863 -254.696958) (xy 138.639226 -254.704777) (xy 138.686758 -254.720221)
			(xy 138.73129 -254.742911) (xy 138.771723 -254.772287) (xy 138.807063 -254.807627) (xy 138.836439 -254.84806)
			(xy 138.859129 -254.892592) (xy 138.874573 -254.940124) (xy 138.882392 -254.989487) (xy 138.882882 -255.014476)
			(xy 139.188439 -255.014476) (xy 139.192534 -254.963748) (xy 139.204713 -254.914334) (xy 139.224661 -254.867514)
			(xy 139.251862 -254.8245) (xy 139.28561 -254.786406) (xy 139.325032 -254.754219) (xy 139.369106 -254.728773)
			(xy 139.416692 -254.710726) (xy 139.466556 -254.700546) (xy 139.517408 -254.698497) (xy 139.567929 -254.704631)
			(xy 139.616813 -254.718791) (xy 139.662792 -254.740608) (xy 139.704676 -254.769518) (xy 139.74138 -254.804773)
			(xy 139.771953 -254.845459) (xy 139.795604 -254.890522) (xy 139.81172 -254.938796) (xy 139.819884 -254.98903)
			(xy 139.820396 -255.014476) (xy 139.819893 -255.039465) (xy 140.12721 -255.039465) (xy 140.12721 -254.989487)
			(xy 140.135029 -254.940124) (xy 140.150473 -254.892592) (xy 140.173163 -254.84806) (xy 140.202539 -254.807627)
			(xy 140.237879 -254.772287) (xy 140.278312 -254.742911) (xy 140.322844 -254.720221) (xy 140.370376 -254.704777)
			(xy 140.419739 -254.696958) (xy 140.469717 -254.696958) (xy 140.51908 -254.704777) (xy 140.566612 -254.720221)
			(xy 140.611144 -254.742911) (xy 140.651577 -254.772287) (xy 140.686917 -254.807627) (xy 140.716293 -254.84806)
			(xy 140.738983 -254.892592) (xy 140.754427 -254.940124) (xy 140.762246 -254.989487) (xy 140.762736 -255.014476)
			(xy 141.068547 -255.014476) (xy 141.072642 -254.963748) (xy 141.084821 -254.914334) (xy 141.104769 -254.867514)
			(xy 141.13197 -254.8245) (xy 141.165718 -254.786406) (xy 141.20514 -254.754219) (xy 141.249214 -254.728773)
			(xy 141.2968 -254.710726) (xy 141.346664 -254.700546) (xy 141.397516 -254.698497) (xy 141.448037 -254.704631)
			(xy 141.496921 -254.718791) (xy 141.5429 -254.740608) (xy 141.584784 -254.769518) (xy 141.621488 -254.804773)
			(xy 141.652061 -254.845459) (xy 141.675712 -254.890522) (xy 141.691828 -254.938796) (xy 141.699992 -254.98903)
			(xy 141.700504 -255.014476) (xy 142.008601 -255.014476) (xy 142.012696 -254.963748) (xy 142.024875 -254.914334)
			(xy 142.044823 -254.867514) (xy 142.072024 -254.8245) (xy 142.105772 -254.786406) (xy 142.145194 -254.754219)
			(xy 142.189268 -254.728773) (xy 142.236854 -254.710726) (xy 142.286718 -254.700546) (xy 142.33757 -254.698497)
			(xy 142.388091 -254.704631) (xy 142.436975 -254.718791) (xy 142.482954 -254.740608) (xy 142.524838 -254.769518)
			(xy 142.561542 -254.804773) (xy 142.592115 -254.845459) (xy 142.615766 -254.890522) (xy 142.631882 -254.938796)
			(xy 142.640046 -254.98903) (xy 142.640558 -255.014476) (xy 142.640055 -255.039465) (xy 142.947118 -255.039465)
			(xy 142.947118 -254.989487) (xy 142.954937 -254.940124) (xy 142.970381 -254.892592) (xy 142.993071 -254.84806)
			(xy 143.022447 -254.807627) (xy 143.057787 -254.772287) (xy 143.09822 -254.742911) (xy 143.142752 -254.720221)
			(xy 143.190284 -254.704777) (xy 143.239647 -254.696958) (xy 143.289625 -254.696958) (xy 143.338988 -254.704777)
			(xy 143.38652 -254.720221) (xy 143.431052 -254.742911) (xy 143.471485 -254.772287) (xy 143.506825 -254.807627)
			(xy 143.536201 -254.84806) (xy 143.558891 -254.892592) (xy 143.574335 -254.940124) (xy 143.582154 -254.989487)
			(xy 143.582644 -255.014476) (xy 143.582154 -255.039465) (xy 143.574335 -255.088828) (xy 143.558891 -255.13636)
			(xy 143.536201 -255.180892) (xy 143.506825 -255.221325) (xy 143.471485 -255.256665) (xy 143.431052 -255.286041)
			(xy 143.38652 -255.308731) (xy 143.338988 -255.324175) (xy 143.289625 -255.331994) (xy 143.239647 -255.331994)
			(xy 143.190284 -255.324175) (xy 143.142752 -255.308731) (xy 143.09822 -255.286041) (xy 143.057787 -255.256665)
			(xy 143.022447 -255.221325) (xy 142.993071 -255.180892) (xy 142.970381 -255.13636) (xy 142.954937 -255.088828)
			(xy 142.947118 -255.039465) (xy 142.640055 -255.039465) (xy 142.640046 -255.039922) (xy 142.631882 -255.090156)
			(xy 142.615766 -255.13843) (xy 142.592115 -255.183493) (xy 142.561542 -255.224179) (xy 142.524838 -255.259434)
			(xy 142.482954 -255.288344) (xy 142.436975 -255.310161) (xy 142.388091 -255.324321) (xy 142.33757 -255.330455)
			(xy 142.286718 -255.328406) (xy 142.236854 -255.318226) (xy 142.189268 -255.300179) (xy 142.145194 -255.274733)
			(xy 142.105772 -255.242546) (xy 142.072024 -255.204452) (xy 142.044823 -255.161438) (xy 142.024875 -255.114618)
			(xy 142.012696 -255.065204) (xy 142.008601 -255.014476) (xy 141.700504 -255.014476) (xy 141.699992 -255.039922)
			(xy 141.691828 -255.090156) (xy 141.675712 -255.13843) (xy 141.652061 -255.183493) (xy 141.621488 -255.224179)
			(xy 141.584784 -255.259434) (xy 141.5429 -255.288344) (xy 141.496921 -255.310161) (xy 141.448037 -255.324321)
			(xy 141.397516 -255.330455) (xy 141.346664 -255.328406) (xy 141.2968 -255.318226) (xy 141.249214 -255.300179)
			(xy 141.20514 -255.274733) (xy 141.165718 -255.242546) (xy 141.13197 -255.204452) (xy 141.104769 -255.161438)
			(xy 141.084821 -255.114618) (xy 141.072642 -255.065204) (xy 141.068547 -255.014476) (xy 140.762736 -255.014476)
			(xy 140.762246 -255.039465) (xy 140.754427 -255.088828) (xy 140.738983 -255.13636) (xy 140.716293 -255.180892)
			(xy 140.686917 -255.221325) (xy 140.651577 -255.256665) (xy 140.611144 -255.286041) (xy 140.566612 -255.308731)
			(xy 140.51908 -255.324175) (xy 140.469717 -255.331994) (xy 140.419739 -255.331994) (xy 140.370376 -255.324175)
			(xy 140.322844 -255.308731) (xy 140.278312 -255.286041) (xy 140.237879 -255.256665) (xy 140.202539 -255.221325)
			(xy 140.173163 -255.180892) (xy 140.150473 -255.13636) (xy 140.135029 -255.088828) (xy 140.12721 -255.039465)
			(xy 139.819893 -255.039465) (xy 139.819884 -255.039922) (xy 139.81172 -255.090156) (xy 139.795604 -255.13843)
			(xy 139.771953 -255.183493) (xy 139.74138 -255.224179) (xy 139.704676 -255.259434) (xy 139.662792 -255.288344)
			(xy 139.616813 -255.310161) (xy 139.567929 -255.324321) (xy 139.517408 -255.330455) (xy 139.466556 -255.328406)
			(xy 139.416692 -255.318226) (xy 139.369106 -255.300179) (xy 139.325032 -255.274733) (xy 139.28561 -255.242546)
			(xy 139.251862 -255.204452) (xy 139.224661 -255.161438) (xy 139.204713 -255.114618) (xy 139.192534 -255.065204)
			(xy 139.188439 -255.014476) (xy 138.882882 -255.014476) (xy 138.882392 -255.039465) (xy 138.874573 -255.088828)
			(xy 138.859129 -255.13636) (xy 138.836439 -255.180892) (xy 138.807063 -255.221325) (xy 138.771723 -255.256665)
			(xy 138.73129 -255.286041) (xy 138.686758 -255.308731) (xy 138.639226 -255.324175) (xy 138.589863 -255.331994)
			(xy 138.539885 -255.331994) (xy 138.490522 -255.324175) (xy 138.44299 -255.308731) (xy 138.398458 -255.286041)
			(xy 138.358025 -255.256665) (xy 138.322685 -255.221325) (xy 138.293309 -255.180892) (xy 138.270619 -255.13636)
			(xy 138.255175 -255.088828) (xy 138.247356 -255.039465) (xy 137.940039 -255.039465) (xy 137.94003 -255.039922)
			(xy 137.931866 -255.090156) (xy 137.91575 -255.13843) (xy 137.892099 -255.183493) (xy 137.861526 -255.224179)
			(xy 137.824822 -255.259434) (xy 137.782938 -255.288344) (xy 137.736959 -255.310161) (xy 137.688075 -255.324321)
			(xy 137.637554 -255.330455) (xy 137.586702 -255.328406) (xy 137.536838 -255.318226) (xy 137.489252 -255.300179)
			(xy 137.445178 -255.274733) (xy 137.405756 -255.242546) (xy 137.372008 -255.204452) (xy 137.344807 -255.161438)
			(xy 137.324859 -255.114618) (xy 137.31268 -255.065204) (xy 137.308585 -255.014476) (xy 137.002774 -255.014476)
			(xy 137.002284 -255.039465) (xy 136.994465 -255.088828) (xy 136.979021 -255.13636) (xy 136.956331 -255.180892)
			(xy 136.926955 -255.221325) (xy 136.891615 -255.256665) (xy 136.851182 -255.286041) (xy 136.80665 -255.308731)
			(xy 136.759118 -255.324175) (xy 136.709755 -255.331994) (xy 136.659777 -255.331994) (xy 136.610414 -255.324175)
			(xy 136.562882 -255.308731) (xy 136.51835 -255.286041) (xy 136.477917 -255.256665) (xy 136.442577 -255.221325)
			(xy 136.413201 -255.180892) (xy 136.390511 -255.13636) (xy 136.375067 -255.088828) (xy 136.367248 -255.039465)
			(xy 136.059931 -255.039465) (xy 136.059922 -255.039922) (xy 136.051758 -255.090156) (xy 136.035642 -255.13843)
			(xy 136.011991 -255.183493) (xy 135.981418 -255.224179) (xy 135.944714 -255.259434) (xy 135.90283 -255.288344)
			(xy 135.856851 -255.310161) (xy 135.807967 -255.324321) (xy 135.757446 -255.330455) (xy 135.706594 -255.328406)
			(xy 135.65673 -255.318226) (xy 135.609144 -255.300179) (xy 135.56507 -255.274733) (xy 135.525648 -255.242546)
			(xy 135.4919 -255.204452) (xy 135.464699 -255.161438) (xy 135.444751 -255.114618) (xy 135.432572 -255.065204)
			(xy 135.428477 -255.014476) (xy 135.12038 -255.014476) (xy 135.119868 -255.039922) (xy 135.111704 -255.090156)
			(xy 135.095588 -255.13843) (xy 135.071937 -255.183493) (xy 135.041364 -255.224179) (xy 135.00466 -255.259434)
			(xy 134.962776 -255.288344) (xy 134.916797 -255.310161) (xy 134.867913 -255.324321) (xy 134.817392 -255.330455)
			(xy 134.76654 -255.328406) (xy 134.716676 -255.318226) (xy 134.66909 -255.300179) (xy 134.625016 -255.274733)
			(xy 134.585594 -255.242546) (xy 134.551846 -255.204452) (xy 134.524645 -255.161438) (xy 134.504697 -255.114618)
			(xy 134.492518 -255.065204) (xy 134.488423 -255.014476) (xy 134.182866 -255.014476) (xy 134.182376 -255.039465)
			(xy 134.174557 -255.088828) (xy 134.159113 -255.13636) (xy 134.136423 -255.180892) (xy 134.107047 -255.221325)
			(xy 134.071707 -255.256665) (xy 134.031274 -255.286041) (xy 133.986742 -255.308731) (xy 133.93921 -255.324175)
			(xy 133.889847 -255.331994) (xy 133.839869 -255.331994) (xy 133.790506 -255.324175) (xy 133.742974 -255.308731)
			(xy 133.698442 -255.286041) (xy 133.658009 -255.256665) (xy 133.622669 -255.221325) (xy 133.593293 -255.180892)
			(xy 133.570603 -255.13636) (xy 133.555159 -255.088828) (xy 133.54734 -255.039465) (xy 133.240023 -255.039465)
			(xy 133.240014 -255.039922) (xy 133.23185 -255.090156) (xy 133.215734 -255.13843) (xy 133.192083 -255.183493)
			(xy 133.16151 -255.224179) (xy 133.124806 -255.259434) (xy 133.082922 -255.288344) (xy 133.036943 -255.310161)
			(xy 132.988059 -255.324321) (xy 132.937538 -255.330455) (xy 132.886686 -255.328406) (xy 132.836822 -255.318226)
			(xy 132.789236 -255.300179) (xy 132.745162 -255.274733) (xy 132.70574 -255.242546) (xy 132.671992 -255.204452)
			(xy 132.644791 -255.161438) (xy 132.624843 -255.114618) (xy 132.612664 -255.065204) (xy 132.608569 -255.014476)
			(xy 132.302758 -255.014476) (xy 132.302268 -255.039465) (xy 132.294449 -255.088828) (xy 132.279005 -255.13636)
			(xy 132.256315 -255.180892) (xy 132.226939 -255.221325) (xy 132.191599 -255.256665) (xy 132.151166 -255.286041)
			(xy 132.106634 -255.308731) (xy 132.059102 -255.324175) (xy 132.009739 -255.331994) (xy 131.959761 -255.331994)
			(xy 131.910398 -255.324175) (xy 131.862866 -255.308731) (xy 131.818334 -255.286041) (xy 131.777901 -255.256665)
			(xy 131.742561 -255.221325) (xy 131.713185 -255.180892) (xy 131.690495 -255.13636) (xy 131.675051 -255.088828)
			(xy 131.667232 -255.039465) (xy 131.359915 -255.039465) (xy 131.359906 -255.039922) (xy 131.351742 -255.090156)
			(xy 131.335626 -255.13843) (xy 131.311975 -255.183493) (xy 131.281402 -255.224179) (xy 131.244698 -255.259434)
			(xy 131.202814 -255.288344) (xy 131.156835 -255.310161) (xy 131.107951 -255.324321) (xy 131.05743 -255.330455)
			(xy 131.006578 -255.328406) (xy 130.956714 -255.318226) (xy 130.909128 -255.300179) (xy 130.865054 -255.274733)
			(xy 130.825632 -255.242546) (xy 130.791884 -255.204452) (xy 130.764683 -255.161438) (xy 130.744735 -255.114618)
			(xy 130.732556 -255.065204) (xy 130.728461 -255.014476) (xy 130.42265 -255.014476) (xy 130.42216 -255.039465)
			(xy 130.414341 -255.088828) (xy 130.398897 -255.13636) (xy 130.376207 -255.180892) (xy 130.346831 -255.221325)
			(xy 130.311491 -255.256665) (xy 130.271058 -255.286041) (xy 130.226526 -255.308731) (xy 130.178994 -255.324175)
			(xy 130.129631 -255.331994) (xy 130.079653 -255.331994) (xy 130.03029 -255.324175) (xy 129.982758 -255.308731)
			(xy 129.938226 -255.286041) (xy 129.897793 -255.256665) (xy 129.862453 -255.221325) (xy 129.833077 -255.180892)
			(xy 129.810387 -255.13636) (xy 129.794943 -255.088828) (xy 129.787124 -255.039465) (xy 129.480061 -255.039465)
			(xy 129.480052 -255.039922) (xy 129.471888 -255.090156) (xy 129.455772 -255.13843) (xy 129.432121 -255.183493)
			(xy 129.401548 -255.224179) (xy 129.364844 -255.259434) (xy 129.32296 -255.288344) (xy 129.276981 -255.310161)
			(xy 129.228097 -255.324321) (xy 129.177576 -255.330455) (xy 129.126724 -255.328406) (xy 129.07686 -255.318226)
			(xy 129.029274 -255.300179) (xy 128.9852 -255.274733) (xy 128.945778 -255.242546) (xy 128.91203 -255.204452)
			(xy 128.884829 -255.161438) (xy 128.864881 -255.114618) (xy 128.852702 -255.065204) (xy 128.848607 -255.014476)
			(xy 128.54051 -255.014476) (xy 128.539998 -255.039922) (xy 128.531834 -255.090156) (xy 128.515718 -255.13843)
			(xy 128.492067 -255.183493) (xy 128.461494 -255.224179) (xy 128.42479 -255.259434) (xy 128.382906 -255.288344)
			(xy 128.336927 -255.310161) (xy 128.288043 -255.324321) (xy 128.237522 -255.330455) (xy 128.18667 -255.328406)
			(xy 128.136806 -255.318226) (xy 128.08922 -255.300179) (xy 128.045146 -255.274733) (xy 128.005724 -255.242546)
			(xy 127.971976 -255.204452) (xy 127.944775 -255.161438) (xy 127.924827 -255.114618) (xy 127.912648 -255.065204)
			(xy 127.908553 -255.014476) (xy 126.662688 -255.014476) (xy 126.662198 -255.039465) (xy 126.654379 -255.088828)
			(xy 126.638935 -255.13636) (xy 126.616245 -255.180892) (xy 126.586869 -255.221325) (xy 126.551529 -255.256665)
			(xy 126.511096 -255.286041) (xy 126.466564 -255.308731) (xy 126.419032 -255.324175) (xy 126.369669 -255.331994)
			(xy 126.319691 -255.331994) (xy 126.270328 -255.324175) (xy 126.222796 -255.308731) (xy 126.178264 -255.286041)
			(xy 126.137831 -255.256665) (xy 126.102491 -255.221325) (xy 126.073115 -255.180892) (xy 126.050425 -255.13636)
			(xy 126.034981 -255.088828) (xy 126.027162 -255.039465) (xy 124.782344 -255.039465) (xy 124.774525 -255.088828)
			(xy 124.759081 -255.13636) (xy 124.736391 -255.180892) (xy 124.707015 -255.221325) (xy 124.671675 -255.256665)
			(xy 124.631242 -255.286041) (xy 124.58671 -255.308731) (xy 124.539178 -255.324175) (xy 124.489815 -255.331994)
			(xy 124.439837 -255.331994) (xy 124.390474 -255.324175) (xy 124.342942 -255.308731) (xy 124.29841 -255.286041)
			(xy 124.257977 -255.256665) (xy 124.222637 -255.221325) (xy 124.193261 -255.180892) (xy 124.170571 -255.13636)
			(xy 124.155127 -255.088828) (xy 124.147308 -255.039465) (xy 122.902236 -255.039465) (xy 122.894417 -255.088828)
			(xy 122.878973 -255.13636) (xy 122.856283 -255.180892) (xy 122.826907 -255.221325) (xy 122.791567 -255.256665)
			(xy 122.751134 -255.286041) (xy 122.706602 -255.308731) (xy 122.65907 -255.324175) (xy 122.609707 -255.331994)
			(xy 122.559729 -255.331994) (xy 122.510366 -255.324175) (xy 122.462834 -255.308731) (xy 122.418302 -255.286041)
			(xy 122.377869 -255.256665) (xy 122.342529 -255.221325) (xy 122.313153 -255.180892) (xy 122.290463 -255.13636)
			(xy 122.275019 -255.088828) (xy 122.2672 -255.039465) (xy 102.365395 -255.039465) (xy 102.303834 -255.146048)
			(xy 102.29312 -255.163629) (xy 102.266141 -255.19472) (xy 102.233704 -255.220064) (xy 102.197012 -255.238722)
			(xy 102.157424 -255.250002) (xy 102.136956 -255.25222) (xy 102.129497 -255.253103) (xy 102.115548 -255.258655)
			(xy 102.109524 -255.263142) (xy 102.088268 -255.279345) (xy 102.041488 -255.305186) (xy 101.991054 -255.322865)
			(xy 101.938378 -255.331885) (xy 101.911658 -255.332484) (xy 101.91115 -255.332484) (xy 101.886159 -255.331997)
			(xy 101.836791 -255.324185) (xy 101.789254 -255.308745) (xy 101.744718 -255.286057) (xy 101.70428 -255.256681)
			(xy 101.668936 -255.22134) (xy 101.639556 -255.180904) (xy 101.616865 -255.13637) (xy 101.601421 -255.088834)
			(xy 101.593605 -255.039467) (xy 101.593142 -255.014476) (xy 100.740464 -255.014476) (xy 100.740464 -255.589532)
			(xy 100.740718 -255.594612) (xy 100.743004 -255.60528) (xy 100.750878 -255.627378) (xy 100.75545 -255.633728)
			(xy 100.755704 -255.633982) (xy 100.770594 -255.654745) (xy 100.794256 -255.700026) (xy 100.810378 -255.748506)
			(xy 100.818545 -255.79894) (xy 100.818546 -255.824482) (xy 101.122988 -255.824482) (xy 101.123714 -255.793103)
			(xy 101.135991 -255.731559) (xy 101.147372 -255.702308) (xy 101.149009 -255.69817) (xy 101.150918 -255.689479)
			(xy 101.151182 -255.685036) (xy 101.152586 -255.664699) (xy 101.162071 -255.62506) (xy 101.178893 -255.587935)
			(xy 101.202442 -255.554669) (xy 101.231866 -255.526465) (xy 101.2661 -255.504346) (xy 101.303904 -255.489112)
			(xy 101.34391 -255.481314) (xy 101.364288 -255.48082) (xy 101.619304 -255.48082) (xy 101.619304 -255.489964)
			(xy 101.619749 -255.499983) (xy 101.627408 -255.5185) (xy 101.641573 -255.532674) (xy 101.660085 -255.540344)
			(xy 101.670104 -255.540764) (xy 101.833172 -255.540764) (xy 101.843173 -255.54131) (xy 101.861658 -255.548954)
			(xy 101.875811 -255.563088) (xy 101.883477 -255.581563) (xy 101.883972 -255.591564) (xy 101.883972 -256.099564)
			(xy 103.8098 -256.099564) (xy 103.8098 -255.591564) (xy 103.810259 -255.581554) (xy 103.81793 -255.563061)
			(xy 103.832092 -255.54891) (xy 103.85059 -255.541251) (xy 103.8606 -255.540764) (xy 104.074468 -255.540764)
			(xy 104.074468 -255.53162) (xy 104.075004 -255.521618) (xy 104.082651 -255.503132) (xy 104.096789 -255.48898)
			(xy 104.115266 -255.481314) (xy 104.125268 -255.48082) (xy 104.329484 -255.48082) (xy 104.349045 -255.481209)
			(xy 104.387512 -255.488339) (xy 104.424034 -255.502362) (xy 104.457388 -255.522808) (xy 104.46576 -255.53035)
			(xy 105.134664 -255.53035) (xy 105.135195 -255.502367) (xy 105.143956 -255.447091) (xy 105.161256 -255.393865)
			(xy 105.186668 -255.344001) (xy 105.219566 -255.298725) (xy 105.259142 -255.259152) (xy 105.30442 -255.226256)
			(xy 105.354286 -255.200848) (xy 105.407512 -255.183551) (xy 105.462789 -255.174793) (xy 105.490772 -255.174242)
			(xy 105.516139 -255.174672) (xy 105.566367 -255.181807) (xy 105.590848 -255.188466) (xy 105.597706 -255.190752)
			(xy 105.65511 -255.190752) (xy 105.684828 -255.22047) (xy 105.684828 -255.2319) (xy 105.69829 -255.241044)
			(xy 105.704882 -255.245524) (xy 105.720041 -255.250432) (xy 105.728008 -255.250696) (xy 106.167936 -255.250696)
			(xy 106.175892 -255.25038) (xy 106.191025 -255.245455) (xy 106.197654 -255.241044) (xy 106.206784 -255.234623)
			(xy 106.225721 -255.222803) (xy 106.2355 -255.217422) (xy 106.2355 -255.190752) (xy 106.298238 -255.190752)
			(xy 106.305096 -255.188466) (xy 106.329574 -255.181793) (xy 106.379804 -255.174654) (xy 106.405172 -255.174242)
			(xy 106.432669 -255.17475) (xy 106.487017 -255.183162) (xy 106.513376 -255.191006) (xy 106.521504 -255.192784)
			(xy 106.540247 -255.195979) (xy 106.576271 -255.208125) (xy 106.609571 -255.226468) (xy 106.63909 -255.250424)
			(xy 106.663894 -255.279235) (xy 106.673904 -255.2954) (xy 106.67873 -255.302258) (xy 106.694226 -255.321576)
			(xy 106.720351 -255.363645) (xy 106.740401 -255.408926) (xy 106.753988 -255.456546) (xy 106.760851 -255.505589)
			(xy 106.76128 -255.53035) (xy 106.761276 -255.530604) (xy 117.084602 -255.530604) (xy 117.084602 -255.53035)
			(xy 117.085013 -255.505341) (xy 117.092023 -255.455816) (xy 117.105898 -255.40776) (xy 117.126364 -255.36212)
			(xy 117.153019 -255.319796) (xy 117.185338 -255.28162) (xy 117.203728 -255.264666) (xy 117.207538 -255.260856)
			(xy 117.222207 -255.245388) (xy 117.256507 -255.220085) (xy 117.295143 -255.202085) (xy 117.315742 -255.196594)
			(xy 117.320822 -255.19507) (xy 117.349835 -255.185345) (xy 117.410117 -255.174874) (xy 117.44071 -255.174242)
			(xy 117.466077 -255.174664) (xy 117.516306 -255.181804) (xy 117.540786 -255.188466) (xy 117.547644 -255.190752)
			(xy 117.620288 -255.190752) (xy 117.620288 -255.19507) (xy 117.620932 -255.207483) (xy 117.632497 -255.229451)
			(xy 117.642386 -255.23698) (xy 117.648228 -255.241044) (xy 117.654835 -255.2455) (xy 117.669982 -255.250423)
			(xy 117.677946 -255.250696) (xy 117.834664 -255.250696) (xy 117.844682 -255.251149) (xy 117.863198 -255.258806)
			(xy 117.877371 -255.272969) (xy 117.885043 -255.291478) (xy 117.885464 -255.301496) (xy 117.885464 -255.808988)
			(xy 117.88507 -255.819013) (xy 117.882805 -255.824482) (xy 120.856756 -255.824482) (xy 120.857137 -255.800362)
			(xy 120.864413 -255.752675) (xy 120.87881 -255.706635) (xy 120.899997 -255.663298) (xy 120.927489 -255.623659)
			(xy 120.960654 -255.58863) (xy 120.998731 -255.559012) (xy 121.01957 -255.54686) (xy 121.02973 -255.539494)
			(xy 121.044735 -255.525922) (xy 121.078797 -255.504098) (xy 121.116352 -255.489061) (xy 121.156063 -255.481348)
			(xy 121.176288 -255.48082) (xy 121.431304 -255.48082) (xy 121.431304 -255.489964) (xy 121.431749 -255.499983)
			(xy 121.439408 -255.5185) (xy 121.453573 -255.532674) (xy 121.472085 -255.540344) (xy 121.482104 -255.540764)
			(xy 121.645172 -255.540764) (xy 121.655173 -255.54131) (xy 121.673658 -255.548954) (xy 121.687811 -255.563088)
			(xy 121.695477 -255.581563) (xy 121.695972 -255.591564) (xy 121.695972 -255.824482) (xy 122.73661 -255.824482)
			(xy 122.737005 -255.800024) (xy 122.744485 -255.751685) (xy 122.759279 -255.705061) (xy 122.781041 -255.661253)
			(xy 122.809255 -255.621295) (xy 122.843256 -255.586129) (xy 122.882242 -255.556586) (xy 122.925292 -255.533363)
			(xy 122.948192 -255.524762) (xy 122.96013 -255.518666) (xy 122.978115 -255.506877) (xy 123.017669 -255.490015)
			(xy 123.05979 -255.481379) (xy 123.081288 -255.48082) (xy 123.336304 -255.48082) (xy 123.336304 -255.489964)
			(xy 123.336749 -255.499983) (xy 123.344408 -255.5185) (xy 123.358573 -255.532674) (xy 123.377085 -255.540344)
			(xy 123.387104 -255.540764) (xy 123.550172 -255.540764) (xy 123.560173 -255.54131) (xy 123.578658 -255.548954)
			(xy 123.592811 -255.563088) (xy 123.600477 -255.581563) (xy 123.600972 -255.591564) (xy 123.600972 -255.824482)
			(xy 124.616718 -255.824482) (xy 124.617063 -255.803065) (xy 124.62283 -255.76062) (xy 124.634257 -255.719337)
			(xy 124.642372 -255.699514) (xy 124.644052 -255.695379) (xy 124.646098 -255.686692) (xy 124.646436 -255.682242)
			(xy 124.648071 -255.662101) (xy 124.657894 -255.622913) (xy 124.674909 -255.586269) (xy 124.698509 -255.553477)
			(xy 124.727853 -255.525706) (xy 124.761894 -255.503946) (xy 124.799418 -255.488972) (xy 124.839088 -255.48132)
			(xy 124.859288 -255.48082) (xy 125.114304 -255.48082) (xy 125.114304 -255.489964) (xy 125.114749 -255.499983)
			(xy 125.122408 -255.5185) (xy 125.136573 -255.532674) (xy 125.155085 -255.540344) (xy 125.165104 -255.540764)
			(xy 125.328172 -255.540764) (xy 125.338173 -255.54131) (xy 125.356658 -255.548954) (xy 125.370811 -255.563088)
			(xy 125.378477 -255.581563) (xy 125.378972 -255.591564) (xy 125.378972 -255.849471) (xy 126.497316 -255.849471)
			(xy 126.497316 -255.799493) (xy 126.505135 -255.75013) (xy 126.520579 -255.702598) (xy 126.543269 -255.658066)
			(xy 126.572645 -255.617633) (xy 126.607985 -255.582293) (xy 126.648418 -255.552917) (xy 126.69295 -255.530227)
			(xy 126.740482 -255.514783) (xy 126.789845 -255.506964) (xy 126.839823 -255.506964) (xy 126.889186 -255.514783)
			(xy 126.936718 -255.530227) (xy 126.98125 -255.552917) (xy 127.021683 -255.582293) (xy 127.057023 -255.617633)
			(xy 127.086399 -255.658066) (xy 127.109089 -255.702598) (xy 127.124533 -255.75013) (xy 127.132352 -255.799493)
			(xy 127.132842 -255.824482) (xy 127.438399 -255.824482) (xy 127.442494 -255.773754) (xy 127.454673 -255.72434)
			(xy 127.474621 -255.67752) (xy 127.501822 -255.634506) (xy 127.53557 -255.596412) (xy 127.574992 -255.564225)
			(xy 127.619066 -255.538779) (xy 127.666652 -255.520732) (xy 127.716516 -255.510552) (xy 127.767368 -255.508503)
			(xy 127.817889 -255.514637) (xy 127.866773 -255.528797) (xy 127.912752 -255.550614) (xy 127.954636 -255.579524)
			(xy 127.99134 -255.614779) (xy 128.021913 -255.655465) (xy 128.045564 -255.700528) (xy 128.06168 -255.748802)
			(xy 128.069844 -255.799036) (xy 128.070356 -255.824482) (xy 128.069853 -255.849471) (xy 128.37717 -255.849471)
			(xy 128.37717 -255.799493) (xy 128.384989 -255.75013) (xy 128.400433 -255.702598) (xy 128.423123 -255.658066)
			(xy 128.452499 -255.617633) (xy 128.487839 -255.582293) (xy 128.528272 -255.552917) (xy 128.572804 -255.530227)
			(xy 128.620336 -255.514783) (xy 128.669699 -255.506964) (xy 128.719677 -255.506964) (xy 128.76904 -255.514783)
			(xy 128.816572 -255.530227) (xy 128.861104 -255.552917) (xy 128.901537 -255.582293) (xy 128.936877 -255.617633)
			(xy 128.966253 -255.658066) (xy 128.988943 -255.702598) (xy 129.004387 -255.75013) (xy 129.012206 -255.799493)
			(xy 129.012696 -255.824482) (xy 129.318507 -255.824482) (xy 129.322602 -255.773754) (xy 129.334781 -255.72434)
			(xy 129.354729 -255.67752) (xy 129.38193 -255.634506) (xy 129.415678 -255.596412) (xy 129.4551 -255.564225)
			(xy 129.499174 -255.538779) (xy 129.54676 -255.520732) (xy 129.596624 -255.510552) (xy 129.647476 -255.508503)
			(xy 129.697997 -255.514637) (xy 129.746881 -255.528797) (xy 129.79286 -255.550614) (xy 129.834744 -255.579524)
			(xy 129.871448 -255.614779) (xy 129.902021 -255.655465) (xy 129.925672 -255.700528) (xy 129.941788 -255.748802)
			(xy 129.949952 -255.799036) (xy 129.950464 -255.824482) (xy 129.949961 -255.849471) (xy 130.257278 -255.849471)
			(xy 130.257278 -255.799493) (xy 130.265097 -255.75013) (xy 130.280541 -255.702598) (xy 130.303231 -255.658066)
			(xy 130.332607 -255.617633) (xy 130.367947 -255.582293) (xy 130.40838 -255.552917) (xy 130.452912 -255.530227)
			(xy 130.500444 -255.514783) (xy 130.549807 -255.506964) (xy 130.599785 -255.506964) (xy 130.649148 -255.514783)
			(xy 130.69668 -255.530227) (xy 130.741212 -255.552917) (xy 130.781645 -255.582293) (xy 130.816985 -255.617633)
			(xy 130.846361 -255.658066) (xy 130.869051 -255.702598) (xy 130.884495 -255.75013) (xy 130.892314 -255.799493)
			(xy 130.892804 -255.824482) (xy 131.198615 -255.824482) (xy 131.20271 -255.773754) (xy 131.214889 -255.72434)
			(xy 131.234837 -255.67752) (xy 131.262038 -255.634506) (xy 131.295786 -255.596412) (xy 131.335208 -255.564225)
			(xy 131.379282 -255.538779) (xy 131.426868 -255.520732) (xy 131.476732 -255.510552) (xy 131.527584 -255.508503)
			(xy 131.578105 -255.514637) (xy 131.626989 -255.528797) (xy 131.672968 -255.550614) (xy 131.714852 -255.579524)
			(xy 131.751556 -255.614779) (xy 131.782129 -255.655465) (xy 131.80578 -255.700528) (xy 131.821896 -255.748802)
			(xy 131.83006 -255.799036) (xy 131.830572 -255.824482) (xy 132.138415 -255.824482) (xy 132.14251 -255.773754)
			(xy 132.154689 -255.72434) (xy 132.174637 -255.67752) (xy 132.201838 -255.634506) (xy 132.235586 -255.596412)
			(xy 132.275008 -255.564225) (xy 132.319082 -255.538779) (xy 132.366668 -255.520732) (xy 132.416532 -255.510552)
			(xy 132.467384 -255.508503) (xy 132.517905 -255.514637) (xy 132.566789 -255.528797) (xy 132.612768 -255.550614)
			(xy 132.654652 -255.579524) (xy 132.691356 -255.614779) (xy 132.721929 -255.655465) (xy 132.74558 -255.700528)
			(xy 132.761696 -255.748802) (xy 132.76986 -255.799036) (xy 132.770372 -255.824482) (xy 132.769869 -255.849471)
			(xy 133.077186 -255.849471) (xy 133.077186 -255.799493) (xy 133.085005 -255.75013) (xy 133.100449 -255.702598)
			(xy 133.123139 -255.658066) (xy 133.152515 -255.617633) (xy 133.187855 -255.582293) (xy 133.228288 -255.552917)
			(xy 133.27282 -255.530227) (xy 133.320352 -255.514783) (xy 133.369715 -255.506964) (xy 133.419693 -255.506964)
			(xy 133.469056 -255.514783) (xy 133.516588 -255.530227) (xy 133.56112 -255.552917) (xy 133.601553 -255.582293)
			(xy 133.636893 -255.617633) (xy 133.666269 -255.658066) (xy 133.688959 -255.702598) (xy 133.704403 -255.75013)
			(xy 133.712222 -255.799493) (xy 133.712712 -255.824482) (xy 134.018523 -255.824482) (xy 134.022618 -255.773754)
			(xy 134.034797 -255.72434) (xy 134.054745 -255.67752) (xy 134.081946 -255.634506) (xy 134.115694 -255.596412)
			(xy 134.155116 -255.564225) (xy 134.19919 -255.538779) (xy 134.246776 -255.520732) (xy 134.29664 -255.510552)
			(xy 134.347492 -255.508503) (xy 134.398013 -255.514637) (xy 134.446897 -255.528797) (xy 134.492876 -255.550614)
			(xy 134.53476 -255.579524) (xy 134.571464 -255.614779) (xy 134.602037 -255.655465) (xy 134.625688 -255.700528)
			(xy 134.641804 -255.748802) (xy 134.649968 -255.799036) (xy 134.65048 -255.824482) (xy 134.649977 -255.849471)
			(xy 134.957294 -255.849471) (xy 134.957294 -255.799493) (xy 134.965113 -255.75013) (xy 134.980557 -255.702598)
			(xy 135.003247 -255.658066) (xy 135.032623 -255.617633) (xy 135.067963 -255.582293) (xy 135.108396 -255.552917)
			(xy 135.152928 -255.530227) (xy 135.20046 -255.514783) (xy 135.249823 -255.506964) (xy 135.299801 -255.506964)
			(xy 135.349164 -255.514783) (xy 135.396696 -255.530227) (xy 135.441228 -255.552917) (xy 135.481661 -255.582293)
			(xy 135.517001 -255.617633) (xy 135.546377 -255.658066) (xy 135.569067 -255.702598) (xy 135.584511 -255.75013)
			(xy 135.59233 -255.799493) (xy 135.59282 -255.824482) (xy 135.898631 -255.824482) (xy 135.902726 -255.773754)
			(xy 135.914905 -255.72434) (xy 135.934853 -255.67752) (xy 135.962054 -255.634506) (xy 135.995802 -255.596412)
			(xy 136.035224 -255.564225) (xy 136.079298 -255.538779) (xy 136.126884 -255.520732) (xy 136.176748 -255.510552)
			(xy 136.2276 -255.508503) (xy 136.278121 -255.514637) (xy 136.327005 -255.528797) (xy 136.372984 -255.550614)
			(xy 136.414868 -255.579524) (xy 136.451572 -255.614779) (xy 136.482145 -255.655465) (xy 136.505796 -255.700528)
			(xy 136.521912 -255.748802) (xy 136.530076 -255.799036) (xy 136.530588 -255.824482) (xy 136.53008 -255.849725)
			(xy 136.836894 -255.849725) (xy 136.836894 -255.799747) (xy 136.844713 -255.750384) (xy 136.860157 -255.702852)
			(xy 136.882847 -255.65832) (xy 136.912223 -255.617887) (xy 136.947563 -255.582547) (xy 136.987996 -255.553171)
			(xy 137.032528 -255.530481) (xy 137.08006 -255.515037) (xy 137.129423 -255.507218) (xy 137.179401 -255.507218)
			(xy 137.228764 -255.515037) (xy 137.276296 -255.530481) (xy 137.320828 -255.553171) (xy 137.361261 -255.582547)
			(xy 137.396601 -255.617887) (xy 137.425977 -255.65832) (xy 137.448667 -255.702852) (xy 137.464111 -255.750384)
			(xy 137.47193 -255.799747) (xy 137.472415 -255.824482) (xy 137.778485 -255.824482) (xy 137.78258 -255.773754)
			(xy 137.794759 -255.72434) (xy 137.814707 -255.67752) (xy 137.841908 -255.634506) (xy 137.875656 -255.596412)
			(xy 137.915078 -255.564225) (xy 137.959152 -255.538779) (xy 138.006738 -255.520732) (xy 138.056602 -255.510552)
			(xy 138.107454 -255.508503) (xy 138.157975 -255.514637) (xy 138.206859 -255.528797) (xy 138.252838 -255.550614)
			(xy 138.294722 -255.579524) (xy 138.331426 -255.614779) (xy 138.361999 -255.655465) (xy 138.38565 -255.700528)
			(xy 138.401766 -255.748802) (xy 138.40993 -255.799036) (xy 138.410442 -255.824482) (xy 138.718539 -255.824482)
			(xy 138.722634 -255.773754) (xy 138.734813 -255.72434) (xy 138.754761 -255.67752) (xy 138.781962 -255.634506)
			(xy 138.81571 -255.596412) (xy 138.855132 -255.564225) (xy 138.899206 -255.538779) (xy 138.946792 -255.520732)
			(xy 138.996656 -255.510552) (xy 139.047508 -255.508503) (xy 139.098029 -255.514637) (xy 139.146913 -255.528797)
			(xy 139.192892 -255.550614) (xy 139.234776 -255.579524) (xy 139.27148 -255.614779) (xy 139.302053 -255.655465)
			(xy 139.325704 -255.700528) (xy 139.34182 -255.748802) (xy 139.349984 -255.799036) (xy 139.350496 -255.824482)
			(xy 139.349993 -255.849471) (xy 139.65731 -255.849471) (xy 139.65731 -255.799493) (xy 139.665129 -255.75013)
			(xy 139.680573 -255.702598) (xy 139.703263 -255.658066) (xy 139.732639 -255.617633) (xy 139.767979 -255.582293)
			(xy 139.808412 -255.552917) (xy 139.852944 -255.530227) (xy 139.900476 -255.514783) (xy 139.949839 -255.506964)
			(xy 139.999817 -255.506964) (xy 140.04918 -255.514783) (xy 140.096712 -255.530227) (xy 140.141244 -255.552917)
			(xy 140.181677 -255.582293) (xy 140.217017 -255.617633) (xy 140.246393 -255.658066) (xy 140.269083 -255.702598)
			(xy 140.284527 -255.75013) (xy 140.292346 -255.799493) (xy 140.292836 -255.824482) (xy 140.598647 -255.824482)
			(xy 140.602742 -255.773754) (xy 140.614921 -255.72434) (xy 140.634869 -255.67752) (xy 140.66207 -255.634506)
			(xy 140.695818 -255.596412) (xy 140.73524 -255.564225) (xy 140.779314 -255.538779) (xy 140.8269 -255.520732)
			(xy 140.876764 -255.510552) (xy 140.927616 -255.508503) (xy 140.978137 -255.514637) (xy 141.027021 -255.528797)
			(xy 141.073 -255.550614) (xy 141.114884 -255.579524) (xy 141.151588 -255.614779) (xy 141.182161 -255.655465)
			(xy 141.205812 -255.700528) (xy 141.221928 -255.748802) (xy 141.230092 -255.799036) (xy 141.230604 -255.824482)
			(xy 141.230101 -255.849471) (xy 141.537164 -255.849471) (xy 141.537164 -255.799493) (xy 141.544983 -255.75013)
			(xy 141.560427 -255.702598) (xy 141.583117 -255.658066) (xy 141.612493 -255.617633) (xy 141.647833 -255.582293)
			(xy 141.688266 -255.552917) (xy 141.732798 -255.530227) (xy 141.78033 -255.514783) (xy 141.829693 -255.506964)
			(xy 141.879671 -255.506964) (xy 141.929034 -255.514783) (xy 141.976566 -255.530227) (xy 142.021098 -255.552917)
			(xy 142.061531 -255.582293) (xy 142.096871 -255.617633) (xy 142.126247 -255.658066) (xy 142.148937 -255.702598)
			(xy 142.164381 -255.75013) (xy 142.1722 -255.799493) (xy 142.17269 -255.824482) (xy 142.478501 -255.824482)
			(xy 142.482596 -255.773754) (xy 142.494775 -255.72434) (xy 142.514723 -255.67752) (xy 142.541924 -255.634506)
			(xy 142.575672 -255.596412) (xy 142.615094 -255.564225) (xy 142.659168 -255.538779) (xy 142.706754 -255.520732)
			(xy 142.756618 -255.510552) (xy 142.80747 -255.508503) (xy 142.857991 -255.514637) (xy 142.906875 -255.528797)
			(xy 142.952854 -255.550614) (xy 142.994738 -255.579524) (xy 143.031442 -255.614779) (xy 143.062015 -255.655465)
			(xy 143.085666 -255.700528) (xy 143.101782 -255.748802) (xy 143.109946 -255.799036) (xy 143.110458 -255.824482)
			(xy 143.109955 -255.849471) (xy 143.417272 -255.849471) (xy 143.417272 -255.799493) (xy 143.425091 -255.75013)
			(xy 143.440535 -255.702598) (xy 143.463225 -255.658066) (xy 143.492601 -255.617633) (xy 143.527941 -255.582293)
			(xy 143.568374 -255.552917) (xy 143.612906 -255.530227) (xy 143.660438 -255.514783) (xy 143.709801 -255.506964)
			(xy 143.759779 -255.506964) (xy 143.809142 -255.514783) (xy 143.856674 -255.530227) (xy 143.901206 -255.552917)
			(xy 143.941639 -255.582293) (xy 143.976979 -255.617633) (xy 144.006355 -255.658066) (xy 144.029045 -255.702598)
			(xy 144.044489 -255.75013) (xy 144.052308 -255.799493) (xy 144.052798 -255.824482) (xy 144.052308 -255.849471)
			(xy 144.044489 -255.898834) (xy 144.029045 -255.946366) (xy 144.006355 -255.990898) (xy 143.976979 -256.031331)
			(xy 143.941639 -256.066671) (xy 143.901206 -256.096047) (xy 143.856674 -256.118737) (xy 143.809142 -256.134181)
			(xy 143.759779 -256.142) (xy 143.709801 -256.142) (xy 143.660438 -256.134181) (xy 143.612906 -256.118737)
			(xy 143.568374 -256.096047) (xy 143.527941 -256.066671) (xy 143.492601 -256.031331) (xy 143.463225 -255.990898)
			(xy 143.440535 -255.946366) (xy 143.425091 -255.898834) (xy 143.417272 -255.849471) (xy 143.109955 -255.849471)
			(xy 143.109946 -255.849928) (xy 143.101782 -255.900162) (xy 143.085666 -255.948436) (xy 143.062015 -255.993499)
			(xy 143.031442 -256.034185) (xy 142.994738 -256.06944) (xy 142.952854 -256.09835) (xy 142.906875 -256.120167)
			(xy 142.857991 -256.134327) (xy 142.80747 -256.140461) (xy 142.756618 -256.138412) (xy 142.706754 -256.128232)
			(xy 142.659168 -256.110185) (xy 142.615094 -256.084739) (xy 142.575672 -256.052552) (xy 142.541924 -256.014458)
			(xy 142.514723 -255.971444) (xy 142.494775 -255.924624) (xy 142.482596 -255.87521) (xy 142.478501 -255.824482)
			(xy 142.17269 -255.824482) (xy 142.1722 -255.849471) (xy 142.164381 -255.898834) (xy 142.148937 -255.946366)
			(xy 142.126247 -255.990898) (xy 142.096871 -256.031331) (xy 142.061531 -256.066671) (xy 142.021098 -256.096047)
			(xy 141.976566 -256.118737) (xy 141.929034 -256.134181) (xy 141.879671 -256.142) (xy 141.829693 -256.142)
			(xy 141.78033 -256.134181) (xy 141.732798 -256.118737) (xy 141.688266 -256.096047) (xy 141.647833 -256.066671)
			(xy 141.612493 -256.031331) (xy 141.583117 -255.990898) (xy 141.560427 -255.946366) (xy 141.544983 -255.898834)
			(xy 141.537164 -255.849471) (xy 141.230101 -255.849471) (xy 141.230092 -255.849928) (xy 141.221928 -255.900162)
			(xy 141.205812 -255.948436) (xy 141.182161 -255.993499) (xy 141.151588 -256.034185) (xy 141.114884 -256.06944)
			(xy 141.073 -256.09835) (xy 141.027021 -256.120167) (xy 140.978137 -256.134327) (xy 140.927616 -256.140461)
			(xy 140.876764 -256.138412) (xy 140.8269 -256.128232) (xy 140.779314 -256.110185) (xy 140.73524 -256.084739)
			(xy 140.695818 -256.052552) (xy 140.66207 -256.014458) (xy 140.634869 -255.971444) (xy 140.614921 -255.924624)
			(xy 140.602742 -255.87521) (xy 140.598647 -255.824482) (xy 140.292836 -255.824482) (xy 140.292346 -255.849471)
			(xy 140.284527 -255.898834) (xy 140.269083 -255.946366) (xy 140.246393 -255.990898) (xy 140.217017 -256.031331)
			(xy 140.181677 -256.066671) (xy 140.141244 -256.096047) (xy 140.096712 -256.118737) (xy 140.04918 -256.134181)
			(xy 139.999817 -256.142) (xy 139.949839 -256.142) (xy 139.900476 -256.134181) (xy 139.852944 -256.118737)
			(xy 139.808412 -256.096047) (xy 139.767979 -256.066671) (xy 139.732639 -256.031331) (xy 139.703263 -255.990898)
			(xy 139.680573 -255.946366) (xy 139.665129 -255.898834) (xy 139.65731 -255.849471) (xy 139.349993 -255.849471)
			(xy 139.349984 -255.849928) (xy 139.34182 -255.900162) (xy 139.325704 -255.948436) (xy 139.302053 -255.993499)
			(xy 139.27148 -256.034185) (xy 139.234776 -256.06944) (xy 139.192892 -256.09835) (xy 139.146913 -256.120167)
			(xy 139.098029 -256.134327) (xy 139.047508 -256.140461) (xy 138.996656 -256.138412) (xy 138.946792 -256.128232)
			(xy 138.899206 -256.110185) (xy 138.855132 -256.084739) (xy 138.81571 -256.052552) (xy 138.781962 -256.014458)
			(xy 138.754761 -255.971444) (xy 138.734813 -255.924624) (xy 138.722634 -255.87521) (xy 138.718539 -255.824482)
			(xy 138.410442 -255.824482) (xy 138.40993 -255.849928) (xy 138.401766 -255.900162) (xy 138.38565 -255.948436)
			(xy 138.361999 -255.993499) (xy 138.331426 -256.034185) (xy 138.294722 -256.06944) (xy 138.252838 -256.09835)
			(xy 138.206859 -256.120167) (xy 138.157975 -256.134327) (xy 138.107454 -256.140461) (xy 138.056602 -256.138412)
			(xy 138.006738 -256.128232) (xy 137.959152 -256.110185) (xy 137.915078 -256.084739) (xy 137.875656 -256.052552)
			(xy 137.841908 -256.014458) (xy 137.814707 -255.971444) (xy 137.794759 -255.924624) (xy 137.78258 -255.87521)
			(xy 137.778485 -255.824482) (xy 137.472415 -255.824482) (xy 137.47242 -255.824736) (xy 137.47193 -255.849725)
			(xy 137.464111 -255.899088) (xy 137.448667 -255.94662) (xy 137.425977 -255.991152) (xy 137.396601 -256.031585)
			(xy 137.361261 -256.066925) (xy 137.320828 -256.096301) (xy 137.276296 -256.118991) (xy 137.228764 -256.134435)
			(xy 137.179401 -256.142254) (xy 137.129423 -256.142254) (xy 137.08006 -256.134435) (xy 137.032528 -256.118991)
			(xy 136.987996 -256.096301) (xy 136.947563 -256.066925) (xy 136.912223 -256.031585) (xy 136.882847 -255.991152)
			(xy 136.860157 -255.94662) (xy 136.844713 -255.899088) (xy 136.836894 -255.849725) (xy 136.53008 -255.849725)
			(xy 136.530076 -255.849928) (xy 136.521912 -255.900162) (xy 136.505796 -255.948436) (xy 136.482145 -255.993499)
			(xy 136.451572 -256.034185) (xy 136.414868 -256.06944) (xy 136.372984 -256.09835) (xy 136.327005 -256.120167)
			(xy 136.278121 -256.134327) (xy 136.2276 -256.140461) (xy 136.176748 -256.138412) (xy 136.126884 -256.128232)
			(xy 136.079298 -256.110185) (xy 136.035224 -256.084739) (xy 135.995802 -256.052552) (xy 135.962054 -256.014458)
			(xy 135.934853 -255.971444) (xy 135.914905 -255.924624) (xy 135.902726 -255.87521) (xy 135.898631 -255.824482)
			(xy 135.59282 -255.824482) (xy 135.59233 -255.849471) (xy 135.584511 -255.898834) (xy 135.569067 -255.946366)
			(xy 135.546377 -255.990898) (xy 135.517001 -256.031331) (xy 135.481661 -256.066671) (xy 135.441228 -256.096047)
			(xy 135.396696 -256.118737) (xy 135.349164 -256.134181) (xy 135.299801 -256.142) (xy 135.249823 -256.142)
			(xy 135.20046 -256.134181) (xy 135.152928 -256.118737) (xy 135.108396 -256.096047) (xy 135.067963 -256.066671)
			(xy 135.032623 -256.031331) (xy 135.003247 -255.990898) (xy 134.980557 -255.946366) (xy 134.965113 -255.898834)
			(xy 134.957294 -255.849471) (xy 134.649977 -255.849471) (xy 134.649968 -255.849928) (xy 134.641804 -255.900162)
			(xy 134.625688 -255.948436) (xy 134.602037 -255.993499) (xy 134.571464 -256.034185) (xy 134.53476 -256.06944)
			(xy 134.492876 -256.09835) (xy 134.446897 -256.120167) (xy 134.398013 -256.134327) (xy 134.347492 -256.140461)
			(xy 134.29664 -256.138412) (xy 134.246776 -256.128232) (xy 134.19919 -256.110185) (xy 134.155116 -256.084739)
			(xy 134.115694 -256.052552) (xy 134.081946 -256.014458) (xy 134.054745 -255.971444) (xy 134.034797 -255.924624)
			(xy 134.022618 -255.87521) (xy 134.018523 -255.824482) (xy 133.712712 -255.824482) (xy 133.712222 -255.849471)
			(xy 133.704403 -255.898834) (xy 133.688959 -255.946366) (xy 133.666269 -255.990898) (xy 133.636893 -256.031331)
			(xy 133.601553 -256.066671) (xy 133.56112 -256.096047) (xy 133.516588 -256.118737) (xy 133.469056 -256.134181)
			(xy 133.419693 -256.142) (xy 133.369715 -256.142) (xy 133.320352 -256.134181) (xy 133.27282 -256.118737)
			(xy 133.228288 -256.096047) (xy 133.187855 -256.066671) (xy 133.152515 -256.031331) (xy 133.123139 -255.990898)
			(xy 133.100449 -255.946366) (xy 133.085005 -255.898834) (xy 133.077186 -255.849471) (xy 132.769869 -255.849471)
			(xy 132.76986 -255.849928) (xy 132.761696 -255.900162) (xy 132.74558 -255.948436) (xy 132.721929 -255.993499)
			(xy 132.691356 -256.034185) (xy 132.654652 -256.06944) (xy 132.612768 -256.09835) (xy 132.566789 -256.120167)
			(xy 132.517905 -256.134327) (xy 132.467384 -256.140461) (xy 132.416532 -256.138412) (xy 132.366668 -256.128232)
			(xy 132.319082 -256.110185) (xy 132.275008 -256.084739) (xy 132.235586 -256.052552) (xy 132.201838 -256.014458)
			(xy 132.174637 -255.971444) (xy 132.154689 -255.924624) (xy 132.14251 -255.87521) (xy 132.138415 -255.824482)
			(xy 131.830572 -255.824482) (xy 131.83006 -255.849928) (xy 131.821896 -255.900162) (xy 131.80578 -255.948436)
			(xy 131.782129 -255.993499) (xy 131.751556 -256.034185) (xy 131.714852 -256.06944) (xy 131.672968 -256.09835)
			(xy 131.626989 -256.120167) (xy 131.578105 -256.134327) (xy 131.527584 -256.140461) (xy 131.476732 -256.138412)
			(xy 131.426868 -256.128232) (xy 131.379282 -256.110185) (xy 131.335208 -256.084739) (xy 131.295786 -256.052552)
			(xy 131.262038 -256.014458) (xy 131.234837 -255.971444) (xy 131.214889 -255.924624) (xy 131.20271 -255.87521)
			(xy 131.198615 -255.824482) (xy 130.892804 -255.824482) (xy 130.892314 -255.849471) (xy 130.884495 -255.898834)
			(xy 130.869051 -255.946366) (xy 130.846361 -255.990898) (xy 130.816985 -256.031331) (xy 130.781645 -256.066671)
			(xy 130.741212 -256.096047) (xy 130.69668 -256.118737) (xy 130.649148 -256.134181) (xy 130.599785 -256.142)
			(xy 130.549807 -256.142) (xy 130.500444 -256.134181) (xy 130.452912 -256.118737) (xy 130.40838 -256.096047)
			(xy 130.367947 -256.066671) (xy 130.332607 -256.031331) (xy 130.303231 -255.990898) (xy 130.280541 -255.946366)
			(xy 130.265097 -255.898834) (xy 130.257278 -255.849471) (xy 129.949961 -255.849471) (xy 129.949952 -255.849928)
			(xy 129.941788 -255.900162) (xy 129.925672 -255.948436) (xy 129.902021 -255.993499) (xy 129.871448 -256.034185)
			(xy 129.834744 -256.06944) (xy 129.79286 -256.09835) (xy 129.746881 -256.120167) (xy 129.697997 -256.134327)
			(xy 129.647476 -256.140461) (xy 129.596624 -256.138412) (xy 129.54676 -256.128232) (xy 129.499174 -256.110185)
			(xy 129.4551 -256.084739) (xy 129.415678 -256.052552) (xy 129.38193 -256.014458) (xy 129.354729 -255.971444)
			(xy 129.334781 -255.924624) (xy 129.322602 -255.87521) (xy 129.318507 -255.824482) (xy 129.012696 -255.824482)
			(xy 129.012206 -255.849471) (xy 129.004387 -255.898834) (xy 128.988943 -255.946366) (xy 128.966253 -255.990898)
			(xy 128.936877 -256.031331) (xy 128.901537 -256.066671) (xy 128.861104 -256.096047) (xy 128.816572 -256.118737)
			(xy 128.76904 -256.134181) (xy 128.719677 -256.142) (xy 128.669699 -256.142) (xy 128.620336 -256.134181)
			(xy 128.572804 -256.118737) (xy 128.528272 -256.096047) (xy 128.487839 -256.066671) (xy 128.452499 -256.031331)
			(xy 128.423123 -255.990898) (xy 128.400433 -255.946366) (xy 128.384989 -255.898834) (xy 128.37717 -255.849471)
			(xy 128.069853 -255.849471) (xy 128.069844 -255.849928) (xy 128.06168 -255.900162) (xy 128.045564 -255.948436)
			(xy 128.021913 -255.993499) (xy 127.99134 -256.034185) (xy 127.954636 -256.06944) (xy 127.912752 -256.09835)
			(xy 127.866773 -256.120167) (xy 127.817889 -256.134327) (xy 127.767368 -256.140461) (xy 127.716516 -256.138412)
			(xy 127.666652 -256.128232) (xy 127.619066 -256.110185) (xy 127.574992 -256.084739) (xy 127.53557 -256.052552)
			(xy 127.501822 -256.014458) (xy 127.474621 -255.971444) (xy 127.454673 -255.924624) (xy 127.442494 -255.87521)
			(xy 127.438399 -255.824482) (xy 127.132842 -255.824482) (xy 127.132352 -255.849471) (xy 127.124533 -255.898834)
			(xy 127.109089 -255.946366) (xy 127.086399 -255.990898) (xy 127.057023 -256.031331) (xy 127.021683 -256.066671)
			(xy 126.98125 -256.096047) (xy 126.936718 -256.118737) (xy 126.889186 -256.134181) (xy 126.839823 -256.142)
			(xy 126.789845 -256.142) (xy 126.740482 -256.134181) (xy 126.69295 -256.118737) (xy 126.648418 -256.096047)
			(xy 126.607985 -256.066671) (xy 126.572645 -256.031331) (xy 126.543269 -255.990898) (xy 126.520579 -255.946366)
			(xy 126.505135 -255.898834) (xy 126.497316 -255.849471) (xy 125.378972 -255.849471) (xy 125.378972 -256.099564)
			(xy 125.37855 -256.109586) (xy 125.370887 -256.128108) (xy 125.356715 -256.142282) (xy 125.338194 -256.149949)
			(xy 125.328172 -256.150364) (xy 125.114304 -256.150364) (xy 125.114304 -256.159508) (xy 125.113818 -256.169516)
			(xy 125.106157 -256.188007) (xy 125.092003 -256.202159) (xy 125.073512 -256.209819) (xy 125.063504 -256.210308)
			(xy 124.859288 -256.210308) (xy 124.838244 -256.209787) (xy 124.796972 -256.201544) (xy 124.758111 -256.185381)
			(xy 124.723168 -256.161922) (xy 124.693494 -256.132075) (xy 124.670237 -256.096997) (xy 124.654299 -256.058044)
			(xy 124.646295 -256.016724) (xy 124.645928 -255.995678) (xy 124.645928 -255.99517) (xy 124.645928 -255.95834)
			(xy 124.642118 -255.948688) (xy 124.63409 -255.928976) (xy 124.622788 -255.887941) (xy 124.617073 -255.845763)
			(xy 124.616718 -255.824482) (xy 123.600972 -255.824482) (xy 123.600972 -256.099564) (xy 123.60055 -256.109586)
			(xy 123.592887 -256.128108) (xy 123.578715 -256.142282) (xy 123.560194 -256.149949) (xy 123.550172 -256.150364)
			(xy 123.336304 -256.150364) (xy 123.336304 -256.159508) (xy 123.335818 -256.169516) (xy 123.328157 -256.188007)
			(xy 123.314003 -256.202159) (xy 123.295512 -256.209819) (xy 123.285504 -256.210308) (xy 123.081288 -256.210308)
			(xy 123.059567 -256.209773) (xy 123.017029 -256.200953) (xy 122.977151 -256.183721) (xy 122.941577 -256.158787)
			(xy 122.911774 -256.127179) (xy 122.899932 -256.108962) (xy 122.896771 -256.104201) (xy 122.888691 -256.096122)
			(xy 122.88393 -256.09296) (xy 122.861743 -256.078203) (xy 122.822194 -256.042497) (xy 122.789142 -256.000704)
			(xy 122.763512 -255.953991) (xy 122.746017 -255.903663) (xy 122.737148 -255.851123) (xy 122.73661 -255.824482)
			(xy 121.695972 -255.824482) (xy 121.695972 -256.099564) (xy 121.69555 -256.109586) (xy 121.687887 -256.128108)
			(xy 121.673715 -256.142282) (xy 121.655194 -256.149949) (xy 121.645172 -256.150364) (xy 121.431304 -256.150364)
			(xy 121.431304 -256.159508) (xy 121.430818 -256.169516) (xy 121.423157 -256.188007) (xy 121.409003 -256.202159)
			(xy 121.390512 -256.209819) (xy 121.380504 -256.210308) (xy 121.176288 -256.210308) (xy 121.155844 -256.209902)
			(xy 121.115701 -256.202127) (xy 121.077776 -256.186844) (xy 121.043459 -256.164613) (xy 121.014007 -256.136251)
			(xy 120.990499 -256.102795) (xy 120.981724 -256.084324) (xy 120.979278 -256.079301) (xy 120.972625 -256.070329)
			(xy 120.968516 -256.066544) (xy 120.947928 -256.048258) (xy 120.912795 -256.005862) (xy 120.885485 -255.958051)
			(xy 120.866814 -255.906252) (xy 120.857338 -255.852013) (xy 120.856756 -255.824482) (xy 117.882805 -255.824482)
			(xy 117.877397 -255.837537) (xy 117.863216 -255.851711) (xy 117.844689 -255.859375) (xy 117.834664 -255.859788)
			(xy 117.620288 -255.859788) (xy 117.620288 -255.868932) (xy 117.619838 -255.878943) (xy 117.612166 -255.897438)
			(xy 117.598001 -255.91159) (xy 117.5795 -255.919247) (xy 117.569488 -255.919732) (xy 117.365526 -255.919732)
			(xy 117.344961 -255.919262) (xy 117.304596 -255.911359) (xy 117.26649 -255.895879) (xy 117.232049 -255.873394)
			(xy 117.202547 -255.844734) (xy 117.179074 -255.810959) (xy 117.162497 -255.773317) (xy 117.1575 -255.753362)
			(xy 117.156253 -255.748539) (xy 117.15216 -255.739457) (xy 117.149372 -255.735328) (xy 117.13406 -255.712743)
			(xy 117.109858 -255.663839) (xy 117.093407 -255.611814) (xy 117.085091 -255.557886) (xy 117.084602 -255.530604)
			(xy 106.761276 -255.530604) (xy 106.760845 -255.554922) (xy 106.754089 -255.6036) (xy 106.740712 -255.650889)
			(xy 106.720967 -255.695892) (xy 106.708448 -255.71704) (xy 106.705781 -255.72156) (xy 106.70219 -255.73142)
			(xy 106.701336 -255.736598) (xy 106.697818 -255.758112) (xy 106.683053 -255.799124) (xy 106.660274 -255.836287)
			(xy 106.630428 -255.868056) (xy 106.594757 -255.893109) (xy 106.554745 -255.910403) (xy 106.512057 -255.919219)
			(xy 106.490262 -255.919732) (xy 106.2355 -255.919732) (xy 106.2355 -255.910588) (xy 106.235022 -255.90058)
			(xy 106.227358 -255.882088) (xy 106.213202 -255.867935) (xy 106.194709 -255.860276) (xy 106.1847 -255.859788)
			(xy 105.684828 -255.859788) (xy 105.684828 -255.868932) (xy 105.684339 -255.878938) (xy 105.676674 -255.897425)
			(xy 105.662522 -255.911576) (xy 105.644034 -255.91924) (xy 105.634028 -255.919732) (xy 105.430066 -255.919732)
			(xy 105.408158 -255.919167) (xy 105.365258 -255.910252) (xy 105.325076 -255.892781) (xy 105.289297 -255.867489)
			(xy 105.259422 -255.835436) (xy 105.236707 -255.797968) (xy 105.228898 -255.777492) (xy 105.227278 -255.773087)
			(xy 105.22268 -255.764906) (xy 105.219754 -255.761236) (xy 105.203757 -255.741841) (xy 105.176842 -255.699377)
			(xy 105.156175 -255.653547) (xy 105.142166 -255.605263) (xy 105.135094 -255.555488) (xy 105.134664 -255.53035)
			(xy 104.46576 -255.53035) (xy 104.486455 -255.548993) (xy 104.510261 -255.580038) (xy 104.528008 -255.614903)
			(xy 104.539102 -255.652419) (xy 104.541574 -255.671828) (xy 104.542117 -255.676037) (xy 104.544422 -255.684205)
			(xy 104.546146 -255.688084) (xy 104.555523 -255.709186) (xy 104.568768 -255.75342) (xy 104.575454 -255.799108)
			(xy 104.575864 -255.822196) (xy 104.575864 -255.82245) (xy 104.575469 -255.845119) (xy 104.569 -255.889992)
			(xy 104.556215 -255.93349) (xy 104.547162 -255.954276) (xy 104.542844 -255.964182) (xy 104.542844 -255.99517)
			(xy 104.542844 -255.995678) (xy 104.542538 -256.016729) (xy 104.534531 -256.058058) (xy 104.518588 -256.09702)
			(xy 104.495324 -256.132106) (xy 104.465641 -256.161957) (xy 104.430687 -256.185419) (xy 104.391816 -256.201582)
			(xy 104.350533 -256.209822) (xy 104.329484 -256.210308) (xy 104.074468 -256.210308) (xy 104.074468 -256.201164)
			(xy 104.074041 -256.19115) (xy 104.066363 -256.172651) (xy 104.052191 -256.158499) (xy 104.033683 -256.150846)
			(xy 104.023668 -256.150364) (xy 103.8606 -256.150364) (xy 103.850574 -256.14998) (xy 103.83205 -256.142303)
			(xy 103.817877 -256.128119) (xy 103.810213 -256.10959) (xy 103.8098 -256.099564) (xy 101.883972 -256.099564)
			(xy 101.88355 -256.109586) (xy 101.875887 -256.128108) (xy 101.861715 -256.142282) (xy 101.843194 -256.149949)
			(xy 101.833172 -256.150364) (xy 101.619304 -256.150364) (xy 101.619304 -256.159508) (xy 101.618818 -256.169516)
			(xy 101.611157 -256.188007) (xy 101.597003 -256.202159) (xy 101.578512 -256.209819) (xy 101.568504 -256.210308)
			(xy 101.364288 -256.210308) (xy 101.343244 -256.209787) (xy 101.301972 -256.201544) (xy 101.263111 -256.185381)
			(xy 101.228168 -256.161922) (xy 101.198494 -256.132075) (xy 101.175237 -256.096997) (xy 101.159299 -256.058044)
			(xy 101.151295 -256.016724) (xy 101.150928 -255.995678) (xy 101.150928 -255.99517) (xy 101.150928 -255.955546)
			(xy 101.147118 -255.946148) (xy 101.135839 -255.917006) (xy 101.123678 -255.855722) (xy 101.122988 -255.824482)
			(xy 100.818546 -255.824482) (xy 100.818547 -255.850031) (xy 100.810385 -255.900465) (xy 100.794268 -255.948947)
			(xy 100.77061 -255.994231) (xy 100.755704 -256.014982) (xy 100.75545 -256.015236) (xy 100.750878 -256.021586)
			(xy 100.743004 -256.043684) (xy 100.740718 -256.054352) (xy 100.740464 -256.059432) (xy 100.740464 -256.236978)
			(xy 100.741066 -256.248021) (xy 100.750416 -256.268037) (xy 100.758498 -256.275586) (xy 100.76053 -256.277364)
			(xy 100.825046 -256.3241) (xy 100.830509 -256.327365) (xy 100.842588 -256.331357) (xy 100.848922 -256.331974)
			(xy 100.852732 -256.332228) (xy 100.871274 -256.332228) (xy 100.878386 -256.329942) (xy 100.900842 -256.323608)
			(xy 100.947005 -256.316844) (xy 100.970334 -256.31648) (xy 100.971096 -256.31648) (xy 100.99581 -256.316948)
			(xy 101.044642 -256.324592) (xy 101.091705 -256.339696) (xy 101.135865 -256.361898) (xy 101.17606 -256.390663)
			(xy 101.211322 -256.425299) (xy 101.240803 -256.464971) (xy 101.263793 -256.508726) (xy 101.27974 -256.55551)
			(xy 101.288258 -256.604198) (xy 101.289104 -256.6289) (xy 101.289104 -256.636012) (xy 101.288414 -256.663228)
			(xy 101.278902 -256.716829) (xy 101.260428 -256.768037) (xy 101.247448 -256.791968) (xy 101.244146 -256.79781)
			(xy 101.242622 -256.803906) (xy 101.240844 -256.81686) (xy 101.240844 -256.88036) (xy 101.240844 -256.881376)
			(xy 101.24076 -256.90263) (xy 101.2332 -256.944449) (xy 101.217539 -256.983954) (xy 101.214545 -256.988564)
			(xy 102.4128 -256.988564) (xy 102.4128 -256.480564) (xy 102.413259 -256.470554) (xy 102.42093 -256.452061)
			(xy 102.435092 -256.43791) (xy 102.45359 -256.430251) (xy 102.4636 -256.429764) (xy 102.58298 -256.429764)
			(xy 102.593323 -256.429327) (xy 102.612337 -256.421182) (xy 102.61981 -256.414016) (xy 102.637925 -256.395611)
			(xy 102.679068 -256.364403) (xy 102.724712 -256.340252) (xy 102.773659 -256.323792) (xy 102.824622 -256.315456)
			(xy 102.850442 -256.314956) (xy 102.875431 -256.315443) (xy 102.924792 -256.323267) (xy 102.972321 -256.338715)
			(xy 103.01685 -256.361406) (xy 103.057281 -256.390784) (xy 103.09262 -256.426123) (xy 103.121997 -256.466555)
			(xy 103.129006 -256.48031) (xy 105.134664 -256.48031) (xy 105.13525 -256.452329) (xy 105.144003 -256.397054)
			(xy 105.161294 -256.34383) (xy 105.186699 -256.293966) (xy 105.219591 -256.248689) (xy 105.25916 -256.209115)
			(xy 105.304433 -256.176219) (xy 105.354295 -256.150809) (xy 105.407517 -256.133512) (xy 105.462791 -256.124753)
			(xy 105.490772 -256.124202) (xy 105.491534 -256.124202) (xy 105.516911 -256.124665) (xy 105.567144 -256.131925)
			(xy 105.59161 -256.13868) (xy 105.598722 -256.140712) (xy 105.65511 -256.140712) (xy 105.684828 -256.17043)
			(xy 105.684828 -256.18186) (xy 105.698798 -256.191258) (xy 105.705391 -256.195571) (xy 105.72039 -256.20036)
			(xy 105.728262 -256.200656) (xy 106.167682 -256.200656) (xy 106.175555 -256.200352) (xy 106.190559 -256.195579)
			(xy 106.197146 -256.191258) (xy 106.206394 -256.184758) (xy 106.225586 -256.172812) (xy 106.2355 -256.167382)
			(xy 106.2355 -256.140712) (xy 106.297222 -256.140712) (xy 106.304334 -256.13868) (xy 106.328989 -256.131897)
			(xy 106.379604 -256.124627) (xy 106.405172 -256.124202) (xy 106.43307 -256.124742) (xy 106.488186 -256.133416)
			(xy 106.5149 -256.141474) (xy 106.522774 -256.143252) (xy 106.541279 -256.146504) (xy 106.576832 -256.15864)
			(xy 106.609706 -256.176824) (xy 106.638881 -256.200493) (xy 106.663451 -256.228912) (xy 106.673396 -256.244852)
			(xy 106.678222 -256.251456) (xy 106.693821 -256.270813) (xy 106.720127 -256.312995) (xy 106.740309 -256.358425)
			(xy 106.748651 -256.3876) (xy 107.291886 -256.3876) (xy 107.292464 -256.359333) (xy 107.301486 -256.303521)
			(xy 107.319193 -256.249829) (xy 107.345144 -256.199601) (xy 107.361482 -256.176526) (xy 107.36603 -256.169809)
			(xy 107.371087 -256.154406) (xy 107.371388 -256.1463) (xy 107.371388 -256.073656) (xy 107.371852 -256.063647)
			(xy 107.379524 -256.045157) (xy 107.393683 -256.031006) (xy 107.412179 -256.023346) (xy 107.422188 -256.022856)
			(xy 107.92968 -256.022856) (xy 107.939681 -256.023403) (xy 107.958164 -256.031048) (xy 107.972316 -256.045182)
			(xy 107.979984 -256.063656) (xy 107.98048 -256.073656) (xy 107.98048 -256.251202) (xy 107.980577 -256.255611)
			(xy 107.982115 -256.264296) (xy 107.983528 -256.268474) (xy 107.989878 -256.287524) (xy 108.010706 -256.287524)
			(xy 108.040424 -256.317242) (xy 108.040424 -256.3876) (xy 108.241846 -256.3876) (xy 108.242431 -256.359333)
			(xy 108.251452 -256.303522) (xy 108.269158 -256.249831) (xy 108.295105 -256.199601) (xy 108.311442 -256.176526)
			(xy 108.315996 -256.169813) (xy 108.321048 -256.154406) (xy 108.321348 -256.1463) (xy 108.321348 -256.073656)
			(xy 108.321685 -256.063626) (xy 108.329378 -256.045099) (xy 108.343576 -256.030926) (xy 108.362117 -256.023266)
			(xy 108.372148 -256.022856) (xy 108.87964 -256.022856) (xy 108.889645 -256.023354) (xy 108.908129 -256.031019)
			(xy 108.922279 -256.045168) (xy 108.929945 -256.063651) (xy 108.93044 -256.073656) (xy 108.93044 -256.251202)
			(xy 108.930539 -256.255611) (xy 108.932076 -256.264296) (xy 108.933488 -256.268474) (xy 108.939838 -256.287524)
			(xy 108.960666 -256.287524) (xy 108.990384 -256.317242) (xy 108.990384 -256.3876) (xy 109.191806 -256.3876)
			(xy 109.19238 -256.359333) (xy 109.201403 -256.303521) (xy 109.219111 -256.249829) (xy 109.245063 -256.1996)
			(xy 109.261402 -256.176526) (xy 109.265952 -256.16981) (xy 109.271007 -256.154406) (xy 109.271308 -256.1463)
			(xy 109.271308 -256.073656) (xy 109.271752 -256.063645) (xy 109.279428 -256.04515) (xy 109.293594 -256.030999)
			(xy 109.312096 -256.023342) (xy 109.322108 -256.022856) (xy 109.8296 -256.022856) (xy 109.839602 -256.023387)
			(xy 109.858086 -256.031038) (xy 109.872237 -256.045178) (xy 109.879904 -256.063654) (xy 109.8804 -256.073656)
			(xy 109.8804 -256.251202) (xy 109.880501 -256.255611) (xy 109.882037 -256.264295) (xy 109.883448 -256.268474)
			(xy 109.889798 -256.287524) (xy 109.910626 -256.287524) (xy 109.940344 -256.317242) (xy 109.940344 -256.3876)
			(xy 110.141766 -256.3876) (xy 110.142348 -256.359333) (xy 110.151369 -256.303522) (xy 110.169076 -256.24983)
			(xy 110.195025 -256.199601) (xy 110.211362 -256.176526) (xy 110.215918 -256.169814) (xy 110.220968 -256.154406)
			(xy 110.221268 -256.1463) (xy 110.221268 -256.073656) (xy 110.221751 -256.063649) (xy 110.229419 -256.045163)
			(xy 110.243573 -256.031013) (xy 110.262061 -256.023349) (xy 110.272068 -256.022856) (xy 110.77956 -256.022856)
			(xy 110.78956 -256.02342) (xy 110.808042 -256.031058) (xy 110.822195 -256.045187) (xy 110.829864 -256.063657)
			(xy 110.83036 -256.073656) (xy 110.83036 -256.251202) (xy 110.830458 -256.255611) (xy 110.831995 -256.264296)
			(xy 110.833408 -256.268474) (xy 110.839758 -256.287524) (xy 110.860586 -256.287524) (xy 110.890304 -256.317242)
			(xy 110.890304 -256.3876) (xy 111.091726 -256.3876) (xy 111.091726 -256.387092) (xy 111.092256 -256.358789)
			(xy 111.101225 -256.302897) (xy 111.118936 -256.249132) (xy 111.144941 -256.198852) (xy 111.161322 -256.175764)
			(xy 111.165839 -256.169105) (xy 111.170872 -256.153831) (xy 111.171228 -256.145792) (xy 111.171228 -256.073656)
			(xy 111.171653 -256.063642) (xy 111.179332 -256.045144) (xy 111.193504 -256.030992) (xy 111.212013 -256.023339)
			(xy 111.222028 -256.022856) (xy 111.730028 -256.022856) (xy 111.740032 -256.023364) (xy 111.758516 -256.031025)
			(xy 111.772666 -256.045171) (xy 111.780333 -256.063652) (xy 111.780828 -256.073656) (xy 111.780828 -256.251964)
			(xy 111.78091 -256.256298) (xy 111.782307 -256.264852) (xy 111.783622 -256.268982) (xy 111.789718 -256.287524)
			(xy 111.789972 -256.287524) (xy 111.799994 -256.287943) (xy 111.818515 -256.295608) (xy 111.832689 -256.309781)
			(xy 111.840356 -256.328302) (xy 111.840772 -256.338324) (xy 111.840772 -256.3876) (xy 112.041686 -256.3876)
			(xy 112.041686 -256.387092) (xy 112.042204 -256.358788) (xy 112.051175 -256.302895) (xy 112.068889 -256.24913)
			(xy 112.094899 -256.198851) (xy 112.111282 -256.175764) (xy 112.115795 -256.169103) (xy 112.120832 -256.153831)
			(xy 112.121188 -256.145792) (xy 112.121188 -256.073656) (xy 112.121652 -256.063647) (xy 112.129324 -256.045157)
			(xy 112.143483 -256.031006) (xy 112.161979 -256.023346) (xy 112.171988 -256.022856) (xy 112.679988 -256.022856)
			(xy 112.689989 -256.023397) (xy 112.708473 -256.031044) (xy 112.722624 -256.04518) (xy 112.730292 -256.063655)
			(xy 112.730788 -256.073656) (xy 112.730788 -256.251964) (xy 112.730872 -256.256298) (xy 112.732268 -256.264852)
			(xy 112.733582 -256.268982) (xy 112.739678 -256.287524) (xy 112.739932 -256.287524) (xy 112.749945 -256.287962)
			(xy 112.768442 -256.295637) (xy 112.782594 -256.309805) (xy 112.790249 -256.328311) (xy 112.790732 -256.338324)
			(xy 112.790732 -256.3876) (xy 112.9919 -256.3876) (xy 112.992426 -256.359308) (xy 113.001335 -256.303431)
			(xy 113.018975 -256.249668) (xy 113.044902 -256.199374) (xy 113.061242 -256.176272) (xy 113.065758 -256.169613)
			(xy 113.070792 -256.154339) (xy 113.071148 -256.1463) (xy 113.071148 -256.073656) (xy 113.071485 -256.063626)
			(xy 113.079178 -256.045099) (xy 113.093376 -256.030926) (xy 113.111917 -256.023266) (xy 113.121948 -256.022856)
			(xy 113.629948 -256.022856) (xy 113.639953 -256.023348) (xy 113.658438 -256.031015) (xy 113.672587 -256.045166)
			(xy 113.680253 -256.063651) (xy 113.680748 -256.073656) (xy 113.680748 -256.251202) (xy 113.680883 -256.255546)
			(xy 113.68241 -256.264101) (xy 113.683796 -256.26822) (xy 113.689892 -256.287524) (xy 113.699916 -256.287927)
			(xy 113.718437 -256.295598) (xy 113.732611 -256.309776) (xy 113.740277 -256.3283) (xy 113.740692 -256.338324)
			(xy 113.740692 -256.3876) (xy 113.94186 -256.3876) (xy 113.942375 -256.359307) (xy 113.951285 -256.303429)
			(xy 113.968928 -256.249666) (xy 113.994859 -256.199373) (xy 114.011202 -256.176272) (xy 114.015714 -256.16961)
			(xy 114.020751 -256.154339) (xy 114.021108 -256.1463) (xy 114.021108 -256.073656) (xy 114.021552 -256.063645)
			(xy 114.029228 -256.04515) (xy 114.043394 -256.030999) (xy 114.061896 -256.023342) (xy 114.071908 -256.022856)
			(xy 114.579908 -256.022856) (xy 114.589911 -256.023381) (xy 114.608394 -256.031035) (xy 114.622545 -256.045176)
			(xy 114.630212 -256.063654) (xy 114.630708 -256.073656) (xy 114.630708 -256.251202) (xy 114.630845 -256.255546)
			(xy 114.632371 -256.264101) (xy 114.633756 -256.26822) (xy 114.639852 -256.287524) (xy 114.649873 -256.287959)
			(xy 114.668394 -256.295618) (xy 114.682569 -256.309786) (xy 114.690236 -256.328303) (xy 114.690652 -256.338324)
			(xy 114.690652 -256.3876) (xy 114.89182 -256.3876) (xy 114.892342 -256.359308) (xy 114.901251 -256.30343)
			(xy 114.918892 -256.249667) (xy 114.944821 -256.199374) (xy 114.961162 -256.176272) (xy 114.96567 -256.169608)
			(xy 114.97071 -256.154338) (xy 114.971068 -256.1463) (xy 114.971068 -256.073656) (xy 114.971551 -256.063649)
			(xy 114.979219 -256.045163) (xy 114.993373 -256.031013) (xy 115.011861 -256.023349) (xy 115.021868 -256.022856)
			(xy 115.529868 -256.022856) (xy 115.539868 -256.023413) (xy 115.558351 -256.031054) (xy 115.572504 -256.045185)
			(xy 115.580172 -256.063657) (xy 115.580668 -256.073656) (xy 115.580668 -256.251202) (xy 115.580807 -256.255546)
			(xy 115.582332 -256.264101) (xy 115.583716 -256.26822) (xy 115.589812 -256.287524) (xy 115.599837 -256.28791)
			(xy 115.618359 -256.295589) (xy 115.632531 -256.309771) (xy 115.640197 -256.328299) (xy 115.640612 -256.338324)
			(xy 115.640612 -256.3876) (xy 115.84178 -256.3876) (xy 115.84231 -256.359308) (xy 115.851218 -256.303431)
			(xy 115.868857 -256.249668) (xy 115.894782 -256.199374) (xy 115.911122 -256.176272) (xy 115.915636 -256.169612)
			(xy 115.920671 -256.154339) (xy 115.921028 -256.1463) (xy 115.921028 -256.073656) (xy 115.921453 -256.063642)
			(xy 115.929132 -256.045144) (xy 115.943304 -256.030992) (xy 115.961813 -256.023339) (xy 115.971828 -256.022856)
			(xy 116.479828 -256.022856) (xy 116.489832 -256.023364) (xy 116.508316 -256.031025) (xy 116.522466 -256.045171)
			(xy 116.530133 -256.063652) (xy 116.530628 -256.073656) (xy 116.530628 -256.251202) (xy 116.530764 -256.255546)
			(xy 116.53229 -256.264101) (xy 116.533676 -256.26822) (xy 116.539772 -256.287524) (xy 116.549794 -256.287943)
			(xy 116.568315 -256.295608) (xy 116.582489 -256.309781) (xy 116.590156 -256.328302) (xy 116.590572 -256.338324)
			(xy 116.590572 -256.48031) (xy 117.084602 -256.48031) (xy 117.085043 -256.45518) (xy 117.092109 -256.405419)
			(xy 117.106102 -256.357146) (xy 117.126743 -256.31132) (xy 117.153624 -256.268852) (xy 117.186209 -256.230585)
			(xy 117.204744 -256.21361) (xy 117.208554 -256.2098) (xy 117.222924 -256.194873) (xy 117.256288 -256.170312)
			(xy 117.293748 -256.152617) (xy 117.31371 -256.147062) (xy 117.31879 -256.145538) (xy 117.348268 -256.135528)
			(xy 117.409585 -256.124798) (xy 117.44071 -256.124202) (xy 117.466279 -256.124617) (xy 117.516896 -256.131882)
			(xy 117.541548 -256.13868) (xy 117.54866 -256.140712) (xy 117.620288 -256.140712) (xy 117.620288 -256.144776)
			(xy 117.620924 -256.157291) (xy 117.632628 -256.179408) (xy 117.64264 -256.18694) (xy 117.648736 -256.191258)
			(xy 117.65532 -256.195586) (xy 117.670326 -256.200365) (xy 117.6782 -256.200656) (xy 117.834664 -256.200656)
			(xy 117.844664 -256.201216) (xy 117.863147 -256.208856) (xy 117.877299 -256.222986) (xy 117.884968 -256.241457)
			(xy 117.885464 -256.251456) (xy 117.885464 -256.659477) (xy 122.2672 -256.659477) (xy 122.2672 -256.609499)
			(xy 122.275019 -256.560136) (xy 122.290463 -256.512604) (xy 122.313153 -256.468072) (xy 122.342529 -256.427639)
			(xy 122.377869 -256.392299) (xy 122.418302 -256.362923) (xy 122.462834 -256.340233) (xy 122.510366 -256.324789)
			(xy 122.559729 -256.31697) (xy 122.609707 -256.31697) (xy 122.65907 -256.324789) (xy 122.706602 -256.340233)
			(xy 122.751134 -256.362923) (xy 122.791567 -256.392299) (xy 122.826907 -256.427639) (xy 122.856283 -256.468072)
			(xy 122.878973 -256.512604) (xy 122.894417 -256.560136) (xy 122.902236 -256.609499) (xy 122.902726 -256.634488)
			(xy 122.902236 -256.659477) (xy 124.147308 -256.659477) (xy 124.147308 -256.609499) (xy 124.155127 -256.560136)
			(xy 124.170571 -256.512604) (xy 124.193261 -256.468072) (xy 124.222637 -256.427639) (xy 124.257977 -256.392299)
			(xy 124.29841 -256.362923) (xy 124.342942 -256.340233) (xy 124.390474 -256.324789) (xy 124.439837 -256.31697)
			(xy 124.489815 -256.31697) (xy 124.539178 -256.324789) (xy 124.58671 -256.340233) (xy 124.631242 -256.362923)
			(xy 124.671675 -256.392299) (xy 124.707015 -256.427639) (xy 124.736391 -256.468072) (xy 124.759081 -256.512604)
			(xy 124.774525 -256.560136) (xy 124.782344 -256.609499) (xy 124.782834 -256.634488) (xy 124.782344 -256.659477)
			(xy 126.027162 -256.659477) (xy 126.027162 -256.609499) (xy 126.034981 -256.560136) (xy 126.050425 -256.512604)
			(xy 126.073115 -256.468072) (xy 126.102491 -256.427639) (xy 126.137831 -256.392299) (xy 126.178264 -256.362923)
			(xy 126.222796 -256.340233) (xy 126.270328 -256.324789) (xy 126.319691 -256.31697) (xy 126.369669 -256.31697)
			(xy 126.419032 -256.324789) (xy 126.466564 -256.340233) (xy 126.511096 -256.362923) (xy 126.551529 -256.392299)
			(xy 126.586869 -256.427639) (xy 126.616245 -256.468072) (xy 126.638935 -256.512604) (xy 126.654379 -256.560136)
			(xy 126.662198 -256.609499) (xy 126.662688 -256.634488) (xy 126.662198 -256.659477) (xy 127.90727 -256.659477)
			(xy 127.90727 -256.609499) (xy 127.915089 -256.560136) (xy 127.930533 -256.512604) (xy 127.953223 -256.468072)
			(xy 127.982599 -256.427639) (xy 128.017939 -256.392299) (xy 128.058372 -256.362923) (xy 128.102904 -256.340233)
			(xy 128.150436 -256.324789) (xy 128.199799 -256.31697) (xy 128.249777 -256.31697) (xy 128.29914 -256.324789)
			(xy 128.346672 -256.340233) (xy 128.391204 -256.362923) (xy 128.431637 -256.392299) (xy 128.466977 -256.427639)
			(xy 128.496353 -256.468072) (xy 128.519043 -256.512604) (xy 128.534487 -256.560136) (xy 128.542306 -256.609499)
			(xy 128.542796 -256.634488) (xy 128.848607 -256.634488) (xy 128.852702 -256.58376) (xy 128.864881 -256.534346)
			(xy 128.884829 -256.487526) (xy 128.91203 -256.444512) (xy 128.945778 -256.406418) (xy 128.9852 -256.374231)
			(xy 129.029274 -256.348785) (xy 129.07686 -256.330738) (xy 129.126724 -256.320558) (xy 129.177576 -256.318509)
			(xy 129.228097 -256.324643) (xy 129.276981 -256.338803) (xy 129.32296 -256.36062) (xy 129.364844 -256.38953)
			(xy 129.401548 -256.424785) (xy 129.432121 -256.465471) (xy 129.455772 -256.510534) (xy 129.471888 -256.558808)
			(xy 129.480052 -256.609042) (xy 129.480564 -256.634488) (xy 129.480061 -256.659477) (xy 130.727178 -256.659477)
			(xy 130.727178 -256.609499) (xy 130.734997 -256.560136) (xy 130.750441 -256.512604) (xy 130.773131 -256.468072)
			(xy 130.802507 -256.427639) (xy 130.837847 -256.392299) (xy 130.87828 -256.362923) (xy 130.922812 -256.340233)
			(xy 130.970344 -256.324789) (xy 131.019707 -256.31697) (xy 131.069685 -256.31697) (xy 131.119048 -256.324789)
			(xy 131.16658 -256.340233) (xy 131.211112 -256.362923) (xy 131.251545 -256.392299) (xy 131.286885 -256.427639)
			(xy 131.316261 -256.468072) (xy 131.338951 -256.512604) (xy 131.354395 -256.560136) (xy 131.362214 -256.609499)
			(xy 131.362704 -256.634488) (xy 131.362214 -256.659477) (xy 131.667232 -256.659477) (xy 131.667232 -256.609499)
			(xy 131.675051 -256.560136) (xy 131.690495 -256.512604) (xy 131.713185 -256.468072) (xy 131.742561 -256.427639)
			(xy 131.777901 -256.392299) (xy 131.818334 -256.362923) (xy 131.862866 -256.340233) (xy 131.910398 -256.324789)
			(xy 131.959761 -256.31697) (xy 132.009739 -256.31697) (xy 132.059102 -256.324789) (xy 132.106634 -256.340233)
			(xy 132.151166 -256.362923) (xy 132.191599 -256.392299) (xy 132.226939 -256.427639) (xy 132.256315 -256.468072)
			(xy 132.279005 -256.512604) (xy 132.294449 -256.560136) (xy 132.302268 -256.609499) (xy 132.302758 -256.634488)
			(xy 132.608569 -256.634488) (xy 132.612664 -256.58376) (xy 132.624843 -256.534346) (xy 132.644791 -256.487526)
			(xy 132.671992 -256.444512) (xy 132.70574 -256.406418) (xy 132.745162 -256.374231) (xy 132.789236 -256.348785)
			(xy 132.836822 -256.330738) (xy 132.886686 -256.320558) (xy 132.937538 -256.318509) (xy 132.988059 -256.324643)
			(xy 133.036943 -256.338803) (xy 133.082922 -256.36062) (xy 133.124806 -256.38953) (xy 133.16151 -256.424785)
			(xy 133.192083 -256.465471) (xy 133.215734 -256.510534) (xy 133.23185 -256.558808) (xy 133.240014 -256.609042)
			(xy 133.240526 -256.634488) (xy 133.240023 -256.659477) (xy 133.54734 -256.659477) (xy 133.54734 -256.609499)
			(xy 133.555159 -256.560136) (xy 133.570603 -256.512604) (xy 133.593293 -256.468072) (xy 133.622669 -256.427639)
			(xy 133.658009 -256.392299) (xy 133.698442 -256.362923) (xy 133.742974 -256.340233) (xy 133.790506 -256.324789)
			(xy 133.839869 -256.31697) (xy 133.889847 -256.31697) (xy 133.93921 -256.324789) (xy 133.986742 -256.340233)
			(xy 134.031274 -256.362923) (xy 134.071707 -256.392299) (xy 134.107047 -256.427639) (xy 134.136423 -256.468072)
			(xy 134.159113 -256.512604) (xy 134.174557 -256.560136) (xy 134.182376 -256.609499) (xy 134.182866 -256.634488)
			(xy 134.182376 -256.659477) (xy 134.48714 -256.659477) (xy 134.48714 -256.609499) (xy 134.494959 -256.560136)
			(xy 134.510403 -256.512604) (xy 134.533093 -256.468072) (xy 134.562469 -256.427639) (xy 134.597809 -256.392299)
			(xy 134.638242 -256.362923) (xy 134.682774 -256.340233) (xy 134.730306 -256.324789) (xy 134.779669 -256.31697)
			(xy 134.829647 -256.31697) (xy 134.87901 -256.324789) (xy 134.926542 -256.340233) (xy 134.971074 -256.362923)
			(xy 135.011507 -256.392299) (xy 135.046847 -256.427639) (xy 135.076223 -256.468072) (xy 135.098913 -256.512604)
			(xy 135.114357 -256.560136) (xy 135.122176 -256.609499) (xy 135.122666 -256.634488) (xy 135.428477 -256.634488)
			(xy 135.432572 -256.58376) (xy 135.444751 -256.534346) (xy 135.464699 -256.487526) (xy 135.4919 -256.444512)
			(xy 135.525648 -256.406418) (xy 135.56507 -256.374231) (xy 135.609144 -256.348785) (xy 135.65673 -256.330738)
			(xy 135.706594 -256.320558) (xy 135.757446 -256.318509) (xy 135.807967 -256.324643) (xy 135.856851 -256.338803)
			(xy 135.90283 -256.36062) (xy 135.944714 -256.38953) (xy 135.981418 -256.424785) (xy 136.011991 -256.465471)
			(xy 136.035642 -256.510534) (xy 136.051758 -256.558808) (xy 136.059922 -256.609042) (xy 136.060434 -256.634488)
			(xy 136.059931 -256.659477) (xy 137.307302 -256.659477) (xy 137.307302 -256.609499) (xy 137.315121 -256.560136)
			(xy 137.330565 -256.512604) (xy 137.353255 -256.468072) (xy 137.382631 -256.427639) (xy 137.417971 -256.392299)
			(xy 137.458404 -256.362923) (xy 137.502936 -256.340233) (xy 137.550468 -256.324789) (xy 137.599831 -256.31697)
			(xy 137.649809 -256.31697) (xy 137.699172 -256.324789) (xy 137.746704 -256.340233) (xy 137.791236 -256.362923)
			(xy 137.831669 -256.392299) (xy 137.867009 -256.427639) (xy 137.896385 -256.468072) (xy 137.919075 -256.512604)
			(xy 137.934519 -256.560136) (xy 137.942338 -256.609499) (xy 137.942828 -256.634488) (xy 137.942338 -256.659477)
			(xy 138.247356 -256.659477) (xy 138.247356 -256.609499) (xy 138.255175 -256.560136) (xy 138.270619 -256.512604)
			(xy 138.293309 -256.468072) (xy 138.322685 -256.427639) (xy 138.358025 -256.392299) (xy 138.398458 -256.362923)
			(xy 138.44299 -256.340233) (xy 138.490522 -256.324789) (xy 138.539885 -256.31697) (xy 138.589863 -256.31697)
			(xy 138.639226 -256.324789) (xy 138.686758 -256.340233) (xy 138.73129 -256.362923) (xy 138.771723 -256.392299)
			(xy 138.807063 -256.427639) (xy 138.836439 -256.468072) (xy 138.859129 -256.512604) (xy 138.874573 -256.560136)
			(xy 138.882392 -256.609499) (xy 138.882882 -256.634488) (xy 139.188439 -256.634488) (xy 139.192534 -256.58376)
			(xy 139.204713 -256.534346) (xy 139.224661 -256.487526) (xy 139.251862 -256.444512) (xy 139.28561 -256.406418)
			(xy 139.325032 -256.374231) (xy 139.369106 -256.348785) (xy 139.416692 -256.330738) (xy 139.466556 -256.320558)
			(xy 139.517408 -256.318509) (xy 139.567929 -256.324643) (xy 139.616813 -256.338803) (xy 139.662792 -256.36062)
			(xy 139.704676 -256.38953) (xy 139.74138 -256.424785) (xy 139.771953 -256.465471) (xy 139.795604 -256.510534)
			(xy 139.81172 -256.558808) (xy 139.819884 -256.609042) (xy 139.820396 -256.634488) (xy 139.819893 -256.659477)
			(xy 140.12721 -256.659477) (xy 140.12721 -256.609499) (xy 140.135029 -256.560136) (xy 140.150473 -256.512604)
			(xy 140.173163 -256.468072) (xy 140.202539 -256.427639) (xy 140.237879 -256.392299) (xy 140.278312 -256.362923)
			(xy 140.322844 -256.340233) (xy 140.370376 -256.324789) (xy 140.419739 -256.31697) (xy 140.469717 -256.31697)
			(xy 140.51908 -256.324789) (xy 140.566612 -256.340233) (xy 140.611144 -256.362923) (xy 140.651577 -256.392299)
			(xy 140.686917 -256.427639) (xy 140.716293 -256.468072) (xy 140.738983 -256.512604) (xy 140.754427 -256.560136)
			(xy 140.762246 -256.609499) (xy 140.762736 -256.634488) (xy 140.762246 -256.659477) (xy 141.067264 -256.659477)
			(xy 141.067264 -256.609499) (xy 141.075083 -256.560136) (xy 141.090527 -256.512604) (xy 141.113217 -256.468072)
			(xy 141.142593 -256.427639) (xy 141.177933 -256.392299) (xy 141.218366 -256.362923) (xy 141.262898 -256.340233)
			(xy 141.31043 -256.324789) (xy 141.359793 -256.31697) (xy 141.409771 -256.31697) (xy 141.459134 -256.324789)
			(xy 141.506666 -256.340233) (xy 141.551198 -256.362923) (xy 141.591631 -256.392299) (xy 141.626971 -256.427639)
			(xy 141.656347 -256.468072) (xy 141.679037 -256.512604) (xy 141.694481 -256.560136) (xy 141.7023 -256.609499)
			(xy 141.70279 -256.634488) (xy 142.008601 -256.634488) (xy 142.012696 -256.58376) (xy 142.024875 -256.534346)
			(xy 142.044823 -256.487526) (xy 142.072024 -256.444512) (xy 142.105772 -256.406418) (xy 142.145194 -256.374231)
			(xy 142.189268 -256.348785) (xy 142.236854 -256.330738) (xy 142.286718 -256.320558) (xy 142.33757 -256.318509)
			(xy 142.388091 -256.324643) (xy 142.436975 -256.338803) (xy 142.482954 -256.36062) (xy 142.524838 -256.38953)
			(xy 142.561542 -256.424785) (xy 142.592115 -256.465471) (xy 142.615766 -256.510534) (xy 142.631882 -256.558808)
			(xy 142.640046 -256.609042) (xy 142.640558 -256.634488) (xy 142.640055 -256.659477) (xy 143.887172 -256.659477)
			(xy 143.887172 -256.609499) (xy 143.894991 -256.560136) (xy 143.910435 -256.512604) (xy 143.933125 -256.468072)
			(xy 143.962501 -256.427639) (xy 143.997841 -256.392299) (xy 144.038274 -256.362923) (xy 144.082806 -256.340233)
			(xy 144.130338 -256.324789) (xy 144.179701 -256.31697) (xy 144.229679 -256.31697) (xy 144.279042 -256.324789)
			(xy 144.326574 -256.340233) (xy 144.371106 -256.362923) (xy 144.411539 -256.392299) (xy 144.446879 -256.427639)
			(xy 144.476255 -256.468072) (xy 144.498945 -256.512604) (xy 144.514389 -256.560136) (xy 144.522208 -256.609499)
			(xy 144.522698 -256.634488) (xy 144.522208 -256.659477) (xy 144.514389 -256.70884) (xy 144.498945 -256.756372)
			(xy 144.476255 -256.800904) (xy 144.446879 -256.841337) (xy 144.411539 -256.876677) (xy 144.371106 -256.906053)
			(xy 144.326574 -256.928743) (xy 144.279042 -256.944187) (xy 144.229679 -256.952006) (xy 144.179701 -256.952006)
			(xy 144.130338 -256.944187) (xy 144.082806 -256.928743) (xy 144.038274 -256.906053) (xy 143.997841 -256.876677)
			(xy 143.962501 -256.841337) (xy 143.933125 -256.800904) (xy 143.910435 -256.756372) (xy 143.894991 -256.70884)
			(xy 143.887172 -256.659477) (xy 142.640055 -256.659477) (xy 142.640046 -256.659934) (xy 142.631882 -256.710168)
			(xy 142.615766 -256.758442) (xy 142.592115 -256.803505) (xy 142.561542 -256.844191) (xy 142.524838 -256.879446)
			(xy 142.482954 -256.908356) (xy 142.436975 -256.930173) (xy 142.388091 -256.944333) (xy 142.33757 -256.950467)
			(xy 142.286718 -256.948418) (xy 142.236854 -256.938238) (xy 142.189268 -256.920191) (xy 142.145194 -256.894745)
			(xy 142.105772 -256.862558) (xy 142.072024 -256.824464) (xy 142.044823 -256.78145) (xy 142.024875 -256.73463)
			(xy 142.012696 -256.685216) (xy 142.008601 -256.634488) (xy 141.70279 -256.634488) (xy 141.7023 -256.659477)
			(xy 141.694481 -256.70884) (xy 141.679037 -256.756372) (xy 141.656347 -256.800904) (xy 141.626971 -256.841337)
			(xy 141.591631 -256.876677) (xy 141.551198 -256.906053) (xy 141.506666 -256.928743) (xy 141.459134 -256.944187)
			(xy 141.409771 -256.952006) (xy 141.359793 -256.952006) (xy 141.31043 -256.944187) (xy 141.262898 -256.928743)
			(xy 141.218366 -256.906053) (xy 141.177933 -256.876677) (xy 141.142593 -256.841337) (xy 141.113217 -256.800904)
			(xy 141.090527 -256.756372) (xy 141.075083 -256.70884) (xy 141.067264 -256.659477) (xy 140.762246 -256.659477)
			(xy 140.754427 -256.70884) (xy 140.738983 -256.756372) (xy 140.716293 -256.800904) (xy 140.686917 -256.841337)
			(xy 140.651577 -256.876677) (xy 140.611144 -256.906053) (xy 140.566612 -256.928743) (xy 140.51908 -256.944187)
			(xy 140.469717 -256.952006) (xy 140.419739 -256.952006) (xy 140.370376 -256.944187) (xy 140.322844 -256.928743)
			(xy 140.278312 -256.906053) (xy 140.237879 -256.876677) (xy 140.202539 -256.841337) (xy 140.173163 -256.800904)
			(xy 140.150473 -256.756372) (xy 140.135029 -256.70884) (xy 140.12721 -256.659477) (xy 139.819893 -256.659477)
			(xy 139.819884 -256.659934) (xy 139.81172 -256.710168) (xy 139.795604 -256.758442) (xy 139.771953 -256.803505)
			(xy 139.74138 -256.844191) (xy 139.704676 -256.879446) (xy 139.662792 -256.908356) (xy 139.616813 -256.930173)
			(xy 139.567929 -256.944333) (xy 139.517408 -256.950467) (xy 139.466556 -256.948418) (xy 139.416692 -256.938238)
			(xy 139.369106 -256.920191) (xy 139.325032 -256.894745) (xy 139.28561 -256.862558) (xy 139.251862 -256.824464)
			(xy 139.224661 -256.78145) (xy 139.204713 -256.73463) (xy 139.192534 -256.685216) (xy 139.188439 -256.634488)
			(xy 138.882882 -256.634488) (xy 138.882392 -256.659477) (xy 138.874573 -256.70884) (xy 138.859129 -256.756372)
			(xy 138.836439 -256.800904) (xy 138.807063 -256.841337) (xy 138.771723 -256.876677) (xy 138.73129 -256.906053)
			(xy 138.686758 -256.928743) (xy 138.639226 -256.944187) (xy 138.589863 -256.952006) (xy 138.539885 -256.952006)
			(xy 138.490522 -256.944187) (xy 138.44299 -256.928743) (xy 138.398458 -256.906053) (xy 138.358025 -256.876677)
			(xy 138.322685 -256.841337) (xy 138.293309 -256.800904) (xy 138.270619 -256.756372) (xy 138.255175 -256.70884)
			(xy 138.247356 -256.659477) (xy 137.942338 -256.659477) (xy 137.934519 -256.70884) (xy 137.919075 -256.756372)
			(xy 137.896385 -256.800904) (xy 137.867009 -256.841337) (xy 137.831669 -256.876677) (xy 137.791236 -256.906053)
			(xy 137.746704 -256.928743) (xy 137.699172 -256.944187) (xy 137.649809 -256.952006) (xy 137.599831 -256.952006)
			(xy 137.550468 -256.944187) (xy 137.502936 -256.928743) (xy 137.458404 -256.906053) (xy 137.417971 -256.876677)
			(xy 137.382631 -256.841337) (xy 137.353255 -256.800904) (xy 137.330565 -256.756372) (xy 137.315121 -256.70884)
			(xy 137.307302 -256.659477) (xy 136.059931 -256.659477) (xy 136.059922 -256.659934) (xy 136.051758 -256.710168)
			(xy 136.035642 -256.758442) (xy 136.011991 -256.803505) (xy 135.981418 -256.844191) (xy 135.944714 -256.879446)
			(xy 135.90283 -256.908356) (xy 135.856851 -256.930173) (xy 135.807967 -256.944333) (xy 135.757446 -256.950467)
			(xy 135.706594 -256.948418) (xy 135.65673 -256.938238) (xy 135.609144 -256.920191) (xy 135.56507 -256.894745)
			(xy 135.525648 -256.862558) (xy 135.4919 -256.824464) (xy 135.464699 -256.78145) (xy 135.444751 -256.73463)
			(xy 135.432572 -256.685216) (xy 135.428477 -256.634488) (xy 135.122666 -256.634488) (xy 135.122176 -256.659477)
			(xy 135.114357 -256.70884) (xy 135.098913 -256.756372) (xy 135.076223 -256.800904) (xy 135.046847 -256.841337)
			(xy 135.011507 -256.876677) (xy 134.971074 -256.906053) (xy 134.926542 -256.928743) (xy 134.87901 -256.944187)
			(xy 134.829647 -256.952006) (xy 134.779669 -256.952006) (xy 134.730306 -256.944187) (xy 134.682774 -256.928743)
			(xy 134.638242 -256.906053) (xy 134.597809 -256.876677) (xy 134.562469 -256.841337) (xy 134.533093 -256.800904)
			(xy 134.510403 -256.756372) (xy 134.494959 -256.70884) (xy 134.48714 -256.659477) (xy 134.182376 -256.659477)
			(xy 134.174557 -256.70884) (xy 134.159113 -256.756372) (xy 134.136423 -256.800904) (xy 134.107047 -256.841337)
			(xy 134.071707 -256.876677) (xy 134.031274 -256.906053) (xy 133.986742 -256.928743) (xy 133.93921 -256.944187)
			(xy 133.889847 -256.952006) (xy 133.839869 -256.952006) (xy 133.790506 -256.944187) (xy 133.742974 -256.928743)
			(xy 133.698442 -256.906053) (xy 133.658009 -256.876677) (xy 133.622669 -256.841337) (xy 133.593293 -256.800904)
			(xy 133.570603 -256.756372) (xy 133.555159 -256.70884) (xy 133.54734 -256.659477) (xy 133.240023 -256.659477)
			(xy 133.240014 -256.659934) (xy 133.23185 -256.710168) (xy 133.215734 -256.758442) (xy 133.192083 -256.803505)
			(xy 133.16151 -256.844191) (xy 133.124806 -256.879446) (xy 133.082922 -256.908356) (xy 133.036943 -256.930173)
			(xy 132.988059 -256.944333) (xy 132.937538 -256.950467) (xy 132.886686 -256.948418) (xy 132.836822 -256.938238)
			(xy 132.789236 -256.920191) (xy 132.745162 -256.894745) (xy 132.70574 -256.862558) (xy 132.671992 -256.824464)
			(xy 132.644791 -256.78145) (xy 132.624843 -256.73463) (xy 132.612664 -256.685216) (xy 132.608569 -256.634488)
			(xy 132.302758 -256.634488) (xy 132.302268 -256.659477) (xy 132.294449 -256.70884) (xy 132.279005 -256.756372)
			(xy 132.256315 -256.800904) (xy 132.226939 -256.841337) (xy 132.191599 -256.876677) (xy 132.151166 -256.906053)
			(xy 132.106634 -256.928743) (xy 132.059102 -256.944187) (xy 132.009739 -256.952006) (xy 131.959761 -256.952006)
			(xy 131.910398 -256.944187) (xy 131.862866 -256.928743) (xy 131.818334 -256.906053) (xy 131.777901 -256.876677)
			(xy 131.742561 -256.841337) (xy 131.713185 -256.800904) (xy 131.690495 -256.756372) (xy 131.675051 -256.70884)
			(xy 131.667232 -256.659477) (xy 131.362214 -256.659477) (xy 131.354395 -256.70884) (xy 131.338951 -256.756372)
			(xy 131.316261 -256.800904) (xy 131.286885 -256.841337) (xy 131.251545 -256.876677) (xy 131.211112 -256.906053)
			(xy 131.16658 -256.928743) (xy 131.119048 -256.944187) (xy 131.069685 -256.952006) (xy 131.019707 -256.952006)
			(xy 130.970344 -256.944187) (xy 130.922812 -256.928743) (xy 130.87828 -256.906053) (xy 130.837847 -256.876677)
			(xy 130.802507 -256.841337) (xy 130.773131 -256.800904) (xy 130.750441 -256.756372) (xy 130.734997 -256.70884)
			(xy 130.727178 -256.659477) (xy 129.480061 -256.659477) (xy 129.480052 -256.659934) (xy 129.471888 -256.710168)
			(xy 129.455772 -256.758442) (xy 129.432121 -256.803505) (xy 129.401548 -256.844191) (xy 129.364844 -256.879446)
			(xy 129.32296 -256.908356) (xy 129.276981 -256.930173) (xy 129.228097 -256.944333) (xy 129.177576 -256.950467)
			(xy 129.126724 -256.948418) (xy 129.07686 -256.938238) (xy 129.029274 -256.920191) (xy 128.9852 -256.894745)
			(xy 128.945778 -256.862558) (xy 128.91203 -256.824464) (xy 128.884829 -256.78145) (xy 128.864881 -256.73463)
			(xy 128.852702 -256.685216) (xy 128.848607 -256.634488) (xy 128.542796 -256.634488) (xy 128.542306 -256.659477)
			(xy 128.534487 -256.70884) (xy 128.519043 -256.756372) (xy 128.496353 -256.800904) (xy 128.466977 -256.841337)
			(xy 128.431637 -256.876677) (xy 128.391204 -256.906053) (xy 128.346672 -256.928743) (xy 128.29914 -256.944187)
			(xy 128.249777 -256.952006) (xy 128.199799 -256.952006) (xy 128.150436 -256.944187) (xy 128.102904 -256.928743)
			(xy 128.058372 -256.906053) (xy 128.017939 -256.876677) (xy 127.982599 -256.841337) (xy 127.953223 -256.800904)
			(xy 127.930533 -256.756372) (xy 127.915089 -256.70884) (xy 127.90727 -256.659477) (xy 126.662198 -256.659477)
			(xy 126.654379 -256.70884) (xy 126.638935 -256.756372) (xy 126.616245 -256.800904) (xy 126.586869 -256.841337)
			(xy 126.551529 -256.876677) (xy 126.511096 -256.906053) (xy 126.466564 -256.928743) (xy 126.419032 -256.944187)
			(xy 126.369669 -256.952006) (xy 126.319691 -256.952006) (xy 126.270328 -256.944187) (xy 126.222796 -256.928743)
			(xy 126.178264 -256.906053) (xy 126.137831 -256.876677) (xy 126.102491 -256.841337) (xy 126.073115 -256.800904)
			(xy 126.050425 -256.756372) (xy 126.034981 -256.70884) (xy 126.027162 -256.659477) (xy 124.782344 -256.659477)
			(xy 124.774525 -256.70884) (xy 124.759081 -256.756372) (xy 124.736391 -256.800904) (xy 124.707015 -256.841337)
			(xy 124.671675 -256.876677) (xy 124.631242 -256.906053) (xy 124.58671 -256.928743) (xy 124.539178 -256.944187)
			(xy 124.489815 -256.952006) (xy 124.439837 -256.952006) (xy 124.390474 -256.944187) (xy 124.342942 -256.928743)
			(xy 124.29841 -256.906053) (xy 124.257977 -256.876677) (xy 124.222637 -256.841337) (xy 124.193261 -256.800904)
			(xy 124.170571 -256.756372) (xy 124.155127 -256.70884) (xy 124.147308 -256.659477) (xy 122.902236 -256.659477)
			(xy 122.894417 -256.70884) (xy 122.878973 -256.756372) (xy 122.856283 -256.800904) (xy 122.826907 -256.841337)
			(xy 122.791567 -256.876677) (xy 122.751134 -256.906053) (xy 122.706602 -256.928743) (xy 122.65907 -256.944187)
			(xy 122.609707 -256.952006) (xy 122.559729 -256.952006) (xy 122.510366 -256.944187) (xy 122.462834 -256.928743)
			(xy 122.418302 -256.906053) (xy 122.377869 -256.876677) (xy 122.342529 -256.841337) (xy 122.313153 -256.800904)
			(xy 122.290463 -256.756372) (xy 122.275019 -256.70884) (xy 122.2672 -256.659477) (xy 117.885464 -256.659477)
			(xy 117.885464 -256.759456) (xy 117.885044 -256.769479) (xy 117.877381 -256.788002) (xy 117.863208 -256.802177)
			(xy 117.844687 -256.809842) (xy 117.834664 -256.810256) (xy 117.620288 -256.810256) (xy 117.620288 -256.8194)
			(xy 117.61988 -256.829423) (xy 117.612208 -256.847942) (xy 117.598032 -256.862115) (xy 117.579511 -256.869783)
			(xy 117.569488 -256.8702) (xy 117.365526 -256.8702) (xy 117.344919 -256.869671) (xy 117.304479 -256.861714)
			(xy 117.266316 -256.846149) (xy 117.231846 -256.823553) (xy 117.202351 -256.794765) (xy 117.178924 -256.760855)
			(xy 117.162436 -256.723082) (xy 117.1575 -256.703068) (xy 117.156251 -256.698245) (xy 117.15216 -256.689163)
			(xy 117.149372 -256.685034) (xy 117.134104 -256.662422) (xy 117.109905 -256.613525) (xy 117.09345 -256.561508)
			(xy 117.085124 -256.507589) (xy 117.084602 -256.48031) (xy 116.590572 -256.48031) (xy 116.590572 -256.54254)
			(xy 116.590113 -256.563587) (xy 116.581863 -256.604865) (xy 116.565692 -256.643729) (xy 116.542224 -256.678675)
			(xy 116.512368 -256.708349) (xy 116.477281 -256.731604) (xy 116.438319 -256.747539) (xy 116.396992 -256.755537)
			(xy 116.375942 -256.7559) (xy 116.375434 -256.7559) (xy 116.076222 -256.7559) (xy 116.075714 -256.7559)
			(xy 116.054669 -256.755454) (xy 116.01335 -256.747467) (xy 115.974395 -256.731544) (xy 115.939312 -256.708301)
			(xy 115.90946 -256.678637) (xy 115.885994 -256.643703) (xy 115.869824 -256.604849) (xy 115.861576 -256.563582)
			(xy 115.861084 -256.54254) (xy 115.861084 -256.503932) (xy 115.858798 -256.496312) (xy 115.850838 -256.469843)
			(xy 115.842297 -256.415236) (xy 115.84178 -256.3876) (xy 115.640612 -256.3876) (xy 115.640612 -256.54254)
			(xy 115.640213 -256.563591) (xy 115.63196 -256.604876) (xy 115.615783 -256.643746) (xy 115.592307 -256.678695)
			(xy 115.562442 -256.708371) (xy 115.527344 -256.731623) (xy 115.488372 -256.747553) (xy 115.447036 -256.755542)
			(xy 115.425982 -256.7559) (xy 115.425474 -256.7559) (xy 115.126262 -256.7559) (xy 115.125754 -256.7559)
			(xy 115.104707 -256.755508) (xy 115.063386 -256.747511) (xy 115.02443 -256.731578) (xy 114.989348 -256.708326)
			(xy 114.959497 -256.678655) (xy 114.936033 -256.643715) (xy 114.919864 -256.604856) (xy 114.911616 -256.563584)
			(xy 114.911124 -256.54254) (xy 114.911124 -256.503932) (xy 114.908838 -256.496312) (xy 114.900879 -256.469843)
			(xy 114.892337 -256.415236) (xy 114.89182 -256.3876) (xy 114.690652 -256.3876) (xy 114.690652 -256.54254)
			(xy 114.690213 -256.563588) (xy 114.681962 -256.604869) (xy 114.665789 -256.643735) (xy 114.642318 -256.678681)
			(xy 114.61246 -256.708356) (xy 114.577369 -256.73161) (xy 114.538403 -256.747543) (xy 114.497073 -256.755539)
			(xy 114.476022 -256.7559) (xy 114.475514 -256.7559) (xy 114.176302 -256.7559) (xy 114.175794 -256.7559)
			(xy 114.154748 -256.755472) (xy 114.113429 -256.747482) (xy 114.074473 -256.731555) (xy 114.03939 -256.708309)
			(xy 114.009539 -256.678643) (xy 113.986074 -256.643707) (xy 113.969904 -256.604852) (xy 113.961656 -256.563583)
			(xy 113.961164 -256.54254) (xy 113.961164 -256.503932) (xy 113.958878 -256.496312) (xy 113.95092 -256.469842)
			(xy 113.942377 -256.415236) (xy 113.94186 -256.3876) (xy 113.740692 -256.3876) (xy 113.740692 -256.54254)
			(xy 113.740213 -256.563586) (xy 113.731964 -256.604861) (xy 113.715794 -256.643723) (xy 113.692329 -256.678668)
			(xy 113.662477 -256.708342) (xy 113.627393 -256.731597) (xy 113.588435 -256.747534) (xy 113.54711 -256.755535)
			(xy 113.526062 -256.7559) (xy 113.525554 -256.7559) (xy 113.226342 -256.7559) (xy 113.225834 -256.7559)
			(xy 113.204787 -256.755527) (xy 113.163464 -256.747526) (xy 113.124508 -256.731589) (xy 113.089426 -256.708335)
			(xy 113.059575 -256.678662) (xy 113.036112 -256.643719) (xy 113.019943 -256.604859) (xy 113.011695 -256.563585)
			(xy 113.011204 -256.54254) (xy 113.011204 -256.503932) (xy 113.008918 -256.496312) (xy 113.000958 -256.469843)
			(xy 112.992417 -256.415236) (xy 112.9919 -256.3876) (xy 112.790732 -256.3876) (xy 112.790732 -256.54254)
			(xy 112.790313 -256.56359) (xy 112.782061 -256.604872) (xy 112.765886 -256.64374) (xy 112.742413 -256.678688)
			(xy 112.712551 -256.708364) (xy 112.677456 -256.731617) (xy 112.638488 -256.747548) (xy 112.597154 -256.755541)
			(xy 112.576102 -256.7559) (xy 112.575594 -256.7559) (xy 112.276382 -256.7559) (xy 112.275874 -256.7559)
			(xy 112.254828 -256.75549) (xy 112.213507 -256.747496) (xy 112.174552 -256.731566) (xy 112.139469 -256.708317)
			(xy 112.109618 -256.678649) (xy 112.086153 -256.643711) (xy 112.069984 -256.604854) (xy 112.061736 -256.563583)
			(xy 112.061244 -256.54254) (xy 112.061244 -256.504694) (xy 112.058958 -256.497074) (xy 112.050895 -256.470427)
			(xy 112.04222 -256.415436) (xy 112.041686 -256.3876) (xy 111.840772 -256.3876) (xy 111.840772 -256.54254)
			(xy 111.840313 -256.563587) (xy 111.832063 -256.604865) (xy 111.815892 -256.643729) (xy 111.792424 -256.678675)
			(xy 111.762568 -256.708349) (xy 111.727481 -256.731604) (xy 111.688519 -256.747539) (xy 111.647192 -256.755537)
			(xy 111.626142 -256.7559) (xy 111.625634 -256.7559) (xy 111.326422 -256.7559) (xy 111.325914 -256.7559)
			(xy 111.304869 -256.755454) (xy 111.26355 -256.747467) (xy 111.224595 -256.731544) (xy 111.189512 -256.708301)
			(xy 111.15966 -256.678637) (xy 111.136194 -256.643703) (xy 111.120024 -256.604849) (xy 111.111776 -256.563582)
			(xy 111.111284 -256.54254) (xy 111.111284 -256.504694) (xy 111.108998 -256.497074) (xy 111.100933 -256.470427)
			(xy 111.09226 -256.415436) (xy 111.091726 -256.3876) (xy 110.890304 -256.3876) (xy 110.890304 -256.54254)
			(xy 110.889813 -256.563585) (xy 110.881565 -256.604859) (xy 110.865396 -256.64372) (xy 110.841933 -256.678664)
			(xy 110.812082 -256.708338) (xy 110.777 -256.731593) (xy 110.738044 -256.747531) (xy 110.696722 -256.755534)
			(xy 110.675674 -256.7559) (xy 110.67542 -256.7559) (xy 110.376208 -256.7559) (xy 110.375954 -256.7559)
			(xy 110.354907 -256.755508) (xy 110.313586 -256.747511) (xy 110.27463 -256.731578) (xy 110.239548 -256.708326)
			(xy 110.209697 -256.678655) (xy 110.186233 -256.643715) (xy 110.170064 -256.604856) (xy 110.161816 -256.563584)
			(xy 110.161324 -256.54254) (xy 110.161324 -256.503932) (xy 110.158784 -256.496312) (xy 110.150826 -256.469842)
			(xy 110.142283 -256.415236) (xy 110.141766 -256.3876) (xy 109.940344 -256.3876) (xy 109.940344 -256.54254)
			(xy 109.939913 -256.563589) (xy 109.931662 -256.60487) (xy 109.915488 -256.643737) (xy 109.892016 -256.678684)
			(xy 109.862156 -256.708359) (xy 109.827064 -256.731613) (xy 109.788097 -256.747545) (xy 109.746765 -256.755539)
			(xy 109.725714 -256.7559) (xy 109.72546 -256.7559) (xy 109.426248 -256.7559) (xy 109.425994 -256.7559)
			(xy 109.404948 -256.755472) (xy 109.363629 -256.747482) (xy 109.324673 -256.731555) (xy 109.28959 -256.708309)
			(xy 109.259739 -256.678643) (xy 109.236274 -256.643707) (xy 109.220104 -256.604852) (xy 109.211856 -256.563583)
			(xy 109.211364 -256.54254) (xy 109.211364 -256.503932) (xy 109.208824 -256.496312) (xy 109.200864 -256.469843)
			(xy 109.192323 -256.415236) (xy 109.191806 -256.3876) (xy 108.990384 -256.3876) (xy 108.990384 -256.54254)
			(xy 108.989913 -256.563586) (xy 108.981664 -256.604863) (xy 108.965493 -256.643726) (xy 108.942027 -256.678671)
			(xy 108.912174 -256.708345) (xy 108.877088 -256.7316) (xy 108.838128 -256.747536) (xy 108.796803 -256.755536)
			(xy 108.775754 -256.7559) (xy 108.7755 -256.7559) (xy 108.476288 -256.7559) (xy 108.476034 -256.7559)
			(xy 108.454987 -256.755527) (xy 108.413664 -256.747526) (xy 108.374708 -256.731589) (xy 108.339626 -256.708335)
			(xy 108.309775 -256.678662) (xy 108.286312 -256.643719) (xy 108.270143 -256.604859) (xy 108.261895 -256.563585)
			(xy 108.261404 -256.54254) (xy 108.261404 -256.503932) (xy 108.258864 -256.496312) (xy 108.250905 -256.469842)
			(xy 108.242363 -256.415236) (xy 108.241846 -256.3876) (xy 108.040424 -256.3876) (xy 108.040424 -256.54254)
			(xy 108.040013 -256.56359) (xy 108.031761 -256.604874) (xy 108.015585 -256.643742) (xy 107.992111 -256.678691)
			(xy 107.962248 -256.708366) (xy 107.927152 -256.73162) (xy 107.888182 -256.74755) (xy 107.846847 -256.755541)
			(xy 107.825794 -256.7559) (xy 107.82554 -256.7559) (xy 107.526328 -256.7559) (xy 107.526074 -256.7559)
			(xy 107.505028 -256.75549) (xy 107.463707 -256.747496) (xy 107.424752 -256.731566) (xy 107.389669 -256.708317)
			(xy 107.359818 -256.678649) (xy 107.336353 -256.643711) (xy 107.320184 -256.604854) (xy 107.311936 -256.563583)
			(xy 107.311444 -256.54254) (xy 107.311444 -256.503932) (xy 107.308904 -256.496312) (xy 107.300944 -256.469843)
			(xy 107.292403 -256.415236) (xy 107.291886 -256.3876) (xy 106.748651 -256.3876) (xy 106.753976 -256.406221)
			(xy 106.760862 -256.455454) (xy 106.76128 -256.48031) (xy 106.760872 -256.504883) (xy 106.754108 -256.553562)
			(xy 106.740723 -256.60085) (xy 106.72097 -256.645853) (xy 106.708448 -256.667) (xy 106.705765 -256.671511)
			(xy 106.702185 -256.681378) (xy 106.701336 -256.686558) (xy 106.697827 -256.708097) (xy 106.683089 -256.749168)
			(xy 106.66033 -256.786397) (xy 106.630495 -256.818239) (xy 106.594823 -256.84337) (xy 106.554797 -256.860747)
			(xy 106.512079 -256.869647) (xy 106.490262 -256.8702) (xy 106.2355 -256.8702) (xy 106.2355 -256.861056)
			(xy 106.235048 -256.851046) (xy 106.227374 -256.832553) (xy 106.21321 -256.818401) (xy 106.194711 -256.810743)
			(xy 106.1847 -256.810256) (xy 105.684828 -256.810256) (xy 105.684828 -256.8194) (xy 105.684313 -256.829404)
			(xy 105.676658 -256.847891) (xy 105.662514 -256.862042) (xy 105.644032 -256.869707) (xy 105.634028 -256.8702)
			(xy 105.430066 -256.8702) (xy 105.408098 -256.869661) (xy 105.3651 -256.860622) (xy 105.324845 -256.843013)
			(xy 105.289022 -256.817572) (xy 105.259133 -256.785366) (xy 105.236433 -256.747747) (xy 105.228644 -256.727198)
			(xy 105.227017 -256.722796) (xy 105.222423 -256.714614) (xy 105.2195 -256.710942) (xy 105.203563 -256.691544)
			(xy 105.176728 -256.649115) (xy 105.156121 -256.603336) (xy 105.142151 -256.555116) (xy 105.135095 -256.505411)
			(xy 105.134664 -256.48031) (xy 103.129006 -256.48031) (xy 103.144688 -256.511084) (xy 103.160134 -256.558614)
			(xy 103.167957 -256.607975) (xy 103.16845 -256.632964) (xy 103.16845 -256.633218) (xy 103.167841 -256.661246)
			(xy 103.158006 -256.716434) (xy 103.148892 -256.742946) (xy 103.145844 -256.751328) (xy 103.145844 -256.88417)
			(xy 103.145844 -256.884678) (xy 103.145538 -256.905729) (xy 103.137531 -256.947058) (xy 103.121588 -256.98602)
			(xy 103.098324 -257.021106) (xy 103.068641 -257.050957) (xy 103.033687 -257.074419) (xy 102.994816 -257.090582)
			(xy 102.953533 -257.098822) (xy 102.932484 -257.099308) (xy 102.677468 -257.099308) (xy 102.677468 -257.090164)
			(xy 102.677041 -257.08015) (xy 102.669363 -257.061651) (xy 102.655191 -257.047499) (xy 102.636683 -257.039846)
			(xy 102.626668 -257.039364) (xy 102.4636 -257.039364) (xy 102.453574 -257.03898) (xy 102.43505 -257.031303)
			(xy 102.420877 -257.017119) (xy 102.413213 -256.99859) (xy 102.4128 -256.988564) (xy 101.214545 -256.988564)
			(xy 101.194391 -257.019593) (xy 101.164668 -257.049964) (xy 101.129536 -257.073875) (xy 101.090377 -257.090384)
			(xy 101.048731 -257.098843) (xy 101.027484 -257.099308) (xy 100.790502 -257.099308) (xy 100.780679 -257.099783)
			(xy 100.76252 -257.107282) (xy 100.7486 -257.121144) (xy 100.741025 -257.139271) (xy 100.740464 -257.149092)
			(xy 100.740464 -257.43027) (xy 105.134664 -257.43027) (xy 105.135213 -257.402287) (xy 105.143972 -257.347012)
			(xy 105.161269 -257.293787) (xy 105.186678 -257.243922) (xy 105.219574 -257.198646) (xy 105.259148 -257.159073)
			(xy 105.304424 -257.126177) (xy 105.354289 -257.100768) (xy 105.407514 -257.083471) (xy 105.462789 -257.074713)
			(xy 105.490772 -257.074162) (xy 105.491534 -257.074162) (xy 105.516911 -257.074623) (xy 105.567144 -257.081884)
			(xy 105.59161 -257.08864) (xy 105.598722 -257.090672) (xy 105.65511 -257.090672) (xy 105.684828 -257.12039)
			(xy 105.684828 -257.13182) (xy 105.698798 -257.141218) (xy 105.705387 -257.145537) (xy 105.720389 -257.150321)
			(xy 105.728262 -257.150616) (xy 106.167682 -257.150616) (xy 106.175556 -257.150319) (xy 106.19056 -257.145542)
			(xy 106.197146 -257.141218) (xy 106.206395 -257.13472) (xy 106.225586 -257.122772) (xy 106.2355 -257.117342)
			(xy 106.2355 -257.090672) (xy 106.297222 -257.090672) (xy 106.304334 -257.08864) (xy 106.328989 -257.081856)
			(xy 106.379604 -257.074587) (xy 106.405172 -257.074162) (xy 106.433069 -257.074704) (xy 106.488186 -257.083376)
			(xy 106.5149 -257.091434) (xy 106.522774 -257.093212) (xy 106.541275 -257.096482) (xy 106.576827 -257.108615)
			(xy 106.609701 -257.126796) (xy 106.638876 -257.15046) (xy 106.663449 -257.178874) (xy 106.673396 -257.194812)
			(xy 106.678222 -257.201416) (xy 106.693849 -257.220752) (xy 106.72015 -257.262939) (xy 106.740327 -257.308375)
			(xy 106.753988 -257.356176) (xy 106.760866 -257.405412) (xy 106.76128 -257.43027) (xy 106.760854 -257.454842)
			(xy 106.754095 -257.503521) (xy 106.740715 -257.550809) (xy 106.720968 -257.595812) (xy 106.708448 -257.61696)
			(xy 106.705775 -257.621477) (xy 106.702188 -257.631339) (xy 106.701336 -257.636518) (xy 106.697797 -257.658051)
			(xy 106.683067 -257.699122) (xy 106.660314 -257.736353) (xy 106.651998 -257.74523) (xy 107.561634 -257.74523)
			(xy 107.561634 -257.744722) (xy 107.562087 -257.718779) (xy 107.56966 -257.667449) (xy 107.584618 -257.617765)
			(xy 107.606643 -257.570786) (xy 107.620562 -257.548888) (xy 107.626658 -257.535934) (xy 107.632876 -257.5176)
			(xy 107.650861 -257.483324) (xy 107.67472 -257.452845) (xy 107.703674 -257.427155) (xy 107.736778 -257.407095)
			(xy 107.772951 -257.393319) (xy 107.811013 -257.386277) (xy 107.830366 -257.38582) (xy 108.05541 -257.38582)
			(xy 108.085128 -257.415538) (xy 108.085128 -257.431032) (xy 108.099098 -257.438906) (xy 108.105014 -257.442124)
			(xy 108.11802 -257.445596) (xy 108.124752 -257.445764) (xy 108.6358 -257.445764) (xy 108.6358 -257.43662)
			(xy 108.636236 -257.4266) (xy 108.6439 -257.408084) (xy 108.658067 -257.393911) (xy 108.67658 -257.38624)
			(xy 108.6866 -257.38582) (xy 108.890562 -257.38582) (xy 108.910247 -257.386307) (xy 108.948945 -257.393544)
			(xy 108.985659 -257.407759) (xy 109.01914 -257.428471) (xy 109.048251 -257.454976) (xy 109.060488 -257.470402)
			(xy 109.0676 -257.477768) (xy 109.086226 -257.494767) (xy 109.118976 -257.53311) (xy 109.145989 -257.575691)
			(xy 109.166724 -257.621657) (xy 109.180767 -257.670088) (xy 109.187835 -257.720017) (xy 109.18825 -257.74523)
			(xy 109.18825 -257.745484) (xy 109.187724 -257.773501) (xy 109.17893 -257.828841) (xy 109.16157 -257.882118)
			(xy 109.136076 -257.932017) (xy 109.103077 -257.977303) (xy 109.083602 -257.997452) (xy 109.082441 -257.998976)
			(xy 110.866428 -257.998976) (xy 110.866428 -257.491484) (xy 110.866807 -257.481458) (xy 110.874488 -257.462936)
			(xy 110.888673 -257.448763) (xy 110.907202 -257.441099) (xy 110.917228 -257.440684) (xy 111.131096 -257.440684)
			(xy 111.131096 -257.43154) (xy 111.131552 -257.421522) (xy 111.139208 -257.403007) (xy 111.15337 -257.388833)
			(xy 111.171878 -257.381161) (xy 111.181896 -257.38074) (xy 111.386112 -257.38074) (xy 111.406168 -257.381205)
			(xy 111.445576 -257.388683) (xy 111.482893 -257.403393) (xy 111.516804 -257.424816) (xy 111.546115 -257.452198)
			(xy 111.558324 -257.468116) (xy 111.565944 -257.476498) (xy 111.586516 -257.495045) (xy 111.622159 -257.537441)
			(xy 111.650812 -257.584842) (xy 111.671786 -257.636106) (xy 111.684574 -257.689998) (xy 111.688869 -257.74522)
			(xy 111.684568 -257.800441) (xy 111.671774 -257.854331) (xy 111.650794 -257.905593) (xy 111.622136 -257.952991)
			(xy 111.586488 -257.995383) (xy 111.582515 -257.998976) (xy 113.11636 -257.998976) (xy 113.11636 -257.491484)
			(xy 113.116874 -257.48148) (xy 113.124531 -257.462996) (xy 113.138676 -257.448845) (xy 113.157156 -257.441178)
			(xy 113.16716 -257.440684) (xy 113.381028 -257.440684) (xy 113.381028 -257.43154) (xy 113.381453 -257.421518)
			(xy 113.389115 -257.402996) (xy 113.403286 -257.388822) (xy 113.421806 -257.381155) (xy 113.431828 -257.38074)
			(xy 113.636044 -257.38074) (xy 113.656101 -257.381182) (xy 113.69551 -257.388666) (xy 113.732827 -257.403381)
			(xy 113.766738 -257.42481) (xy 113.796048 -257.452196) (xy 113.808256 -257.468116) (xy 113.815876 -257.476498)
			(xy 113.836446 -257.495046) (xy 113.872086 -257.537444) (xy 113.900737 -257.584845) (xy 113.921708 -257.636108)
			(xy 113.934496 -257.689999) (xy 113.93879 -257.74522) (xy 113.934489 -257.80044) (xy 113.921696 -257.854329)
			(xy 113.900719 -257.90559) (xy 113.872063 -257.952989) (xy 113.836419 -257.995382) (xy 113.832445 -257.998976)
			(xy 115.716304 -257.998976) (xy 115.716304 -257.491484) (xy 115.716775 -257.481475) (xy 115.72444 -257.462982)
			(xy 115.738599 -257.448829) (xy 115.757095 -257.441171) (xy 115.767104 -257.440684) (xy 115.980972 -257.440684)
			(xy 115.980972 -257.43154) (xy 115.981452 -257.421525) (xy 115.989103 -257.403014) (xy 116.003257 -257.388841)
			(xy 116.021757 -257.381165) (xy 116.031772 -257.38074) (xy 116.235988 -257.38074) (xy 116.256046 -257.381151)
			(xy 116.295457 -257.388643) (xy 116.332774 -257.403366) (xy 116.366684 -257.424801) (xy 116.372536 -257.43027)
			(xy 117.084602 -257.43027) (xy 117.085016 -257.405139) (xy 117.092087 -257.355377) (xy 117.106085 -257.307103)
			(xy 117.126732 -257.261277) (xy 117.153618 -257.21881) (xy 117.186207 -257.180545) (xy 117.204744 -257.16357)
			(xy 117.208554 -257.15976) (xy 117.222934 -257.144842) (xy 117.256293 -257.120277) (xy 117.293749 -257.102578)
			(xy 117.31371 -257.097022) (xy 117.31879 -257.095498) (xy 117.348268 -257.08549) (xy 117.409585 -257.074758)
			(xy 117.44071 -257.074162) (xy 117.466279 -257.074578) (xy 117.516896 -257.081843) (xy 117.541548 -257.08864)
			(xy 117.54866 -257.090672) (xy 117.620288 -257.090672) (xy 117.620288 -257.094736) (xy 117.620888 -257.107255)
			(xy 117.632618 -257.129372) (xy 117.64264 -257.1369) (xy 117.648736 -257.141218) (xy 117.655317 -257.145551)
			(xy 117.670325 -257.150326) (xy 117.6782 -257.150616) (xy 117.834664 -257.150616) (xy 117.844685 -257.151049)
			(xy 117.863204 -257.158711) (xy 117.877378 -257.172879) (xy 117.885047 -257.191395) (xy 117.885464 -257.201416)
			(xy 117.885464 -257.709416) (xy 117.885093 -257.719443) (xy 117.877411 -257.737967) (xy 117.863223 -257.75214)
			(xy 117.844691 -257.759803) (xy 117.834664 -257.760216) (xy 117.620288 -257.760216) (xy 117.620288 -257.76936)
			(xy 117.619847 -257.77938) (xy 117.612188 -257.797899) (xy 117.598022 -257.812073) (xy 117.579508 -257.819742)
			(xy 117.569488 -257.82016) (xy 117.365526 -257.82016) (xy 117.344917 -257.819662) (xy 117.304473 -257.811703)
			(xy 117.266307 -257.796135) (xy 117.231837 -257.773534) (xy 117.202341 -257.744741) (xy 117.178917 -257.710824)
			(xy 117.162433 -257.673044) (xy 117.1575 -257.653028) (xy 117.156261 -257.648202) (xy 117.152163 -257.639122)
			(xy 117.149372 -257.634994) (xy 117.13413 -257.612365) (xy 117.109925 -257.563474) (xy 117.093463 -257.511462)
			(xy 117.085128 -257.457547) (xy 117.084602 -257.43027) (xy 116.372536 -257.43027) (xy 116.395993 -257.452193)
			(xy 116.4082 -257.468116) (xy 116.41582 -257.476498) (xy 116.436393 -257.495044) (xy 116.472038 -257.53744)
			(xy 116.500694 -257.584841) (xy 116.521669 -257.636105) (xy 116.534458 -257.689997) (xy 116.538754 -257.74522)
			(xy 116.534452 -257.800442) (xy 116.521657 -257.854333) (xy 116.500676 -257.905595) (xy 116.485678 -257.930397)
			(xy 120.852967 -257.930397) (xy 120.857266 -257.875178) (xy 120.870058 -257.821289) (xy 120.891035 -257.770029)
			(xy 120.919692 -257.722633) (xy 120.955338 -257.680242) (xy 120.975882 -257.661664) (xy 120.983502 -257.653282)
			(xy 120.99569 -257.637334) (xy 121.024998 -257.609913) (xy 121.058907 -257.588443) (xy 121.096227 -257.573677)
			(xy 121.135647 -257.566135) (xy 121.155714 -257.565652) (xy 121.410476 -257.565652) (xy 121.410476 -257.574796)
			(xy 121.410991 -257.5848) (xy 121.418645 -257.603287) (xy 121.432789 -257.61744) (xy 121.451272 -257.625104)
			(xy 121.461276 -257.625596) (xy 121.624852 -257.625596) (xy 121.63487 -257.626059) (xy 121.653385 -257.633712)
			(xy 121.667559 -257.647871) (xy 121.675231 -257.666379) (xy 121.675652 -257.676396) (xy 121.675652 -257.930397)
			(xy 122.77855 -257.930397) (xy 122.782849 -257.875179) (xy 122.79564 -257.821291) (xy 122.816615 -257.770031)
			(xy 122.84527 -257.722635) (xy 122.880914 -257.680243) (xy 122.901456 -257.661664) (xy 122.909076 -257.653282)
			(xy 122.92128 -257.637346) (xy 122.950583 -257.609925) (xy 122.984489 -257.588452) (xy 123.021805 -257.573684)
			(xy 123.061222 -257.566138) (xy 123.081288 -257.565652) (xy 123.336304 -257.565652) (xy 123.336304 -257.574796)
			(xy 123.336723 -257.584818) (xy 123.344392 -257.603335) (xy 123.358565 -257.617508) (xy 123.377082 -257.625177)
			(xy 123.387104 -257.625596) (xy 123.550172 -257.625596) (xy 123.560191 -257.626043) (xy 123.578706 -257.633703)
			(xy 123.59288 -257.647867) (xy 123.600551 -257.666377) (xy 123.600972 -257.676396) (xy 123.600972 -258.08051)
			(xy 124.645928 -258.08051) (xy 124.645928 -258.080002) (xy 124.645928 -257.780282) (xy 124.646317 -257.759234)
			(xy 124.654311 -257.717911) (xy 124.670242 -257.678953) (xy 124.693494 -257.643868) (xy 124.723165 -257.614016)
			(xy 124.758108 -257.590552) (xy 124.796969 -257.574385) (xy 124.838243 -257.566141) (xy 124.859288 -257.565652)
			(xy 125.114304 -257.565652) (xy 125.114304 -257.58013) (xy 125.149102 -257.59156) (xy 125.14961 -257.59156)
			(xy 125.166181 -257.597084) (xy 125.198244 -257.610954) (xy 125.213618 -257.619246) (xy 125.219348 -257.622189)
			(xy 125.231817 -257.625405) (xy 125.238256 -257.625596) (xy 125.328172 -257.625596) (xy 125.338191 -257.626043)
			(xy 125.356706 -257.633703) (xy 125.37088 -257.647867) (xy 125.378551 -257.666377) (xy 125.378972 -257.676396)
			(xy 125.378972 -257.820922) (xy 125.381258 -257.828034) (xy 125.388299 -257.853035) (xy 125.395819 -257.904426)
			(xy 125.396244 -257.930396) (xy 125.395777 -257.956362) (xy 125.388252 -258.007747) (xy 125.381258 -258.032758)
			(xy 125.378972 -258.03987) (xy 125.378972 -258.184396) (xy 125.378577 -258.194421) (xy 125.370903 -258.212943)
			(xy 125.356723 -258.227116) (xy 125.338197 -258.234781) (xy 125.328172 -258.235196) (xy 125.238256 -258.235196)
			(xy 125.231816 -258.235386) (xy 125.219343 -258.238592) (xy 125.213618 -258.241546) (xy 125.198241 -258.249833)
			(xy 125.166178 -258.263698) (xy 125.14961 -258.269232) (xy 125.149102 -258.269232) (xy 125.114304 -258.280662)
			(xy 125.114304 -258.29514) (xy 124.859288 -258.29514) (xy 124.83824 -258.294687) (xy 124.796959 -258.286441)
			(xy 124.758092 -258.270271) (xy 124.723145 -258.246803) (xy 124.693469 -258.216946) (xy 124.670215 -258.181856)
			(xy 124.654282 -258.142891) (xy 124.646289 -258.101561) (xy 124.645928 -258.08051) (xy 123.600972 -258.08051)
			(xy 123.600972 -258.184396) (xy 123.600577 -258.194421) (xy 123.592903 -258.212943) (xy 123.578723 -258.227116)
			(xy 123.560197 -258.234781) (xy 123.550172 -258.235196) (xy 123.336304 -258.235196) (xy 123.336304 -258.24434)
			(xy 123.335845 -258.25435) (xy 123.328173 -258.272842) (xy 123.314011 -258.286993) (xy 123.295514 -258.294652)
			(xy 123.285504 -258.29514) (xy 123.081288 -258.29514) (xy 123.061219 -258.294644) (xy 123.021791 -258.287132)
			(xy 122.984465 -258.272377) (xy 122.950558 -258.2509) (xy 122.921268 -258.223458) (xy 122.909076 -258.20751)
			(xy 122.901456 -258.199128) (xy 122.88091 -258.180553) (xy 122.845267 -258.138161) (xy 122.816613 -258.090764)
			(xy 122.795638 -258.039504) (xy 122.782848 -257.985616) (xy 122.77855 -257.930397) (xy 121.675652 -257.930397)
			(xy 121.675652 -258.184396) (xy 121.675276 -258.194423) (xy 121.667598 -258.212949) (xy 121.653412 -258.227123)
			(xy 121.634879 -258.234785) (xy 121.624852 -258.235196) (xy 121.410476 -258.235196) (xy 121.410476 -258.24434)
			(xy 121.410044 -258.254353) (xy 121.402367 -258.27285) (xy 121.388197 -258.287003) (xy 121.36969 -258.294657)
			(xy 121.359676 -258.29514) (xy 121.155714 -258.29514) (xy 121.135643 -258.294697) (xy 121.096212 -258.287172)
			(xy 121.058885 -258.272404) (xy 121.024979 -258.250915) (xy 120.995691 -258.223462) (xy 120.983502 -258.20751)
			(xy 120.975882 -258.199128) (xy 120.955335 -258.180554) (xy 120.919689 -258.138163) (xy 120.891033 -258.090766)
			(xy 120.870057 -258.039506) (xy 120.857265 -257.985617) (xy 120.852967 -257.930397) (xy 116.485678 -257.930397)
			(xy 116.472015 -257.952992) (xy 116.436365 -257.995384) (xy 116.41582 -258.013962) (xy 116.4082 -258.022344)
			(xy 116.396001 -258.038269) (xy 116.366682 -258.065645) (xy 116.332768 -258.087065) (xy 116.295452 -258.101778)
			(xy 116.256044 -258.109264) (xy 116.235988 -258.10972) (xy 115.980972 -258.10972) (xy 115.980972 -258.100576)
			(xy 115.980599 -258.09055) (xy 115.972916 -258.072027) (xy 115.958729 -258.057855) (xy 115.940199 -258.050191)
			(xy 115.930172 -258.049776) (xy 115.767104 -258.049776) (xy 115.75708 -258.049377) (xy 115.738559 -258.041704)
			(xy 115.724385 -258.027525) (xy 115.716719 -258.009) (xy 115.716304 -257.998976) (xy 113.832445 -257.998976)
			(xy 113.815876 -258.013962) (xy 113.808256 -258.022344) (xy 113.796024 -258.038243) (xy 113.766714 -258.06562)
			(xy 113.732808 -258.087045) (xy 113.695499 -258.101764) (xy 113.656098 -258.109259) (xy 113.636044 -258.10972)
			(xy 113.381028 -258.10972) (xy 113.381028 -258.100576) (xy 113.380532 -258.09057) (xy 113.37287 -258.072083)
			(xy 113.35872 -258.057932) (xy 113.340234 -258.050268) (xy 113.330228 -258.049776) (xy 113.16716 -258.049776)
			(xy 113.157147 -258.049344) (xy 113.13865 -258.041667) (xy 113.124497 -258.027497) (xy 113.116843 -258.00899)
			(xy 113.11636 -257.998976) (xy 111.582515 -257.998976) (xy 111.565944 -258.013962) (xy 111.558324 -258.022344)
			(xy 111.546111 -258.038258) (xy 111.516796 -258.065634) (xy 111.482885 -258.087057) (xy 111.445572 -258.101772)
			(xy 111.406167 -258.109262) (xy 111.386112 -258.10972) (xy 111.131096 -258.10972) (xy 111.131096 -258.100576)
			(xy 111.130632 -258.090566) (xy 111.122963 -258.072073) (xy 111.108803 -258.057921) (xy 111.090306 -258.050263)
			(xy 111.080296 -258.049776) (xy 110.917228 -258.049776) (xy 110.907206 -258.049357) (xy 110.888685 -258.041692)
			(xy 110.874511 -258.027519) (xy 110.866844 -258.008998) (xy 110.866428 -257.998976) (xy 109.082441 -257.998976)
			(xy 109.075474 -258.00812) (xy 109.06383 -258.027272) (xy 109.033903 -258.060629) (xy 108.997695 -258.087034)
			(xy 108.956787 -258.105333) (xy 108.912968 -258.114726) (xy 108.890562 -258.115308) (xy 108.6358 -258.115308)
			(xy 108.6358 -258.106164) (xy 108.635341 -258.096154) (xy 108.62767 -258.077661) (xy 108.613508 -258.06351)
			(xy 108.59501 -258.055851) (xy 108.585 -258.055364) (xy 108.093002 -258.055364) (xy 108.085128 -258.059428)
			(xy 108.085128 -258.064508) (xy 108.084619 -258.074513) (xy 108.076962 -258.092999) (xy 108.062816 -258.107151)
			(xy 108.044332 -258.114815) (xy 108.034328 -258.115308) (xy 107.830366 -258.115308) (xy 107.809911 -258.114796)
			(xy 107.769759 -258.106944) (xy 107.731837 -258.091591) (xy 107.697531 -258.0693) (xy 107.668096 -258.040885)
			(xy 107.64461 -258.007386) (xy 107.627931 -257.970028) (xy 107.622848 -257.950208) (xy 107.621787 -257.946108)
			(xy 107.618467 -257.938318) (xy 107.616244 -257.934714) (xy 107.603282 -257.913347) (xy 107.582866 -257.86773)
			(xy 107.569032 -257.819706) (xy 107.562052 -257.770219) (xy 107.561634 -257.74523) (xy 106.651998 -257.74523)
			(xy 106.630484 -257.768196) (xy 106.594816 -257.793329) (xy 106.554793 -257.810706) (xy 106.512078 -257.819607)
			(xy 106.490262 -257.82016) (xy 106.2355 -257.82016) (xy 106.2355 -257.811016) (xy 106.235068 -257.800996)
			(xy 106.227403 -257.782479) (xy 106.213234 -257.768306) (xy 106.19472 -257.760636) (xy 106.1847 -257.760216)
			(xy 105.684828 -257.760216) (xy 105.684828 -257.76936) (xy 105.684348 -257.779375) (xy 105.676697 -257.797886)
			(xy 105.662543 -257.812059) (xy 105.644043 -257.819735) (xy 105.634028 -257.82016) (xy 105.430066 -257.82016)
			(xy 105.408101 -257.819582) (xy 105.365107 -257.810546) (xy 105.324856 -257.792943) (xy 105.289033 -257.767509)
			(xy 105.259143 -257.735313) (xy 105.236436 -257.697703) (xy 105.228644 -257.677158) (xy 105.227025 -257.672752)
			(xy 105.222426 -257.664572) (xy 105.2195 -257.660902) (xy 105.203591 -257.641482) (xy 105.176752 -257.599059)
			(xy 105.156139 -257.553286) (xy 105.142163 -257.505071) (xy 105.135099 -257.45537) (xy 105.134664 -257.43027)
			(xy 100.740464 -257.43027) (xy 100.740464 -257.515868) (xy 100.740991 -257.52569) (xy 100.748583 -257.543812)
			(xy 100.762514 -257.557668) (xy 100.780678 -257.565163) (xy 100.790502 -257.565652) (xy 101.009196 -257.565652)
			(xy 101.029062 -257.566111) (xy 101.068102 -257.573505) (xy 101.105097 -257.588001) (xy 101.138768 -257.609097)
			(xy 101.16795 -257.636063) (xy 101.180138 -257.651758) (xy 101.180392 -257.652266) (xy 101.18217 -257.654552)
			(xy 101.18852 -257.66141) (xy 101.190552 -257.663188) (xy 101.210838 -257.681742) (xy 101.246009 -257.723992)
			(xy 101.274271 -257.771145) (xy 101.294951 -257.82208) (xy 101.30756 -257.875588) (xy 101.311796 -257.930396)
			(xy 101.584506 -257.930396) (xy 101.584888 -257.906522) (xy 101.591279 -257.859205) (xy 101.603947 -257.813169)
			(xy 101.622662 -257.769242) (xy 101.634544 -257.748532) (xy 101.636518 -257.745006) (xy 101.639457 -257.737479)
			(xy 101.640386 -257.733546) (xy 101.64528 -257.71346) (xy 101.661712 -257.675532) (xy 101.685128 -257.641469)
			(xy 101.714655 -257.612541) (xy 101.74919 -257.589828) (xy 101.787447 -257.574176) (xy 101.827999 -257.566168)
			(xy 101.848666 -257.565652) (xy 102.07371 -257.565652) (xy 102.103428 -257.59537) (xy 102.103428 -257.613658)
			(xy 102.114096 -257.619246) (xy 102.119776 -257.622142) (xy 102.132109 -257.625362) (xy 102.13848 -257.625596)
			(xy 102.6541 -257.625596) (xy 102.6541 -257.616452) (xy 102.654549 -257.606441) (xy 102.662224 -257.587948)
			(xy 102.676389 -257.573797) (xy 102.694889 -257.566139) (xy 102.7049 -257.565652) (xy 102.908862 -257.565652)
			(xy 102.928932 -257.566115) (xy 102.968362 -257.573635) (xy 103.005688 -257.588398) (xy 103.039595 -257.609883)
			(xy 103.068884 -257.637332) (xy 103.081074 -257.653282) (xy 103.088694 -257.661664) (xy 103.109234 -257.680246)
			(xy 103.144882 -257.722635) (xy 103.173541 -257.77003) (xy 103.194519 -257.82129) (xy 103.207312 -257.875178)
			(xy 103.211611 -257.930397) (xy 103.207313 -257.985616) (xy 103.194521 -258.039505) (xy 103.173543 -258.090765)
			(xy 103.144885 -258.138161) (xy 103.109238 -258.180551) (xy 103.088694 -258.199128) (xy 103.081074 -258.20751)
			(xy 103.068839 -258.22342) (xy 103.039544 -258.250844) (xy 103.005646 -258.272321) (xy 102.968337 -258.287096)
			(xy 102.928925 -258.29465) (xy 102.908862 -258.29514) (xy 102.6541 -258.29514) (xy 102.6541 -258.285996)
			(xy 102.653615 -258.275988) (xy 102.645954 -258.257496) (xy 102.6318 -258.243344) (xy 102.613308 -258.235684)
			(xy 102.6033 -258.235196) (xy 102.13848 -258.235196) (xy 102.132104 -258.235402) (xy 102.119761 -258.238613)
			(xy 102.114096 -258.241546) (xy 102.103428 -258.247134) (xy 102.103428 -258.265422) (xy 102.07371 -258.29514)
			(xy 101.848666 -258.29514) (xy 101.827991 -258.294691) (xy 101.787419 -258.286706) (xy 101.749143 -258.27106)
			(xy 101.714594 -258.248339) (xy 101.685065 -258.219392) (xy 101.661661 -258.185302) (xy 101.645256 -258.147345)
			(xy 101.640386 -258.127246) (xy 101.63946 -258.123312) (xy 101.636522 -258.115784) (xy 101.634544 -258.11226)
			(xy 101.622658 -258.091554) (xy 101.603973 -258.047617) (xy 101.591314 -258.001581) (xy 101.584907 -257.954268)
			(xy 101.584506 -257.930396) (xy 101.311796 -257.930396) (xy 101.311796 -257.930397) (xy 101.307561 -257.985207)
			(xy 101.294953 -258.038715) (xy 101.274273 -258.089651) (xy 101.246012 -258.136804) (xy 101.210841 -258.179054)
			(xy 101.190552 -258.197604) (xy 101.18852 -258.199382) (xy 101.18217 -258.20624) (xy 101.180392 -258.208526)
			(xy 101.180138 -258.209034) (xy 101.167932 -258.224711) (xy 101.138741 -258.251656) (xy 101.105072 -258.272742)
			(xy 101.068087 -258.287242) (xy 101.029058 -258.294657) (xy 101.009196 -258.29514) (xy 100.790502 -258.29514)
			(xy 100.780674 -258.295614) (xy 100.762504 -258.30311) (xy 100.748566 -258.31697) (xy 100.740969 -258.335099)
			(xy 100.740464 -258.344924) (xy 100.740464 -258.38023) (xy 105.134664 -258.38023) (xy 105.13524 -258.352247)
			(xy 105.143991 -258.296969) (xy 105.161281 -258.243741) (xy 105.186685 -258.193872) (xy 105.219577 -258.148592)
			(xy 105.259148 -258.109015) (xy 105.304423 -258.076115) (xy 105.354287 -258.050703) (xy 105.407513 -258.033404)
			(xy 105.462789 -258.024645) (xy 105.490772 -258.024122) (xy 105.491534 -258.024122) (xy 105.516911 -258.024585)
			(xy 105.567144 -258.031845) (xy 105.59161 -258.0386) (xy 105.598722 -258.040632) (xy 105.65511 -258.040632)
			(xy 105.684828 -258.07035) (xy 105.684828 -258.08178) (xy 105.698798 -258.091178) (xy 105.70539 -258.095493)
			(xy 105.72039 -258.10028) (xy 105.728262 -258.100576) (xy 106.167682 -258.100576) (xy 106.175555 -258.100268)
			(xy 106.190559 -258.095498) (xy 106.197146 -258.091178) (xy 106.206394 -258.084678) (xy 106.225586 -258.072732)
			(xy 106.2355 -258.067302) (xy 106.2355 -258.040632) (xy 106.297222 -258.040632) (xy 106.304334 -258.0386)
			(xy 106.328989 -258.031815) (xy 106.379604 -258.024547) (xy 106.405172 -258.024122) (xy 106.433069 -258.024666)
			(xy 106.488186 -258.033337) (xy 106.5149 -258.041394) (xy 106.522774 -258.043172) (xy 106.541281 -258.046415)
			(xy 106.576835 -258.058552) (xy 106.609709 -258.076738) (xy 106.638883 -258.100409) (xy 106.663452 -258.12883)
			(xy 106.673396 -258.144772) (xy 106.678222 -258.151376) (xy 106.69383 -258.170726) (xy 106.720135 -258.21291)
			(xy 106.740315 -258.258342) (xy 106.75398 -258.30614) (xy 106.760864 -258.355373) (xy 106.76128 -258.38023)
			(xy 117.084602 -258.38023) (xy 117.085056 -258.3551) (xy 117.09212 -258.30534) (xy 117.10611 -258.257067)
			(xy 117.126749 -258.211241) (xy 117.153627 -258.168773) (xy 117.18621 -258.130506) (xy 117.204744 -258.11353)
			(xy 117.208554 -258.10972) (xy 117.222927 -258.094796) (xy 117.25629 -258.070234) (xy 117.293749 -258.052537)
			(xy 117.31371 -258.046982) (xy 117.31879 -258.045458) (xy 117.348268 -258.035449) (xy 117.409585 -258.024718)
			(xy 117.44071 -258.024122) (xy 117.466279 -258.024536) (xy 117.516896 -258.031802) (xy 117.541548 -258.0386)
			(xy 117.54866 -258.040632) (xy 117.620288 -258.040632) (xy 117.620288 -258.044696) (xy 117.620912 -258.057212)
			(xy 117.632625 -258.079329) (xy 117.64264 -258.08686) (xy 117.648736 -258.091178) (xy 117.655319 -258.095507)
			(xy 117.670326 -258.100285) (xy 117.6782 -258.100576) (xy 117.834664 -258.100576) (xy 117.84468 -258.101049)
			(xy 117.863192 -258.108702) (xy 117.877364 -258.122858) (xy 117.88504 -258.141361) (xy 117.885464 -258.151376)
			(xy 117.885464 -258.659376) (xy 117.88506 -258.6694) (xy 117.877391 -258.687923) (xy 117.863213 -258.702098)
			(xy 117.844688 -258.709762) (xy 117.834664 -258.710176) (xy 117.620288 -258.710176) (xy 117.620288 -258.71932)
			(xy 117.619828 -258.72933) (xy 117.61216 -258.747825) (xy 117.597998 -258.761978) (xy 117.579499 -258.769635)
			(xy 117.569488 -258.77012) (xy 117.365526 -258.77012) (xy 117.34492 -258.769575) (xy 117.304482 -258.76162)
			(xy 117.26632 -258.746056) (xy 117.231851 -258.723462) (xy 117.202356 -258.694678) (xy 117.178928 -258.660771)
			(xy 117.162438 -258.623) (xy 117.1575 -258.602988) (xy 117.156246 -258.598167) (xy 117.152158 -258.589084)
			(xy 117.149372 -258.584954) (xy 117.134113 -258.562336) (xy 117.109912 -258.513441) (xy 117.093454 -258.461426)
			(xy 117.085125 -258.407508) (xy 117.084602 -258.38023) (xy 106.76128 -258.38023) (xy 106.760836 -258.404802)
			(xy 106.754082 -258.453479) (xy 106.740708 -258.500768) (xy 106.720966 -258.545772) (xy 106.708448 -258.56692)
			(xy 106.705786 -258.571443) (xy 106.702192 -258.581301) (xy 106.701336 -258.586478) (xy 106.697767 -258.608006)
			(xy 106.683044 -258.649077) (xy 106.660297 -258.686308) (xy 106.630472 -258.718153) (xy 106.594809 -258.743287)
			(xy 106.554789 -258.760665) (xy 106.512076 -258.769566) (xy 106.490262 -258.77012) (xy 106.2355 -258.77012)
			(xy 106.2355 -258.760976) (xy 106.235032 -258.750967) (xy 106.227364 -258.732474) (xy 106.213205 -258.718322)
			(xy 106.194709 -258.710664) (xy 106.1847 -258.710176) (xy 105.684828 -258.710176) (xy 105.684828 -258.71932)
			(xy 105.684329 -258.729326) (xy 105.676668 -258.747812) (xy 105.662519 -258.761964) (xy 105.644033 -258.769628)
			(xy 105.634028 -258.77012) (xy 105.430066 -258.77012) (xy 105.408099 -258.769568) (xy 105.365102 -258.76053)
			(xy 105.324848 -258.742923) (xy 105.289026 -258.717485) (xy 105.259136 -258.685282) (xy 105.236433 -258.647666)
			(xy 105.228644 -258.627118) (xy 105.227012 -258.622718) (xy 105.222422 -258.614534) (xy 105.2195 -258.610862)
			(xy 105.203572 -258.591457) (xy 105.176736 -258.54903) (xy 105.156127 -258.503253) (xy 105.142155 -258.455034)
			(xy 105.135097 -258.405331) (xy 105.134664 -258.38023) (xy 100.740464 -258.38023) (xy 100.740464 -258.415536)
			(xy 100.740831 -258.425442) (xy 100.748339 -258.443771) (xy 100.762308 -258.457814) (xy 100.780598 -258.465417)
			(xy 100.790502 -258.465828) (xy 101.008942 -258.465828) (xy 101.028868 -258.466277) (xy 101.068028 -258.473679)
			(xy 101.105135 -258.488218) (xy 101.138899 -258.50939) (xy 101.168149 -258.536459) (xy 101.180392 -258.552188)
			(xy 101.1809 -258.55295) (xy 101.181662 -258.553712) (xy 101.18852 -258.561332) (xy 101.190552 -258.56311)
			(xy 101.210836 -258.581664) (xy 101.246004 -258.623914) (xy 101.274263 -258.671065) (xy 101.29494 -258.721998)
			(xy 101.307546 -258.775504) (xy 101.31178 -258.830312) (xy 101.31178 -258.830318) (xy 101.584506 -258.830318)
			(xy 101.584897 -258.806445) (xy 101.591286 -258.759128) (xy 101.603951 -258.713091) (xy 101.622664 -258.669165)
			(xy 101.634544 -258.648454) (xy 101.636514 -258.644926) (xy 101.639455 -258.6374) (xy 101.640386 -258.633468)
			(xy 101.645305 -258.613396) (xy 101.661721 -258.575478) (xy 101.685131 -258.541431) (xy 101.714659 -258.512529)
			(xy 101.749199 -258.489852) (xy 101.787459 -258.474251) (xy 101.828007 -258.466308) (xy 101.848666 -258.465828)
			(xy 102.07371 -258.465828) (xy 102.103428 -258.495546) (xy 102.103428 -258.51358) (xy 102.113842 -258.519168)
			(xy 102.119619 -258.522193) (xy 102.132218 -258.525537) (xy 102.138734 -258.525772) (xy 102.6541 -258.525772)
			(xy 102.6541 -258.516628) (xy 102.654543 -258.506609) (xy 102.662203 -258.488092) (xy 102.676369 -258.473919)
			(xy 102.694881 -258.466248) (xy 102.7049 -258.465828) (xy 102.908862 -258.465828) (xy 102.928919 -258.466262)
			(xy 102.968329 -258.473749) (xy 103.005645 -258.488466) (xy 103.039556 -258.509896) (xy 103.068866 -258.537284)
			(xy 103.081074 -258.553204) (xy 103.088694 -258.561586) (xy 103.109256 -258.580144) (xy 103.144904 -258.622537)
			(xy 103.173562 -258.669936) (xy 103.194539 -258.721199) (xy 103.20733 -258.77509) (xy 103.2089 -258.795266)
			(xy 107.561634 -258.795266) (xy 107.562012 -258.771392) (xy 107.568406 -258.724075) (xy 107.581075 -258.678039)
			(xy 107.599791 -258.634113) (xy 107.611672 -258.613402) (xy 107.613654 -258.60988) (xy 107.616588 -258.60235)
			(xy 107.617514 -258.598416) (xy 107.622372 -258.578328) (xy 107.6388 -258.540409) (xy 107.662222 -258.506362)
			(xy 107.691759 -258.477462) (xy 107.726308 -258.454788) (xy 107.764576 -258.439191) (xy 107.805131 -258.431253)
			(xy 107.825794 -258.430776) (xy 108.050838 -258.430776) (xy 108.080556 -258.460494) (xy 108.080556 -258.478528)
			(xy 108.09097 -258.484116) (xy 108.096744 -258.487146) (xy 108.109345 -258.490488) (xy 108.115862 -258.49072)
			(xy 108.631228 -258.49072) (xy 108.631228 -258.481576) (xy 108.631601 -258.47155) (xy 108.639284 -258.453027)
			(xy 108.653471 -258.438855) (xy 108.672001 -258.431191) (xy 108.682028 -258.430776) (xy 108.88599 -258.430776)
			(xy 108.906047 -258.431211) (xy 108.945455 -258.438701) (xy 108.982771 -258.453419) (xy 109.016681 -258.474848)
			(xy 109.045992 -258.502233) (xy 109.058202 -258.518152) (xy 109.065822 -258.526534) (xy 109.086331 -258.545148)
			(xy 109.121976 -258.587534) (xy 109.150633 -258.634925) (xy 109.171611 -258.68618) (xy 109.184405 -258.740063)
			(xy 109.188706 -258.795266) (xy 110.061756 -258.795266) (xy 110.062131 -258.771392) (xy 110.068526 -258.724075)
			(xy 110.081195 -258.678039) (xy 110.099912 -258.634113) (xy 110.111794 -258.613402) (xy 110.113778 -258.609881)
			(xy 110.11671 -258.60235) (xy 110.117636 -258.598416) (xy 110.122474 -258.578322) (xy 110.138905 -258.540402)
			(xy 110.162329 -258.506354) (xy 110.19187 -258.477453) (xy 110.226423 -258.454781) (xy 110.264694 -258.439186)
			(xy 110.305252 -258.431251) (xy 110.325916 -258.430776) (xy 110.551214 -258.430776) (xy 110.580932 -258.460494)
			(xy 110.580932 -258.478528) (xy 110.591092 -258.484116) (xy 110.596922 -258.487177) (xy 110.609656 -258.490514)
			(xy 110.616238 -258.49072) (xy 111.131096 -258.49072) (xy 111.131096 -258.481576) (xy 111.131568 -258.471567)
			(xy 111.139235 -258.453076) (xy 111.153392 -258.438924) (xy 111.171887 -258.431264) (xy 111.181896 -258.430776)
			(xy 111.386112 -258.430776) (xy 111.406166 -258.431267) (xy 111.445571 -258.438742) (xy 111.482887 -258.453447)
			(xy 111.516798 -258.474864) (xy 111.546112 -258.502238) (xy 111.558324 -258.518152) (xy 111.565944 -258.526534)
			(xy 111.586452 -258.545149) (xy 111.622095 -258.587535) (xy 111.65075 -258.634927) (xy 111.671727 -258.686181)
			(xy 111.68452 -258.740064) (xy 111.688821 -258.795278) (xy 111.684527 -258.850492) (xy 111.671741 -258.904376)
			(xy 111.65077 -258.955633) (xy 111.622121 -259.003028) (xy 111.586483 -259.045419) (xy 111.582511 -259.049012)
			(xy 113.11636 -259.049012) (xy 113.11636 -258.54152) (xy 113.116903 -258.531519) (xy 113.124549 -258.513035)
			(xy 113.138684 -258.498883) (xy 113.157159 -258.491215) (xy 113.16716 -258.49072) (xy 113.381028 -258.49072)
			(xy 113.381028 -258.481576) (xy 113.381401 -258.47155) (xy 113.389084 -258.453027) (xy 113.403271 -258.438855)
			(xy 113.421801 -258.431191) (xy 113.431828 -258.430776) (xy 113.636044 -258.430776) (xy 113.656099 -258.431244)
			(xy 113.695506 -258.438725) (xy 113.732821 -258.453436) (xy 113.766732 -258.474858) (xy 113.796045 -258.502236)
			(xy 113.808256 -258.518152) (xy 113.815876 -258.526534) (xy 113.836382 -258.54515) (xy 113.872022 -258.587537)
			(xy 113.900675 -258.634929) (xy 113.92165 -258.686183) (xy 113.934441 -258.740065) (xy 113.938742 -258.795278)
			(xy 113.934448 -258.850491) (xy 113.921663 -258.904374) (xy 113.900695 -258.955631) (xy 113.872048 -259.003026)
			(xy 113.836414 -259.045418) (xy 113.832441 -259.049012) (xy 115.716304 -259.049012) (xy 115.716304 -258.54152)
			(xy 115.716736 -258.5315) (xy 115.7244 -258.512982) (xy 115.738569 -258.498809) (xy 115.757084 -258.491139)
			(xy 115.767104 -258.49072) (xy 115.980972 -258.49072) (xy 115.980972 -258.481576) (xy 115.981468 -258.47157)
			(xy 115.98913 -258.453083) (xy 116.00328 -258.438932) (xy 116.021766 -258.431268) (xy 116.031772 -258.430776)
			(xy 116.235988 -258.430776) (xy 116.256045 -258.431212) (xy 116.295453 -258.438702) (xy 116.332768 -258.45342)
			(xy 116.366679 -258.474849) (xy 116.39599 -258.502234) (xy 116.4082 -258.518152) (xy 116.41582 -258.526534)
			(xy 116.436329 -258.545148) (xy 116.471975 -258.587534) (xy 116.500632 -258.634925) (xy 116.52161 -258.68618)
			(xy 116.534404 -258.740063) (xy 116.538705 -258.795278) (xy 116.53598 -258.830312) (xy 120.852984 -258.830312)
			(xy 120.85728 -258.775095) (xy 120.87007 -258.721208) (xy 120.891044 -258.66995) (xy 120.919697 -258.622554)
			(xy 120.95534 -258.580164) (xy 120.975882 -258.561586) (xy 120.983502 -258.553204) (xy 120.995686 -258.537267)
			(xy 121.02501 -258.509895) (xy 121.058928 -258.488478) (xy 121.096248 -258.473768) (xy 121.135657 -258.466283)
			(xy 121.155714 -258.465828) (xy 121.410476 -258.465828) (xy 121.410476 -258.474972) (xy 121.410942 -258.484988)
			(xy 121.418598 -258.5035) (xy 121.432756 -258.517672) (xy 121.45126 -258.525348) (xy 121.461276 -258.525772)
			(xy 121.624852 -258.525772) (xy 121.634867 -258.526258) (xy 121.653377 -258.533907) (xy 121.66755 -258.548059)
			(xy 121.675227 -258.566558) (xy 121.675652 -258.576572) (xy 121.675652 -258.830312) (xy 122.778567 -258.830312)
			(xy 122.782863 -258.775096) (xy 122.795651 -258.72121) (xy 122.816624 -258.669952) (xy 122.845275 -258.622556)
			(xy 122.880915 -258.580165) (xy 122.901456 -258.561586) (xy 122.909076 -258.553204) (xy 122.921275 -258.537279)
			(xy 122.950596 -258.509906) (xy 122.98451 -258.488487) (xy 123.021826 -258.473775) (xy 123.061232 -258.466286)
			(xy 123.081288 -258.465828) (xy 123.336304 -258.465828) (xy 123.336304 -258.474972) (xy 123.336743 -258.484992)
			(xy 123.344404 -258.503509) (xy 123.358571 -258.517682) (xy 123.377084 -258.525353) (xy 123.387104 -258.525772)
			(xy 123.550172 -258.525772) (xy 123.560174 -258.52631) (xy 123.57866 -258.533955) (xy 123.592813 -258.548093)
			(xy 123.600479 -258.56657) (xy 123.600972 -258.576572) (xy 123.600972 -258.980178) (xy 124.645928 -258.980178)
			(xy 124.645928 -258.979924) (xy 124.645928 -258.680458) (xy 124.646295 -258.65941) (xy 124.654294 -258.618085)
			(xy 124.670229 -258.579127) (xy 124.693484 -258.544043) (xy 124.723158 -258.514191) (xy 124.758103 -258.490728)
			(xy 124.796966 -258.474561) (xy 124.838242 -258.466317) (xy 124.859288 -258.465828) (xy 125.114304 -258.465828)
			(xy 125.114304 -258.480052) (xy 125.149356 -258.491482) (xy 125.165936 -258.497062) (xy 125.197997 -258.511063)
			(xy 125.213364 -258.519422) (xy 125.219144 -258.522409) (xy 125.231751 -258.525612) (xy 125.238256 -258.525772)
			(xy 125.328172 -258.525772) (xy 125.338174 -258.52631) (xy 125.35666 -258.533955) (xy 125.370813 -258.548093)
			(xy 125.378479 -258.56657) (xy 125.378972 -258.576572) (xy 125.378972 -258.720844) (xy 125.381258 -258.727956)
			(xy 125.388282 -258.752961) (xy 125.395813 -258.804349) (xy 125.396244 -258.830318) (xy 125.395782 -258.856284)
			(xy 125.388254 -258.907669) (xy 125.381258 -258.93268) (xy 125.378972 -258.939792) (xy 125.378972 -259.084064)
			(xy 125.37855 -259.094086) (xy 125.370887 -259.112608) (xy 125.356715 -259.126782) (xy 125.338194 -259.134449)
			(xy 125.328172 -259.134864) (xy 125.238256 -259.134864) (xy 125.231751 -259.135015) (xy 125.219147 -259.138232)
			(xy 125.213364 -259.141214) (xy 125.19799 -259.149559) (xy 125.165929 -259.163556) (xy 125.149356 -259.169154)
			(xy 125.114304 -259.180584) (xy 125.114304 -259.194808) (xy 124.859288 -259.194808) (xy 124.838244 -259.194287)
			(xy 124.796972 -259.186044) (xy 124.758111 -259.169881) (xy 124.723168 -259.146422) (xy 124.693494 -259.116575)
			(xy 124.670237 -259.081497) (xy 124.654299 -259.042544) (xy 124.646295 -259.001224) (xy 124.645928 -258.980178)
			(xy 123.600972 -258.980178) (xy 123.600972 -259.084064) (xy 123.60055 -259.094086) (xy 123.592887 -259.112608)
			(xy 123.578715 -259.126782) (xy 123.560194 -259.134449) (xy 123.550172 -259.134864) (xy 123.336304 -259.134864)
			(xy 123.336304 -259.144008) (xy 123.335818 -259.154016) (xy 123.328157 -259.172507) (xy 123.314003 -259.186659)
			(xy 123.295512 -259.194319) (xy 123.285504 -259.194808) (xy 123.081288 -259.194808) (xy 123.061233 -259.194324)
			(xy 123.021827 -259.186847) (xy 122.984512 -259.172141) (xy 122.9506 -259.150723) (xy 122.921287 -259.123347)
			(xy 122.909076 -259.107432) (xy 122.901456 -259.09905) (xy 122.880932 -259.080452) (xy 122.845289 -259.038063)
			(xy 122.816634 -258.990669) (xy 122.795658 -258.939413) (xy 122.782867 -258.885527) (xy 122.778567 -258.830312)
			(xy 121.675652 -258.830312) (xy 121.675652 -259.084064) (xy 121.67525 -259.094089) (xy 121.667583 -259.112614)
			(xy 121.653404 -259.126789) (xy 121.634877 -259.134452) (xy 121.624852 -259.134864) (xy 121.410476 -259.134864)
			(xy 121.410476 -259.144008) (xy 121.410086 -259.154033) (xy 121.402409 -259.172554) (xy 121.388228 -259.186727)
			(xy 121.369701 -259.194393) (xy 121.359676 -259.194808) (xy 121.155714 -259.194808) (xy 121.135657 -259.194377)
			(xy 121.096248 -259.186887) (xy 121.058932 -259.172168) (xy 121.025022 -259.150738) (xy 120.995711 -259.123351)
			(xy 120.983502 -259.107432) (xy 120.975882 -259.09905) (xy 120.955357 -259.080453) (xy 120.919711 -259.038065)
			(xy 120.891054 -258.990671) (xy 120.870077 -258.939414) (xy 120.857284 -258.885528) (xy 120.852984 -258.830312)
			(xy 116.53598 -258.830312) (xy 116.534411 -258.850493) (xy 116.521624 -258.904378) (xy 116.500652 -258.955635)
			(xy 116.472001 -259.00303) (xy 116.43636 -259.04542) (xy 116.41582 -259.063998) (xy 116.4082 -259.07238)
			(xy 116.39601 -259.088313) (xy 116.366688 -259.115686) (xy 116.332772 -259.137104) (xy 116.295453 -259.151815)
			(xy 116.256045 -259.1593) (xy 116.235988 -259.159756) (xy 115.980972 -259.159756) (xy 115.980972 -259.150612)
			(xy 115.98057 -259.140588) (xy 115.972899 -259.122066) (xy 115.958721 -259.107892) (xy 115.940196 -259.100227)
			(xy 115.930172 -259.099812) (xy 115.767104 -259.099812) (xy 115.757098 -259.099309) (xy 115.738609 -259.091653)
			(xy 115.724456 -259.077505) (xy 115.716794 -259.059018) (xy 115.716304 -259.049012) (xy 113.832441 -259.049012)
			(xy 113.815876 -259.063998) (xy 113.808256 -259.07238) (xy 113.796034 -259.088286) (xy 113.76672 -259.115661)
			(xy 113.732811 -259.137084) (xy 113.6955 -259.151801) (xy 113.656098 -259.159295) (xy 113.636044 -259.159756)
			(xy 113.381028 -259.159756) (xy 113.381028 -259.150612) (xy 113.380503 -259.140609) (xy 113.372852 -259.122122)
			(xy 113.358711 -259.10797) (xy 113.340231 -259.100305) (xy 113.330228 -259.099812) (xy 113.16716 -259.099812)
			(xy 113.157151 -259.099345) (xy 113.138661 -259.091674) (xy 113.12451 -259.077516) (xy 113.11685 -259.059021)
			(xy 113.11636 -259.049012) (xy 111.582511 -259.049012) (xy 111.565944 -259.063998) (xy 111.558324 -259.07238)
			(xy 111.54612 -259.088302) (xy 111.516802 -259.115675) (xy 111.482889 -259.137095) (xy 111.445573 -259.151809)
			(xy 111.406168 -259.159298) (xy 111.386112 -259.159756) (xy 111.131096 -259.159756) (xy 111.131096 -259.150612)
			(xy 111.130671 -259.140591) (xy 111.123004 -259.122073) (xy 111.108833 -259.107901) (xy 111.090317 -259.100231)
			(xy 111.080296 -259.099812) (xy 110.616238 -259.099812) (xy 110.609649 -259.099954) (xy 110.596907 -259.103313)
			(xy 110.591092 -259.106416) (xy 110.580932 -259.112004) (xy 110.580932 -259.130038) (xy 110.551214 -259.159756)
			(xy 110.325916 -259.159756) (xy 110.305264 -259.159249) (xy 110.264737 -259.151262) (xy 110.226498 -259.13564)
			(xy 110.191972 -259.112966) (xy 110.162443 -259.084083) (xy 110.13901 -259.050066) (xy 110.122547 -259.012182)
			(xy 110.117636 -258.992116) (xy 110.1167 -258.988185) (xy 110.113769 -258.980655) (xy 110.111794 -258.97713)
			(xy 110.099941 -258.956406) (xy 110.081246 -258.912476) (xy 110.068578 -258.866446) (xy 110.062162 -258.819137)
			(xy 110.061756 -258.795266) (xy 109.188706 -258.795266) (xy 109.188707 -258.795278) (xy 109.184412 -258.850493)
			(xy 109.171625 -258.904378) (xy 109.150653 -258.955635) (xy 109.122002 -259.00303) (xy 109.086362 -259.04542)
			(xy 109.065822 -259.063998) (xy 109.058202 -259.07238) (xy 109.046011 -259.088312) (xy 109.016689 -259.115685)
			(xy 108.982773 -259.137103) (xy 108.945455 -259.151814) (xy 108.906047 -259.1593) (xy 108.88599 -259.159756)
			(xy 108.631228 -259.159756) (xy 108.631228 -259.150612) (xy 108.630703 -259.140609) (xy 108.623052 -259.122122)
			(xy 108.608911 -259.10797) (xy 108.590431 -259.100305) (xy 108.580428 -259.099812) (xy 108.115862 -259.099812)
			(xy 108.109342 -259.100027) (xy 108.096735 -259.103364) (xy 108.09097 -259.106416) (xy 108.080556 -259.112004)
			(xy 108.080556 -259.130038) (xy 108.050838 -259.159756) (xy 107.825794 -259.159756) (xy 107.805144 -259.15918)
			(xy 107.764621 -259.151208) (xy 107.726384 -259.135599) (xy 107.691857 -259.112936) (xy 107.662326 -259.084063)
			(xy 107.638892 -259.050055) (xy 107.622426 -259.012179) (xy 107.617514 -258.992116) (xy 107.61658 -258.988184)
			(xy 107.613648 -258.980655) (xy 107.611672 -258.97713) (xy 107.599817 -258.956407) (xy 107.581123 -258.912477)
			(xy 107.568456 -258.866446) (xy 107.56204 -258.819137) (xy 107.561634 -258.795266) (xy 103.2089 -258.795266)
			(xy 103.211628 -258.830312) (xy 103.207327 -258.885533) (xy 103.194532 -258.939424) (xy 103.173551 -258.990685)
			(xy 103.14489 -259.038082) (xy 103.10924 -259.080472) (xy 103.088694 -259.09905) (xy 103.081074 -259.107432)
			(xy 103.068829 -259.12332) (xy 103.039522 -259.150699) (xy 103.00562 -259.172126) (xy 102.968314 -259.186847)
			(xy 102.928915 -259.194346) (xy 102.908862 -259.194808) (xy 102.6541 -259.194808) (xy 102.6541 -259.185664)
			(xy 102.653641 -259.175654) (xy 102.64597 -259.157161) (xy 102.631808 -259.14301) (xy 102.61331 -259.135351)
			(xy 102.6033 -259.134864) (xy 102.138734 -259.134864) (xy 102.132213 -259.135074) (xy 102.119607 -259.138415)
			(xy 102.113842 -259.141468) (xy 102.103428 -259.147056) (xy 102.103428 -259.16509) (xy 102.07371 -259.194808)
			(xy 101.848666 -259.194808) (xy 101.828013 -259.194294) (xy 101.787484 -259.186314) (xy 101.749243 -259.170697)
			(xy 101.714714 -259.148024) (xy 101.685185 -259.119141) (xy 101.661754 -259.085122) (xy 101.645294 -259.047236)
			(xy 101.640386 -259.027168) (xy 101.639455 -259.023236) (xy 101.636521 -259.015707) (xy 101.634544 -259.012182)
			(xy 101.622667 -258.991471) (xy 101.60398 -258.947536) (xy 101.591318 -258.901502) (xy 101.584909 -258.85419)
			(xy 101.584506 -258.830318) (xy 101.31178 -258.830318) (xy 101.307542 -258.885119) (xy 101.294933 -258.938624)
			(xy 101.274252 -258.989556) (xy 101.24599 -259.036706) (xy 101.210819 -259.078953) (xy 101.190552 -259.097526)
			(xy 101.18852 -259.099304) (xy 101.181662 -259.106924) (xy 101.1809 -259.107686) (xy 101.180392 -259.108448)
			(xy 101.168173 -259.124196) (xy 101.138918 -259.151263) (xy 101.105147 -259.172429) (xy 101.068035 -259.186958)
			(xy 101.02887 -259.194346) (xy 101.008942 -259.194808) (xy 100.790502 -259.194808) (xy 100.780603 -259.195228)
			(xy 100.762322 -259.202831) (xy 100.748364 -259.216873) (xy 100.74087 -259.235198) (xy 100.740464 -259.2451)
			(xy 100.740464 -259.315712) (xy 100.740981 -259.325541) (xy 100.74303 -259.330444) (xy 105.134664 -259.330444)
			(xy 105.135253 -259.302461) (xy 105.144001 -259.247184) (xy 105.16129 -259.193956) (xy 105.186692 -259.144087)
			(xy 105.219583 -259.098807) (xy 105.259152 -259.059229) (xy 105.304426 -259.026329) (xy 105.354289 -259.000917)
			(xy 105.407514 -258.983618) (xy 105.462789 -258.974859) (xy 105.490772 -258.974336) (xy 105.516139 -258.974766)
			(xy 105.566367 -258.981901) (xy 105.590848 -258.98856) (xy 105.597706 -258.990592) (xy 105.65511 -258.990592)
			(xy 105.684828 -259.02031) (xy 105.684828 -259.031994) (xy 105.69829 -259.041138) (xy 105.704886 -259.045446)
			(xy 105.719882 -259.050238) (xy 105.727754 -259.050536) (xy 106.16819 -259.050536) (xy 106.176064 -259.050239)
			(xy 106.191068 -259.045462) (xy 106.197654 -259.041138) (xy 106.206784 -259.034717) (xy 106.225721 -259.022897)
			(xy 106.2355 -259.017516) (xy 106.2355 -258.990592) (xy 106.298238 -258.990592) (xy 106.305096 -258.98856)
			(xy 106.32957 -258.981868) (xy 106.379803 -258.974726) (xy 106.405172 -258.974336) (xy 106.43267 -258.97484)
			(xy 106.487017 -258.983254) (xy 106.513376 -258.9911) (xy 106.521504 -258.992878) (xy 106.540256 -258.99603)
			(xy 106.576283 -259.008183) (xy 106.609584 -259.026534) (xy 106.639101 -259.050501) (xy 106.663898 -259.079324)
			(xy 106.673904 -259.095494) (xy 106.67873 -259.102352) (xy 106.694223 -259.121672) (xy 106.720349 -259.16374)
			(xy 106.740399 -259.209021) (xy 106.753987 -259.256641) (xy 106.760851 -259.305684) (xy 106.76128 -259.330444)
			(xy 106.761275 -259.330698) (xy 117.084602 -259.330698) (xy 117.084602 -259.330444) (xy 117.085009 -259.305435)
			(xy 117.092019 -259.255909) (xy 117.105895 -259.207854) (xy 117.126363 -259.162214) (xy 117.153018 -259.11989)
			(xy 117.185337 -259.081714) (xy 117.203728 -259.06476) (xy 117.207538 -259.06095) (xy 117.222206 -259.045481)
			(xy 117.256507 -259.020178) (xy 117.295143 -259.002179) (xy 117.315742 -258.996688) (xy 117.320822 -258.995164)
			(xy 117.349835 -258.985439) (xy 117.410117 -258.974967) (xy 117.44071 -258.974336) (xy 117.466077 -258.974758)
			(xy 117.516306 -258.981898) (xy 117.540786 -258.98856) (xy 117.547644 -258.990592) (xy 117.620288 -258.990592)
			(xy 117.620288 -258.995164) (xy 117.620936 -259.007577) (xy 117.632498 -259.029545) (xy 117.642386 -259.037074)
			(xy 117.648228 -259.041138) (xy 117.654815 -259.045461) (xy 117.669818 -259.050244) (xy 117.677692 -259.050536)
			(xy 117.834664 -259.050536) (xy 117.844687 -259.05095) (xy 117.86321 -259.058615) (xy 117.877385 -259.07279)
			(xy 117.88505 -259.091313) (xy 117.885464 -259.101336) (xy 117.885464 -259.609336) (xy 117.885041 -259.61935)
			(xy 117.877362 -259.63785) (xy 117.863189 -259.652003) (xy 117.844679 -259.659655) (xy 117.834664 -259.660136)
			(xy 117.620288 -259.660136) (xy 117.620288 -259.66928) (xy 117.619864 -259.679301) (xy 117.612198 -259.69782)
			(xy 117.598027 -259.711993) (xy 117.579509 -259.719662) (xy 117.569488 -259.72008) (xy 117.365526 -259.72008)
			(xy 117.344945 -259.719582) (xy 117.304548 -259.711679) (xy 117.266415 -259.696181) (xy 117.231959 -259.673662)
			(xy 117.202457 -259.644956) (xy 117.179004 -259.611129) (xy 117.162468 -259.573434) (xy 117.1575 -259.553456)
			(xy 117.156254 -259.548632) (xy 117.152161 -259.539551) (xy 117.149372 -259.535422) (xy 117.134057 -259.512839)
			(xy 117.109856 -259.463934) (xy 117.093405 -259.411908) (xy 117.08509 -259.357981) (xy 117.084602 -259.330698)
			(xy 106.761275 -259.330698) (xy 106.760842 -259.355016) (xy 106.754087 -259.403694) (xy 106.740711 -259.450982)
			(xy 106.720967 -259.495986) (xy 106.708448 -259.517134) (xy 106.705782 -259.521655) (xy 106.702191 -259.531514)
			(xy 106.701336 -259.536692) (xy 106.697661 -259.558182) (xy 106.682907 -259.599194) (xy 106.660151 -259.636368)
			(xy 106.630337 -259.668163) (xy 106.594702 -259.69326) (xy 106.554722 -259.710618) (xy 106.512054 -259.719519)
			(xy 106.490262 -259.72008) (xy 106.2355 -259.72008) (xy 106.2355 -259.710936) (xy 106.235051 -259.700917)
			(xy 106.227393 -259.682401) (xy 106.213229 -259.668227) (xy 106.194719 -259.660556) (xy 106.1847 -259.660136)
			(xy 105.684828 -259.660136) (xy 105.684828 -259.66928) (xy 105.684296 -259.679283) (xy 105.676649 -259.697769)
			(xy 105.662509 -259.711922) (xy 105.64403 -259.719587) (xy 105.634028 -259.72008) (xy 105.430066 -259.72008)
			(xy 105.408139 -259.719511) (xy 105.365204 -259.71059) (xy 105.324995 -259.693089) (xy 105.289206 -259.667747)
			(xy 105.259346 -259.635631) (xy 105.236674 -259.598094) (xy 105.228898 -259.577586) (xy 105.22728 -259.57318)
			(xy 105.22268 -259.565) (xy 105.219754 -259.56133) (xy 105.203754 -259.541937) (xy 105.17684 -259.499473)
			(xy 105.156173 -259.453642) (xy 105.142164 -259.405357) (xy 105.135094 -259.355582) (xy 105.134664 -259.330444)
			(xy 100.74303 -259.330444) (xy 100.748564 -259.343683) (xy 100.762497 -259.357556) (xy 100.780671 -259.365061)
			(xy 100.790502 -259.365496) (xy 101.009196 -259.365496) (xy 101.029062 -259.365956) (xy 101.0681 -259.373351)
			(xy 101.105093 -259.387848) (xy 101.138761 -259.408947) (xy 101.167938 -259.435916) (xy 101.180138 -259.451602)
			(xy 101.180392 -259.45211) (xy 101.18217 -259.454396) (xy 101.18852 -259.461254) (xy 101.190552 -259.463032)
			(xy 101.210834 -259.481586) (xy 101.245999 -259.523835) (xy 101.274254 -259.570985) (xy 101.294929 -259.621917)
			(xy 101.307532 -259.675421) (xy 101.311763 -259.730226) (xy 101.311762 -259.73024) (xy 101.584506 -259.73024)
			(xy 101.584907 -259.706367) (xy 101.591293 -259.65905) (xy 101.603955 -259.613014) (xy 101.622665 -259.569087)
			(xy 101.634544 -259.548376) (xy 101.63653 -259.544856) (xy 101.639461 -259.537324) (xy 101.640386 -259.53339)
			(xy 101.645309 -259.513312) (xy 101.661734 -259.475383) (xy 101.685144 -259.441318) (xy 101.714665 -259.412389)
			(xy 101.749197 -259.389674) (xy 101.787451 -259.374021) (xy 101.828 -259.366012) (xy 101.848666 -259.365496)
			(xy 102.07371 -259.365496) (xy 102.103428 -259.395214) (xy 102.103428 -259.413502) (xy 102.114096 -259.41909)
			(xy 102.119775 -259.421989) (xy 102.132108 -259.425206) (xy 102.13848 -259.42544) (xy 102.6541 -259.42544)
			(xy 102.6541 -259.416296) (xy 102.654585 -259.406288) (xy 102.662246 -259.387796) (xy 102.6764 -259.373644)
			(xy 102.694892 -259.365984) (xy 102.7049 -259.365496) (xy 102.908862 -259.365496) (xy 102.928933 -259.365942)
			(xy 102.968364 -259.373464) (xy 103.005692 -259.38823) (xy 103.039598 -259.40972) (xy 103.068885 -259.437173)
			(xy 103.081074 -259.453126) (xy 103.088694 -259.461508) (xy 103.109278 -259.480043) (xy 103.144926 -259.522439)
			(xy 103.173583 -259.569841) (xy 103.194559 -259.621107) (xy 103.207349 -259.675002) (xy 103.211644 -259.730226)
			(xy 103.207341 -259.78545) (xy 103.194543 -259.839343) (xy 103.192104 -259.845302) (xy 107.561634 -259.845302)
			(xy 107.562028 -259.821429) (xy 107.568418 -259.774112) (xy 107.581082 -259.728076) (xy 107.599793 -259.684149)
			(xy 107.611672 -259.663438) (xy 107.613647 -259.659912) (xy 107.616585 -259.652385) (xy 107.617514 -259.648452)
			(xy 107.622397 -259.62837) (xy 107.638819 -259.590451) (xy 107.662234 -259.556403) (xy 107.691768 -259.527501)
			(xy 107.726314 -259.504826) (xy 107.76458 -259.489228) (xy 107.805132 -259.481289) (xy 107.825794 -259.480812)
			(xy 108.050838 -259.480812) (xy 108.080556 -259.51053) (xy 108.080556 -259.528564) (xy 108.09097 -259.534152)
			(xy 108.096743 -259.537185) (xy 108.109345 -259.540524) (xy 108.115862 -259.540756) (xy 108.631228 -259.540756)
			(xy 108.631228 -259.531612) (xy 108.63163 -259.521588) (xy 108.639301 -259.503066) (xy 108.653479 -259.488892)
			(xy 108.672004 -259.481227) (xy 108.682028 -259.480812) (xy 108.88599 -259.480812) (xy 108.906048 -259.481232)
			(xy 108.945457 -259.488724) (xy 108.982774 -259.503445) (xy 109.016684 -259.524878) (xy 109.045994 -259.552267)
			(xy 109.058202 -259.568188) (xy 109.065822 -259.57657) (xy 109.086367 -259.595146) (xy 109.122012 -259.637537)
			(xy 109.150668 -259.684934) (xy 109.171644 -259.736194) (xy 109.184436 -259.790082) (xy 109.188734 -259.845301)
			(xy 109.188734 -259.845302) (xy 110.061756 -259.845302) (xy 110.062147 -259.821429) (xy 110.068537 -259.774112)
			(xy 110.081202 -259.728076) (xy 110.099914 -259.684149) (xy 110.111794 -259.663438) (xy 110.113771 -259.659913)
			(xy 110.116708 -259.652385) (xy 110.117636 -259.648452) (xy 110.122498 -259.628364) (xy 110.138923 -259.590443)
			(xy 110.162341 -259.556394) (xy 110.191879 -259.527492) (xy 110.226428 -259.504819) (xy 110.264697 -259.489222)
			(xy 110.305253 -259.481287) (xy 110.325916 -259.480812) (xy 110.551214 -259.480812) (xy 110.580932 -259.51053)
			(xy 110.580932 -259.528564) (xy 110.591092 -259.534152) (xy 110.596921 -259.537215) (xy 110.609656 -259.54055)
			(xy 110.616238 -259.540756) (xy 111.131096 -259.540756) (xy 111.131096 -259.531612) (xy 111.131529 -259.521592)
			(xy 111.139194 -259.503076) (xy 111.153363 -259.488903) (xy 111.171876 -259.481232) (xy 111.181896 -259.480812)
			(xy 111.386112 -259.480812) (xy 111.406167 -259.481288) (xy 111.445574 -259.488765) (xy 111.48289 -259.503473)
			(xy 111.516801 -259.524893) (xy 111.546114 -259.552272) (xy 111.558324 -259.568188) (xy 111.565944 -259.57657)
			(xy 111.586488 -259.595147) (xy 111.622131 -259.637539) (xy 111.650785 -259.684936) (xy 111.67176 -259.736195)
			(xy 111.68455 -259.790083) (xy 111.688848 -259.845301) (xy 111.688848 -259.845302) (xy 112.311688 -259.845302)
			(xy 112.312075 -259.821429) (xy 112.318465 -259.774111) (xy 112.331131 -259.728075) (xy 112.349845 -259.684149)
			(xy 112.361726 -259.663438) (xy 112.363698 -259.659911) (xy 112.366638 -259.652384) (xy 112.367568 -259.648452)
			(xy 112.372493 -259.628382) (xy 112.38891 -259.590466) (xy 112.41232 -259.55642) (xy 112.441846 -259.527518)
			(xy 112.476385 -259.504842) (xy 112.514643 -259.489239) (xy 112.555189 -259.481293) (xy 112.575848 -259.480812)
			(xy 112.801146 -259.480812) (xy 112.830864 -259.51053) (xy 112.830864 -259.528564) (xy 112.841024 -259.534152)
			(xy 112.846864 -259.537192) (xy 112.85959 -259.540542) (xy 112.86617 -259.540756) (xy 113.381028 -259.540756)
			(xy 113.381028 -259.531612) (xy 113.38143 -259.521588) (xy 113.389101 -259.503066) (xy 113.403279 -259.488892)
			(xy 113.421804 -259.481227) (xy 113.431828 -259.480812) (xy 113.636044 -259.480812) (xy 113.6561 -259.481265)
			(xy 113.695508 -259.488748) (xy 113.732824 -259.503462) (xy 113.766735 -259.524887) (xy 113.796047 -259.55227)
			(xy 113.808256 -259.568188) (xy 113.815876 -259.57657) (xy 113.836418 -259.595148) (xy 113.872058 -259.637541)
			(xy 113.90071 -259.684938) (xy 113.921683 -259.736197) (xy 113.934472 -259.790084) (xy 113.938769 -259.845301)
			(xy 113.938769 -259.845302) (xy 114.911632 -259.845302) (xy 114.912013 -259.821428) (xy 114.918404 -259.774111)
			(xy 114.931072 -259.728074) (xy 114.949788 -259.684148) (xy 114.96167 -259.663438) (xy 114.963645 -259.659912)
			(xy 114.966583 -259.652385) (xy 114.967512 -259.648452) (xy 114.972396 -259.62837) (xy 114.988818 -259.590451)
			(xy 115.012234 -259.556404) (xy 115.041767 -259.527502) (xy 115.076313 -259.504827) (xy 115.114578 -259.489228)
			(xy 115.155131 -259.481289) (xy 115.175792 -259.480812) (xy 115.40109 -259.480812) (xy 115.430808 -259.51053)
			(xy 115.430808 -259.528564) (xy 115.440968 -259.534152) (xy 115.446801 -259.537207) (xy 115.459533 -259.540548)
			(xy 115.466114 -259.540756) (xy 115.980972 -259.540756) (xy 115.980972 -259.531612) (xy 115.981497 -259.521609)
			(xy 115.989148 -259.503122) (xy 116.003289 -259.48897) (xy 116.021769 -259.481305) (xy 116.031772 -259.480812)
			(xy 116.235988 -259.480812) (xy 116.256046 -259.481234) (xy 116.295455 -259.488725) (xy 116.332772 -259.503446)
			(xy 116.366682 -259.524878) (xy 116.395992 -259.552267) (xy 116.4082 -259.568188) (xy 116.41582 -259.57657)
			(xy 116.436365 -259.595146) (xy 116.47201 -259.637537) (xy 116.500667 -259.684934) (xy 116.519201 -259.730226)
			(xy 120.853 -259.730226) (xy 120.857294 -259.675012) (xy 120.870081 -259.621127) (xy 120.891052 -259.56987)
			(xy 120.919702 -259.522476) (xy 120.955342 -259.480086) (xy 120.975882 -259.461508) (xy 120.983502 -259.453126)
			(xy 120.995676 -259.437166) (xy 121.024989 -259.40975) (xy 121.058902 -259.388283) (xy 121.096225 -259.37352)
			(xy 121.135646 -259.365979) (xy 121.155714 -259.365496) (xy 121.410476 -259.365496) (xy 121.410476 -259.37464)
			(xy 121.410955 -259.384647) (xy 121.418623 -259.403135) (xy 121.432778 -259.417286) (xy 121.451269 -259.424948)
			(xy 121.461276 -259.42544) (xy 121.624852 -259.42544) (xy 121.634875 -259.42586) (xy 121.653399 -259.433521)
			(xy 121.667574 -259.447695) (xy 121.675239 -259.466217) (xy 121.675652 -259.47624) (xy 121.675652 -259.730226)
			(xy 122.778583 -259.730226) (xy 122.782877 -259.675013) (xy 122.795663 -259.621129) (xy 122.816632 -259.569872)
			(xy 122.84528 -259.522478) (xy 122.880917 -259.480087) (xy 122.901456 -259.461508) (xy 122.909076 -259.453126)
			(xy 122.921265 -259.437179) (xy 122.950574 -259.409761) (xy 122.984483 -259.388292) (xy 123.021803 -259.373526)
			(xy 123.061222 -259.365981) (xy 123.081288 -259.365496) (xy 123.336304 -259.365496) (xy 123.336304 -259.37464)
			(xy 123.336755 -259.384651) (xy 123.344429 -259.403144) (xy 123.358593 -259.417296) (xy 123.377093 -259.424953)
			(xy 123.387104 -259.42544) (xy 123.550172 -259.42544) (xy 123.560196 -259.425844) (xy 123.57872 -259.433512)
			(xy 123.592895 -259.44769) (xy 123.600559 -259.466215) (xy 123.600972 -259.47624) (xy 123.600972 -259.880354)
			(xy 124.645928 -259.880354) (xy 124.645928 -259.879846) (xy 124.645928 -259.580126) (xy 124.646266 -259.559077)
			(xy 124.65427 -259.517751) (xy 124.67021 -259.478792) (xy 124.69347 -259.443708) (xy 124.723148 -259.413857)
			(xy 124.758097 -259.390394) (xy 124.796962 -259.374228) (xy 124.838241 -259.365984) (xy 124.859288 -259.365496)
			(xy 125.114304 -259.365496) (xy 125.114304 -259.379974) (xy 125.149102 -259.391404) (xy 125.14961 -259.391404)
			(xy 125.16618 -259.396932) (xy 125.198243 -259.410799) (xy 125.213618 -259.41909) (xy 125.219347 -259.422036)
			(xy 125.231817 -259.42525) (xy 125.238256 -259.42544) (xy 125.328172 -259.42544) (xy 125.338196 -259.425844)
			(xy 125.35672 -259.433512) (xy 125.370895 -259.44769) (xy 125.378559 -259.466215) (xy 125.378972 -259.47624)
			(xy 125.378972 -259.620766) (xy 125.381258 -259.627878) (xy 125.388287 -259.652882) (xy 125.395815 -259.704271)
			(xy 125.396244 -259.73024) (xy 125.395765 -259.756206) (xy 125.388248 -259.80759) (xy 125.381258 -259.832602)
			(xy 125.378972 -259.839714) (xy 125.378972 -259.98424) (xy 125.378544 -259.994254) (xy 125.370866 -260.012752)
			(xy 125.356695 -260.026904) (xy 125.338186 -260.034557) (xy 125.328172 -260.03504) (xy 125.238256 -260.03504)
			(xy 125.231816 -260.035225) (xy 125.219342 -260.038434) (xy 125.213618 -260.04139) (xy 125.19824 -260.049674)
			(xy 125.166177 -260.063541) (xy 125.14961 -260.069076) (xy 125.149102 -260.069076) (xy 125.114304 -260.080506)
			(xy 125.114304 -260.094984) (xy 124.859288 -260.094984) (xy 124.838243 -260.094487) (xy 124.796967 -260.086243)
			(xy 124.758105 -260.070077) (xy 124.72316 -260.046615) (xy 124.693485 -260.016765) (xy 124.670229 -259.981682)
			(xy 124.654293 -259.942725) (xy 124.646293 -259.901402) (xy 124.645928 -259.880354) (xy 123.600972 -259.880354)
			(xy 123.600972 -259.98424) (xy 123.600544 -259.994254) (xy 123.592866 -260.012752) (xy 123.578695 -260.026904)
			(xy 123.560186 -260.034557) (xy 123.550172 -260.03504) (xy 123.336304 -260.03504) (xy 123.336304 -260.044184)
			(xy 123.335868 -260.054204) (xy 123.328204 -260.07272) (xy 123.314037 -260.086892) (xy 123.295524 -260.094564)
			(xy 123.285504 -260.094984) (xy 123.081288 -260.094984) (xy 123.061218 -260.094511) (xy 123.021788 -260.086997)
			(xy 122.98446 -260.072238) (xy 122.950553 -260.050754) (xy 122.921265 -260.023305) (xy 122.909076 -260.007354)
			(xy 122.901456 -259.998972) (xy 122.880954 -259.980351) (xy 122.845311 -259.937965) (xy 122.816656 -259.890575)
			(xy 122.795679 -259.839321) (xy 122.782885 -259.785439) (xy 122.778583 -259.730226) (xy 121.675652 -259.730226)
			(xy 121.675652 -259.98424) (xy 121.675312 -259.99427) (xy 121.66762 -260.012797) (xy 121.653423 -260.026969)
			(xy 121.634883 -260.034629) (xy 121.624852 -260.03504) (xy 121.410476 -260.03504) (xy 121.410476 -260.044184)
			(xy 121.410067 -260.054207) (xy 121.402398 -260.072729) (xy 121.388222 -260.086902) (xy 121.369699 -260.094569)
			(xy 121.359676 -260.094984) (xy 121.155714 -260.094984) (xy 121.135642 -260.094563) (xy 121.096208 -260.087036)
			(xy 121.05888 -260.072264) (xy 121.024975 -260.050769) (xy 120.99569 -260.02331) (xy 120.983502 -260.007354)
			(xy 120.975882 -259.998972) (xy 120.955379 -259.980351) (xy 120.919733 -259.937967) (xy 120.891076 -259.890577)
			(xy 120.870097 -259.839323) (xy 120.857303 -259.78544) (xy 120.853 -259.730226) (xy 116.519201 -259.730226)
			(xy 116.521643 -259.736194) (xy 116.534434 -259.790082) (xy 116.538733 -259.845301) (xy 116.534434 -259.90052)
			(xy 116.521642 -259.954409) (xy 116.500665 -260.005669) (xy 116.472009 -260.053065) (xy 116.436363 -260.095456)
			(xy 116.41582 -260.114034) (xy 116.4082 -260.122416) (xy 116.395993 -260.138336) (xy 116.366678 -260.165713)
			(xy 116.332766 -260.187135) (xy 116.29545 -260.201849) (xy 116.256044 -260.209336) (xy 116.235988 -260.209792)
			(xy 115.980972 -260.209792) (xy 115.980972 -260.200648) (xy 115.980541 -260.190626) (xy 115.972881 -260.172105)
			(xy 115.958712 -260.15793) (xy 115.940193 -260.150263) (xy 115.930172 -260.149848) (xy 115.466114 -260.149848)
			(xy 115.459527 -260.150026) (xy 115.446786 -260.153361) (xy 115.440968 -260.156452) (xy 115.430808 -260.16204)
			(xy 115.430808 -260.180074) (xy 115.40109 -260.209792) (xy 115.175792 -260.209792) (xy 115.155139 -260.209268)
			(xy 115.11461 -260.201292) (xy 115.076368 -260.185678) (xy 115.041839 -260.163007) (xy 115.012308 -260.134124)
			(xy 114.988878 -260.100106) (xy 114.972419 -260.06222) (xy 114.967512 -260.042152) (xy 114.966591 -260.038217)
			(xy 114.963651 -260.030689) (xy 114.96167 -260.027166) (xy 114.949789 -260.006457) (xy 114.931102 -259.962522)
			(xy 114.918442 -259.916486) (xy 114.912034 -259.869174) (xy 114.911632 -259.845302) (xy 113.938769 -259.845302)
			(xy 113.934471 -259.900518) (xy 113.921682 -259.954405) (xy 113.900709 -260.005664) (xy 113.872057 -260.053061)
			(xy 113.836416 -260.095454) (xy 113.815876 -260.114034) (xy 113.808256 -260.122416) (xy 113.796017 -260.138309)
			(xy 113.766709 -260.165689) (xy 113.732806 -260.187115) (xy 113.695498 -260.201835) (xy 113.656097 -260.209331)
			(xy 113.636044 -260.209792) (xy 113.381028 -260.209792) (xy 113.381028 -260.200648) (xy 113.380542 -260.190633)
			(xy 113.372893 -260.172123) (xy 113.358741 -260.15795) (xy 113.340242 -260.150273) (xy 113.330228 -260.149848)
			(xy 112.86617 -260.149848) (xy 112.859582 -260.150009) (xy 112.846841 -260.153355) (xy 112.841024 -260.156452)
			(xy 112.830864 -260.16204) (xy 112.830864 -260.180074) (xy 112.801146 -260.209792) (xy 112.575848 -260.209792)
			(xy 112.555194 -260.209306) (xy 112.514662 -260.201323) (xy 112.47642 -260.185701) (xy 112.441891 -260.163024)
			(xy 112.412361 -260.134135) (xy 112.388932 -260.100112) (xy 112.372475 -260.062222) (xy 112.367568 -260.042152)
			(xy 112.366642 -260.038218) (xy 112.363705 -260.03069) (xy 112.361726 -260.027166) (xy 112.349851 -260.006454)
			(xy 112.331161 -259.96252) (xy 112.318499 -259.916486) (xy 112.31209 -259.869174) (xy 112.311688 -259.845302)
			(xy 111.688848 -259.845302) (xy 111.68455 -259.900519) (xy 111.671759 -259.954407) (xy 111.650784 -260.005667)
			(xy 111.622129 -260.053063) (xy 111.586486 -260.095455) (xy 111.565944 -260.114034) (xy 111.558324 -260.122416)
			(xy 111.546103 -260.138324) (xy 111.516791 -260.165703) (xy 111.482883 -260.187127) (xy 111.445571 -260.201843)
			(xy 111.406167 -260.209334) (xy 111.386112 -260.209792) (xy 111.131096 -260.209792) (xy 111.131096 -260.200648)
			(xy 111.130641 -260.190629) (xy 111.122986 -260.172113) (xy 111.108824 -260.157939) (xy 111.090314 -260.150268)
			(xy 111.080296 -260.149848) (xy 110.616238 -260.149848) (xy 110.609649 -260.149998) (xy 110.596908 -260.153352)
			(xy 110.591092 -260.156452) (xy 110.580932 -260.16204) (xy 110.580932 -260.180074) (xy 110.551214 -260.209792)
			(xy 110.325916 -260.209792) (xy 110.30526 -260.209335) (xy 110.264728 -260.201345) (xy 110.226485 -260.185718)
			(xy 110.191956 -260.163036) (xy 110.162427 -260.134143) (xy 110.138999 -260.100116) (xy 110.122542 -260.062223)
			(xy 110.117636 -260.042152) (xy 110.116713 -260.038217) (xy 110.113774 -260.030689) (xy 110.111794 -260.027166)
			(xy 110.099915 -260.006456) (xy 110.081227 -259.962521) (xy 110.068566 -259.916486) (xy 110.062158 -259.869174)
			(xy 110.061756 -259.845302) (xy 109.188734 -259.845302) (xy 109.184435 -259.90052) (xy 109.171644 -259.954409)
			(xy 109.150667 -260.005668) (xy 109.122011 -260.053065) (xy 109.086365 -260.095456) (xy 109.065822 -260.114034)
			(xy 109.058202 -260.122416) (xy 109.045994 -260.138335) (xy 109.016679 -260.165712) (xy 108.982767 -260.187135)
			(xy 108.945452 -260.201848) (xy 108.906046 -260.209336) (xy 108.88599 -260.209792) (xy 108.631228 -260.209792)
			(xy 108.631228 -260.200648) (xy 108.630742 -260.190633) (xy 108.623093 -260.172123) (xy 108.608941 -260.15795)
			(xy 108.590442 -260.150273) (xy 108.580428 -260.149848) (xy 108.115862 -260.149848) (xy 108.109342 -260.15007)
			(xy 108.096736 -260.153403) (xy 108.09097 -260.156452) (xy 108.080556 -260.16204) (xy 108.080556 -260.180074)
			(xy 108.050838 -260.209792) (xy 107.825794 -260.209792) (xy 107.805141 -260.209266) (xy 107.764612 -260.201291)
			(xy 107.72637 -260.185677) (xy 107.691841 -260.163006) (xy 107.662311 -260.134124) (xy 107.63888 -260.100106)
			(xy 107.622421 -260.06222) (xy 107.617514 -260.042152) (xy 107.616593 -260.038217) (xy 107.613652 -260.030689)
			(xy 107.611672 -260.027166) (xy 107.599791 -260.006457) (xy 107.581104 -259.962522) (xy 107.568444 -259.916486)
			(xy 107.562036 -259.869174) (xy 107.561634 -259.845302) (xy 103.192104 -259.845302) (xy 103.17356 -259.890606)
			(xy 103.144896 -259.938004) (xy 103.109241 -259.980394) (xy 103.088694 -259.998972) (xy 103.081074 -260.007354)
			(xy 103.068851 -260.023273) (xy 103.039551 -260.050695) (xy 103.00565 -260.072168) (xy 102.968339 -260.086941)
			(xy 102.928926 -260.094494) (xy 102.908862 -260.094984) (xy 102.6541 -260.094984) (xy 102.6541 -260.08584)
			(xy 102.653648 -260.075821) (xy 102.645991 -260.057305) (xy 102.631828 -260.043132) (xy 102.613318 -260.03546)
			(xy 102.6033 -260.03504) (xy 102.13848 -260.03504) (xy 102.132103 -260.035241) (xy 102.119761 -260.038455)
			(xy 102.114096 -260.04139) (xy 102.103428 -260.046978) (xy 102.103428 -260.065266) (xy 102.07371 -260.094984)
			(xy 101.848666 -260.094984) (xy 101.827993 -260.094501) (xy 101.787425 -260.086517) (xy 101.749152 -260.070875)
			(xy 101.714605 -260.04816) (xy 101.685076 -260.019219) (xy 101.661669 -259.985137) (xy 101.64526 -259.947186)
			(xy 101.640386 -259.92709) (xy 101.63945 -259.923159) (xy 101.636519 -259.915629) (xy 101.634544 -259.912104)
			(xy 101.622676 -259.891388) (xy 101.603986 -259.847455) (xy 101.591322 -259.801422) (xy 101.58491 -259.754111)
			(xy 101.584506 -259.73024) (xy 101.311762 -259.73024) (xy 101.307524 -259.785031) (xy 101.294913 -259.838533)
			(xy 101.274231 -259.889462) (xy 101.245968 -259.936608) (xy 101.210797 -259.978852) (xy 101.190552 -259.997448)
			(xy 101.18852 -259.999226) (xy 101.18217 -260.006084) (xy 101.180392 -260.00837) (xy 101.180138 -260.008878)
			(xy 101.16793 -260.024552) (xy 101.138737 -260.051492) (xy 101.105068 -260.072574) (xy 101.068084 -260.087071)
			(xy 101.029057 -260.094484) (xy 101.009196 -260.094984) (xy 100.790502 -260.094984) (xy 100.780677 -260.095458)
			(xy 100.762514 -260.102956) (xy 100.748588 -260.116818) (xy 100.741005 -260.134946) (xy 100.740464 -260.144768)
			(xy 100.740464 -261.377176) (xy 100.74148 -261.387082) (xy 100.743184 -261.394242) (xy 100.750014 -261.40727)
			(xy 100.754942 -261.412736) (xy 101.22154 -261.879334) (xy 101.228229 -261.886649) (xy 101.235707 -261.904988)
			(xy 101.236018 -261.914894) (xy 101.236018 -261.95909) (xy 101.236272 -261.961376) (xy 101.236272 -262.242808)
			(xy 101.237291 -262.252523) (xy 101.245653 -262.270158) (xy 101.252528 -262.277098) (xy 101.260148 -262.28421)
			(xy 101.307138 -262.326882) (xy 101.311228 -262.330404) (xy 101.320578 -262.33579) (xy 101.32568 -262.33755)
			(xy 101.334824 -262.340598) (xy 101.345746 -262.339836) (xy 101.354128 -262.339074) (xy 101.355144 -262.339074)
			(xy 101.364288 -262.33882) (xy 101.451918 -262.33882) (xy 101.462061 -262.338376) (xy 101.480769 -262.330534)
			(xy 101.494997 -262.316074) (xy 101.499162 -262.306816) (xy 101.524054 -262.244332) (xy 101.533198 -262.221472)
			(xy 101.53582 -262.214345) (xy 101.537119 -262.199221) (xy 101.535738 -262.191754) (xy 101.534214 -262.184388)
			(xy 101.526848 -262.171434) (xy 101.52126 -262.1661) (xy 101.503015 -262.147978) (xy 101.472041 -262.106934)
			(xy 101.448071 -262.061442) (xy 101.431728 -262.012688) (xy 101.423438 -261.96194) (xy 101.422962 -261.93623)
			(xy 101.423409 -261.911779) (xy 101.430894 -261.863454) (xy 101.445693 -261.816846) (xy 101.467456 -261.773054)
			(xy 101.495669 -261.733113) (xy 101.51237 -261.71525) (xy 101.512624 -261.714996) (xy 101.519081 -261.708047)
			(xy 101.526735 -261.690708) (xy 101.527509 -261.671769) (xy 101.524816 -261.662672) (xy 101.487224 -261.573772)
			(xy 101.484565 -261.568352) (xy 101.47712 -261.558852) (xy 101.472492 -261.554976) (xy 101.465595 -261.55)
			(xy 101.449497 -261.544542) (xy 101.440996 -261.544308) (xy 101.364288 -261.544308) (xy 101.343692 -261.543802)
			(xy 101.303274 -261.535855) (xy 101.265125 -261.520316) (xy 101.230657 -261.49776) (xy 101.201146 -261.46902)
			(xy 101.189028 -261.45236) (xy 101.184964 -261.44728) (xy 101.179884 -261.441692) (xy 101.17455 -261.436612)
			(xy 101.159564 -261.424166) (xy 101.152198 -261.421118) (xy 101.135429 -261.414109) (xy 101.103474 -261.396793)
			(xy 101.088444 -261.386574) (xy 101.070918 -261.373366) (xy 101.052849 -261.35818) (xy 101.020965 -261.323379)
			(xy 100.994575 -261.284247) (xy 100.974261 -261.241644) (xy 100.96047 -261.196505) (xy 100.953503 -261.149823)
			(xy 100.953062 -261.126224) (xy 100.953551 -261.101233) (xy 100.961366 -261.051865) (xy 100.976807 -261.004328)
			(xy 100.999495 -260.959791) (xy 101.028871 -260.919352) (xy 101.064211 -260.884006) (xy 101.104645 -260.854624)
			(xy 101.149178 -260.831928) (xy 101.196712 -260.816478) (xy 101.246079 -260.808655) (xy 101.27107 -260.808216)
			(xy 101.271832 -260.808216) (xy 101.286654 -260.808413) (xy 101.316165 -260.811216) (xy 101.33076 -260.813804)
			(xy 101.332284 -260.814058) (xy 101.336094 -260.814566) (xy 101.345746 -260.815836) (xy 101.350064 -260.815328)
			(xy 101.352858 -260.815328) (xy 101.35743 -260.815074) (xy 101.357938 -260.815074) (xy 101.364288 -260.81482)
			(xy 101.589586 -260.81482) (xy 101.619304 -260.844538) (xy 101.619304 -260.85292) (xy 101.6222 -260.856854)
			(xy 101.629238 -260.863628) (xy 101.633274 -260.866382) (xy 101.639602 -260.870254) (xy 101.6538 -260.874529)
			(xy 101.661214 -260.874764) (xy 101.854254 -260.874764) (xy 101.883972 -260.904482) (xy 101.883972 -260.919468)
			(xy 101.884226 -260.922008) (xy 101.884226 -261.433564) (xy 103.6828 -261.433564) (xy 103.6828 -260.925564)
			(xy 103.683259 -260.915554) (xy 103.69093 -260.897061) (xy 103.705092 -260.88291) (xy 103.72359 -260.875251)
			(xy 103.7336 -260.874764) (xy 103.879396 -260.874764) (xy 103.886972 -260.874451) (xy 103.901436 -260.869927)
			(xy 103.907844 -260.865874) (xy 103.917378 -260.859537) (xy 103.937209 -260.848095) (xy 103.947468 -260.843014)
			(xy 103.947468 -260.81482) (xy 104.03332 -260.81482) (xy 104.037384 -260.814312) (xy 104.049935 -260.812419)
			(xy 104.075238 -260.810386) (xy 104.08793 -260.810248) (xy 104.100623 -260.810363) (xy 104.125927 -260.812401)
			(xy 104.138476 -260.814312) (xy 104.14254 -260.81482) (xy 104.202484 -260.81482) (xy 104.223529 -260.815339)
			(xy 104.264804 -260.823577) (xy 104.303666 -260.839739) (xy 104.338612 -260.863198) (xy 104.368287 -260.893045)
			(xy 104.391543 -260.928126) (xy 104.40748 -260.967081) (xy 104.41548 -261.008403) (xy 104.415844 -261.02945)
			(xy 104.415844 -261.029958) (xy 104.415844 -261.32917) (xy 104.415844 -261.329678) (xy 104.415538 -261.350729)
			(xy 104.407531 -261.392058) (xy 104.391588 -261.43102) (xy 104.368324 -261.466106) (xy 104.338641 -261.495957)
			(xy 104.303687 -261.519419) (xy 104.264816 -261.535582) (xy 104.223533 -261.543822) (xy 104.202484 -261.544308)
			(xy 103.947468 -261.544308) (xy 103.947468 -261.535164) (xy 103.947041 -261.52515) (xy 103.939363 -261.506651)
			(xy 103.925191 -261.492499) (xy 103.906683 -261.484846) (xy 103.896668 -261.484364) (xy 103.7336 -261.484364)
			(xy 103.723574 -261.48398) (xy 103.70505 -261.476303) (xy 103.690877 -261.462119) (xy 103.683213 -261.44359)
			(xy 103.6828 -261.433564) (xy 101.884226 -261.433564) (xy 101.884226 -261.43712) (xy 101.883972 -261.43966)
			(xy 101.883972 -261.454646) (xy 101.854254 -261.484364) (xy 101.668834 -261.484364) (xy 101.659653 -261.484822)
			(xy 101.642537 -261.491486) (xy 101.628939 -261.503833) (xy 101.62066 -261.520229) (xy 101.619304 -261.529322)
			(xy 101.619304 -261.57428) (xy 101.61972 -261.584304) (xy 101.627387 -261.602827) (xy 101.64156 -261.617004)
			(xy 101.66008 -261.624677) (xy 101.670104 -261.62508) (xy 101.67493 -261.62508) (xy 101.679756 -261.624064)
			(xy 101.694908 -261.621302) (xy 101.725569 -261.618372) (xy 101.74097 -261.618222) (xy 101.76596 -261.618685)
			(xy 101.815326 -261.626499) (xy 101.862862 -261.64194) (xy 101.907397 -261.664628) (xy 101.947833 -261.694004)
			(xy 101.983177 -261.729344) (xy 102.012556 -261.769778) (xy 102.035248 -261.81431) (xy 102.050694 -261.861844)
			(xy 102.058513 -261.91121) (xy 102.058513 -261.96119) (xy 102.050694 -262.010556) (xy 102.035248 -262.05809)
			(xy 102.012556 -262.102622) (xy 101.983177 -262.143056) (xy 101.947833 -262.178396) (xy 101.907397 -262.207772)
			(xy 101.862862 -262.23046) (xy 101.815326 -262.245901) (xy 101.76596 -262.253715) (xy 101.74097 -262.254238)
			(xy 101.725506 -262.254092) (xy 101.694717 -262.251167) (xy 101.679502 -262.248396) (xy 101.674676 -262.24738)
			(xy 101.66985 -262.24738) (xy 101.659847 -262.247876) (xy 101.641369 -262.255544) (xy 101.627227 -262.269694)
			(xy 101.61957 -262.288177) (xy 101.61905 -262.29818) (xy 101.61905 -262.34898) (xy 101.619572 -262.35877)
			(xy 101.627119 -262.376842) (xy 101.640969 -262.390689) (xy 101.659044 -262.398231) (xy 101.668834 -262.398764)
			(xy 101.854254 -262.398764) (xy 101.883972 -262.428482) (xy 101.883972 -262.443468) (xy 101.884226 -262.446008)
			(xy 101.884226 -262.957564) (xy 103.6828 -262.957564) (xy 103.6828 -262.449564) (xy 103.683259 -262.439554)
			(xy 103.69093 -262.421061) (xy 103.705092 -262.40691) (xy 103.72359 -262.399251) (xy 103.7336 -262.398764)
			(xy 103.947468 -262.398764) (xy 103.947468 -262.38962) (xy 103.948004 -262.379618) (xy 103.955651 -262.361132)
			(xy 103.969789 -262.34698) (xy 103.988266 -262.339314) (xy 103.998268 -262.33882) (xy 104.202484 -262.33882)
			(xy 104.223529 -262.339339) (xy 104.264804 -262.347577) (xy 104.303666 -262.363739) (xy 104.338612 -262.387198)
			(xy 104.368287 -262.417045) (xy 104.391543 -262.452126) (xy 104.40748 -262.491081) (xy 104.41548 -262.532403)
			(xy 104.415844 -262.55345) (xy 104.415844 -262.553958) (xy 104.415844 -262.853678) (xy 104.415538 -262.874729)
			(xy 104.407531 -262.916058) (xy 104.391588 -262.95502) (xy 104.368324 -262.990106) (xy 104.338641 -263.019957)
			(xy 104.303687 -263.043419) (xy 104.264816 -263.059582) (xy 104.223533 -263.067822) (xy 104.202484 -263.068308)
			(xy 103.977186 -263.068308) (xy 103.947468 -263.03859) (xy 103.947468 -263.03351) (xy 103.916734 -263.016238)
			(xy 103.910527 -263.012619) (xy 103.896736 -263.008616) (xy 103.889556 -263.008364) (xy 103.7336 -263.008364)
			(xy 103.723574 -263.00798) (xy 103.70505 -263.000303) (xy 103.690877 -262.986119) (xy 103.683213 -262.96759)
			(xy 103.6828 -262.957564) (xy 101.884226 -262.957564) (xy 101.884226 -262.96112) (xy 101.883972 -262.96366)
			(xy 101.883972 -262.978646) (xy 101.854254 -263.008364) (xy 101.668834 -263.008364) (xy 101.659653 -263.008822)
			(xy 101.642537 -263.015486) (xy 101.628939 -263.027833) (xy 101.62066 -263.044229) (xy 101.619304 -263.053322)
			(xy 101.619304 -263.068308) (xy 101.364034 -263.068308) (xy 101.353615 -263.068186) (xy 101.332877 -263.066147)
			(xy 101.322632 -263.064244) (xy 101.313996 -263.062466) (xy 101.306376 -263.063482) (xy 101.302231 -263.064045)
			(xy 101.294188 -263.066338) (xy 101.290374 -263.068054) (xy 101.271324 -263.077452) (xy 101.264974 -263.084056)
			(xy 101.26472 -263.08431) (xy 101.250496 -263.099042) (xy 101.24402 -263.106396) (xy 101.236713 -263.124558)
			(xy 101.236272 -263.134348) (xy 101.236272 -263.55929) (xy 101.237288 -263.569196) (xy 101.238994 -263.576355)
			(xy 101.245828 -263.58938) (xy 101.25075 -263.59485) (xy 101.252782 -263.596882) (xy 101.259953 -263.603506)
			(xy 101.277867 -263.611219) (xy 101.297366 -263.611641) (xy 101.30663 -263.608566) (xy 101.390958 -263.576816)
			(xy 101.397668 -263.57409) (xy 101.409273 -263.565438) (xy 101.413818 -263.559798) (xy 101.418136 -263.55421)
			(xy 101.423216 -263.540494) (xy 101.423724 -263.533128) (xy 101.426174 -263.506749) (xy 101.438722 -263.455283)
			(xy 101.459628 -263.406609) (xy 101.488313 -263.362073) (xy 101.523983 -263.322908) (xy 101.565651 -263.290197)
			(xy 101.612164 -263.264845) (xy 101.662237 -263.247553) (xy 101.714483 -263.2388) (xy 101.74097 -263.238234)
			(xy 101.765962 -263.238697) (xy 101.81533 -263.246512) (xy 101.862867 -263.261955) (xy 101.907403 -263.284646)
			(xy 101.94784 -263.314025) (xy 101.983183 -263.349369) (xy 102.01256 -263.389807) (xy 102.035249 -263.434344)
			(xy 102.050691 -263.481882) (xy 102.058504 -263.53125) (xy 102.058978 -263.556242) (xy 102.058883 -263.568289)
			(xy 102.057105 -263.592318) (xy 102.055422 -263.604248) (xy 102.053898 -263.61517) (xy 102.056946 -263.625838)
			(xy 102.05861 -263.631058) (xy 102.063869 -263.640666) (xy 102.06736 -263.644888) (xy 102.116382 -263.701784)
			(xy 102.1239 -263.709774) (xy 102.14378 -263.719001) (xy 102.154736 -263.719564) (xy 104.14889 -263.719564)
			(xy 104.158727 -263.719026) (xy 104.176889 -263.711441) (xy 104.184196 -263.704832) (xy 104.662732 -263.226296)
			(xy 104.669444 -263.219057) (xy 104.677038 -263.200853) (xy 104.677464 -263.19099) (xy 104.677464 -261.073138)
			(xy 104.677998 -261.063299) (xy 104.685579 -261.045133) (xy 104.692196 -261.037832) (xy 105.043732 -260.686296)
			(xy 105.050971 -260.679585) (xy 105.069176 -260.671997) (xy 105.079038 -260.671564) (xy 105.137966 -260.671564)
			(xy 105.151174 -260.669786) (xy 105.159778 -260.667097) (xy 105.174482 -260.656688) (xy 105.179876 -260.649466)
			(xy 105.207308 -260.609334) (xy 105.226104 -260.581648) (xy 105.229305 -260.576607) (xy 105.233536 -260.565445)
			(xy 105.234486 -260.55955) (xy 105.23601 -260.547612) (xy 105.2322 -260.536182) (xy 105.231438 -260.534404)
			(xy 105.231438 -260.53415) (xy 105.230168 -260.530594) (xy 105.22839 -260.526022) (xy 105.219754 -260.511798)
			(xy 105.216198 -260.507226) (xy 105.21569 -260.506718) (xy 105.20045 -260.487525) (xy 105.174822 -260.445752)
			(xy 105.155157 -260.400863) (xy 105.141825 -260.353703) (xy 105.135078 -260.305162) (xy 105.134664 -260.280658)
			(xy 105.134664 -260.272276) (xy 105.135833 -260.244479) (xy 105.145733 -260.189734) (xy 105.164022 -260.137193)
			(xy 105.190257 -260.088135) (xy 105.2238 -260.043751) (xy 105.263834 -260.005121) (xy 105.309388 -259.973185)
			(xy 105.359351 -259.948718) (xy 105.412511 -259.932316) (xy 105.439972 -259.927852) (xy 105.452603 -259.926162)
			(xy 105.478028 -259.924381) (xy 105.490772 -259.924296) (xy 105.516012 -259.924738) (xy 105.565984 -259.931882)
			(xy 105.59034 -259.93852) (xy 105.597706 -259.940552) (xy 105.655618 -259.940552) (xy 105.701084 -259.986018)
			(xy 105.706582 -259.991009) (xy 105.719746 -259.997861) (xy 105.726992 -259.99948) (xy 105.736644 -260.000496)
			(xy 106.160062 -260.000496) (xy 106.163805 -260.000416) (xy 106.171203 -259.999269) (xy 106.174794 -259.99821)
			(xy 106.18978 -259.993384) (xy 106.193269 -259.992218) (xy 106.199898 -259.98903) (xy 106.202988 -259.987034)
			(xy 106.229912 -259.97027) (xy 106.230166 -259.97027) (xy 106.235246 -259.967476) (xy 106.246676 -259.956046)
			(xy 106.24693 -259.955792) (xy 106.254358 -259.948851) (xy 106.273094 -259.941006) (xy 106.283252 -259.940552)
			(xy 106.298238 -259.940552) (xy 106.30027 -259.940044) (xy 106.305604 -259.93852) (xy 106.32996 -259.931885)
			(xy 106.379932 -259.924744) (xy 106.405172 -259.924296) (xy 106.408728 -259.924296) (xy 106.433112 -259.925312)
			(xy 106.43362 -259.925312) (xy 106.448777 -259.926719) (xy 106.47879 -259.931806) (xy 106.493564 -259.935472)
			(xy 106.494072 -259.935472) (xy 106.510582 -259.940044) (xy 106.510836 -259.940298) (xy 106.512106 -259.940552)
			(xy 106.512868 -259.940806) (xy 106.519218 -259.942584) (xy 106.52252 -259.943092) (xy 106.532353 -259.944713)
			(xy 106.551688 -259.949549) (xy 106.561128 -259.952744) (xy 106.577627 -259.958953) (xy 106.608489 -259.975984)
			(xy 106.63614 -259.997846) (xy 106.64825 -260.010656) (xy 106.661966 -260.02742) (xy 106.673142 -260.044184)
			(xy 106.673904 -260.045454) (xy 106.678476 -260.051804) (xy 106.679746 -260.053582) (xy 106.684318 -260.059424)
			(xy 106.684826 -260.059932) (xy 106.694883 -260.072963) (xy 106.712815 -260.100568) (xy 106.72064 -260.11505)
			(xy 106.733468 -260.14071) (xy 106.751666 -260.195111) (xy 106.760924 -260.251723) (xy 106.761534 -260.280404)
			(xy 106.76128 -260.286246) (xy 106.76128 -260.286754) (xy 106.760567 -260.3092) (xy 106.754195 -260.353656)
			(xy 106.74858 -260.3754) (xy 106.746294 -260.383274) (xy 106.739578 -260.404388) (xy 106.721621 -260.444894)
			(xy 106.71048 -260.464046) (xy 106.70794 -260.46811) (xy 106.70159 -260.48589) (xy 106.700574 -260.491732)
			(xy 106.694732 -260.516878) (xy 106.694732 -260.517386) (xy 106.68889 -260.534658) (xy 106.68889 -260.534912)
			(xy 106.685242 -260.545889) (xy 106.687242 -260.568907) (xy 106.6927 -260.579108) (xy 106.71302 -260.60908)
			(xy 106.71302 -260.609588) (xy 106.740452 -260.649466) (xy 106.745839 -260.656695) (xy 106.760547 -260.667101)
			(xy 106.769154 -260.669786) (xy 106.782362 -260.671564) (xy 117.07368 -260.671564) (xy 117.086127 -260.670883)
			(xy 117.108105 -260.659178) (xy 117.11559 -260.649212) (xy 117.148102 -260.60146) (xy 117.148102 -260.600952)
			(xy 117.162326 -260.57987) (xy 117.165939 -260.57373) (xy 117.169944 -260.560065) (xy 117.1702 -260.552946)
			(xy 117.166644 -260.534404) (xy 117.165882 -260.532372) (xy 117.16258 -260.52272) (xy 117.160548 -260.515862)
			(xy 117.158262 -260.506972) (xy 117.157754 -260.504432) (xy 117.156992 -260.501638) (xy 117.14988 -260.48589)
			(xy 117.147086 -260.48208) (xy 117.132342 -260.459725) (xy 117.109008 -260.411525) (xy 117.093145 -260.360378)
			(xy 117.085112 -260.307433) (xy 117.084602 -260.280658) (xy 117.084602 -260.273292) (xy 117.084856 -260.268466)
			(xy 117.086388 -260.239647) (xy 117.097608 -260.183041) (xy 117.117805 -260.128983) (xy 117.146452 -260.078887)
			(xy 117.182798 -260.034064) (xy 117.203982 -260.014466) (xy 117.207792 -260.010656) (xy 117.217698 -260.000496)
			(xy 117.218206 -259.999988) (xy 117.222778 -259.99567) (xy 117.223286 -259.995162) (xy 117.238012 -259.982496)
			(xy 117.271114 -259.962179) (xy 117.289072 -259.954776) (xy 117.295977 -259.952121) (xy 117.310087 -259.947671)
			(xy 117.317266 -259.945886) (xy 117.318282 -259.945632) (xy 117.347824 -259.935616) (xy 117.409268 -259.924891)
			(xy 117.440456 -259.924296) (xy 117.44071 -259.924296) (xy 117.465951 -259.924733) (xy 117.515925 -259.93187)
			(xy 117.540278 -259.93852) (xy 117.547644 -259.940552) (xy 117.591078 -259.940552) (xy 117.622828 -259.972302)
			(xy 117.630448 -259.978398) (xy 117.642132 -259.986526) (xy 117.644164 -259.987796) (xy 117.656102 -259.993638)
			(xy 117.670072 -259.99821) (xy 117.673853 -259.999293) (xy 117.681633 -260.000437) (xy 117.685566 -260.000496)
			(xy 117.834664 -260.000496) (xy 117.84469 -260.000909) (xy 117.86322 -260.008573) (xy 117.877405 -260.022746)
			(xy 117.885083 -260.04127) (xy 117.885464 -260.051296) (xy 117.885464 -260.559296) (xy 117.885044 -260.569315)
			(xy 117.877374 -260.587827) (xy 117.8632 -260.601992) (xy 117.844683 -260.609651) (xy 117.834664 -260.610096)
			(xy 117.815106 -260.610096) (xy 117.800135 -260.610668) (xy 117.771501 -260.619432) (xy 117.746638 -260.636121)
			(xy 117.72768 -260.659301) (xy 117.716257 -260.686981) (xy 117.713348 -260.716784) (xy 117.719205 -260.746151)
			(xy 117.733323 -260.772559) (xy 117.743478 -260.783578) (xy 117.870732 -260.910832) (xy 117.87744 -260.918072)
			(xy 117.885023 -260.936277) (xy 117.885464 -260.946138) (xy 117.885464 -261.126224) (xy 121.62663 -261.126224)
			(xy 121.62663 -261.12597) (xy 121.627116 -261.10026) (xy 121.635405 -261.049514) (xy 121.651746 -261.00076)
			(xy 121.675714 -260.955268) (xy 121.706685 -260.914223) (xy 121.724928 -260.8961) (xy 121.724928 -260.895846)
			(xy 121.725477 -260.8749) (xy 121.733693 -260.833819) (xy 121.749759 -260.795129) (xy 121.773059 -260.760312)
			(xy 121.802699 -260.730705) (xy 121.837542 -260.707445) (xy 121.876251 -260.691422) (xy 121.917341 -260.683253)
			(xy 121.938288 -260.68274) (xy 122.193304 -260.68274) (xy 122.193304 -260.691884) (xy 122.193733 -260.701905)
			(xy 122.201398 -260.720422) (xy 122.215568 -260.734595) (xy 122.234083 -260.742265) (xy 122.244104 -260.742684)
			(xy 122.407172 -260.742684) (xy 122.417189 -260.743142) (xy 122.435703 -260.7508) (xy 122.449875 -260.76496)
			(xy 122.457549 -260.783467) (xy 122.457972 -260.793484) (xy 122.457972 -261.126224) (xy 123.506738 -261.126224)
			(xy 123.507306 -261.09889) (xy 123.516634 -261.045025) (xy 123.535038 -260.993549) (xy 123.561974 -260.945979)
			(xy 123.596649 -260.903717) (xy 123.616974 -260.885432) (xy 123.623175 -260.879552) (xy 123.63174 -260.864783)
			(xy 123.633738 -260.856476) (xy 123.63811 -260.835818) (xy 123.653924 -260.796671) (xy 123.677125 -260.761398)
			(xy 123.706808 -260.731373) (xy 123.741815 -260.70777) (xy 123.780778 -260.69151) (xy 123.822178 -260.683227)
			(xy 123.843288 -260.68274) (xy 124.098304 -260.68274) (xy 124.098304 -260.691884) (xy 124.098733 -260.701905)
			(xy 124.106398 -260.720422) (xy 124.120568 -260.734595) (xy 124.139083 -260.742265) (xy 124.149104 -260.742684)
			(xy 124.312172 -260.742684) (xy 124.322189 -260.743142) (xy 124.340703 -260.7508) (xy 124.354875 -260.76496)
			(xy 124.362549 -260.783467) (xy 124.362972 -260.793484) (xy 124.362972 -261.151213) (xy 125.387336 -261.151213)
			(xy 125.387336 -261.101235) (xy 125.395155 -261.051872) (xy 125.410599 -261.00434) (xy 125.433289 -260.959808)
			(xy 125.462665 -260.919375) (xy 125.498005 -260.884035) (xy 125.538438 -260.854659) (xy 125.58297 -260.831969)
			(xy 125.630502 -260.816525) (xy 125.679865 -260.808706) (xy 125.729843 -260.808706) (xy 125.779206 -260.816525)
			(xy 125.826738 -260.831969) (xy 125.87127 -260.854659) (xy 125.911703 -260.884035) (xy 125.947043 -260.919375)
			(xy 125.976419 -260.959808) (xy 125.999109 -261.00434) (xy 126.014553 -261.051872) (xy 126.022372 -261.101235)
			(xy 126.022862 -261.126224) (xy 126.022372 -261.151213) (xy 127.26719 -261.151213) (xy 127.26719 -261.101235)
			(xy 127.275009 -261.051872) (xy 127.290453 -261.00434) (xy 127.313143 -260.959808) (xy 127.342519 -260.919375)
			(xy 127.377859 -260.884035) (xy 127.418292 -260.854659) (xy 127.462824 -260.831969) (xy 127.510356 -260.816525)
			(xy 127.559719 -260.808706) (xy 127.609697 -260.808706) (xy 127.65906 -260.816525) (xy 127.706592 -260.831969)
			(xy 127.751124 -260.854659) (xy 127.791557 -260.884035) (xy 127.826897 -260.919375) (xy 127.856273 -260.959808)
			(xy 127.878963 -261.00434) (xy 127.894407 -261.051872) (xy 127.902226 -261.101235) (xy 127.902716 -261.126224)
			(xy 127.902226 -261.151213) (xy 128.207244 -261.151213) (xy 128.207244 -261.101235) (xy 128.215063 -261.051872)
			(xy 128.230507 -261.00434) (xy 128.253197 -260.959808) (xy 128.282573 -260.919375) (xy 128.317913 -260.884035)
			(xy 128.358346 -260.854659) (xy 128.402878 -260.831969) (xy 128.45041 -260.816525) (xy 128.499773 -260.808706)
			(xy 128.549751 -260.808706) (xy 128.599114 -260.816525) (xy 128.646646 -260.831969) (xy 128.691178 -260.854659)
			(xy 128.731611 -260.884035) (xy 128.766951 -260.919375) (xy 128.796327 -260.959808) (xy 128.819017 -261.00434)
			(xy 128.834461 -261.051872) (xy 128.84228 -261.101235) (xy 128.84277 -261.126224) (xy 128.84228 -261.151213)
			(xy 129.147298 -261.151213) (xy 129.147298 -261.101235) (xy 129.155117 -261.051872) (xy 129.170561 -261.00434)
			(xy 129.193251 -260.959808) (xy 129.222627 -260.919375) (xy 129.257967 -260.884035) (xy 129.2984 -260.854659)
			(xy 129.342932 -260.831969) (xy 129.390464 -260.816525) (xy 129.439827 -260.808706) (xy 129.489805 -260.808706)
			(xy 129.539168 -260.816525) (xy 129.5867 -260.831969) (xy 129.631232 -260.854659) (xy 129.671665 -260.884035)
			(xy 129.707005 -260.919375) (xy 129.736381 -260.959808) (xy 129.759071 -261.00434) (xy 129.774515 -261.051872)
			(xy 129.782334 -261.101235) (xy 129.782824 -261.126224) (xy 129.782334 -261.151213) (xy 130.087352 -261.151213)
			(xy 130.087352 -261.101235) (xy 130.095171 -261.051872) (xy 130.110615 -261.00434) (xy 130.133305 -260.959808)
			(xy 130.162681 -260.919375) (xy 130.198021 -260.884035) (xy 130.238454 -260.854659) (xy 130.282986 -260.831969)
			(xy 130.330518 -260.816525) (xy 130.379881 -260.808706) (xy 130.429859 -260.808706) (xy 130.479222 -260.816525)
			(xy 130.526754 -260.831969) (xy 130.571286 -260.854659) (xy 130.611719 -260.884035) (xy 130.647059 -260.919375)
			(xy 130.676435 -260.959808) (xy 130.699125 -261.00434) (xy 130.714569 -261.051872) (xy 130.722388 -261.101235)
			(xy 130.722878 -261.126224) (xy 130.722388 -261.151213) (xy 131.027152 -261.151213) (xy 131.027152 -261.101235)
			(xy 131.034971 -261.051872) (xy 131.050415 -261.00434) (xy 131.073105 -260.959808) (xy 131.102481 -260.919375)
			(xy 131.137821 -260.884035) (xy 131.178254 -260.854659) (xy 131.222786 -260.831969) (xy 131.270318 -260.816525)
			(xy 131.319681 -260.808706) (xy 131.369659 -260.808706) (xy 131.419022 -260.816525) (xy 131.466554 -260.831969)
			(xy 131.511086 -260.854659) (xy 131.551519 -260.884035) (xy 131.586859 -260.919375) (xy 131.616235 -260.959808)
			(xy 131.638925 -261.00434) (xy 131.654369 -261.051872) (xy 131.662188 -261.101235) (xy 131.662678 -261.126224)
			(xy 131.662188 -261.151213) (xy 131.967206 -261.151213) (xy 131.967206 -261.101235) (xy 131.975025 -261.051872)
			(xy 131.990469 -261.00434) (xy 132.013159 -260.959808) (xy 132.042535 -260.919375) (xy 132.077875 -260.884035)
			(xy 132.118308 -260.854659) (xy 132.16284 -260.831969) (xy 132.210372 -260.816525) (xy 132.259735 -260.808706)
			(xy 132.309713 -260.808706) (xy 132.359076 -260.816525) (xy 132.406608 -260.831969) (xy 132.45114 -260.854659)
			(xy 132.491573 -260.884035) (xy 132.526913 -260.919375) (xy 132.556289 -260.959808) (xy 132.578979 -261.00434)
			(xy 132.594423 -261.051872) (xy 132.602242 -261.101235) (xy 132.602732 -261.126224) (xy 132.602242 -261.151213)
			(xy 132.90726 -261.151213) (xy 132.90726 -261.101235) (xy 132.915079 -261.051872) (xy 132.930523 -261.00434)
			(xy 132.953213 -260.959808) (xy 132.982589 -260.919375) (xy 133.017929 -260.884035) (xy 133.058362 -260.854659)
			(xy 133.102894 -260.831969) (xy 133.150426 -260.816525) (xy 133.199789 -260.808706) (xy 133.249767 -260.808706)
			(xy 133.29913 -260.816525) (xy 133.346662 -260.831969) (xy 133.391194 -260.854659) (xy 133.431627 -260.884035)
			(xy 133.466967 -260.919375) (xy 133.496343 -260.959808) (xy 133.519033 -261.00434) (xy 133.534477 -261.051872)
			(xy 133.542296 -261.101235) (xy 133.542786 -261.126224) (xy 133.542296 -261.151213) (xy 133.847314 -261.151213)
			(xy 133.847314 -261.101235) (xy 133.855133 -261.051872) (xy 133.870577 -261.00434) (xy 133.893267 -260.959808)
			(xy 133.922643 -260.919375) (xy 133.957983 -260.884035) (xy 133.998416 -260.854659) (xy 134.042948 -260.831969)
			(xy 134.09048 -260.816525) (xy 134.139843 -260.808706) (xy 134.189821 -260.808706) (xy 134.239184 -260.816525)
			(xy 134.286716 -260.831969) (xy 134.331248 -260.854659) (xy 134.371681 -260.884035) (xy 134.407021 -260.919375)
			(xy 134.436397 -260.959808) (xy 134.459087 -261.00434) (xy 134.474531 -261.051872) (xy 134.48235 -261.101235)
			(xy 134.48284 -261.126224) (xy 134.48235 -261.151213) (xy 134.787114 -261.151213) (xy 134.787114 -261.101235)
			(xy 134.794933 -261.051872) (xy 134.810377 -261.00434) (xy 134.833067 -260.959808) (xy 134.862443 -260.919375)
			(xy 134.897783 -260.884035) (xy 134.938216 -260.854659) (xy 134.982748 -260.831969) (xy 135.03028 -260.816525)
			(xy 135.079643 -260.808706) (xy 135.129621 -260.808706) (xy 135.178984 -260.816525) (xy 135.226516 -260.831969)
			(xy 135.271048 -260.854659) (xy 135.311481 -260.884035) (xy 135.346821 -260.919375) (xy 135.376197 -260.959808)
			(xy 135.398887 -261.00434) (xy 135.414331 -261.051872) (xy 135.42215 -261.101235) (xy 135.42264 -261.126224)
			(xy 135.42215 -261.151213) (xy 135.727168 -261.151213) (xy 135.727168 -261.101235) (xy 135.734987 -261.051872)
			(xy 135.750431 -261.00434) (xy 135.773121 -260.959808) (xy 135.802497 -260.919375) (xy 135.837837 -260.884035)
			(xy 135.87827 -260.854659) (xy 135.922802 -260.831969) (xy 135.970334 -260.816525) (xy 136.019697 -260.808706)
			(xy 136.069675 -260.808706) (xy 136.119038 -260.816525) (xy 136.16657 -260.831969) (xy 136.211102 -260.854659)
			(xy 136.251535 -260.884035) (xy 136.286875 -260.919375) (xy 136.316251 -260.959808) (xy 136.338941 -261.00434)
			(xy 136.354385 -261.051872) (xy 136.362204 -261.101235) (xy 136.362694 -261.126224) (xy 136.362204 -261.151213)
			(xy 136.667222 -261.151213) (xy 136.667222 -261.101235) (xy 136.675041 -261.051872) (xy 136.690485 -261.00434)
			(xy 136.713175 -260.959808) (xy 136.742551 -260.919375) (xy 136.777891 -260.884035) (xy 136.818324 -260.854659)
			(xy 136.862856 -260.831969) (xy 136.910388 -260.816525) (xy 136.959751 -260.808706) (xy 137.009729 -260.808706)
			(xy 137.059092 -260.816525) (xy 137.106624 -260.831969) (xy 137.151156 -260.854659) (xy 137.191589 -260.884035)
			(xy 137.226929 -260.919375) (xy 137.256305 -260.959808) (xy 137.278995 -261.00434) (xy 137.294439 -261.051872)
			(xy 137.302258 -261.101235) (xy 137.302748 -261.126224) (xy 137.302258 -261.151213) (xy 137.607276 -261.151213)
			(xy 137.607276 -261.101235) (xy 137.615095 -261.051872) (xy 137.630539 -261.00434) (xy 137.653229 -260.959808)
			(xy 137.682605 -260.919375) (xy 137.717945 -260.884035) (xy 137.758378 -260.854659) (xy 137.80291 -260.831969)
			(xy 137.850442 -260.816525) (xy 137.899805 -260.808706) (xy 137.949783 -260.808706) (xy 137.999146 -260.816525)
			(xy 138.046678 -260.831969) (xy 138.09121 -260.854659) (xy 138.131643 -260.884035) (xy 138.166983 -260.919375)
			(xy 138.196359 -260.959808) (xy 138.219049 -261.00434) (xy 138.234493 -261.051872) (xy 138.242312 -261.101235)
			(xy 138.242802 -261.126224) (xy 138.242312 -261.151213) (xy 138.54733 -261.151213) (xy 138.54733 -261.101235)
			(xy 138.555149 -261.051872) (xy 138.570593 -261.00434) (xy 138.593283 -260.959808) (xy 138.622659 -260.919375)
			(xy 138.657999 -260.884035) (xy 138.698432 -260.854659) (xy 138.742964 -260.831969) (xy 138.790496 -260.816525)
			(xy 138.839859 -260.808706) (xy 138.889837 -260.808706) (xy 138.9392 -260.816525) (xy 138.986732 -260.831969)
			(xy 139.031264 -260.854659) (xy 139.071697 -260.884035) (xy 139.107037 -260.919375) (xy 139.136413 -260.959808)
			(xy 139.159103 -261.00434) (xy 139.174547 -261.051872) (xy 139.182366 -261.101235) (xy 139.182856 -261.126224)
			(xy 139.182366 -261.151213) (xy 139.48713 -261.151213) (xy 139.48713 -261.101235) (xy 139.494949 -261.051872)
			(xy 139.510393 -261.00434) (xy 139.533083 -260.959808) (xy 139.562459 -260.919375) (xy 139.597799 -260.884035)
			(xy 139.638232 -260.854659) (xy 139.682764 -260.831969) (xy 139.730296 -260.816525) (xy 139.779659 -260.808706)
			(xy 139.829637 -260.808706) (xy 139.879 -260.816525) (xy 139.926532 -260.831969) (xy 139.971064 -260.854659)
			(xy 140.011497 -260.884035) (xy 140.046837 -260.919375) (xy 140.076213 -260.959808) (xy 140.098903 -261.00434)
			(xy 140.114347 -261.051872) (xy 140.122166 -261.101235) (xy 140.122656 -261.126224) (xy 140.122166 -261.151213)
			(xy 140.427184 -261.151213) (xy 140.427184 -261.101235) (xy 140.435003 -261.051872) (xy 140.450447 -261.00434)
			(xy 140.473137 -260.959808) (xy 140.502513 -260.919375) (xy 140.537853 -260.884035) (xy 140.578286 -260.854659)
			(xy 140.622818 -260.831969) (xy 140.67035 -260.816525) (xy 140.719713 -260.808706) (xy 140.769691 -260.808706)
			(xy 140.819054 -260.816525) (xy 140.866586 -260.831969) (xy 140.911118 -260.854659) (xy 140.951551 -260.884035)
			(xy 140.986891 -260.919375) (xy 141.016267 -260.959808) (xy 141.038957 -261.00434) (xy 141.054401 -261.051872)
			(xy 141.06222 -261.101235) (xy 141.06271 -261.126224) (xy 141.06222 -261.151213) (xy 141.367238 -261.151213)
			(xy 141.367238 -261.101235) (xy 141.375057 -261.051872) (xy 141.390501 -261.00434) (xy 141.413191 -260.959808)
			(xy 141.442567 -260.919375) (xy 141.477907 -260.884035) (xy 141.51834 -260.854659) (xy 141.562872 -260.831969)
			(xy 141.610404 -260.816525) (xy 141.659767 -260.808706) (xy 141.709745 -260.808706) (xy 141.759108 -260.816525)
			(xy 141.80664 -260.831969) (xy 141.851172 -260.854659) (xy 141.891605 -260.884035) (xy 141.926945 -260.919375)
			(xy 141.956321 -260.959808) (xy 141.979011 -261.00434) (xy 141.994455 -261.051872) (xy 142.002274 -261.101235)
			(xy 142.002764 -261.126224) (xy 142.002274 -261.151213) (xy 142.307292 -261.151213) (xy 142.307292 -261.101235)
			(xy 142.315111 -261.051872) (xy 142.330555 -261.00434) (xy 142.353245 -260.959808) (xy 142.382621 -260.919375)
			(xy 142.417961 -260.884035) (xy 142.458394 -260.854659) (xy 142.502926 -260.831969) (xy 142.550458 -260.816525)
			(xy 142.599821 -260.808706) (xy 142.649799 -260.808706) (xy 142.699162 -260.816525) (xy 142.746694 -260.831969)
			(xy 142.791226 -260.854659) (xy 142.831659 -260.884035) (xy 142.866999 -260.919375) (xy 142.896375 -260.959808)
			(xy 142.919065 -261.00434) (xy 142.934509 -261.051872) (xy 142.942328 -261.101235) (xy 142.942818 -261.126224)
			(xy 142.942328 -261.151213) (xy 143.247346 -261.151213) (xy 143.247346 -261.101235) (xy 143.255165 -261.051872)
			(xy 143.270609 -261.00434) (xy 143.293299 -260.959808) (xy 143.322675 -260.919375) (xy 143.358015 -260.884035)
			(xy 143.398448 -260.854659) (xy 143.44298 -260.831969) (xy 143.490512 -260.816525) (xy 143.539875 -260.808706)
			(xy 143.589853 -260.808706) (xy 143.639216 -260.816525) (xy 143.686748 -260.831969) (xy 143.73128 -260.854659)
			(xy 143.771713 -260.884035) (xy 143.807053 -260.919375) (xy 143.836429 -260.959808) (xy 143.859119 -261.00434)
			(xy 143.874563 -261.051872) (xy 143.882382 -261.101235) (xy 143.882872 -261.126224) (xy 143.882382 -261.151213)
			(xy 144.187146 -261.151213) (xy 144.187146 -261.101235) (xy 144.194965 -261.051872) (xy 144.210409 -261.00434)
			(xy 144.233099 -260.959808) (xy 144.262475 -260.919375) (xy 144.297815 -260.884035) (xy 144.338248 -260.854659)
			(xy 144.38278 -260.831969) (xy 144.430312 -260.816525) (xy 144.479675 -260.808706) (xy 144.529653 -260.808706)
			(xy 144.579016 -260.816525) (xy 144.626548 -260.831969) (xy 144.67108 -260.854659) (xy 144.711513 -260.884035)
			(xy 144.746853 -260.919375) (xy 144.776229 -260.959808) (xy 144.798919 -261.00434) (xy 144.814363 -261.051872)
			(xy 144.822182 -261.101235) (xy 144.822672 -261.126224) (xy 144.822182 -261.151213) (xy 144.814363 -261.200576)
			(xy 144.798919 -261.248108) (xy 144.776229 -261.29264) (xy 144.746853 -261.333073) (xy 144.711513 -261.368413)
			(xy 144.67108 -261.397789) (xy 144.626548 -261.420479) (xy 144.579016 -261.435923) (xy 144.529653 -261.443742)
			(xy 144.479675 -261.443742) (xy 144.430312 -261.435923) (xy 144.38278 -261.420479) (xy 144.338248 -261.397789)
			(xy 144.297815 -261.368413) (xy 144.262475 -261.333073) (xy 144.233099 -261.29264) (xy 144.210409 -261.248108)
			(xy 144.194965 -261.200576) (xy 144.187146 -261.151213) (xy 143.882382 -261.151213) (xy 143.874563 -261.200576)
			(xy 143.859119 -261.248108) (xy 143.836429 -261.29264) (xy 143.807053 -261.333073) (xy 143.771713 -261.368413)
			(xy 143.73128 -261.397789) (xy 143.686748 -261.420479) (xy 143.639216 -261.435923) (xy 143.589853 -261.443742)
			(xy 143.539875 -261.443742) (xy 143.490512 -261.435923) (xy 143.44298 -261.420479) (xy 143.398448 -261.397789)
			(xy 143.358015 -261.368413) (xy 143.322675 -261.333073) (xy 143.293299 -261.29264) (xy 143.270609 -261.248108)
			(xy 143.255165 -261.200576) (xy 143.247346 -261.151213) (xy 142.942328 -261.151213) (xy 142.934509 -261.200576)
			(xy 142.919065 -261.248108) (xy 142.896375 -261.29264) (xy 142.866999 -261.333073) (xy 142.831659 -261.368413)
			(xy 142.791226 -261.397789) (xy 142.746694 -261.420479) (xy 142.699162 -261.435923) (xy 142.649799 -261.443742)
			(xy 142.599821 -261.443742) (xy 142.550458 -261.435923) (xy 142.502926 -261.420479) (xy 142.458394 -261.397789)
			(xy 142.417961 -261.368413) (xy 142.382621 -261.333073) (xy 142.353245 -261.29264) (xy 142.330555 -261.248108)
			(xy 142.315111 -261.200576) (xy 142.307292 -261.151213) (xy 142.002274 -261.151213) (xy 141.994455 -261.200576)
			(xy 141.979011 -261.248108) (xy 141.956321 -261.29264) (xy 141.926945 -261.333073) (xy 141.891605 -261.368413)
			(xy 141.851172 -261.397789) (xy 141.80664 -261.420479) (xy 141.759108 -261.435923) (xy 141.709745 -261.443742)
			(xy 141.659767 -261.443742) (xy 141.610404 -261.435923) (xy 141.562872 -261.420479) (xy 141.51834 -261.397789)
			(xy 141.477907 -261.368413) (xy 141.442567 -261.333073) (xy 141.413191 -261.29264) (xy 141.390501 -261.248108)
			(xy 141.375057 -261.200576) (xy 141.367238 -261.151213) (xy 141.06222 -261.151213) (xy 141.054401 -261.200576)
			(xy 141.038957 -261.248108) (xy 141.016267 -261.29264) (xy 140.986891 -261.333073) (xy 140.951551 -261.368413)
			(xy 140.911118 -261.397789) (xy 140.866586 -261.420479) (xy 140.819054 -261.435923) (xy 140.769691 -261.443742)
			(xy 140.719713 -261.443742) (xy 140.67035 -261.435923) (xy 140.622818 -261.420479) (xy 140.578286 -261.397789)
			(xy 140.537853 -261.368413) (xy 140.502513 -261.333073) (xy 140.473137 -261.29264) (xy 140.450447 -261.248108)
			(xy 140.435003 -261.200576) (xy 140.427184 -261.151213) (xy 140.122166 -261.151213) (xy 140.114347 -261.200576)
			(xy 140.098903 -261.248108) (xy 140.076213 -261.29264) (xy 140.046837 -261.333073) (xy 140.011497 -261.368413)
			(xy 139.971064 -261.397789) (xy 139.926532 -261.420479) (xy 139.879 -261.435923) (xy 139.829637 -261.443742)
			(xy 139.779659 -261.443742) (xy 139.730296 -261.435923) (xy 139.682764 -261.420479) (xy 139.638232 -261.397789)
			(xy 139.597799 -261.368413) (xy 139.562459 -261.333073) (xy 139.533083 -261.29264) (xy 139.510393 -261.248108)
			(xy 139.494949 -261.200576) (xy 139.48713 -261.151213) (xy 139.182366 -261.151213) (xy 139.174547 -261.200576)
			(xy 139.159103 -261.248108) (xy 139.136413 -261.29264) (xy 139.107037 -261.333073) (xy 139.071697 -261.368413)
			(xy 139.031264 -261.397789) (xy 138.986732 -261.420479) (xy 138.9392 -261.435923) (xy 138.889837 -261.443742)
			(xy 138.839859 -261.443742) (xy 138.790496 -261.435923) (xy 138.742964 -261.420479) (xy 138.698432 -261.397789)
			(xy 138.657999 -261.368413) (xy 138.622659 -261.333073) (xy 138.593283 -261.29264) (xy 138.570593 -261.248108)
			(xy 138.555149 -261.200576) (xy 138.54733 -261.151213) (xy 138.242312 -261.151213) (xy 138.234493 -261.200576)
			(xy 138.219049 -261.248108) (xy 138.196359 -261.29264) (xy 138.166983 -261.333073) (xy 138.131643 -261.368413)
			(xy 138.09121 -261.397789) (xy 138.046678 -261.420479) (xy 137.999146 -261.435923) (xy 137.949783 -261.443742)
			(xy 137.899805 -261.443742) (xy 137.850442 -261.435923) (xy 137.80291 -261.420479) (xy 137.758378 -261.397789)
			(xy 137.717945 -261.368413) (xy 137.682605 -261.333073) (xy 137.653229 -261.29264) (xy 137.630539 -261.248108)
			(xy 137.615095 -261.200576) (xy 137.607276 -261.151213) (xy 137.302258 -261.151213) (xy 137.294439 -261.200576)
			(xy 137.278995 -261.248108) (xy 137.256305 -261.29264) (xy 137.226929 -261.333073) (xy 137.191589 -261.368413)
			(xy 137.151156 -261.397789) (xy 137.106624 -261.420479) (xy 137.059092 -261.435923) (xy 137.009729 -261.443742)
			(xy 136.959751 -261.443742) (xy 136.910388 -261.435923) (xy 136.862856 -261.420479) (xy 136.818324 -261.397789)
			(xy 136.777891 -261.368413) (xy 136.742551 -261.333073) (xy 136.713175 -261.29264) (xy 136.690485 -261.248108)
			(xy 136.675041 -261.200576) (xy 136.667222 -261.151213) (xy 136.362204 -261.151213) (xy 136.354385 -261.200576)
			(xy 136.338941 -261.248108) (xy 136.316251 -261.29264) (xy 136.286875 -261.333073) (xy 136.251535 -261.368413)
			(xy 136.211102 -261.397789) (xy 136.16657 -261.420479) (xy 136.119038 -261.435923) (xy 136.069675 -261.443742)
			(xy 136.019697 -261.443742) (xy 135.970334 -261.435923) (xy 135.922802 -261.420479) (xy 135.87827 -261.397789)
			(xy 135.837837 -261.368413) (xy 135.802497 -261.333073) (xy 135.773121 -261.29264) (xy 135.750431 -261.248108)
			(xy 135.734987 -261.200576) (xy 135.727168 -261.151213) (xy 135.42215 -261.151213) (xy 135.414331 -261.200576)
			(xy 135.398887 -261.248108) (xy 135.376197 -261.29264) (xy 135.346821 -261.333073) (xy 135.311481 -261.368413)
			(xy 135.271048 -261.397789) (xy 135.226516 -261.420479) (xy 135.178984 -261.435923) (xy 135.129621 -261.443742)
			(xy 135.079643 -261.443742) (xy 135.03028 -261.435923) (xy 134.982748 -261.420479) (xy 134.938216 -261.397789)
			(xy 134.897783 -261.368413) (xy 134.862443 -261.333073) (xy 134.833067 -261.29264) (xy 134.810377 -261.248108)
			(xy 134.794933 -261.200576) (xy 134.787114 -261.151213) (xy 134.48235 -261.151213) (xy 134.474531 -261.200576)
			(xy 134.459087 -261.248108) (xy 134.436397 -261.29264) (xy 134.407021 -261.333073) (xy 134.371681 -261.368413)
			(xy 134.331248 -261.397789) (xy 134.286716 -261.420479) (xy 134.239184 -261.435923) (xy 134.189821 -261.443742)
			(xy 134.139843 -261.443742) (xy 134.09048 -261.435923) (xy 134.042948 -261.420479) (xy 133.998416 -261.397789)
			(xy 133.957983 -261.368413) (xy 133.922643 -261.333073) (xy 133.893267 -261.29264) (xy 133.870577 -261.248108)
			(xy 133.855133 -261.200576) (xy 133.847314 -261.151213) (xy 133.542296 -261.151213) (xy 133.534477 -261.200576)
			(xy 133.519033 -261.248108) (xy 133.496343 -261.29264) (xy 133.466967 -261.333073) (xy 133.431627 -261.368413)
			(xy 133.391194 -261.397789) (xy 133.346662 -261.420479) (xy 133.29913 -261.435923) (xy 133.249767 -261.443742)
			(xy 133.199789 -261.443742) (xy 133.150426 -261.435923) (xy 133.102894 -261.420479) (xy 133.058362 -261.397789)
			(xy 133.017929 -261.368413) (xy 132.982589 -261.333073) (xy 132.953213 -261.29264) (xy 132.930523 -261.248108)
			(xy 132.915079 -261.200576) (xy 132.90726 -261.151213) (xy 132.602242 -261.151213) (xy 132.594423 -261.200576)
			(xy 132.578979 -261.248108) (xy 132.556289 -261.29264) (xy 132.526913 -261.333073) (xy 132.491573 -261.368413)
			(xy 132.45114 -261.397789) (xy 132.406608 -261.420479) (xy 132.359076 -261.435923) (xy 132.309713 -261.443742)
			(xy 132.259735 -261.443742) (xy 132.210372 -261.435923) (xy 132.16284 -261.420479) (xy 132.118308 -261.397789)
			(xy 132.077875 -261.368413) (xy 132.042535 -261.333073) (xy 132.013159 -261.29264) (xy 131.990469 -261.248108)
			(xy 131.975025 -261.200576) (xy 131.967206 -261.151213) (xy 131.662188 -261.151213) (xy 131.654369 -261.200576)
			(xy 131.638925 -261.248108) (xy 131.616235 -261.29264) (xy 131.586859 -261.333073) (xy 131.551519 -261.368413)
			(xy 131.511086 -261.397789) (xy 131.466554 -261.420479) (xy 131.419022 -261.435923) (xy 131.369659 -261.443742)
			(xy 131.319681 -261.443742) (xy 131.270318 -261.435923) (xy 131.222786 -261.420479) (xy 131.178254 -261.397789)
			(xy 131.137821 -261.368413) (xy 131.102481 -261.333073) (xy 131.073105 -261.29264) (xy 131.050415 -261.248108)
			(xy 131.034971 -261.200576) (xy 131.027152 -261.151213) (xy 130.722388 -261.151213) (xy 130.714569 -261.200576)
			(xy 130.699125 -261.248108) (xy 130.676435 -261.29264) (xy 130.647059 -261.333073) (xy 130.611719 -261.368413)
			(xy 130.571286 -261.397789) (xy 130.526754 -261.420479) (xy 130.479222 -261.435923) (xy 130.429859 -261.443742)
			(xy 130.379881 -261.443742) (xy 130.330518 -261.435923) (xy 130.282986 -261.420479) (xy 130.238454 -261.397789)
			(xy 130.198021 -261.368413) (xy 130.162681 -261.333073) (xy 130.133305 -261.29264) (xy 130.110615 -261.248108)
			(xy 130.095171 -261.200576) (xy 130.087352 -261.151213) (xy 129.782334 -261.151213) (xy 129.774515 -261.200576)
			(xy 129.759071 -261.248108) (xy 129.736381 -261.29264) (xy 129.707005 -261.333073) (xy 129.671665 -261.368413)
			(xy 129.631232 -261.397789) (xy 129.5867 -261.420479) (xy 129.539168 -261.435923) (xy 129.489805 -261.443742)
			(xy 129.439827 -261.443742) (xy 129.390464 -261.435923) (xy 129.342932 -261.420479) (xy 129.2984 -261.397789)
			(xy 129.257967 -261.368413) (xy 129.222627 -261.333073) (xy 129.193251 -261.29264) (xy 129.170561 -261.248108)
			(xy 129.155117 -261.200576) (xy 129.147298 -261.151213) (xy 128.84228 -261.151213) (xy 128.834461 -261.200576)
			(xy 128.819017 -261.248108) (xy 128.796327 -261.29264) (xy 128.766951 -261.333073) (xy 128.731611 -261.368413)
			(xy 128.691178 -261.397789) (xy 128.646646 -261.420479) (xy 128.599114 -261.435923) (xy 128.549751 -261.443742)
			(xy 128.499773 -261.443742) (xy 128.45041 -261.435923) (xy 128.402878 -261.420479) (xy 128.358346 -261.397789)
			(xy 128.317913 -261.368413) (xy 128.282573 -261.333073) (xy 128.253197 -261.29264) (xy 128.230507 -261.248108)
			(xy 128.215063 -261.200576) (xy 128.207244 -261.151213) (xy 127.902226 -261.151213) (xy 127.894407 -261.200576)
			(xy 127.878963 -261.248108) (xy 127.856273 -261.29264) (xy 127.826897 -261.333073) (xy 127.791557 -261.368413)
			(xy 127.751124 -261.397789) (xy 127.706592 -261.420479) (xy 127.65906 -261.435923) (xy 127.609697 -261.443742)
			(xy 127.559719 -261.443742) (xy 127.510356 -261.435923) (xy 127.462824 -261.420479) (xy 127.418292 -261.397789)
			(xy 127.377859 -261.368413) (xy 127.342519 -261.333073) (xy 127.313143 -261.29264) (xy 127.290453 -261.248108)
			(xy 127.275009 -261.200576) (xy 127.26719 -261.151213) (xy 126.022372 -261.151213) (xy 126.014553 -261.200576)
			(xy 125.999109 -261.248108) (xy 125.976419 -261.29264) (xy 125.947043 -261.333073) (xy 125.911703 -261.368413)
			(xy 125.87127 -261.397789) (xy 125.826738 -261.420479) (xy 125.779206 -261.435923) (xy 125.729843 -261.443742)
			(xy 125.679865 -261.443742) (xy 125.630502 -261.435923) (xy 125.58297 -261.420479) (xy 125.538438 -261.397789)
			(xy 125.498005 -261.368413) (xy 125.462665 -261.333073) (xy 125.433289 -261.29264) (xy 125.410599 -261.248108)
			(xy 125.395155 -261.200576) (xy 125.387336 -261.151213) (xy 124.362972 -261.151213) (xy 124.362972 -261.300976)
			(xy 124.36256 -261.310999) (xy 124.354893 -261.329521) (xy 124.340718 -261.343695) (xy 124.322195 -261.351361)
			(xy 124.312172 -261.351776) (xy 124.098304 -261.351776) (xy 124.098304 -261.36092) (xy 124.097829 -261.370928)
			(xy 124.090163 -261.38942) (xy 124.076007 -261.403572) (xy 124.057513 -261.411232) (xy 124.047504 -261.41172)
			(xy 123.964954 -261.41172) (xy 123.955048 -261.416292) (xy 123.93447 -261.425114) (xy 123.891461 -261.437559)
			(xy 123.847132 -261.443847) (xy 123.824746 -261.444232) (xy 123.799757 -261.443701) (xy 123.750394 -261.435889)
			(xy 123.702861 -261.420452) (xy 123.658328 -261.397768) (xy 123.617892 -261.368397) (xy 123.582549 -261.333061)
			(xy 123.553169 -261.292632) (xy 123.530475 -261.248104) (xy 123.515027 -261.200574) (xy 123.507205 -261.151213)
			(xy 123.506738 -261.126224) (xy 122.457972 -261.126224) (xy 122.457972 -261.300976) (xy 122.45756 -261.310999)
			(xy 122.449893 -261.329521) (xy 122.435718 -261.343695) (xy 122.417195 -261.351361) (xy 122.407172 -261.351776)
			(xy 122.193304 -261.351776) (xy 122.193304 -261.36092) (xy 122.192829 -261.370928) (xy 122.185163 -261.38942)
			(xy 122.171007 -261.403572) (xy 122.152513 -261.411232) (xy 122.142504 -261.41172) (xy 122.084846 -261.41172)
			(xy 122.07494 -261.416292) (xy 122.054363 -261.425116) (xy 122.011354 -261.43756) (xy 121.967024 -261.443847)
			(xy 121.944638 -261.444232) (xy 121.919649 -261.443708) (xy 121.870286 -261.435896) (xy 121.822752 -261.420457)
			(xy 121.778219 -261.397772) (xy 121.737783 -261.3684) (xy 121.70244 -261.333064) (xy 121.67306 -261.292634)
			(xy 121.650367 -261.248105) (xy 121.634919 -261.200575) (xy 121.627097 -261.151213) (xy 121.62663 -261.126224)
			(xy 117.885464 -261.126224) (xy 117.885464 -261.412482) (xy 117.88648 -261.422388) (xy 117.888184 -261.429547)
			(xy 117.895016 -261.442575) (xy 117.899942 -261.448042) (xy 118.137178 -261.685278) (xy 118.142673 -261.690273)
			(xy 118.155837 -261.697132) (xy 118.163086 -261.69874) (xy 118.172738 -261.699756) (xy 118.55831 -261.699756)
			(xy 118.568153 -261.70028) (xy 118.586334 -261.707847) (xy 118.593616 -261.714488) (xy 118.824756 -261.945882)
			(xy 118.82501 -261.945882) (xy 119.070628 -262.191754) (xy 119.071898 -262.193024) (xy 119.074527 -262.195552)
			(xy 119.080394 -262.199886) (xy 119.083582 -262.20166) (xy 119.089211 -262.204485) (xy 119.101417 -262.207569)
			(xy 119.107712 -262.207756) (xy 122.01906 -262.207756) (xy 122.029288 -262.207284) (xy 122.048061 -262.199164)
			(xy 122.055382 -262.192008) (xy 122.105928 -262.137652) (xy 122.110955 -262.131466) (xy 122.117289 -262.116848)
			(xy 122.118374 -262.10895) (xy 122.118374 -262.095234) (xy 122.11812 -262.081518) (xy 122.11812 -262.051038)
			(xy 122.115072 -262.042656) (xy 122.106574 -262.016937) (xy 122.097373 -261.963564) (xy 122.096784 -261.936484)
			(xy 122.096784 -261.935976) (xy 122.09733 -261.908892) (xy 122.10653 -261.855512) (xy 122.115072 -261.829804)
			(xy 122.11812 -261.821422) (xy 122.11812 -261.786624) (xy 122.11812 -261.78637) (xy 122.118483 -261.76532)
			(xy 122.126479 -261.723993) (xy 122.142413 -261.685031) (xy 122.165668 -261.649943) (xy 122.195343 -261.620088)
			(xy 122.230289 -261.596622) (xy 122.269154 -261.580452) (xy 122.310433 -261.572206) (xy 122.33148 -261.57174)
			(xy 122.556778 -261.57174) (xy 122.586496 -261.601458) (xy 122.586496 -261.60984) (xy 122.589393 -261.613773)
			(xy 122.596432 -261.620546) (xy 122.600466 -261.623302) (xy 122.606797 -261.627161) (xy 122.620996 -261.631408)
			(xy 122.628406 -261.631684) (xy 122.821446 -261.631684) (xy 122.851164 -261.661402) (xy 122.851164 -261.676134)
			(xy 122.851418 -261.678674) (xy 122.851418 -262.157972) (xy 122.851793 -262.167808) (xy 122.859276 -262.185998)
			(xy 122.87318 -262.19991) (xy 122.891366 -262.207402) (xy 122.901202 -262.207756) (xy 123.00331 -262.207756)
			(xy 123.013153 -262.20828) (xy 123.031334 -262.215847) (xy 123.038616 -262.222488) (xy 123.124214 -262.308086)
			(xy 123.129712 -262.313076) (xy 123.142877 -262.319925) (xy 123.150122 -262.321548) (xy 123.159774 -262.322564)
			(xy 123.928378 -262.322564) (xy 123.933409 -262.32242) (xy 123.943261 -262.320365) (xy 123.947936 -262.3185)
			(xy 123.953366 -262.316104) (xy 123.963 -262.30918) (xy 123.966986 -262.304784) (xy 123.971304 -262.298688)
			(xy 124.016008 -262.228076) (xy 124.019245 -262.222546) (xy 124.023109 -262.210332) (xy 124.023628 -262.203946)
			(xy 124.02439 -262.190992) (xy 124.018802 -262.179308) (xy 124.018802 -262.1788) (xy 124.00903 -262.156886)
			(xy 123.998523 -262.110078) (xy 123.997974 -262.08609) (xy 123.997974 -262.051546) (xy 123.994926 -262.043164)
			(xy 123.986387 -262.017521) (xy 123.977185 -261.964267) (xy 123.976638 -261.937246) (xy 123.976638 -261.935976)
			(xy 123.977185 -261.908892) (xy 123.986386 -261.855512) (xy 123.994926 -261.829804) (xy 123.997974 -261.821422)
			(xy 123.997974 -261.786624) (xy 123.997974 -261.78637) (xy 123.998337 -261.765322) (xy 124.006334 -261.723999)
			(xy 124.022269 -261.685041) (xy 124.045525 -261.649959) (xy 124.075201 -261.62011) (xy 124.110148 -261.596652)
			(xy 124.149012 -261.580491) (xy 124.190289 -261.572255) (xy 124.211334 -261.57174) (xy 124.436378 -261.57174)
			(xy 124.466096 -261.601458) (xy 124.466096 -261.609586) (xy 124.473567 -261.619253) (xy 124.495059 -261.630791)
			(xy 124.507244 -261.631684) (xy 124.680472 -261.631684) (xy 124.690498 -261.632099) (xy 124.709027 -261.639763)
			(xy 124.723212 -261.653936) (xy 124.730893 -261.672458) (xy 124.731272 -261.682484) (xy 124.731272 -261.961219)
			(xy 125.857236 -261.961219) (xy 125.857236 -261.911241) (xy 125.865055 -261.861878) (xy 125.880499 -261.814346)
			(xy 125.903189 -261.769814) (xy 125.932565 -261.729381) (xy 125.967905 -261.694041) (xy 126.008338 -261.664665)
			(xy 126.05287 -261.641975) (xy 126.100402 -261.626531) (xy 126.149765 -261.618712) (xy 126.199743 -261.618712)
			(xy 126.249106 -261.626531) (xy 126.296638 -261.641975) (xy 126.34117 -261.664665) (xy 126.381603 -261.694041)
			(xy 126.416943 -261.729381) (xy 126.446319 -261.769814) (xy 126.469009 -261.814346) (xy 126.484453 -261.861878)
			(xy 126.492272 -261.911241) (xy 126.492762 -261.93623) (xy 127.738627 -261.93623) (xy 127.742722 -261.885502)
			(xy 127.754901 -261.836088) (xy 127.774849 -261.789268) (xy 127.80205 -261.746254) (xy 127.835798 -261.70816)
			(xy 127.87522 -261.675973) (xy 127.919294 -261.650527) (xy 127.96688 -261.63248) (xy 128.016744 -261.6223)
			(xy 128.067596 -261.620251) (xy 128.118117 -261.626385) (xy 128.167001 -261.640545) (xy 128.21298 -261.662362)
			(xy 128.254864 -261.691272) (xy 128.291568 -261.726527) (xy 128.322141 -261.767213) (xy 128.345792 -261.812276)
			(xy 128.361908 -261.86055) (xy 128.370072 -261.910784) (xy 128.370584 -261.93623) (xy 128.370081 -261.961219)
			(xy 128.677144 -261.961219) (xy 128.677144 -261.911241) (xy 128.684963 -261.861878) (xy 128.700407 -261.814346)
			(xy 128.723097 -261.769814) (xy 128.752473 -261.729381) (xy 128.787813 -261.694041) (xy 128.828246 -261.664665)
			(xy 128.872778 -261.641975) (xy 128.92031 -261.626531) (xy 128.969673 -261.618712) (xy 129.019651 -261.618712)
			(xy 129.069014 -261.626531) (xy 129.116546 -261.641975) (xy 129.161078 -261.664665) (xy 129.201511 -261.694041)
			(xy 129.236851 -261.729381) (xy 129.266227 -261.769814) (xy 129.288917 -261.814346) (xy 129.304361 -261.861878)
			(xy 129.31218 -261.911241) (xy 129.31267 -261.93623) (xy 129.31218 -261.961219) (xy 129.617198 -261.961219)
			(xy 129.617198 -261.911241) (xy 129.625017 -261.861878) (xy 129.640461 -261.814346) (xy 129.663151 -261.769814)
			(xy 129.692527 -261.729381) (xy 129.727867 -261.694041) (xy 129.7683 -261.664665) (xy 129.812832 -261.641975)
			(xy 129.860364 -261.626531) (xy 129.909727 -261.618712) (xy 129.959705 -261.618712) (xy 130.009068 -261.626531)
			(xy 130.0566 -261.641975) (xy 130.101132 -261.664665) (xy 130.141565 -261.694041) (xy 130.176905 -261.729381)
			(xy 130.206281 -261.769814) (xy 130.228971 -261.814346) (xy 130.244415 -261.861878) (xy 130.252234 -261.911241)
			(xy 130.252724 -261.93623) (xy 130.252234 -261.961219) (xy 130.557252 -261.961219) (xy 130.557252 -261.911241)
			(xy 130.565071 -261.861878) (xy 130.580515 -261.814346) (xy 130.603205 -261.769814) (xy 130.632581 -261.729381)
			(xy 130.667921 -261.694041) (xy 130.708354 -261.664665) (xy 130.752886 -261.641975) (xy 130.800418 -261.626531)
			(xy 130.849781 -261.618712) (xy 130.899759 -261.618712) (xy 130.949122 -261.626531) (xy 130.996654 -261.641975)
			(xy 131.041186 -261.664665) (xy 131.081619 -261.694041) (xy 131.116959 -261.729381) (xy 131.146335 -261.769814)
			(xy 131.169025 -261.814346) (xy 131.184469 -261.861878) (xy 131.192288 -261.911241) (xy 131.192778 -261.93623)
			(xy 131.498589 -261.93623) (xy 131.502684 -261.885502) (xy 131.514863 -261.836088) (xy 131.534811 -261.789268)
			(xy 131.562012 -261.746254) (xy 131.59576 -261.70816) (xy 131.635182 -261.675973) (xy 131.679256 -261.650527)
			(xy 131.726842 -261.63248) (xy 131.776706 -261.6223) (xy 131.827558 -261.620251) (xy 131.878079 -261.626385)
			(xy 131.926963 -261.640545) (xy 131.972942 -261.662362) (xy 132.014826 -261.691272) (xy 132.05153 -261.726527)
			(xy 132.082103 -261.767213) (xy 132.105754 -261.812276) (xy 132.12187 -261.86055) (xy 132.130034 -261.910784)
			(xy 132.130546 -261.93623) (xy 132.130043 -261.961219) (xy 132.437106 -261.961219) (xy 132.437106 -261.911241)
			(xy 132.444925 -261.861878) (xy 132.460369 -261.814346) (xy 132.483059 -261.769814) (xy 132.512435 -261.729381)
			(xy 132.547775 -261.694041) (xy 132.588208 -261.664665) (xy 132.63274 -261.641975) (xy 132.680272 -261.626531)
			(xy 132.729635 -261.618712) (xy 132.779613 -261.618712) (xy 132.828976 -261.626531) (xy 132.876508 -261.641975)
			(xy 132.92104 -261.664665) (xy 132.961473 -261.694041) (xy 132.996813 -261.729381) (xy 133.026189 -261.769814)
			(xy 133.048879 -261.814346) (xy 133.064323 -261.861878) (xy 133.072142 -261.911241) (xy 133.072632 -261.93623)
			(xy 133.072142 -261.961219) (xy 133.37716 -261.961219) (xy 133.37716 -261.911241) (xy 133.384979 -261.861878)
			(xy 133.400423 -261.814346) (xy 133.423113 -261.769814) (xy 133.452489 -261.729381) (xy 133.487829 -261.694041)
			(xy 133.528262 -261.664665) (xy 133.572794 -261.641975) (xy 133.620326 -261.626531) (xy 133.669689 -261.618712)
			(xy 133.719667 -261.618712) (xy 133.76903 -261.626531) (xy 133.816562 -261.641975) (xy 133.861094 -261.664665)
			(xy 133.901527 -261.694041) (xy 133.936867 -261.729381) (xy 133.966243 -261.769814) (xy 133.988933 -261.814346)
			(xy 134.004377 -261.861878) (xy 134.012196 -261.911241) (xy 134.012686 -261.93623) (xy 134.318497 -261.93623)
			(xy 134.322592 -261.885502) (xy 134.334771 -261.836088) (xy 134.354719 -261.789268) (xy 134.38192 -261.746254)
			(xy 134.415668 -261.70816) (xy 134.45509 -261.675973) (xy 134.499164 -261.650527) (xy 134.54675 -261.63248)
			(xy 134.596614 -261.6223) (xy 134.647466 -261.620251) (xy 134.697987 -261.626385) (xy 134.746871 -261.640545)
			(xy 134.79285 -261.662362) (xy 134.834734 -261.691272) (xy 134.871438 -261.726527) (xy 134.902011 -261.767213)
			(xy 134.925662 -261.812276) (xy 134.941778 -261.86055) (xy 134.949942 -261.910784) (xy 134.950454 -261.93623)
			(xy 134.949951 -261.961219) (xy 135.257268 -261.961219) (xy 135.257268 -261.911241) (xy 135.265087 -261.861878)
			(xy 135.280531 -261.814346) (xy 135.303221 -261.769814) (xy 135.332597 -261.729381) (xy 135.367937 -261.694041)
			(xy 135.40837 -261.664665) (xy 135.452902 -261.641975) (xy 135.500434 -261.626531) (xy 135.549797 -261.618712)
			(xy 135.599775 -261.618712) (xy 135.649138 -261.626531) (xy 135.69667 -261.641975) (xy 135.741202 -261.664665)
			(xy 135.781635 -261.694041) (xy 135.816975 -261.729381) (xy 135.846351 -261.769814) (xy 135.869041 -261.814346)
			(xy 135.884485 -261.861878) (xy 135.892304 -261.911241) (xy 135.892794 -261.93623) (xy 135.892304 -261.961219)
			(xy 136.197322 -261.961219) (xy 136.197322 -261.911241) (xy 136.205141 -261.861878) (xy 136.220585 -261.814346)
			(xy 136.243275 -261.769814) (xy 136.272651 -261.729381) (xy 136.307991 -261.694041) (xy 136.348424 -261.664665)
			(xy 136.392956 -261.641975) (xy 136.440488 -261.626531) (xy 136.489851 -261.618712) (xy 136.539829 -261.618712)
			(xy 136.589192 -261.626531) (xy 136.636724 -261.641975) (xy 136.681256 -261.664665) (xy 136.721689 -261.694041)
			(xy 136.757029 -261.729381) (xy 136.786405 -261.769814) (xy 136.809095 -261.814346) (xy 136.824539 -261.861878)
			(xy 136.832358 -261.911241) (xy 136.832848 -261.93623) (xy 136.832358 -261.961219) (xy 137.137122 -261.961219)
			(xy 137.137122 -261.911241) (xy 137.144941 -261.861878) (xy 137.160385 -261.814346) (xy 137.183075 -261.769814)
			(xy 137.212451 -261.729381) (xy 137.247791 -261.694041) (xy 137.288224 -261.664665) (xy 137.332756 -261.641975)
			(xy 137.380288 -261.626531) (xy 137.429651 -261.618712) (xy 137.479629 -261.618712) (xy 137.528992 -261.626531)
			(xy 137.576524 -261.641975) (xy 137.621056 -261.664665) (xy 137.661489 -261.694041) (xy 137.696829 -261.729381)
			(xy 137.726205 -261.769814) (xy 137.748895 -261.814346) (xy 137.764339 -261.861878) (xy 137.772158 -261.911241)
			(xy 137.772648 -261.93623) (xy 138.078459 -261.93623) (xy 138.082554 -261.885502) (xy 138.094733 -261.836088)
			(xy 138.114681 -261.789268) (xy 138.141882 -261.746254) (xy 138.17563 -261.70816) (xy 138.215052 -261.675973)
			(xy 138.259126 -261.650527) (xy 138.306712 -261.63248) (xy 138.356576 -261.6223) (xy 138.407428 -261.620251)
			(xy 138.457949 -261.626385) (xy 138.506833 -261.640545) (xy 138.552812 -261.662362) (xy 138.594696 -261.691272)
			(xy 138.6314 -261.726527) (xy 138.661973 -261.767213) (xy 138.685624 -261.812276) (xy 138.70174 -261.86055)
			(xy 138.709904 -261.910784) (xy 138.710416 -261.93623) (xy 138.709913 -261.961219) (xy 139.01723 -261.961219)
			(xy 139.01723 -261.911241) (xy 139.025049 -261.861878) (xy 139.040493 -261.814346) (xy 139.063183 -261.769814)
			(xy 139.092559 -261.729381) (xy 139.127899 -261.694041) (xy 139.168332 -261.664665) (xy 139.212864 -261.641975)
			(xy 139.260396 -261.626531) (xy 139.309759 -261.618712) (xy 139.359737 -261.618712) (xy 139.4091 -261.626531)
			(xy 139.456632 -261.641975) (xy 139.501164 -261.664665) (xy 139.541597 -261.694041) (xy 139.576937 -261.729381)
			(xy 139.606313 -261.769814) (xy 139.629003 -261.814346) (xy 139.644447 -261.861878) (xy 139.652266 -261.911241)
			(xy 139.652756 -261.93623) (xy 139.652266 -261.961219) (xy 139.957284 -261.961219) (xy 139.957284 -261.911241)
			(xy 139.965103 -261.861878) (xy 139.980547 -261.814346) (xy 140.003237 -261.769814) (xy 140.032613 -261.729381)
			(xy 140.067953 -261.694041) (xy 140.108386 -261.664665) (xy 140.152918 -261.641975) (xy 140.20045 -261.626531)
			(xy 140.249813 -261.618712) (xy 140.299791 -261.618712) (xy 140.349154 -261.626531) (xy 140.396686 -261.641975)
			(xy 140.441218 -261.664665) (xy 140.481651 -261.694041) (xy 140.516991 -261.729381) (xy 140.546367 -261.769814)
			(xy 140.569057 -261.814346) (xy 140.584501 -261.861878) (xy 140.59232 -261.911241) (xy 140.59281 -261.93623)
			(xy 140.898621 -261.93623) (xy 140.902716 -261.885502) (xy 140.914895 -261.836088) (xy 140.934843 -261.789268)
			(xy 140.962044 -261.746254) (xy 140.995792 -261.70816) (xy 141.035214 -261.675973) (xy 141.079288 -261.650527)
			(xy 141.126874 -261.63248) (xy 141.176738 -261.6223) (xy 141.22759 -261.620251) (xy 141.278111 -261.626385)
			(xy 141.326995 -261.640545) (xy 141.372974 -261.662362) (xy 141.414858 -261.691272) (xy 141.451562 -261.726527)
			(xy 141.482135 -261.767213) (xy 141.505786 -261.812276) (xy 141.521902 -261.86055) (xy 141.530066 -261.910784)
			(xy 141.530578 -261.93623) (xy 141.530075 -261.961219) (xy 141.837138 -261.961219) (xy 141.837138 -261.911241)
			(xy 141.844957 -261.861878) (xy 141.860401 -261.814346) (xy 141.883091 -261.769814) (xy 141.912467 -261.729381)
			(xy 141.947807 -261.694041) (xy 141.98824 -261.664665) (xy 142.032772 -261.641975) (xy 142.080304 -261.626531)
			(xy 142.129667 -261.618712) (xy 142.179645 -261.618712) (xy 142.229008 -261.626531) (xy 142.27654 -261.641975)
			(xy 142.321072 -261.664665) (xy 142.361505 -261.694041) (xy 142.396845 -261.729381) (xy 142.426221 -261.769814)
			(xy 142.448911 -261.814346) (xy 142.464355 -261.861878) (xy 142.472174 -261.911241) (xy 142.472664 -261.93623)
			(xy 142.472174 -261.961219) (xy 142.777192 -261.961219) (xy 142.777192 -261.911241) (xy 142.785011 -261.861878)
			(xy 142.800455 -261.814346) (xy 142.823145 -261.769814) (xy 142.852521 -261.729381) (xy 142.887861 -261.694041)
			(xy 142.928294 -261.664665) (xy 142.972826 -261.641975) (xy 143.020358 -261.626531) (xy 143.069721 -261.618712)
			(xy 143.119699 -261.618712) (xy 143.169062 -261.626531) (xy 143.216594 -261.641975) (xy 143.261126 -261.664665)
			(xy 143.301559 -261.694041) (xy 143.336899 -261.729381) (xy 143.366275 -261.769814) (xy 143.388965 -261.814346)
			(xy 143.404409 -261.861878) (xy 143.412228 -261.911241) (xy 143.412718 -261.93623) (xy 143.412228 -261.961219)
			(xy 143.717246 -261.961219) (xy 143.717246 -261.911241) (xy 143.725065 -261.861878) (xy 143.740509 -261.814346)
			(xy 143.763199 -261.769814) (xy 143.792575 -261.729381) (xy 143.827915 -261.694041) (xy 143.868348 -261.664665)
			(xy 143.91288 -261.641975) (xy 143.960412 -261.626531) (xy 144.009775 -261.618712) (xy 144.059753 -261.618712)
			(xy 144.109116 -261.626531) (xy 144.156648 -261.641975) (xy 144.20118 -261.664665) (xy 144.241613 -261.694041)
			(xy 144.276953 -261.729381) (xy 144.306329 -261.769814) (xy 144.329019 -261.814346) (xy 144.344463 -261.861878)
			(xy 144.352282 -261.911241) (xy 144.352772 -261.93623) (xy 144.352282 -261.961219) (xy 144.344463 -262.010582)
			(xy 144.329019 -262.058114) (xy 144.306329 -262.102646) (xy 144.276953 -262.143079) (xy 144.241613 -262.178419)
			(xy 144.20118 -262.207795) (xy 144.156648 -262.230485) (xy 144.109116 -262.245929) (xy 144.059753 -262.253748)
			(xy 144.009775 -262.253748) (xy 143.960412 -262.245929) (xy 143.91288 -262.230485) (xy 143.868348 -262.207795)
			(xy 143.827915 -262.178419) (xy 143.792575 -262.143079) (xy 143.763199 -262.102646) (xy 143.740509 -262.058114)
			(xy 143.725065 -262.010582) (xy 143.717246 -261.961219) (xy 143.412228 -261.961219) (xy 143.404409 -262.010582)
			(xy 143.388965 -262.058114) (xy 143.366275 -262.102646) (xy 143.336899 -262.143079) (xy 143.301559 -262.178419)
			(xy 143.261126 -262.207795) (xy 143.216594 -262.230485) (xy 143.169062 -262.245929) (xy 143.119699 -262.253748)
			(xy 143.069721 -262.253748) (xy 143.020358 -262.245929) (xy 142.972826 -262.230485) (xy 142.928294 -262.207795)
			(xy 142.887861 -262.178419) (xy 142.852521 -262.143079) (xy 142.823145 -262.102646) (xy 142.800455 -262.058114)
			(xy 142.785011 -262.010582) (xy 142.777192 -261.961219) (xy 142.472174 -261.961219) (xy 142.464355 -262.010582)
			(xy 142.448911 -262.058114) (xy 142.426221 -262.102646) (xy 142.396845 -262.143079) (xy 142.361505 -262.178419)
			(xy 142.321072 -262.207795) (xy 142.27654 -262.230485) (xy 142.229008 -262.245929) (xy 142.179645 -262.253748)
			(xy 142.129667 -262.253748) (xy 142.080304 -262.245929) (xy 142.032772 -262.230485) (xy 141.98824 -262.207795)
			(xy 141.947807 -262.178419) (xy 141.912467 -262.143079) (xy 141.883091 -262.102646) (xy 141.860401 -262.058114)
			(xy 141.844957 -262.010582) (xy 141.837138 -261.961219) (xy 141.530075 -261.961219) (xy 141.530066 -261.961676)
			(xy 141.521902 -262.01191) (xy 141.505786 -262.060184) (xy 141.482135 -262.105247) (xy 141.451562 -262.145933)
			(xy 141.414858 -262.181188) (xy 141.372974 -262.210098) (xy 141.326995 -262.231915) (xy 141.278111 -262.246075)
			(xy 141.22759 -262.252209) (xy 141.176738 -262.25016) (xy 141.126874 -262.23998) (xy 141.079288 -262.221933)
			(xy 141.035214 -262.196487) (xy 140.995792 -262.1643) (xy 140.962044 -262.126206) (xy 140.934843 -262.083192)
			(xy 140.914895 -262.036372) (xy 140.902716 -261.986958) (xy 140.898621 -261.93623) (xy 140.59281 -261.93623)
			(xy 140.59232 -261.961219) (xy 140.584501 -262.010582) (xy 140.569057 -262.058114) (xy 140.546367 -262.102646)
			(xy 140.516991 -262.143079) (xy 140.481651 -262.178419) (xy 140.441218 -262.207795) (xy 140.396686 -262.230485)
			(xy 140.349154 -262.245929) (xy 140.299791 -262.253748) (xy 140.249813 -262.253748) (xy 140.20045 -262.245929)
			(xy 140.152918 -262.230485) (xy 140.108386 -262.207795) (xy 140.067953 -262.178419) (xy 140.032613 -262.143079)
			(xy 140.003237 -262.102646) (xy 139.980547 -262.058114) (xy 139.965103 -262.010582) (xy 139.957284 -261.961219)
			(xy 139.652266 -261.961219) (xy 139.644447 -262.010582) (xy 139.629003 -262.058114) (xy 139.606313 -262.102646)
			(xy 139.576937 -262.143079) (xy 139.541597 -262.178419) (xy 139.501164 -262.207795) (xy 139.456632 -262.230485)
			(xy 139.4091 -262.245929) (xy 139.359737 -262.253748) (xy 139.309759 -262.253748) (xy 139.260396 -262.245929)
			(xy 139.212864 -262.230485) (xy 139.168332 -262.207795) (xy 139.127899 -262.178419) (xy 139.092559 -262.143079)
			(xy 139.063183 -262.102646) (xy 139.040493 -262.058114) (xy 139.025049 -262.010582) (xy 139.01723 -261.961219)
			(xy 138.709913 -261.961219) (xy 138.709904 -261.961676) (xy 138.70174 -262.01191) (xy 138.685624 -262.060184)
			(xy 138.661973 -262.105247) (xy 138.6314 -262.145933) (xy 138.594696 -262.181188) (xy 138.552812 -262.210098)
			(xy 138.506833 -262.231915) (xy 138.457949 -262.246075) (xy 138.407428 -262.252209) (xy 138.356576 -262.25016)
			(xy 138.306712 -262.23998) (xy 138.259126 -262.221933) (xy 138.215052 -262.196487) (xy 138.17563 -262.1643)
			(xy 138.141882 -262.126206) (xy 138.114681 -262.083192) (xy 138.094733 -262.036372) (xy 138.082554 -261.986958)
			(xy 138.078459 -261.93623) (xy 137.772648 -261.93623) (xy 137.772158 -261.961219) (xy 137.764339 -262.010582)
			(xy 137.748895 -262.058114) (xy 137.726205 -262.102646) (xy 137.696829 -262.143079) (xy 137.661489 -262.178419)
			(xy 137.621056 -262.207795) (xy 137.576524 -262.230485) (xy 137.528992 -262.245929) (xy 137.479629 -262.253748)
			(xy 137.429651 -262.253748) (xy 137.380288 -262.245929) (xy 137.332756 -262.230485) (xy 137.288224 -262.207795)
			(xy 137.247791 -262.178419) (xy 137.212451 -262.143079) (xy 137.183075 -262.102646) (xy 137.160385 -262.058114)
			(xy 137.144941 -262.010582) (xy 137.137122 -261.961219) (xy 136.832358 -261.961219) (xy 136.824539 -262.010582)
			(xy 136.809095 -262.058114) (xy 136.786405 -262.102646) (xy 136.757029 -262.143079) (xy 136.721689 -262.178419)
			(xy 136.681256 -262.207795) (xy 136.636724 -262.230485) (xy 136.589192 -262.245929) (xy 136.539829 -262.253748)
			(xy 136.489851 -262.253748) (xy 136.440488 -262.245929) (xy 136.392956 -262.230485) (xy 136.348424 -262.207795)
			(xy 136.307991 -262.178419) (xy 136.272651 -262.143079) (xy 136.243275 -262.102646) (xy 136.220585 -262.058114)
			(xy 136.205141 -262.010582) (xy 136.197322 -261.961219) (xy 135.892304 -261.961219) (xy 135.884485 -262.010582)
			(xy 135.869041 -262.058114) (xy 135.846351 -262.102646) (xy 135.816975 -262.143079) (xy 135.781635 -262.178419)
			(xy 135.741202 -262.207795) (xy 135.69667 -262.230485) (xy 135.649138 -262.245929) (xy 135.599775 -262.253748)
			(xy 135.549797 -262.253748) (xy 135.500434 -262.245929) (xy 135.452902 -262.230485) (xy 135.40837 -262.207795)
			(xy 135.367937 -262.178419) (xy 135.332597 -262.143079) (xy 135.303221 -262.102646) (xy 135.280531 -262.058114)
			(xy 135.265087 -262.010582) (xy 135.257268 -261.961219) (xy 134.949951 -261.961219) (xy 134.949942 -261.961676)
			(xy 134.941778 -262.01191) (xy 134.925662 -262.060184) (xy 134.902011 -262.105247) (xy 134.871438 -262.145933)
			(xy 134.834734 -262.181188) (xy 134.79285 -262.210098) (xy 134.746871 -262.231915) (xy 134.697987 -262.246075)
			(xy 134.647466 -262.252209) (xy 134.596614 -262.25016) (xy 134.54675 -262.23998) (xy 134.499164 -262.221933)
			(xy 134.45509 -262.196487) (xy 134.415668 -262.1643) (xy 134.38192 -262.126206) (xy 134.354719 -262.083192)
			(xy 134.334771 -262.036372) (xy 134.322592 -261.986958) (xy 134.318497 -261.93623) (xy 134.012686 -261.93623)
			(xy 134.012196 -261.961219) (xy 134.004377 -262.010582) (xy 133.988933 -262.058114) (xy 133.966243 -262.102646)
			(xy 133.936867 -262.143079) (xy 133.901527 -262.178419) (xy 133.861094 -262.207795) (xy 133.816562 -262.230485)
			(xy 133.76903 -262.245929) (xy 133.719667 -262.253748) (xy 133.669689 -262.253748) (xy 133.620326 -262.245929)
			(xy 133.572794 -262.230485) (xy 133.528262 -262.207795) (xy 133.487829 -262.178419) (xy 133.452489 -262.143079)
			(xy 133.423113 -262.102646) (xy 133.400423 -262.058114) (xy 133.384979 -262.010582) (xy 133.37716 -261.961219)
			(xy 133.072142 -261.961219) (xy 133.064323 -262.010582) (xy 133.048879 -262.058114) (xy 133.026189 -262.102646)
			(xy 132.996813 -262.143079) (xy 132.961473 -262.178419) (xy 132.92104 -262.207795) (xy 132.876508 -262.230485)
			(xy 132.828976 -262.245929) (xy 132.779613 -262.253748) (xy 132.729635 -262.253748) (xy 132.680272 -262.245929)
			(xy 132.63274 -262.230485) (xy 132.588208 -262.207795) (xy 132.547775 -262.178419) (xy 132.512435 -262.143079)
			(xy 132.483059 -262.102646) (xy 132.460369 -262.058114) (xy 132.444925 -262.010582) (xy 132.437106 -261.961219)
			(xy 132.130043 -261.961219) (xy 132.130034 -261.961676) (xy 132.12187 -262.01191) (xy 132.105754 -262.060184)
			(xy 132.082103 -262.105247) (xy 132.05153 -262.145933) (xy 132.014826 -262.181188) (xy 131.972942 -262.210098)
			(xy 131.926963 -262.231915) (xy 131.878079 -262.246075) (xy 131.827558 -262.252209) (xy 131.776706 -262.25016)
			(xy 131.726842 -262.23998) (xy 131.679256 -262.221933) (xy 131.635182 -262.196487) (xy 131.59576 -262.1643)
			(xy 131.562012 -262.126206) (xy 131.534811 -262.083192) (xy 131.514863 -262.036372) (xy 131.502684 -261.986958)
			(xy 131.498589 -261.93623) (xy 131.192778 -261.93623) (xy 131.192288 -261.961219) (xy 131.184469 -262.010582)
			(xy 131.169025 -262.058114) (xy 131.146335 -262.102646) (xy 131.116959 -262.143079) (xy 131.081619 -262.178419)
			(xy 131.041186 -262.207795) (xy 130.996654 -262.230485) (xy 130.949122 -262.245929) (xy 130.899759 -262.253748)
			(xy 130.849781 -262.253748) (xy 130.800418 -262.245929) (xy 130.752886 -262.230485) (xy 130.708354 -262.207795)
			(xy 130.667921 -262.178419) (xy 130.632581 -262.143079) (xy 130.603205 -262.102646) (xy 130.580515 -262.058114)
			(xy 130.565071 -262.010582) (xy 130.557252 -261.961219) (xy 130.252234 -261.961219) (xy 130.244415 -262.010582)
			(xy 130.228971 -262.058114) (xy 130.206281 -262.102646) (xy 130.176905 -262.143079) (xy 130.141565 -262.178419)
			(xy 130.101132 -262.207795) (xy 130.0566 -262.230485) (xy 130.009068 -262.245929) (xy 129.959705 -262.253748)
			(xy 129.909727 -262.253748) (xy 129.860364 -262.245929) (xy 129.812832 -262.230485) (xy 129.7683 -262.207795)
			(xy 129.727867 -262.178419) (xy 129.692527 -262.143079) (xy 129.663151 -262.102646) (xy 129.640461 -262.058114)
			(xy 129.625017 -262.010582) (xy 129.617198 -261.961219) (xy 129.31218 -261.961219) (xy 129.304361 -262.010582)
			(xy 129.288917 -262.058114) (xy 129.266227 -262.102646) (xy 129.236851 -262.143079) (xy 129.201511 -262.178419)
			(xy 129.161078 -262.207795) (xy 129.116546 -262.230485) (xy 129.069014 -262.245929) (xy 129.019651 -262.253748)
			(xy 128.969673 -262.253748) (xy 128.92031 -262.245929) (xy 128.872778 -262.230485) (xy 128.828246 -262.207795)
			(xy 128.787813 -262.178419) (xy 128.752473 -262.143079) (xy 128.723097 -262.102646) (xy 128.700407 -262.058114)
			(xy 128.684963 -262.010582) (xy 128.677144 -261.961219) (xy 128.370081 -261.961219) (xy 128.370072 -261.961676)
			(xy 128.361908 -262.01191) (xy 128.345792 -262.060184) (xy 128.322141 -262.105247) (xy 128.291568 -262.145933)
			(xy 128.254864 -262.181188) (xy 128.21298 -262.210098) (xy 128.167001 -262.231915) (xy 128.118117 -262.246075)
			(xy 128.067596 -262.252209) (xy 128.016744 -262.25016) (xy 127.96688 -262.23998) (xy 127.919294 -262.221933)
			(xy 127.87522 -262.196487) (xy 127.835798 -262.1643) (xy 127.80205 -262.126206) (xy 127.774849 -262.083192)
			(xy 127.754901 -262.036372) (xy 127.742722 -261.986958) (xy 127.738627 -261.93623) (xy 126.492762 -261.93623)
			(xy 126.492272 -261.961219) (xy 126.484453 -262.010582) (xy 126.469009 -262.058114) (xy 126.446319 -262.102646)
			(xy 126.416943 -262.143079) (xy 126.381603 -262.178419) (xy 126.34117 -262.207795) (xy 126.296638 -262.230485)
			(xy 126.249106 -262.245929) (xy 126.199743 -262.253748) (xy 126.149765 -262.253748) (xy 126.100402 -262.245929)
			(xy 126.05287 -262.230485) (xy 126.008338 -262.207795) (xy 125.967905 -262.178419) (xy 125.932565 -262.143079)
			(xy 125.903189 -262.102646) (xy 125.880499 -262.058114) (xy 125.865055 -262.010582) (xy 125.857236 -261.961219)
			(xy 124.731272 -261.961219) (xy 124.731272 -262.189976) (xy 124.730856 -262.199998) (xy 124.723189 -262.218519)
			(xy 124.709015 -262.232692) (xy 124.690494 -262.240357) (xy 124.680472 -262.240776) (xy 124.516134 -262.240776)
			(xy 124.506268 -262.241241) (xy 124.488073 -262.248892) (xy 124.474192 -262.262922) (xy 124.466736 -262.281197)
			(xy 124.46635 -262.291068) (xy 124.46635 -262.30072) (xy 124.243592 -262.30072) (xy 124.23361 -262.301126)
			(xy 124.215165 -262.308764) (xy 124.201072 -262.322903) (xy 124.196856 -262.331962) (xy 124.186696 -262.356092)
			(xy 124.183145 -262.365538) (xy 124.183032 -262.385702) (xy 124.19074 -262.404335) (xy 124.197618 -262.411718)
			(xy 124.291852 -262.505952) (xy 124.294701 -262.508661) (xy 124.301076 -262.51326) (xy 124.304552 -262.515096)
			(xy 124.309979 -262.517678) (xy 124.321659 -262.5205) (xy 124.327666 -262.520684) (xy 124.333254 -262.520684)
			(xy 124.362972 -262.550402) (xy 124.362972 -262.565642) (xy 124.363226 -262.567674) (xy 124.363226 -262.771225)
			(xy 125.387336 -262.771225) (xy 125.387336 -262.721247) (xy 125.395155 -262.671884) (xy 125.410599 -262.624352)
			(xy 125.433289 -262.57982) (xy 125.462665 -262.539387) (xy 125.498005 -262.504047) (xy 125.538438 -262.474671)
			(xy 125.58297 -262.451981) (xy 125.630502 -262.436537) (xy 125.679865 -262.428718) (xy 125.729843 -262.428718)
			(xy 125.779206 -262.436537) (xy 125.826738 -262.451981) (xy 125.87127 -262.474671) (xy 125.911703 -262.504047)
			(xy 125.947043 -262.539387) (xy 125.976419 -262.57982) (xy 125.999109 -262.624352) (xy 126.014553 -262.671884)
			(xy 126.022372 -262.721247) (xy 126.022862 -262.746236) (xy 126.022372 -262.771225) (xy 127.26719 -262.771225)
			(xy 127.26719 -262.721247) (xy 127.275009 -262.671884) (xy 127.290453 -262.624352) (xy 127.313143 -262.57982)
			(xy 127.342519 -262.539387) (xy 127.377859 -262.504047) (xy 127.418292 -262.474671) (xy 127.462824 -262.451981)
			(xy 127.510356 -262.436537) (xy 127.559719 -262.428718) (xy 127.609697 -262.428718) (xy 127.65906 -262.436537)
			(xy 127.706592 -262.451981) (xy 127.751124 -262.474671) (xy 127.791557 -262.504047) (xy 127.826897 -262.539387)
			(xy 127.856273 -262.57982) (xy 127.878963 -262.624352) (xy 127.894407 -262.671884) (xy 127.902226 -262.721247)
			(xy 127.902716 -262.746236) (xy 128.208527 -262.746236) (xy 128.212622 -262.695508) (xy 128.224801 -262.646094)
			(xy 128.244749 -262.599274) (xy 128.27195 -262.55626) (xy 128.305698 -262.518166) (xy 128.34512 -262.485979)
			(xy 128.389194 -262.460533) (xy 128.43678 -262.442486) (xy 128.486644 -262.432306) (xy 128.537496 -262.430257)
			(xy 128.588017 -262.436391) (xy 128.636901 -262.450551) (xy 128.68288 -262.472368) (xy 128.724764 -262.501278)
			(xy 128.761468 -262.536533) (xy 128.792041 -262.577219) (xy 128.815692 -262.622282) (xy 128.831808 -262.670556)
			(xy 128.839972 -262.72079) (xy 128.840484 -262.746236) (xy 129.148581 -262.746236) (xy 129.152676 -262.695508)
			(xy 129.164855 -262.646094) (xy 129.184803 -262.599274) (xy 129.212004 -262.55626) (xy 129.245752 -262.518166)
			(xy 129.285174 -262.485979) (xy 129.329248 -262.460533) (xy 129.376834 -262.442486) (xy 129.426698 -262.432306)
			(xy 129.47755 -262.430257) (xy 129.528071 -262.436391) (xy 129.576955 -262.450551) (xy 129.622934 -262.472368)
			(xy 129.664818 -262.501278) (xy 129.701522 -262.536533) (xy 129.732095 -262.577219) (xy 129.755746 -262.622282)
			(xy 129.771862 -262.670556) (xy 129.780026 -262.72079) (xy 129.780538 -262.746236) (xy 129.780035 -262.771225)
			(xy 130.087352 -262.771225) (xy 130.087352 -262.721247) (xy 130.095171 -262.671884) (xy 130.110615 -262.624352)
			(xy 130.133305 -262.57982) (xy 130.162681 -262.539387) (xy 130.198021 -262.504047) (xy 130.238454 -262.474671)
			(xy 130.282986 -262.451981) (xy 130.330518 -262.436537) (xy 130.379881 -262.428718) (xy 130.429859 -262.428718)
			(xy 130.479222 -262.436537) (xy 130.526754 -262.451981) (xy 130.571286 -262.474671) (xy 130.611719 -262.504047)
			(xy 130.647059 -262.539387) (xy 130.676435 -262.57982) (xy 130.699125 -262.624352) (xy 130.714569 -262.671884)
			(xy 130.722388 -262.721247) (xy 130.722878 -262.746236) (xy 131.028435 -262.746236) (xy 131.03253 -262.695508)
			(xy 131.044709 -262.646094) (xy 131.064657 -262.599274) (xy 131.091858 -262.55626) (xy 131.125606 -262.518166)
			(xy 131.165028 -262.485979) (xy 131.209102 -262.460533) (xy 131.256688 -262.442486) (xy 131.306552 -262.432306)
			(xy 131.357404 -262.430257) (xy 131.407925 -262.436391) (xy 131.456809 -262.450551) (xy 131.502788 -262.472368)
			(xy 131.544672 -262.501278) (xy 131.581376 -262.536533) (xy 131.611949 -262.577219) (xy 131.6356 -262.622282)
			(xy 131.651716 -262.670556) (xy 131.65988 -262.72079) (xy 131.660392 -262.746236) (xy 131.659889 -262.771225)
			(xy 131.967206 -262.771225) (xy 131.967206 -262.721247) (xy 131.975025 -262.671884) (xy 131.990469 -262.624352)
			(xy 132.013159 -262.57982) (xy 132.042535 -262.539387) (xy 132.077875 -262.504047) (xy 132.118308 -262.474671)
			(xy 132.16284 -262.451981) (xy 132.210372 -262.436537) (xy 132.259735 -262.428718) (xy 132.309713 -262.428718)
			(xy 132.359076 -262.436537) (xy 132.406608 -262.451981) (xy 132.45114 -262.474671) (xy 132.491573 -262.504047)
			(xy 132.526913 -262.539387) (xy 132.556289 -262.57982) (xy 132.578979 -262.624352) (xy 132.594423 -262.671884)
			(xy 132.602242 -262.721247) (xy 132.602732 -262.746236) (xy 132.908543 -262.746236) (xy 132.912638 -262.695508)
			(xy 132.924817 -262.646094) (xy 132.944765 -262.599274) (xy 132.971966 -262.55626) (xy 133.005714 -262.518166)
			(xy 133.045136 -262.485979) (xy 133.08921 -262.460533) (xy 133.136796 -262.442486) (xy 133.18666 -262.432306)
			(xy 133.237512 -262.430257) (xy 133.288033 -262.436391) (xy 133.336917 -262.450551) (xy 133.382896 -262.472368)
			(xy 133.42478 -262.501278) (xy 133.461484 -262.536533) (xy 133.492057 -262.577219) (xy 133.515708 -262.622282)
			(xy 133.531824 -262.670556) (xy 133.539988 -262.72079) (xy 133.5405 -262.746236) (xy 133.539997 -262.771225)
			(xy 133.847314 -262.771225) (xy 133.847314 -262.721247) (xy 133.855133 -262.671884) (xy 133.870577 -262.624352)
			(xy 133.893267 -262.57982) (xy 133.922643 -262.539387) (xy 133.957983 -262.504047) (xy 133.998416 -262.474671)
			(xy 134.042948 -262.451981) (xy 134.09048 -262.436537) (xy 134.139843 -262.428718) (xy 134.189821 -262.428718)
			(xy 134.239184 -262.436537) (xy 134.286716 -262.451981) (xy 134.331248 -262.474671) (xy 134.371681 -262.504047)
			(xy 134.407021 -262.539387) (xy 134.436397 -262.57982) (xy 134.459087 -262.624352) (xy 134.474531 -262.671884)
			(xy 134.48235 -262.721247) (xy 134.48284 -262.746236) (xy 134.788397 -262.746236) (xy 134.792492 -262.695508)
			(xy 134.804671 -262.646094) (xy 134.824619 -262.599274) (xy 134.85182 -262.55626) (xy 134.885568 -262.518166)
			(xy 134.92499 -262.485979) (xy 134.969064 -262.460533) (xy 135.01665 -262.442486) (xy 135.066514 -262.432306)
			(xy 135.117366 -262.430257) (xy 135.167887 -262.436391) (xy 135.216771 -262.450551) (xy 135.26275 -262.472368)
			(xy 135.304634 -262.501278) (xy 135.341338 -262.536533) (xy 135.371911 -262.577219) (xy 135.395562 -262.622282)
			(xy 135.411678 -262.670556) (xy 135.419842 -262.72079) (xy 135.420354 -262.746236) (xy 135.728451 -262.746236)
			(xy 135.732546 -262.695508) (xy 135.744725 -262.646094) (xy 135.764673 -262.599274) (xy 135.791874 -262.55626)
			(xy 135.825622 -262.518166) (xy 135.865044 -262.485979) (xy 135.909118 -262.460533) (xy 135.956704 -262.442486)
			(xy 136.006568 -262.432306) (xy 136.05742 -262.430257) (xy 136.107941 -262.436391) (xy 136.156825 -262.450551)
			(xy 136.202804 -262.472368) (xy 136.244688 -262.501278) (xy 136.281392 -262.536533) (xy 136.311965 -262.577219)
			(xy 136.335616 -262.622282) (xy 136.351732 -262.670556) (xy 136.359896 -262.72079) (xy 136.360408 -262.746236)
			(xy 136.359905 -262.771225) (xy 136.667222 -262.771225) (xy 136.667222 -262.721247) (xy 136.675041 -262.671884)
			(xy 136.690485 -262.624352) (xy 136.713175 -262.57982) (xy 136.742551 -262.539387) (xy 136.777891 -262.504047)
			(xy 136.818324 -262.474671) (xy 136.862856 -262.451981) (xy 136.910388 -262.436537) (xy 136.959751 -262.428718)
			(xy 137.009729 -262.428718) (xy 137.059092 -262.436537) (xy 137.106624 -262.451981) (xy 137.151156 -262.474671)
			(xy 137.191589 -262.504047) (xy 137.226929 -262.539387) (xy 137.256305 -262.57982) (xy 137.278995 -262.624352)
			(xy 137.294439 -262.671884) (xy 137.302258 -262.721247) (xy 137.302748 -262.746236) (xy 137.608559 -262.746236)
			(xy 137.612654 -262.695508) (xy 137.624833 -262.646094) (xy 137.644781 -262.599274) (xy 137.671982 -262.55626)
			(xy 137.70573 -262.518166) (xy 137.745152 -262.485979) (xy 137.789226 -262.460533) (xy 137.836812 -262.442486)
			(xy 137.886676 -262.432306) (xy 137.937528 -262.430257) (xy 137.988049 -262.436391) (xy 138.036933 -262.450551)
			(xy 138.082912 -262.472368) (xy 138.124796 -262.501278) (xy 138.1615 -262.536533) (xy 138.192073 -262.577219)
			(xy 138.215724 -262.622282) (xy 138.23184 -262.670556) (xy 138.240004 -262.72079) (xy 138.240516 -262.746236)
			(xy 138.240013 -262.771225) (xy 138.54733 -262.771225) (xy 138.54733 -262.721247) (xy 138.555149 -262.671884)
			(xy 138.570593 -262.624352) (xy 138.593283 -262.57982) (xy 138.622659 -262.539387) (xy 138.657999 -262.504047)
			(xy 138.698432 -262.474671) (xy 138.742964 -262.451981) (xy 138.790496 -262.436537) (xy 138.839859 -262.428718)
			(xy 138.889837 -262.428718) (xy 138.9392 -262.436537) (xy 138.986732 -262.451981) (xy 139.031264 -262.474671)
			(xy 139.071697 -262.504047) (xy 139.107037 -262.539387) (xy 139.136413 -262.57982) (xy 139.159103 -262.624352)
			(xy 139.174547 -262.671884) (xy 139.182366 -262.721247) (xy 139.182856 -262.746236) (xy 139.488413 -262.746236)
			(xy 139.492508 -262.695508) (xy 139.504687 -262.646094) (xy 139.524635 -262.599274) (xy 139.551836 -262.55626)
			(xy 139.585584 -262.518166) (xy 139.625006 -262.485979) (xy 139.66908 -262.460533) (xy 139.716666 -262.442486)
			(xy 139.76653 -262.432306) (xy 139.817382 -262.430257) (xy 139.867903 -262.436391) (xy 139.916787 -262.450551)
			(xy 139.962766 -262.472368) (xy 140.00465 -262.501278) (xy 140.041354 -262.536533) (xy 140.071927 -262.577219)
			(xy 140.095578 -262.622282) (xy 140.111694 -262.670556) (xy 140.119858 -262.72079) (xy 140.12037 -262.746236)
			(xy 140.119867 -262.771225) (xy 140.427184 -262.771225) (xy 140.427184 -262.721247) (xy 140.435003 -262.671884)
			(xy 140.450447 -262.624352) (xy 140.473137 -262.57982) (xy 140.502513 -262.539387) (xy 140.537853 -262.504047)
			(xy 140.578286 -262.474671) (xy 140.622818 -262.451981) (xy 140.67035 -262.436537) (xy 140.719713 -262.428718)
			(xy 140.769691 -262.428718) (xy 140.819054 -262.436537) (xy 140.866586 -262.451981) (xy 140.911118 -262.474671)
			(xy 140.951551 -262.504047) (xy 140.986891 -262.539387) (xy 141.016267 -262.57982) (xy 141.038957 -262.624352)
			(xy 141.054401 -262.671884) (xy 141.06222 -262.721247) (xy 141.06271 -262.746236) (xy 141.368521 -262.746236)
			(xy 141.372616 -262.695508) (xy 141.384795 -262.646094) (xy 141.404743 -262.599274) (xy 141.431944 -262.55626)
			(xy 141.465692 -262.518166) (xy 141.505114 -262.485979) (xy 141.549188 -262.460533) (xy 141.596774 -262.442486)
			(xy 141.646638 -262.432306) (xy 141.69749 -262.430257) (xy 141.748011 -262.436391) (xy 141.796895 -262.450551)
			(xy 141.842874 -262.472368) (xy 141.884758 -262.501278) (xy 141.921462 -262.536533) (xy 141.952035 -262.577219)
			(xy 141.975686 -262.622282) (xy 141.991802 -262.670556) (xy 141.999966 -262.72079) (xy 142.000478 -262.746236)
			(xy 142.308575 -262.746236) (xy 142.31267 -262.695508) (xy 142.324849 -262.646094) (xy 142.344797 -262.599274)
			(xy 142.371998 -262.55626) (xy 142.405746 -262.518166) (xy 142.445168 -262.485979) (xy 142.489242 -262.460533)
			(xy 142.536828 -262.442486) (xy 142.586692 -262.432306) (xy 142.637544 -262.430257) (xy 142.688065 -262.436391)
			(xy 142.736949 -262.450551) (xy 142.782928 -262.472368) (xy 142.824812 -262.501278) (xy 142.861516 -262.536533)
			(xy 142.892089 -262.577219) (xy 142.91574 -262.622282) (xy 142.931856 -262.670556) (xy 142.94002 -262.72079)
			(xy 142.940532 -262.746236) (xy 142.940029 -262.771225) (xy 143.247092 -262.771225) (xy 143.247092 -262.721247)
			(xy 143.254911 -262.671884) (xy 143.270355 -262.624352) (xy 143.293045 -262.57982) (xy 143.322421 -262.539387)
			(xy 143.357761 -262.504047) (xy 143.398194 -262.474671) (xy 143.442726 -262.451981) (xy 143.490258 -262.436537)
			(xy 143.539621 -262.428718) (xy 143.589599 -262.428718) (xy 143.638962 -262.436537) (xy 143.686494 -262.451981)
			(xy 143.731026 -262.474671) (xy 143.771459 -262.504047) (xy 143.806799 -262.539387) (xy 143.836175 -262.57982)
			(xy 143.858865 -262.624352) (xy 143.874309 -262.671884) (xy 143.882128 -262.721247) (xy 143.882618 -262.746236)
			(xy 143.882128 -262.771225) (xy 143.874309 -262.820588) (xy 143.858865 -262.86812) (xy 143.836175 -262.912652)
			(xy 143.806799 -262.953085) (xy 143.771459 -262.988425) (xy 143.731026 -263.017801) (xy 143.686494 -263.040491)
			(xy 143.638962 -263.055935) (xy 143.589599 -263.063754) (xy 143.539621 -263.063754) (xy 143.490258 -263.055935)
			(xy 143.442726 -263.040491) (xy 143.398194 -263.017801) (xy 143.357761 -262.988425) (xy 143.322421 -262.953085)
			(xy 143.293045 -262.912652) (xy 143.270355 -262.86812) (xy 143.254911 -262.820588) (xy 143.247092 -262.771225)
			(xy 142.940029 -262.771225) (xy 142.94002 -262.771682) (xy 142.931856 -262.821916) (xy 142.91574 -262.87019)
			(xy 142.892089 -262.915253) (xy 142.861516 -262.955939) (xy 142.824812 -262.991194) (xy 142.782928 -263.020104)
			(xy 142.736949 -263.041921) (xy 142.688065 -263.056081) (xy 142.637544 -263.062215) (xy 142.586692 -263.060166)
			(xy 142.536828 -263.049986) (xy 142.489242 -263.031939) (xy 142.445168 -263.006493) (xy 142.405746 -262.974306)
			(xy 142.371998 -262.936212) (xy 142.344797 -262.893198) (xy 142.324849 -262.846378) (xy 142.31267 -262.796964)
			(xy 142.308575 -262.746236) (xy 142.000478 -262.746236) (xy 141.999966 -262.771682) (xy 141.991802 -262.821916)
			(xy 141.975686 -262.87019) (xy 141.952035 -262.915253) (xy 141.921462 -262.955939) (xy 141.884758 -262.991194)
			(xy 141.842874 -263.020104) (xy 141.796895 -263.041921) (xy 141.748011 -263.056081) (xy 141.69749 -263.062215)
			(xy 141.646638 -263.060166) (xy 141.596774 -263.049986) (xy 141.549188 -263.031939) (xy 141.505114 -263.006493)
			(xy 141.465692 -262.974306) (xy 141.431944 -262.936212) (xy 141.404743 -262.893198) (xy 141.384795 -262.846378)
			(xy 141.372616 -262.796964) (xy 141.368521 -262.746236) (xy 141.06271 -262.746236) (xy 141.06222 -262.771225)
			(xy 141.054401 -262.820588) (xy 141.038957 -262.86812) (xy 141.016267 -262.912652) (xy 140.986891 -262.953085)
			(xy 140.951551 -262.988425) (xy 140.911118 -263.017801) (xy 140.866586 -263.040491) (xy 140.819054 -263.055935)
			(xy 140.769691 -263.063754) (xy 140.719713 -263.063754) (xy 140.67035 -263.055935) (xy 140.622818 -263.040491)
			(xy 140.578286 -263.017801) (xy 140.537853 -262.988425) (xy 140.502513 -262.953085) (xy 140.473137 -262.912652)
			(xy 140.450447 -262.86812) (xy 140.435003 -262.820588) (xy 140.427184 -262.771225) (xy 140.119867 -262.771225)
			(xy 140.119858 -262.771682) (xy 140.111694 -262.821916) (xy 140.095578 -262.87019) (xy 140.071927 -262.915253)
			(xy 140.041354 -262.955939) (xy 140.00465 -262.991194) (xy 139.962766 -263.020104) (xy 139.916787 -263.041921)
			(xy 139.867903 -263.056081) (xy 139.817382 -263.062215) (xy 139.76653 -263.060166) (xy 139.716666 -263.049986)
			(xy 139.66908 -263.031939) (xy 139.625006 -263.006493) (xy 139.585584 -262.974306) (xy 139.551836 -262.936212)
			(xy 139.524635 -262.893198) (xy 139.504687 -262.846378) (xy 139.492508 -262.796964) (xy 139.488413 -262.746236)
			(xy 139.182856 -262.746236) (xy 139.182366 -262.771225) (xy 139.174547 -262.820588) (xy 139.159103 -262.86812)
			(xy 139.136413 -262.912652) (xy 139.107037 -262.953085) (xy 139.071697 -262.988425) (xy 139.031264 -263.017801)
			(xy 138.986732 -263.040491) (xy 138.9392 -263.055935) (xy 138.889837 -263.063754) (xy 138.839859 -263.063754)
			(xy 138.790496 -263.055935) (xy 138.742964 -263.040491) (xy 138.698432 -263.017801) (xy 138.657999 -262.988425)
			(xy 138.622659 -262.953085) (xy 138.593283 -262.912652) (xy 138.570593 -262.86812) (xy 138.555149 -262.820588)
			(xy 138.54733 -262.771225) (xy 138.240013 -262.771225) (xy 138.240004 -262.771682) (xy 138.23184 -262.821916)
			(xy 138.215724 -262.87019) (xy 138.192073 -262.915253) (xy 138.1615 -262.955939) (xy 138.124796 -262.991194)
			(xy 138.082912 -263.020104) (xy 138.036933 -263.041921) (xy 137.988049 -263.056081) (xy 137.937528 -263.062215)
			(xy 137.886676 -263.060166) (xy 137.836812 -263.049986) (xy 137.789226 -263.031939) (xy 137.745152 -263.006493)
			(xy 137.70573 -262.974306) (xy 137.671982 -262.936212) (xy 137.644781 -262.893198) (xy 137.624833 -262.846378)
			(xy 137.612654 -262.796964) (xy 137.608559 -262.746236) (xy 137.302748 -262.746236) (xy 137.302258 -262.771225)
			(xy 137.294439 -262.820588) (xy 137.278995 -262.86812) (xy 137.256305 -262.912652) (xy 137.226929 -262.953085)
			(xy 137.191589 -262.988425) (xy 137.151156 -263.017801) (xy 137.106624 -263.040491) (xy 137.059092 -263.055935)
			(xy 137.009729 -263.063754) (xy 136.959751 -263.063754) (xy 136.910388 -263.055935) (xy 136.862856 -263.040491)
			(xy 136.818324 -263.017801) (xy 136.777891 -262.988425) (xy 136.742551 -262.953085) (xy 136.713175 -262.912652)
			(xy 136.690485 -262.86812) (xy 136.675041 -262.820588) (xy 136.667222 -262.771225) (xy 136.359905 -262.771225)
			(xy 136.359896 -262.771682) (xy 136.351732 -262.821916) (xy 136.335616 -262.87019) (xy 136.311965 -262.915253)
			(xy 136.281392 -262.955939) (xy 136.244688 -262.991194) (xy 136.202804 -263.020104) (xy 136.156825 -263.041921)
			(xy 136.107941 -263.056081) (xy 136.05742 -263.062215) (xy 136.006568 -263.060166) (xy 135.956704 -263.049986)
			(xy 135.909118 -263.031939) (xy 135.865044 -263.006493) (xy 135.825622 -262.974306) (xy 135.791874 -262.936212)
			(xy 135.764673 -262.893198) (xy 135.744725 -262.846378) (xy 135.732546 -262.796964) (xy 135.728451 -262.746236)
			(xy 135.420354 -262.746236) (xy 135.419842 -262.771682) (xy 135.411678 -262.821916) (xy 135.395562 -262.87019)
			(xy 135.371911 -262.915253) (xy 135.341338 -262.955939) (xy 135.304634 -262.991194) (xy 135.26275 -263.020104)
			(xy 135.216771 -263.041921) (xy 135.167887 -263.056081) (xy 135.117366 -263.062215) (xy 135.066514 -263.060166)
			(xy 135.01665 -263.049986) (xy 134.969064 -263.031939) (xy 134.92499 -263.006493) (xy 134.885568 -262.974306)
			(xy 134.85182 -262.936212) (xy 134.824619 -262.893198) (xy 134.804671 -262.846378) (xy 134.792492 -262.796964)
			(xy 134.788397 -262.746236) (xy 134.48284 -262.746236) (xy 134.48235 -262.771225) (xy 134.474531 -262.820588)
			(xy 134.459087 -262.86812) (xy 134.436397 -262.912652) (xy 134.407021 -262.953085) (xy 134.371681 -262.988425)
			(xy 134.331248 -263.017801) (xy 134.286716 -263.040491) (xy 134.239184 -263.055935) (xy 134.189821 -263.063754)
			(xy 134.139843 -263.063754) (xy 134.09048 -263.055935) (xy 134.042948 -263.040491) (xy 133.998416 -263.017801)
			(xy 133.957983 -262.988425) (xy 133.922643 -262.953085) (xy 133.893267 -262.912652) (xy 133.870577 -262.86812)
			(xy 133.855133 -262.820588) (xy 133.847314 -262.771225) (xy 133.539997 -262.771225) (xy 133.539988 -262.771682)
			(xy 133.531824 -262.821916) (xy 133.515708 -262.87019) (xy 133.492057 -262.915253) (xy 133.461484 -262.955939)
			(xy 133.42478 -262.991194) (xy 133.382896 -263.020104) (xy 133.336917 -263.041921) (xy 133.288033 -263.056081)
			(xy 133.237512 -263.062215) (xy 133.18666 -263.060166) (xy 133.136796 -263.049986) (xy 133.08921 -263.031939)
			(xy 133.045136 -263.006493) (xy 133.005714 -262.974306) (xy 132.971966 -262.936212) (xy 132.944765 -262.893198)
			(xy 132.924817 -262.846378) (xy 132.912638 -262.796964) (xy 132.908543 -262.746236) (xy 132.602732 -262.746236)
			(xy 132.602242 -262.771225) (xy 132.594423 -262.820588) (xy 132.578979 -262.86812) (xy 132.556289 -262.912652)
			(xy 132.526913 -262.953085) (xy 132.491573 -262.988425) (xy 132.45114 -263.017801) (xy 132.406608 -263.040491)
			(xy 132.359076 -263.055935) (xy 132.309713 -263.063754) (xy 132.259735 -263.063754) (xy 132.210372 -263.055935)
			(xy 132.16284 -263.040491) (xy 132.118308 -263.017801) (xy 132.077875 -262.988425) (xy 132.042535 -262.953085)
			(xy 132.013159 -262.912652) (xy 131.990469 -262.86812) (xy 131.975025 -262.820588) (xy 131.967206 -262.771225)
			(xy 131.659889 -262.771225) (xy 131.65988 -262.771682) (xy 131.651716 -262.821916) (xy 131.6356 -262.87019)
			(xy 131.611949 -262.915253) (xy 131.581376 -262.955939) (xy 131.544672 -262.991194) (xy 131.502788 -263.020104)
			(xy 131.456809 -263.041921) (xy 131.407925 -263.056081) (xy 131.357404 -263.062215) (xy 131.306552 -263.060166)
			(xy 131.256688 -263.049986) (xy 131.209102 -263.031939) (xy 131.165028 -263.006493) (xy 131.125606 -262.974306)
			(xy 131.091858 -262.936212) (xy 131.064657 -262.893198) (xy 131.044709 -262.846378) (xy 131.03253 -262.796964)
			(xy 131.028435 -262.746236) (xy 130.722878 -262.746236) (xy 130.722388 -262.771225) (xy 130.714569 -262.820588)
			(xy 130.699125 -262.86812) (xy 130.676435 -262.912652) (xy 130.647059 -262.953085) (xy 130.611719 -262.988425)
			(xy 130.571286 -263.017801) (xy 130.526754 -263.040491) (xy 130.479222 -263.055935) (xy 130.429859 -263.063754)
			(xy 130.379881 -263.063754) (xy 130.330518 -263.055935) (xy 130.282986 -263.040491) (xy 130.238454 -263.017801)
			(xy 130.198021 -262.988425) (xy 130.162681 -262.953085) (xy 130.133305 -262.912652) (xy 130.110615 -262.86812)
			(xy 130.095171 -262.820588) (xy 130.087352 -262.771225) (xy 129.780035 -262.771225) (xy 129.780026 -262.771682)
			(xy 129.771862 -262.821916) (xy 129.755746 -262.87019) (xy 129.732095 -262.915253) (xy 129.701522 -262.955939)
			(xy 129.664818 -262.991194) (xy 129.622934 -263.020104) (xy 129.576955 -263.041921) (xy 129.528071 -263.056081)
			(xy 129.47755 -263.062215) (xy 129.426698 -263.060166) (xy 129.376834 -263.049986) (xy 129.329248 -263.031939)
			(xy 129.285174 -263.006493) (xy 129.245752 -262.974306) (xy 129.212004 -262.936212) (xy 129.184803 -262.893198)
			(xy 129.164855 -262.846378) (xy 129.152676 -262.796964) (xy 129.148581 -262.746236) (xy 128.840484 -262.746236)
			(xy 128.839972 -262.771682) (xy 128.831808 -262.821916) (xy 128.815692 -262.87019) (xy 128.792041 -262.915253)
			(xy 128.761468 -262.955939) (xy 128.724764 -262.991194) (xy 128.68288 -263.020104) (xy 128.636901 -263.041921)
			(xy 128.588017 -263.056081) (xy 128.537496 -263.062215) (xy 128.486644 -263.060166) (xy 128.43678 -263.049986)
			(xy 128.389194 -263.031939) (xy 128.34512 -263.006493) (xy 128.305698 -262.974306) (xy 128.27195 -262.936212)
			(xy 128.244749 -262.893198) (xy 128.224801 -262.846378) (xy 128.212622 -262.796964) (xy 128.208527 -262.746236)
			(xy 127.902716 -262.746236) (xy 127.902226 -262.771225) (xy 127.894407 -262.820588) (xy 127.878963 -262.86812)
			(xy 127.856273 -262.912652) (xy 127.826897 -262.953085) (xy 127.791557 -262.988425) (xy 127.751124 -263.017801)
			(xy 127.706592 -263.040491) (xy 127.65906 -263.055935) (xy 127.609697 -263.063754) (xy 127.559719 -263.063754)
			(xy 127.510356 -263.055935) (xy 127.462824 -263.040491) (xy 127.418292 -263.017801) (xy 127.377859 -262.988425)
			(xy 127.342519 -262.953085) (xy 127.313143 -262.912652) (xy 127.290453 -262.86812) (xy 127.275009 -262.820588)
			(xy 127.26719 -262.771225) (xy 126.022372 -262.771225) (xy 126.014553 -262.820588) (xy 125.999109 -262.86812)
			(xy 125.976419 -262.912652) (xy 125.947043 -262.953085) (xy 125.911703 -262.988425) (xy 125.87127 -263.017801)
			(xy 125.826738 -263.040491) (xy 125.779206 -263.055935) (xy 125.729843 -263.063754) (xy 125.679865 -263.063754)
			(xy 125.630502 -263.055935) (xy 125.58297 -263.040491) (xy 125.538438 -263.017801) (xy 125.498005 -262.988425)
			(xy 125.462665 -262.953085) (xy 125.433289 -262.912652) (xy 125.410599 -262.86812) (xy 125.395155 -262.820588)
			(xy 125.387336 -262.771225) (xy 124.363226 -262.771225) (xy 124.363226 -262.937244) (xy 124.364242 -262.94715)
			(xy 124.365944 -262.95431) (xy 124.372775 -262.967339) (xy 124.377704 -262.972804) (xy 124.601986 -263.197086)
			(xy 124.607482 -263.202079) (xy 124.620647 -263.208935) (xy 124.627894 -263.210548) (xy 124.637546 -263.211564)
			(xy 132.785358 -263.211564) (xy 132.795422 -263.211999) (xy 132.814005 -263.219736) (xy 132.821426 -263.22655)
			(xy 132.837428 -263.242552) (xy 132.841713 -263.246573) (xy 132.851719 -263.252732) (xy 132.85724 -263.254744)
			(xy 132.880123 -263.262999) (xy 132.923269 -263.285461) (xy 132.962496 -263.314226) (xy 132.996891 -263.348623)
			(xy 133.025652 -263.387853) (xy 133.048111 -263.431001) (xy 133.056376 -263.45388) (xy 133.058381 -263.459405)
			(xy 133.064537 -263.469414) (xy 133.068568 -263.473692) (xy 133.203442 -263.608566) (xy 133.214168 -263.618626)
			(xy 133.239995 -263.632659) (xy 133.268751 -263.63875) (xy 133.298051 -263.636392) (xy 133.325463 -263.625782)
			(xy 133.348714 -263.607799) (xy 133.365875 -263.583935) (xy 133.375524 -263.55617) (xy 133.37667 -263.54151)
			(xy 133.378248 -263.517282) (xy 133.387832 -263.469687) (xy 133.404536 -263.4241) (xy 133.427971 -263.38158)
			(xy 133.457594 -263.343114) (xy 133.492718 -263.309596) (xy 133.532526 -263.281802) (xy 133.576094 -263.26038)
			(xy 133.622411 -263.245824) (xy 133.670402 -263.238475) (xy 133.694678 -263.23798) (xy 133.719689 -263.238444)
			(xy 133.769096 -263.246266) (xy 133.81667 -263.261723) (xy 133.86124 -263.284432) (xy 133.901709 -263.313835)
			(xy 133.937078 -263.349207) (xy 133.966479 -263.389677) (xy 133.989185 -263.434248) (xy 134.004638 -263.481824)
			(xy 134.012458 -263.531231) (xy 134.01294 -263.556242) (xy 134.318497 -263.556242) (xy 134.322592 -263.505514)
			(xy 134.334771 -263.4561) (xy 134.354719 -263.40928) (xy 134.38192 -263.366266) (xy 134.415668 -263.328172)
			(xy 134.45509 -263.295985) (xy 134.499164 -263.270539) (xy 134.54675 -263.252492) (xy 134.596614 -263.242312)
			(xy 134.647466 -263.240263) (xy 134.697987 -263.246397) (xy 134.746871 -263.260557) (xy 134.79285 -263.282374)
			(xy 134.834734 -263.311284) (xy 134.871438 -263.346539) (xy 134.902011 -263.387225) (xy 134.925662 -263.432288)
			(xy 134.941778 -263.480562) (xy 134.949942 -263.530796) (xy 134.950454 -263.556242) (xy 134.949951 -263.581231)
			(xy 135.257268 -263.581231) (xy 135.257268 -263.531253) (xy 135.265087 -263.48189) (xy 135.280531 -263.434358)
			(xy 135.303221 -263.389826) (xy 135.332597 -263.349393) (xy 135.367937 -263.314053) (xy 135.40837 -263.284677)
			(xy 135.452902 -263.261987) (xy 135.500434 -263.246543) (xy 135.549797 -263.238724) (xy 135.599775 -263.238724)
			(xy 135.649138 -263.246543) (xy 135.69667 -263.261987) (xy 135.741202 -263.284677) (xy 135.781635 -263.314053)
			(xy 135.816975 -263.349393) (xy 135.846351 -263.389826) (xy 135.869041 -263.434358) (xy 135.884485 -263.48189)
			(xy 135.892304 -263.531253) (xy 135.892794 -263.556242) (xy 136.198605 -263.556242) (xy 136.2027 -263.505514)
			(xy 136.214879 -263.4561) (xy 136.234827 -263.40928) (xy 136.262028 -263.366266) (xy 136.295776 -263.328172)
			(xy 136.335198 -263.295985) (xy 136.379272 -263.270539) (xy 136.426858 -263.252492) (xy 136.476722 -263.242312)
			(xy 136.527574 -263.240263) (xy 136.578095 -263.246397) (xy 136.626979 -263.260557) (xy 136.672958 -263.282374)
			(xy 136.714842 -263.311284) (xy 136.751546 -263.346539) (xy 136.782119 -263.387225) (xy 136.80577 -263.432288)
			(xy 136.821886 -263.480562) (xy 136.83005 -263.530796) (xy 136.830562 -263.556242) (xy 138.078459 -263.556242)
			(xy 138.082554 -263.505514) (xy 138.094733 -263.4561) (xy 138.114681 -263.40928) (xy 138.141882 -263.366266)
			(xy 138.17563 -263.328172) (xy 138.215052 -263.295985) (xy 138.259126 -263.270539) (xy 138.306712 -263.252492)
			(xy 138.356576 -263.242312) (xy 138.407428 -263.240263) (xy 138.457949 -263.246397) (xy 138.506833 -263.260557)
			(xy 138.552812 -263.282374) (xy 138.594696 -263.311284) (xy 138.6314 -263.346539) (xy 138.661973 -263.387225)
			(xy 138.685624 -263.432288) (xy 138.70174 -263.480562) (xy 138.709904 -263.530796) (xy 138.710416 -263.556242)
			(xy 139.018513 -263.556242) (xy 139.022608 -263.505514) (xy 139.034787 -263.4561) (xy 139.054735 -263.40928)
			(xy 139.081936 -263.366266) (xy 139.115684 -263.328172) (xy 139.155106 -263.295985) (xy 139.19918 -263.270539)
			(xy 139.246766 -263.252492) (xy 139.29663 -263.242312) (xy 139.347482 -263.240263) (xy 139.398003 -263.246397)
			(xy 139.446887 -263.260557) (xy 139.492866 -263.282374) (xy 139.53475 -263.311284) (xy 139.571454 -263.346539)
			(xy 139.602027 -263.387225) (xy 139.625678 -263.432288) (xy 139.641794 -263.480562) (xy 139.649958 -263.530796)
			(xy 139.65047 -263.556242) (xy 139.649967 -263.581231) (xy 139.957284 -263.581231) (xy 139.957284 -263.531253)
			(xy 139.965103 -263.48189) (xy 139.980547 -263.434358) (xy 140.003237 -263.389826) (xy 140.032613 -263.349393)
			(xy 140.067953 -263.314053) (xy 140.108386 -263.284677) (xy 140.152918 -263.261987) (xy 140.20045 -263.246543)
			(xy 140.249813 -263.238724) (xy 140.299791 -263.238724) (xy 140.349154 -263.246543) (xy 140.396686 -263.261987)
			(xy 140.441218 -263.284677) (xy 140.481651 -263.314053) (xy 140.516991 -263.349393) (xy 140.546367 -263.389826)
			(xy 140.569057 -263.434358) (xy 140.584501 -263.48189) (xy 140.59232 -263.531253) (xy 140.59281 -263.556242)
			(xy 140.898621 -263.556242) (xy 140.902716 -263.505514) (xy 140.914895 -263.4561) (xy 140.934843 -263.40928)
			(xy 140.962044 -263.366266) (xy 140.995792 -263.328172) (xy 141.035214 -263.295985) (xy 141.079288 -263.270539)
			(xy 141.126874 -263.252492) (xy 141.176738 -263.242312) (xy 141.22759 -263.240263) (xy 141.278111 -263.246397)
			(xy 141.326995 -263.260557) (xy 141.372974 -263.282374) (xy 141.414858 -263.311284) (xy 141.451562 -263.346539)
			(xy 141.482135 -263.387225) (xy 141.505786 -263.432288) (xy 141.521902 -263.480562) (xy 141.530066 -263.530796)
			(xy 141.530578 -263.556242) (xy 141.530075 -263.581231) (xy 141.837138 -263.581231) (xy 141.837138 -263.531253)
			(xy 141.844957 -263.48189) (xy 141.860401 -263.434358) (xy 141.883091 -263.389826) (xy 141.912467 -263.349393)
			(xy 141.947807 -263.314053) (xy 141.98824 -263.284677) (xy 142.032772 -263.261987) (xy 142.080304 -263.246543)
			(xy 142.129667 -263.238724) (xy 142.179645 -263.238724) (xy 142.229008 -263.246543) (xy 142.27654 -263.261987)
			(xy 142.321072 -263.284677) (xy 142.361505 -263.314053) (xy 142.396845 -263.349393) (xy 142.426221 -263.389826)
			(xy 142.448911 -263.434358) (xy 142.464355 -263.48189) (xy 142.472174 -263.531253) (xy 142.472664 -263.556242)
			(xy 142.778475 -263.556242) (xy 142.78257 -263.505514) (xy 142.794749 -263.4561) (xy 142.814697 -263.40928)
			(xy 142.841898 -263.366266) (xy 142.875646 -263.328172) (xy 142.915068 -263.295985) (xy 142.959142 -263.270539)
			(xy 143.006728 -263.252492) (xy 143.056592 -263.242312) (xy 143.107444 -263.240263) (xy 143.157965 -263.246397)
			(xy 143.206849 -263.260557) (xy 143.252828 -263.282374) (xy 143.294712 -263.311284) (xy 143.331416 -263.346539)
			(xy 143.361989 -263.387225) (xy 143.38564 -263.432288) (xy 143.401756 -263.480562) (xy 143.40992 -263.530796)
			(xy 143.410432 -263.556242) (xy 143.40992 -263.581688) (xy 143.401756 -263.631922) (xy 143.38564 -263.680196)
			(xy 143.361989 -263.725259) (xy 143.331416 -263.765945) (xy 143.294712 -263.8012) (xy 143.252828 -263.83011)
			(xy 143.206849 -263.851927) (xy 143.157965 -263.866087) (xy 143.107444 -263.872221) (xy 143.056592 -263.870172)
			(xy 143.006728 -263.859992) (xy 142.959142 -263.841945) (xy 142.915068 -263.816499) (xy 142.875646 -263.784312)
			(xy 142.841898 -263.746218) (xy 142.814697 -263.703204) (xy 142.794749 -263.656384) (xy 142.78257 -263.60697)
			(xy 142.778475 -263.556242) (xy 142.472664 -263.556242) (xy 142.472174 -263.581231) (xy 142.464355 -263.630594)
			(xy 142.448911 -263.678126) (xy 142.426221 -263.722658) (xy 142.396845 -263.763091) (xy 142.361505 -263.798431)
			(xy 142.321072 -263.827807) (xy 142.27654 -263.850497) (xy 142.229008 -263.865941) (xy 142.179645 -263.87376)
			(xy 142.129667 -263.87376) (xy 142.080304 -263.865941) (xy 142.032772 -263.850497) (xy 141.98824 -263.827807)
			(xy 141.947807 -263.798431) (xy 141.912467 -263.763091) (xy 141.883091 -263.722658) (xy 141.860401 -263.678126)
			(xy 141.844957 -263.630594) (xy 141.837138 -263.581231) (xy 141.530075 -263.581231) (xy 141.530066 -263.581688)
			(xy 141.521902 -263.631922) (xy 141.505786 -263.680196) (xy 141.482135 -263.725259) (xy 141.451562 -263.765945)
			(xy 141.414858 -263.8012) (xy 141.372974 -263.83011) (xy 141.326995 -263.851927) (xy 141.278111 -263.866087)
			(xy 141.22759 -263.872221) (xy 141.176738 -263.870172) (xy 141.126874 -263.859992) (xy 141.079288 -263.841945)
			(xy 141.035214 -263.816499) (xy 140.995792 -263.784312) (xy 140.962044 -263.746218) (xy 140.934843 -263.703204)
			(xy 140.914895 -263.656384) (xy 140.902716 -263.60697) (xy 140.898621 -263.556242) (xy 140.59281 -263.556242)
			(xy 140.59232 -263.581231) (xy 140.584501 -263.630594) (xy 140.569057 -263.678126) (xy 140.546367 -263.722658)
			(xy 140.516991 -263.763091) (xy 140.481651 -263.798431) (xy 140.441218 -263.827807) (xy 140.396686 -263.850497)
			(xy 140.349154 -263.865941) (xy 140.299791 -263.87376) (xy 140.249813 -263.87376) (xy 140.20045 -263.865941)
			(xy 140.152918 -263.850497) (xy 140.108386 -263.827807) (xy 140.067953 -263.798431) (xy 140.032613 -263.763091)
			(xy 140.003237 -263.722658) (xy 139.980547 -263.678126) (xy 139.965103 -263.630594) (xy 139.957284 -263.581231)
			(xy 139.649967 -263.581231) (xy 139.649958 -263.581688) (xy 139.641794 -263.631922) (xy 139.625678 -263.680196)
			(xy 139.602027 -263.725259) (xy 139.571454 -263.765945) (xy 139.53475 -263.8012) (xy 139.492866 -263.83011)
			(xy 139.446887 -263.851927) (xy 139.398003 -263.866087) (xy 139.347482 -263.872221) (xy 139.29663 -263.870172)
			(xy 139.246766 -263.859992) (xy 139.19918 -263.841945) (xy 139.155106 -263.816499) (xy 139.115684 -263.784312)
			(xy 139.081936 -263.746218) (xy 139.054735 -263.703204) (xy 139.034787 -263.656384) (xy 139.022608 -263.60697)
			(xy 139.018513 -263.556242) (xy 138.710416 -263.556242) (xy 138.709904 -263.581688) (xy 138.70174 -263.631922)
			(xy 138.685624 -263.680196) (xy 138.661973 -263.725259) (xy 138.6314 -263.765945) (xy 138.594696 -263.8012)
			(xy 138.552812 -263.83011) (xy 138.506833 -263.851927) (xy 138.457949 -263.866087) (xy 138.407428 -263.872221)
			(xy 138.356576 -263.870172) (xy 138.306712 -263.859992) (xy 138.259126 -263.841945) (xy 138.215052 -263.816499)
			(xy 138.17563 -263.784312) (xy 138.141882 -263.746218) (xy 138.114681 -263.703204) (xy 138.094733 -263.656384)
			(xy 138.082554 -263.60697) (xy 138.078459 -263.556242) (xy 136.830562 -263.556242) (xy 136.83005 -263.581688)
			(xy 136.821886 -263.631922) (xy 136.80577 -263.680196) (xy 136.782119 -263.725259) (xy 136.751546 -263.765945)
			(xy 136.714842 -263.8012) (xy 136.672958 -263.83011) (xy 136.626979 -263.851927) (xy 136.578095 -263.866087)
			(xy 136.527574 -263.872221) (xy 136.476722 -263.870172) (xy 136.426858 -263.859992) (xy 136.379272 -263.841945)
			(xy 136.335198 -263.816499) (xy 136.295776 -263.784312) (xy 136.262028 -263.746218) (xy 136.234827 -263.703204)
			(xy 136.214879 -263.656384) (xy 136.2027 -263.60697) (xy 136.198605 -263.556242) (xy 135.892794 -263.556242)
			(xy 135.892304 -263.581231) (xy 135.884485 -263.630594) (xy 135.869041 -263.678126) (xy 135.846351 -263.722658)
			(xy 135.816975 -263.763091) (xy 135.781635 -263.798431) (xy 135.741202 -263.827807) (xy 135.69667 -263.850497)
			(xy 135.649138 -263.865941) (xy 135.599775 -263.87376) (xy 135.549797 -263.87376) (xy 135.500434 -263.865941)
			(xy 135.452902 -263.850497) (xy 135.40837 -263.827807) (xy 135.367937 -263.798431) (xy 135.332597 -263.763091)
			(xy 135.303221 -263.722658) (xy 135.280531 -263.678126) (xy 135.265087 -263.630594) (xy 135.257268 -263.581231)
			(xy 134.949951 -263.581231) (xy 134.949942 -263.581688) (xy 134.941778 -263.631922) (xy 134.925662 -263.680196)
			(xy 134.902011 -263.725259) (xy 134.871438 -263.765945) (xy 134.834734 -263.8012) (xy 134.79285 -263.83011)
			(xy 134.746871 -263.851927) (xy 134.697987 -263.866087) (xy 134.647466 -263.872221) (xy 134.596614 -263.870172)
			(xy 134.54675 -263.859992) (xy 134.499164 -263.841945) (xy 134.45509 -263.816499) (xy 134.415668 -263.784312)
			(xy 134.38192 -263.746218) (xy 134.354719 -263.703204) (xy 134.334771 -263.656384) (xy 134.322592 -263.60697)
			(xy 134.318497 -263.556242) (xy 134.01294 -263.556242) (xy 134.01248 -263.580516) (xy 134.005104 -263.628502)
			(xy 133.99053 -263.674811) (xy 133.969096 -263.718372) (xy 133.941297 -263.758175) (xy 133.907779 -263.793296)
			(xy 133.869318 -263.822923) (xy 133.826806 -263.846369) (xy 133.781227 -263.863089) (xy 133.733638 -263.872698)
			(xy 133.70941 -263.87425) (xy 133.694775 -263.875454) (xy 133.667076 -263.885165) (xy 133.643276 -263.902344)
			(xy 133.625338 -263.925577) (xy 133.61474 -263.952949) (xy 133.612354 -263.982204) (xy 133.618378 -264.010931)
			(xy 133.632316 -264.036763) (xy 133.642354 -264.047478) (xy 133.767576 -264.1727) (xy 133.777935 -264.1824)
			(xy 133.802739 -264.196169) (xy 133.830373 -264.20258) (xy 133.858705 -264.201137) (xy 133.885546 -264.191954)
			(xy 133.908823 -264.175738) (xy 133.918198 -264.16508) (xy 133.933395 -264.147116) (xy 133.968178 -264.11543)
			(xy 134.007248 -264.08921) (xy 134.049753 -264.06903) (xy 134.094766 -264.055329) (xy 134.141306 -264.048405)
			(xy 134.164832 -264.047986) (xy 134.18984 -264.048454) (xy 134.23924 -264.056283) (xy 134.286807 -264.071744)
			(xy 134.331369 -264.094456) (xy 134.371829 -264.12386) (xy 134.407192 -264.159232) (xy 134.436585 -264.199699)
			(xy 134.459286 -264.244267) (xy 134.474736 -264.291838) (xy 134.482553 -264.34124) (xy 134.483094 -264.366248)
			(xy 134.788397 -264.366248) (xy 134.792492 -264.31552) (xy 134.804671 -264.266106) (xy 134.824619 -264.219286)
			(xy 134.85182 -264.176272) (xy 134.885568 -264.138178) (xy 134.92499 -264.105991) (xy 134.969064 -264.080545)
			(xy 135.01665 -264.062498) (xy 135.066514 -264.052318) (xy 135.117366 -264.050269) (xy 135.167887 -264.056403)
			(xy 135.216771 -264.070563) (xy 135.26275 -264.09238) (xy 135.304634 -264.12129) (xy 135.341338 -264.156545)
			(xy 135.371911 -264.197231) (xy 135.395562 -264.242294) (xy 135.411678 -264.290568) (xy 135.419842 -264.340802)
			(xy 135.420354 -264.366248) (xy 135.728451 -264.366248) (xy 135.732546 -264.31552) (xy 135.744725 -264.266106)
			(xy 135.764673 -264.219286) (xy 135.791874 -264.176272) (xy 135.825622 -264.138178) (xy 135.865044 -264.105991)
			(xy 135.909118 -264.080545) (xy 135.956704 -264.062498) (xy 136.006568 -264.052318) (xy 136.05742 -264.050269)
			(xy 136.107941 -264.056403) (xy 136.156825 -264.070563) (xy 136.202804 -264.09238) (xy 136.244688 -264.12129)
			(xy 136.281392 -264.156545) (xy 136.311965 -264.197231) (xy 136.335616 -264.242294) (xy 136.351732 -264.290568)
			(xy 136.359896 -264.340802) (xy 136.360408 -264.366248) (xy 136.359905 -264.391237) (xy 136.667222 -264.391237)
			(xy 136.667222 -264.341259) (xy 136.675041 -264.291896) (xy 136.690485 -264.244364) (xy 136.713175 -264.199832)
			(xy 136.742551 -264.159399) (xy 136.777891 -264.124059) (xy 136.818324 -264.094683) (xy 136.862856 -264.071993)
			(xy 136.910388 -264.056549) (xy 136.959751 -264.04873) (xy 137.009729 -264.04873) (xy 137.059092 -264.056549)
			(xy 137.106624 -264.071993) (xy 137.151156 -264.094683) (xy 137.191589 -264.124059) (xy 137.226929 -264.159399)
			(xy 137.256305 -264.199832) (xy 137.278995 -264.244364) (xy 137.294439 -264.291896) (xy 137.302258 -264.341259)
			(xy 137.302748 -264.366248) (xy 137.608559 -264.366248) (xy 137.612654 -264.31552) (xy 137.624833 -264.266106)
			(xy 137.644781 -264.219286) (xy 137.671982 -264.176272) (xy 137.70573 -264.138178) (xy 137.745152 -264.105991)
			(xy 137.789226 -264.080545) (xy 137.836812 -264.062498) (xy 137.886676 -264.052318) (xy 137.937528 -264.050269)
			(xy 137.988049 -264.056403) (xy 138.036933 -264.070563) (xy 138.082912 -264.09238) (xy 138.124796 -264.12129)
			(xy 138.1615 -264.156545) (xy 138.192073 -264.197231) (xy 138.215724 -264.242294) (xy 138.23184 -264.290568)
			(xy 138.240004 -264.340802) (xy 138.240516 -264.366248) (xy 138.240013 -264.391237) (xy 138.54733 -264.391237)
			(xy 138.54733 -264.341259) (xy 138.555149 -264.291896) (xy 138.570593 -264.244364) (xy 138.593283 -264.199832)
			(xy 138.622659 -264.159399) (xy 138.657999 -264.124059) (xy 138.698432 -264.094683) (xy 138.742964 -264.071993)
			(xy 138.790496 -264.056549) (xy 138.839859 -264.04873) (xy 138.889837 -264.04873) (xy 138.9392 -264.056549)
			(xy 138.986732 -264.071993) (xy 139.031264 -264.094683) (xy 139.071697 -264.124059) (xy 139.107037 -264.159399)
			(xy 139.136413 -264.199832) (xy 139.159103 -264.244364) (xy 139.174547 -264.291896) (xy 139.182366 -264.341259)
			(xy 139.182856 -264.366248) (xy 139.488413 -264.366248) (xy 139.492508 -264.31552) (xy 139.504687 -264.266106)
			(xy 139.524635 -264.219286) (xy 139.551836 -264.176272) (xy 139.585584 -264.138178) (xy 139.625006 -264.105991)
			(xy 139.66908 -264.080545) (xy 139.716666 -264.062498) (xy 139.76653 -264.052318) (xy 139.817382 -264.050269)
			(xy 139.867903 -264.056403) (xy 139.916787 -264.070563) (xy 139.962766 -264.09238) (xy 140.00465 -264.12129)
			(xy 140.041354 -264.156545) (xy 140.071927 -264.197231) (xy 140.095578 -264.242294) (xy 140.111694 -264.290568)
			(xy 140.119858 -264.340802) (xy 140.12037 -264.366248) (xy 140.119867 -264.391237) (xy 140.427184 -264.391237)
			(xy 140.427184 -264.341259) (xy 140.435003 -264.291896) (xy 140.450447 -264.244364) (xy 140.473137 -264.199832)
			(xy 140.502513 -264.159399) (xy 140.537853 -264.124059) (xy 140.578286 -264.094683) (xy 140.622818 -264.071993)
			(xy 140.67035 -264.056549) (xy 140.719713 -264.04873) (xy 140.769691 -264.04873) (xy 140.819054 -264.056549)
			(xy 140.866586 -264.071993) (xy 140.911118 -264.094683) (xy 140.951551 -264.124059) (xy 140.986891 -264.159399)
			(xy 141.016267 -264.199832) (xy 141.038957 -264.244364) (xy 141.054401 -264.291896) (xy 141.06222 -264.341259)
			(xy 141.06271 -264.366248) (xy 141.368521 -264.366248) (xy 141.372616 -264.31552) (xy 141.384795 -264.266106)
			(xy 141.404743 -264.219286) (xy 141.431944 -264.176272) (xy 141.465692 -264.138178) (xy 141.505114 -264.105991)
			(xy 141.549188 -264.080545) (xy 141.596774 -264.062498) (xy 141.646638 -264.052318) (xy 141.69749 -264.050269)
			(xy 141.748011 -264.056403) (xy 141.796895 -264.070563) (xy 141.842874 -264.09238) (xy 141.884758 -264.12129)
			(xy 141.921462 -264.156545) (xy 141.952035 -264.197231) (xy 141.975686 -264.242294) (xy 141.991802 -264.290568)
			(xy 141.999966 -264.340802) (xy 142.000478 -264.366248) (xy 142.308575 -264.366248) (xy 142.31267 -264.31552)
			(xy 142.324849 -264.266106) (xy 142.344797 -264.219286) (xy 142.371998 -264.176272) (xy 142.405746 -264.138178)
			(xy 142.445168 -264.105991) (xy 142.489242 -264.080545) (xy 142.536828 -264.062498) (xy 142.586692 -264.052318)
			(xy 142.637544 -264.050269) (xy 142.688065 -264.056403) (xy 142.736949 -264.070563) (xy 142.782928 -264.09238)
			(xy 142.824812 -264.12129) (xy 142.861516 -264.156545) (xy 142.892089 -264.197231) (xy 142.91574 -264.242294)
			(xy 142.931856 -264.290568) (xy 142.94002 -264.340802) (xy 142.940532 -264.366248) (xy 142.940029 -264.391237)
			(xy 143.247092 -264.391237) (xy 143.247092 -264.341259) (xy 143.254911 -264.291896) (xy 143.270355 -264.244364)
			(xy 143.293045 -264.199832) (xy 143.322421 -264.159399) (xy 143.357761 -264.124059) (xy 143.398194 -264.094683)
			(xy 143.442726 -264.071993) (xy 143.490258 -264.056549) (xy 143.539621 -264.04873) (xy 143.589599 -264.04873)
			(xy 143.638962 -264.056549) (xy 143.686494 -264.071993) (xy 143.731026 -264.094683) (xy 143.771459 -264.124059)
			(xy 143.806799 -264.159399) (xy 143.836175 -264.199832) (xy 143.858865 -264.244364) (xy 143.874309 -264.291896)
			(xy 143.882128 -264.341259) (xy 143.882618 -264.366248) (xy 143.882128 -264.391237) (xy 143.874309 -264.4406)
			(xy 143.858865 -264.488132) (xy 143.836175 -264.532664) (xy 143.806799 -264.573097) (xy 143.771459 -264.608437)
			(xy 143.731026 -264.637813) (xy 143.686494 -264.660503) (xy 143.638962 -264.675947) (xy 143.589599 -264.683766)
			(xy 143.539621 -264.683766) (xy 143.490258 -264.675947) (xy 143.442726 -264.660503) (xy 143.398194 -264.637813)
			(xy 143.357761 -264.608437) (xy 143.322421 -264.573097) (xy 143.293045 -264.532664) (xy 143.270355 -264.488132)
			(xy 143.254911 -264.4406) (xy 143.247092 -264.391237) (xy 142.940029 -264.391237) (xy 142.94002 -264.391694)
			(xy 142.931856 -264.441928) (xy 142.91574 -264.490202) (xy 142.892089 -264.535265) (xy 142.861516 -264.575951)
			(xy 142.824812 -264.611206) (xy 142.782928 -264.640116) (xy 142.736949 -264.661933) (xy 142.688065 -264.676093)
			(xy 142.637544 -264.682227) (xy 142.586692 -264.680178) (xy 142.536828 -264.669998) (xy 142.489242 -264.651951)
			(xy 142.445168 -264.626505) (xy 142.405746 -264.594318) (xy 142.371998 -264.556224) (xy 142.344797 -264.51321)
			(xy 142.324849 -264.46639) (xy 142.31267 -264.416976) (xy 142.308575 -264.366248) (xy 142.000478 -264.366248)
			(xy 141.999966 -264.391694) (xy 141.991802 -264.441928) (xy 141.975686 -264.490202) (xy 141.952035 -264.535265)
			(xy 141.921462 -264.575951) (xy 141.884758 -264.611206) (xy 141.842874 -264.640116) (xy 141.796895 -264.661933)
			(xy 141.748011 -264.676093) (xy 141.69749 -264.682227) (xy 141.646638 -264.680178) (xy 141.596774 -264.669998)
			(xy 141.549188 -264.651951) (xy 141.505114 -264.626505) (xy 141.465692 -264.594318) (xy 141.431944 -264.556224)
			(xy 141.404743 -264.51321) (xy 141.384795 -264.46639) (xy 141.372616 -264.416976) (xy 141.368521 -264.366248)
			(xy 141.06271 -264.366248) (xy 141.06222 -264.391237) (xy 141.054401 -264.4406) (xy 141.038957 -264.488132)
			(xy 141.016267 -264.532664) (xy 140.986891 -264.573097) (xy 140.951551 -264.608437) (xy 140.911118 -264.637813)
			(xy 140.866586 -264.660503) (xy 140.819054 -264.675947) (xy 140.769691 -264.683766) (xy 140.719713 -264.683766)
			(xy 140.67035 -264.675947) (xy 140.622818 -264.660503) (xy 140.578286 -264.637813) (xy 140.537853 -264.608437)
			(xy 140.502513 -264.573097) (xy 140.473137 -264.532664) (xy 140.450447 -264.488132) (xy 140.435003 -264.4406)
			(xy 140.427184 -264.391237) (xy 140.119867 -264.391237) (xy 140.119858 -264.391694) (xy 140.111694 -264.441928)
			(xy 140.095578 -264.490202) (xy 140.071927 -264.535265) (xy 140.041354 -264.575951) (xy 140.00465 -264.611206)
			(xy 139.962766 -264.640116) (xy 139.916787 -264.661933) (xy 139.867903 -264.676093) (xy 139.817382 -264.682227)
			(xy 139.76653 -264.680178) (xy 139.716666 -264.669998) (xy 139.66908 -264.651951) (xy 139.625006 -264.626505)
			(xy 139.585584 -264.594318) (xy 139.551836 -264.556224) (xy 139.524635 -264.51321) (xy 139.504687 -264.46639)
			(xy 139.492508 -264.416976) (xy 139.488413 -264.366248) (xy 139.182856 -264.366248) (xy 139.182366 -264.391237)
			(xy 139.174547 -264.4406) (xy 139.159103 -264.488132) (xy 139.136413 -264.532664) (xy 139.107037 -264.573097)
			(xy 139.071697 -264.608437) (xy 139.031264 -264.637813) (xy 138.986732 -264.660503) (xy 138.9392 -264.675947)
			(xy 138.889837 -264.683766) (xy 138.839859 -264.683766) (xy 138.790496 -264.675947) (xy 138.742964 -264.660503)
			(xy 138.698432 -264.637813) (xy 138.657999 -264.608437) (xy 138.622659 -264.573097) (xy 138.593283 -264.532664)
			(xy 138.570593 -264.488132) (xy 138.555149 -264.4406) (xy 138.54733 -264.391237) (xy 138.240013 -264.391237)
			(xy 138.240004 -264.391694) (xy 138.23184 -264.441928) (xy 138.215724 -264.490202) (xy 138.192073 -264.535265)
			(xy 138.1615 -264.575951) (xy 138.124796 -264.611206) (xy 138.082912 -264.640116) (xy 138.036933 -264.661933)
			(xy 137.988049 -264.676093) (xy 137.937528 -264.682227) (xy 137.886676 -264.680178) (xy 137.836812 -264.669998)
			(xy 137.789226 -264.651951) (xy 137.745152 -264.626505) (xy 137.70573 -264.594318) (xy 137.671982 -264.556224)
			(xy 137.644781 -264.51321) (xy 137.624833 -264.46639) (xy 137.612654 -264.416976) (xy 137.608559 -264.366248)
			(xy 137.302748 -264.366248) (xy 137.302258 -264.391237) (xy 137.294439 -264.4406) (xy 137.278995 -264.488132)
			(xy 137.256305 -264.532664) (xy 137.226929 -264.573097) (xy 137.191589 -264.608437) (xy 137.151156 -264.637813)
			(xy 137.106624 -264.660503) (xy 137.059092 -264.675947) (xy 137.009729 -264.683766) (xy 136.959751 -264.683766)
			(xy 136.910388 -264.675947) (xy 136.862856 -264.660503) (xy 136.818324 -264.637813) (xy 136.777891 -264.608437)
			(xy 136.742551 -264.573097) (xy 136.713175 -264.532664) (xy 136.690485 -264.488132) (xy 136.675041 -264.4406)
			(xy 136.667222 -264.391237) (xy 136.359905 -264.391237) (xy 136.359896 -264.391694) (xy 136.351732 -264.441928)
			(xy 136.335616 -264.490202) (xy 136.311965 -264.535265) (xy 136.281392 -264.575951) (xy 136.244688 -264.611206)
			(xy 136.202804 -264.640116) (xy 136.156825 -264.661933) (xy 136.107941 -264.676093) (xy 136.05742 -264.682227)
			(xy 136.006568 -264.680178) (xy 135.956704 -264.669998) (xy 135.909118 -264.651951) (xy 135.865044 -264.626505)
			(xy 135.825622 -264.594318) (xy 135.791874 -264.556224) (xy 135.764673 -264.51321) (xy 135.744725 -264.46639)
			(xy 135.732546 -264.416976) (xy 135.728451 -264.366248) (xy 135.420354 -264.366248) (xy 135.419842 -264.391694)
			(xy 135.411678 -264.441928) (xy 135.395562 -264.490202) (xy 135.371911 -264.535265) (xy 135.341338 -264.575951)
			(xy 135.304634 -264.611206) (xy 135.26275 -264.640116) (xy 135.216771 -264.661933) (xy 135.167887 -264.676093)
			(xy 135.117366 -264.682227) (xy 135.066514 -264.680178) (xy 135.01665 -264.669998) (xy 134.969064 -264.651951)
			(xy 134.92499 -264.626505) (xy 134.885568 -264.594318) (xy 134.85182 -264.556224) (xy 134.824619 -264.51321)
			(xy 134.804671 -264.46639) (xy 134.792492 -264.416976) (xy 134.788397 -264.366248) (xy 134.483094 -264.366248)
			(xy 134.482668 -264.389772) (xy 134.475735 -264.436307) (xy 134.462028 -264.481314) (xy 134.441844 -264.523814)
			(xy 134.415625 -264.562879) (xy 134.38394 -264.597659) (xy 134.366 -264.612882) (xy 134.355312 -264.622215)
			(xy 134.339125 -264.645506) (xy 134.329966 -264.67235) (xy 134.32854 -264.700678) (xy 134.334957 -264.728306)
			(xy 134.348724 -264.753104) (xy 134.35838 -264.763504) (xy 134.46379 -264.868914) (xy 134.471072 -264.875527)
			(xy 134.489199 -264.883121) (xy 134.508851 -264.883307) (xy 134.518146 -264.88009) (xy 134.546185 -264.869788)
			(xy 134.604868 -264.858664) (xy 134.634732 -264.857992) (xy 134.659741 -264.858485) (xy 134.709142 -264.866313)
			(xy 134.756711 -264.881772) (xy 134.801277 -264.904481) (xy 134.841742 -264.933881) (xy 134.87711 -264.969248)
			(xy 134.906512 -265.009711) (xy 134.929223 -265.054276) (xy 134.944684 -265.101844) (xy 134.952514 -265.151245)
			(xy 134.952994 -265.176254) (xy 134.952315 -265.206117) (xy 134.941186 -265.264797) (xy 134.930896 -265.29284)
			(xy 134.927738 -265.302143) (xy 134.927955 -265.321772) (xy 134.9355 -265.339893) (xy 134.942072 -265.347196)
			(xy 134.959598 -265.364722) (xy 134.965096 -265.369711) (xy 134.978262 -265.376559) (xy 134.985506 -265.378184)
			(xy 134.995158 -265.3792) (xy 135.16737 -265.3792) (xy 135.182784 -265.378669) (xy 135.212212 -265.369488)
			(xy 135.237566 -265.351953) (xy 135.25654 -265.327657) (xy 135.267409 -265.29881) (xy 135.269184 -265.268034)
			(xy 135.265922 -265.252962) (xy 135.261535 -265.234089) (xy 135.256828 -265.195628) (xy 135.256524 -265.176254)
			(xy 135.257015 -265.151245) (xy 135.264839 -265.101842) (xy 135.280296 -265.054272) (xy 135.303004 -265.009705)
			(xy 135.332404 -264.96924) (xy 135.367772 -264.933872) (xy 135.408237 -264.904472) (xy 135.452804 -264.881764)
			(xy 135.500374 -264.866307) (xy 135.549777 -264.858483) (xy 135.599795 -264.858483) (xy 135.649198 -264.866307)
			(xy 135.696768 -264.881764) (xy 135.741335 -264.904472) (xy 135.7818 -264.933872) (xy 135.817168 -264.96924)
			(xy 135.846568 -265.009705) (xy 135.869276 -265.054272) (xy 135.884733 -265.101842) (xy 135.892557 -265.151245)
			(xy 135.893048 -265.176254) (xy 135.892761 -265.195629) (xy 135.888048 -265.234091) (xy 135.88365 -265.252962)
			(xy 135.880432 -265.26804) (xy 135.882207 -265.298805) (xy 135.893071 -265.327642) (xy 135.912036 -265.351931)
			(xy 135.937378 -265.369465) (xy 135.966794 -265.378648) (xy 135.982202 -265.3792) (xy 136.107424 -265.3792)
			(xy 136.122832 -265.378662) (xy 136.152245 -265.369472) (xy 136.177585 -265.351935) (xy 136.196547 -265.327644)
			(xy 136.207409 -265.298806) (xy 136.209185 -265.268042) (xy 136.205976 -265.252962) (xy 136.201588 -265.234089)
			(xy 136.196881 -265.195628) (xy 136.196578 -265.176254) (xy 136.197069 -265.151245) (xy 136.204893 -265.101842)
			(xy 136.22035 -265.054272) (xy 136.243058 -265.009705) (xy 136.272458 -264.96924) (xy 136.307826 -264.933872)
			(xy 136.348291 -264.904472) (xy 136.392858 -264.881764) (xy 136.440428 -264.866307) (xy 136.489831 -264.858483)
			(xy 136.539849 -264.858483) (xy 136.589252 -264.866307) (xy 136.636822 -264.881764) (xy 136.681389 -264.904472)
			(xy 136.721854 -264.933872) (xy 136.757222 -264.96924) (xy 136.786622 -265.009705) (xy 136.80933 -265.054272)
			(xy 136.824787 -265.101842) (xy 136.832611 -265.151245) (xy 136.833102 -265.176254) (xy 136.832815 -265.195629)
			(xy 136.828102 -265.234091) (xy 136.823704 -265.252962) (xy 136.820486 -265.268042) (xy 136.822263 -265.298811)
			(xy 136.833126 -265.327653) (xy 136.852089 -265.351949) (xy 136.87743 -265.369491) (xy 136.906846 -265.378687)
			(xy 136.922256 -265.3792) (xy 137.047224 -265.3792) (xy 137.062632 -265.378662) (xy 137.092045 -265.369472)
			(xy 137.117385 -265.351935) (xy 137.136347 -265.327644) (xy 137.147209 -265.298806) (xy 137.148985 -265.268042)
			(xy 137.145776 -265.252962) (xy 137.141388 -265.234089) (xy 137.136681 -265.195628) (xy 137.136378 -265.176254)
			(xy 137.136869 -265.151245) (xy 137.144693 -265.101842) (xy 137.16015 -265.054272) (xy 137.182858 -265.009705)
			(xy 137.212258 -264.96924) (xy 137.247626 -264.933872) (xy 137.288091 -264.904472) (xy 137.332658 -264.881764)
			(xy 137.380228 -264.866307) (xy 137.429631 -264.858483) (xy 137.479649 -264.858483) (xy 137.529052 -264.866307)
			(xy 137.576622 -264.881764) (xy 137.621189 -264.904472) (xy 137.661654 -264.933872) (xy 137.697022 -264.96924)
			(xy 137.726422 -265.009705) (xy 137.74913 -265.054272) (xy 137.764587 -265.101842) (xy 137.772411 -265.151245)
			(xy 137.772902 -265.176254) (xy 138.078459 -265.176254) (xy 138.082554 -265.125526) (xy 138.094733 -265.076112)
			(xy 138.114681 -265.029292) (xy 138.141882 -264.986278) (xy 138.17563 -264.948184) (xy 138.215052 -264.915997)
			(xy 138.259126 -264.890551) (xy 138.306712 -264.872504) (xy 138.356576 -264.862324) (xy 138.407428 -264.860275)
			(xy 138.457949 -264.866409) (xy 138.506833 -264.880569) (xy 138.552812 -264.902386) (xy 138.594696 -264.931296)
			(xy 138.6314 -264.966551) (xy 138.661973 -265.007237) (xy 138.685624 -265.0523) (xy 138.70174 -265.100574)
			(xy 138.709904 -265.150808) (xy 138.710416 -265.176254) (xy 138.709913 -265.201243) (xy 139.01723 -265.201243)
			(xy 139.01723 -265.151265) (xy 139.025049 -265.101902) (xy 139.040493 -265.05437) (xy 139.063183 -265.009838)
			(xy 139.092559 -264.969405) (xy 139.127899 -264.934065) (xy 139.168332 -264.904689) (xy 139.212864 -264.881999)
			(xy 139.260396 -264.866555) (xy 139.309759 -264.858736) (xy 139.359737 -264.858736) (xy 139.4091 -264.866555)
			(xy 139.456632 -264.881999) (xy 139.501164 -264.904689) (xy 139.541597 -264.934065) (xy 139.576937 -264.969405)
			(xy 139.606313 -265.009838) (xy 139.629003 -265.05437) (xy 139.644447 -265.101902) (xy 139.652266 -265.151265)
			(xy 139.652756 -265.176254) (xy 139.652266 -265.201243) (xy 139.957284 -265.201243) (xy 139.957284 -265.151265)
			(xy 139.965103 -265.101902) (xy 139.980547 -265.05437) (xy 140.003237 -265.009838) (xy 140.032613 -264.969405)
			(xy 140.067953 -264.934065) (xy 140.108386 -264.904689) (xy 140.152918 -264.881999) (xy 140.20045 -264.866555)
			(xy 140.249813 -264.858736) (xy 140.299791 -264.858736) (xy 140.349154 -264.866555) (xy 140.396686 -264.881999)
			(xy 140.441218 -264.904689) (xy 140.481651 -264.934065) (xy 140.516991 -264.969405) (xy 140.546367 -265.009838)
			(xy 140.569057 -265.05437) (xy 140.584501 -265.101902) (xy 140.59232 -265.151265) (xy 140.59281 -265.176254)
			(xy 140.898621 -265.176254) (xy 140.902716 -265.125526) (xy 140.914895 -265.076112) (xy 140.934843 -265.029292)
			(xy 140.962044 -264.986278) (xy 140.995792 -264.948184) (xy 141.035214 -264.915997) (xy 141.079288 -264.890551)
			(xy 141.126874 -264.872504) (xy 141.176738 -264.862324) (xy 141.22759 -264.860275) (xy 141.278111 -264.866409)
			(xy 141.326995 -264.880569) (xy 141.372974 -264.902386) (xy 141.414858 -264.931296) (xy 141.451562 -264.966551)
			(xy 141.482135 -265.007237) (xy 141.505786 -265.0523) (xy 141.521902 -265.100574) (xy 141.530066 -265.150808)
			(xy 141.530578 -265.176254) (xy 141.530075 -265.201243) (xy 141.837138 -265.201243) (xy 141.837138 -265.151265)
			(xy 141.844957 -265.101902) (xy 141.860401 -265.05437) (xy 141.883091 -265.009838) (xy 141.912467 -264.969405)
			(xy 141.947807 -264.934065) (xy 141.98824 -264.904689) (xy 142.032772 -264.881999) (xy 142.080304 -264.866555)
			(xy 142.129667 -264.858736) (xy 142.179645 -264.858736) (xy 142.229008 -264.866555) (xy 142.27654 -264.881999)
			(xy 142.321072 -264.904689) (xy 142.361505 -264.934065) (xy 142.396845 -264.969405) (xy 142.426221 -265.009838)
			(xy 142.448911 -265.05437) (xy 142.464355 -265.101902) (xy 142.472174 -265.151265) (xy 142.472664 -265.176254)
			(xy 142.472174 -265.201243) (xy 142.777192 -265.201243) (xy 142.777192 -265.151265) (xy 142.785011 -265.101902)
			(xy 142.800455 -265.05437) (xy 142.823145 -265.009838) (xy 142.852521 -264.969405) (xy 142.887861 -264.934065)
			(xy 142.928294 -264.904689) (xy 142.972826 -264.881999) (xy 143.020358 -264.866555) (xy 143.069721 -264.858736)
			(xy 143.119699 -264.858736) (xy 143.169062 -264.866555) (xy 143.216594 -264.881999) (xy 143.261126 -264.904689)
			(xy 143.301559 -264.934065) (xy 143.336899 -264.969405) (xy 143.366275 -265.009838) (xy 143.388965 -265.05437)
			(xy 143.404409 -265.101902) (xy 143.412228 -265.151265) (xy 143.412718 -265.176254) (xy 143.412228 -265.201243)
			(xy 143.717246 -265.201243) (xy 143.717246 -265.151265) (xy 143.725065 -265.101902) (xy 143.740509 -265.05437)
			(xy 143.763199 -265.009838) (xy 143.792575 -264.969405) (xy 143.827915 -264.934065) (xy 143.868348 -264.904689)
			(xy 143.91288 -264.881999) (xy 143.960412 -264.866555) (xy 144.009775 -264.858736) (xy 144.059753 -264.858736)
			(xy 144.109116 -264.866555) (xy 144.156648 -264.881999) (xy 144.20118 -264.904689) (xy 144.241613 -264.934065)
			(xy 144.276953 -264.969405) (xy 144.306329 -265.009838) (xy 144.329019 -265.05437) (xy 144.344463 -265.101902)
			(xy 144.352282 -265.151265) (xy 144.352772 -265.176254) (xy 144.352282 -265.201243) (xy 144.344463 -265.250606)
			(xy 144.329019 -265.298138) (xy 144.306329 -265.34267) (xy 144.276953 -265.383103) (xy 144.241613 -265.418443)
			(xy 144.20118 -265.447819) (xy 144.156648 -265.470509) (xy 144.109116 -265.485953) (xy 144.059753 -265.493772)
			(xy 144.009775 -265.493772) (xy 143.960412 -265.485953) (xy 143.91288 -265.470509) (xy 143.868348 -265.447819)
			(xy 143.827915 -265.418443) (xy 143.792575 -265.383103) (xy 143.763199 -265.34267) (xy 143.740509 -265.298138)
			(xy 143.725065 -265.250606) (xy 143.717246 -265.201243) (xy 143.412228 -265.201243) (xy 143.404409 -265.250606)
			(xy 143.388965 -265.298138) (xy 143.366275 -265.34267) (xy 143.336899 -265.383103) (xy 143.301559 -265.418443)
			(xy 143.261126 -265.447819) (xy 143.216594 -265.470509) (xy 143.169062 -265.485953) (xy 143.119699 -265.493772)
			(xy 143.069721 -265.493772) (xy 143.020358 -265.485953) (xy 142.972826 -265.470509) (xy 142.928294 -265.447819)
			(xy 142.887861 -265.418443) (xy 142.852521 -265.383103) (xy 142.823145 -265.34267) (xy 142.800455 -265.298138)
			(xy 142.785011 -265.250606) (xy 142.777192 -265.201243) (xy 142.472174 -265.201243) (xy 142.464355 -265.250606)
			(xy 142.448911 -265.298138) (xy 142.426221 -265.34267) (xy 142.396845 -265.383103) (xy 142.361505 -265.418443)
			(xy 142.321072 -265.447819) (xy 142.27654 -265.470509) (xy 142.229008 -265.485953) (xy 142.179645 -265.493772)
			(xy 142.129667 -265.493772) (xy 142.080304 -265.485953) (xy 142.032772 -265.470509) (xy 141.98824 -265.447819)
			(xy 141.947807 -265.418443) (xy 141.912467 -265.383103) (xy 141.883091 -265.34267) (xy 141.860401 -265.298138)
			(xy 141.844957 -265.250606) (xy 141.837138 -265.201243) (xy 141.530075 -265.201243) (xy 141.530066 -265.2017)
			(xy 141.521902 -265.251934) (xy 141.505786 -265.300208) (xy 141.482135 -265.345271) (xy 141.451562 -265.385957)
			(xy 141.414858 -265.421212) (xy 141.372974 -265.450122) (xy 141.326995 -265.471939) (xy 141.278111 -265.486099)
			(xy 141.22759 -265.492233) (xy 141.176738 -265.490184) (xy 141.126874 -265.480004) (xy 141.079288 -265.461957)
			(xy 141.035214 -265.436511) (xy 140.995792 -265.404324) (xy 140.962044 -265.36623) (xy 140.934843 -265.323216)
			(xy 140.914895 -265.276396) (xy 140.902716 -265.226982) (xy 140.898621 -265.176254) (xy 140.59281 -265.176254)
			(xy 140.59232 -265.201243) (xy 140.584501 -265.250606) (xy 140.569057 -265.298138) (xy 140.546367 -265.34267)
			(xy 140.516991 -265.383103) (xy 140.481651 -265.418443) (xy 140.441218 -265.447819) (xy 140.396686 -265.470509)
			(xy 140.349154 -265.485953) (xy 140.299791 -265.493772) (xy 140.249813 -265.493772) (xy 140.20045 -265.485953)
			(xy 140.152918 -265.470509) (xy 140.108386 -265.447819) (xy 140.067953 -265.418443) (xy 140.032613 -265.383103)
			(xy 140.003237 -265.34267) (xy 139.980547 -265.298138) (xy 139.965103 -265.250606) (xy 139.957284 -265.201243)
			(xy 139.652266 -265.201243) (xy 139.644447 -265.250606) (xy 139.629003 -265.298138) (xy 139.606313 -265.34267)
			(xy 139.576937 -265.383103) (xy 139.541597 -265.418443) (xy 139.501164 -265.447819) (xy 139.456632 -265.470509)
			(xy 139.4091 -265.485953) (xy 139.359737 -265.493772) (xy 139.309759 -265.493772) (xy 139.260396 -265.485953)
			(xy 139.212864 -265.470509) (xy 139.168332 -265.447819) (xy 139.127899 -265.418443) (xy 139.092559 -265.383103)
			(xy 139.063183 -265.34267) (xy 139.040493 -265.298138) (xy 139.025049 -265.250606) (xy 139.01723 -265.201243)
			(xy 138.709913 -265.201243) (xy 138.709904 -265.2017) (xy 138.70174 -265.251934) (xy 138.685624 -265.300208)
			(xy 138.661973 -265.345271) (xy 138.6314 -265.385957) (xy 138.594696 -265.421212) (xy 138.552812 -265.450122)
			(xy 138.506833 -265.471939) (xy 138.457949 -265.486099) (xy 138.407428 -265.492233) (xy 138.356576 -265.490184)
			(xy 138.306712 -265.480004) (xy 138.259126 -265.461957) (xy 138.215052 -265.436511) (xy 138.17563 -265.404324)
			(xy 138.141882 -265.36623) (xy 138.114681 -265.323216) (xy 138.094733 -265.276396) (xy 138.082554 -265.226982)
			(xy 138.078459 -265.176254) (xy 137.772902 -265.176254) (xy 137.772391 -265.202152) (xy 137.764001 -265.253264)
			(xy 137.747451 -265.302345) (xy 137.723178 -265.348101) (xy 137.691821 -265.389327) (xy 137.654206 -265.424935)
			(xy 137.611325 -265.453988) (xy 137.564309 -265.475719) (xy 137.539476 -265.483086) (xy 137.524977 -265.487626)
			(xy 137.499331 -265.503886) (xy 137.479604 -265.526971) (xy 137.467541 -265.554838) (xy 137.464211 -265.58502)
			(xy 137.469907 -265.614847) (xy 137.484126 -265.641678) (xy 137.494518 -265.652758) (xy 137.58037 -265.73861)
			(xy 137.591508 -265.748973) (xy 137.618365 -265.763232) (xy 137.648225 -265.768971) (xy 137.678454 -265.765685)
			(xy 137.706383 -265.753663) (xy 137.718292 -265.744198) (xy 137.740063 -265.726399) (xy 137.788576 -265.697969)
			(xy 137.841328 -265.678503) (xy 137.89668 -265.668607) (xy 137.924794 -265.667998) (xy 137.949805 -265.668488)
			(xy 137.99921 -265.676312) (xy 138.046784 -265.691767) (xy 138.091354 -265.714474) (xy 138.131824 -265.743873)
			(xy 138.167197 -265.779241) (xy 138.196602 -265.819707) (xy 138.219315 -265.864274) (xy 138.234778 -265.911845)
			(xy 138.242608 -265.961249) (xy 138.243056 -265.98626) (xy 138.242537 -266.01173) (xy 138.234372 -266.062012)
			(xy 138.2268 -266.086336) (xy 138.222892 -266.099518) (xy 138.22149 -266.126966) (xy 138.227463 -266.153793)
			(xy 138.240376 -266.178054) (xy 138.259295 -266.197989) (xy 138.282847 -266.212155) (xy 138.309325 -266.219523)
			(xy 138.323066 -266.21994)
		)
		(stroke
			(width 0)
			(type solid)
		)
		(fill yes)
		(layer "B.Cu")
		(net "PVDDCR_SOC_P1")
	)
	(gr_poly
		(pts
			(xy 94.803722 -296.485564) (xy 94.81291 -296.485113) (xy 94.830044 -296.478459) (xy 94.843661 -296.466113)
			(xy 94.851957 -296.449712) (xy 94.853252 -296.440606) (xy 94.853252 -296.042842) (xy 94.851474 -296.030396)
			(xy 94.850966 -296.02811) (xy 94.847208 -296.01038) (xy 94.843259 -295.974351) (xy 94.843092 -295.956228)
			(xy 94.843582 -295.931239) (xy 94.851401 -295.881876) (xy 94.866845 -295.834344) (xy 94.889535 -295.789812)
			(xy 94.918911 -295.749379) (xy 94.954251 -295.714039) (xy 94.994684 -295.684663) (xy 95.039216 -295.661973)
			(xy 95.086748 -295.646529) (xy 95.136111 -295.63871) (xy 95.186089 -295.63871) (xy 95.235452 -295.646529)
			(xy 95.282984 -295.661973) (xy 95.327516 -295.684663) (xy 95.367949 -295.714039) (xy 95.403289 -295.749379)
			(xy 95.432665 -295.789812) (xy 95.455355 -295.834344) (xy 95.470799 -295.881876) (xy 95.478618 -295.931239)
			(xy 95.479108 -295.956228) (xy 95.479108 -295.95699) (xy 95.478841 -295.975579) (xy 95.474507 -296.012502)
			(xy 95.470472 -296.03065) (xy 95.468948 -296.036492) (xy 95.468948 -296.440606) (xy 95.470293 -296.449697)
			(xy 95.47858 -296.466082) (xy 95.492183 -296.478415) (xy 95.509299 -296.485063) (xy 95.518478 -296.485564)
			(xy 95.743522 -296.485564) (xy 95.753352 -296.485046) (xy 95.771495 -296.477462) (xy 95.785372 -296.463531)
			(xy 95.792885 -296.445358) (xy 95.793306 -296.435526) (xy 95.793306 -296.037762) (xy 95.791782 -296.031666)
			(xy 95.787584 -296.013091) (xy 95.783124 -295.97527) (xy 95.782892 -295.956228) (xy 95.783383 -295.931219)
			(xy 95.791207 -295.881816) (xy 95.806664 -295.834246) (xy 95.829372 -295.789679) (xy 95.858772 -295.749214)
			(xy 95.89414 -295.713846) (xy 95.934605 -295.684446) (xy 95.979172 -295.661738) (xy 96.026742 -295.646281)
			(xy 96.076145 -295.638457) (xy 96.126163 -295.638457) (xy 96.175566 -295.646281) (xy 96.223136 -295.661738)
			(xy 96.267703 -295.684446) (xy 96.308168 -295.713846) (xy 96.343536 -295.749214) (xy 96.372936 -295.789679)
			(xy 96.395644 -295.834246) (xy 96.411101 -295.881816) (xy 96.418925 -295.931219) (xy 96.419416 -295.956228)
			(xy 96.419182 -295.97527) (xy 96.418481 -295.981217) (xy 101.423452 -295.981217) (xy 101.423452 -295.931239)
			(xy 101.431271 -295.881876) (xy 101.446715 -295.834344) (xy 101.469405 -295.789812) (xy 101.498781 -295.749379)
			(xy 101.534121 -295.714039) (xy 101.574554 -295.684663) (xy 101.619086 -295.661973) (xy 101.666618 -295.646529)
			(xy 101.715981 -295.63871) (xy 101.765959 -295.63871) (xy 101.815322 -295.646529) (xy 101.862854 -295.661973)
			(xy 101.907386 -295.684663) (xy 101.947819 -295.714039) (xy 101.983159 -295.749379) (xy 102.012535 -295.789812)
			(xy 102.035225 -295.834344) (xy 102.050669 -295.881876) (xy 102.058488 -295.931239) (xy 102.058978 -295.956228)
			(xy 102.058488 -295.981217) (xy 107.063522 -295.981217) (xy 107.063522 -295.931239) (xy 107.071341 -295.881876)
			(xy 107.086785 -295.834344) (xy 107.109475 -295.789812) (xy 107.138851 -295.749379) (xy 107.174191 -295.714039)
			(xy 107.214624 -295.684663) (xy 107.259156 -295.661973) (xy 107.306688 -295.646529) (xy 107.356051 -295.63871)
			(xy 107.406029 -295.63871) (xy 107.455392 -295.646529) (xy 107.502924 -295.661973) (xy 107.547456 -295.684663)
			(xy 107.587889 -295.714039) (xy 107.623229 -295.749379) (xy 107.652605 -295.789812) (xy 107.675295 -295.834344)
			(xy 107.690739 -295.881876) (xy 107.698558 -295.931239) (xy 107.699048 -295.956228) (xy 107.698558 -295.981217)
			(xy 107.690739 -296.03058) (xy 107.675295 -296.078112) (xy 107.652605 -296.122644) (xy 107.623229 -296.163077)
			(xy 107.587889 -296.198417) (xy 107.547456 -296.227793) (xy 107.502924 -296.250483) (xy 107.455392 -296.265927)
			(xy 107.406029 -296.273746) (xy 107.356051 -296.273746) (xy 107.306688 -296.265927) (xy 107.259156 -296.250483)
			(xy 107.214624 -296.227793) (xy 107.174191 -296.198417) (xy 107.138851 -296.163077) (xy 107.109475 -296.122644)
			(xy 107.086785 -296.078112) (xy 107.071341 -296.03058) (xy 107.063522 -295.981217) (xy 102.058488 -295.981217)
			(xy 102.050669 -296.03058) (xy 102.035225 -296.078112) (xy 102.012535 -296.122644) (xy 101.983159 -296.163077)
			(xy 101.947819 -296.198417) (xy 101.907386 -296.227793) (xy 101.862854 -296.250483) (xy 101.815322 -296.265927)
			(xy 101.765959 -296.273746) (xy 101.715981 -296.273746) (xy 101.666618 -296.265927) (xy 101.619086 -296.250483)
			(xy 101.574554 -296.227793) (xy 101.534121 -296.198417) (xy 101.498781 -296.163077) (xy 101.469405 -296.122644)
			(xy 101.446715 -296.078112) (xy 101.431271 -296.03058) (xy 101.423452 -295.981217) (xy 96.418481 -295.981217)
			(xy 96.414723 -296.013091) (xy 96.410526 -296.031666) (xy 96.409002 -296.037762) (xy 96.409002 -296.38752)
			(xy 96.409534 -296.397475) (xy 96.417192 -296.41586) (xy 96.431242 -296.429975) (xy 96.440244 -296.434256)
			(xy 96.460564 -296.442638) (xy 96.479868 -296.442892) (xy 96.489266 -296.439336) (xy 96.49361 -296.437755)
			(xy 96.502681 -296.435975) (xy 96.5073 -296.43578) (xy 108.001054 -296.43578) (xy 108.011119 -296.435347)
			(xy 108.029708 -296.427616) (xy 108.037122 -296.420794) (xy 108.368592 -296.089324) (xy 108.3691 -296.088816)
			(xy 108.375683 -296.081436) (xy 108.383131 -296.063136) (xy 108.383578 -296.053256) (xy 108.383578 -295.051226)
			(xy 108.384014 -295.041161) (xy 108.391745 -295.022574) (xy 108.398564 -295.015158) (xy 108.787692 -294.62603)
			(xy 108.94187 -294.471598) (xy 108.946451 -294.466649) (xy 108.95313 -294.454941) (xy 108.955078 -294.448484)
			(xy 108.956856 -294.441626) (xy 108.956602 -294.428418) (xy 108.954824 -294.421814) (xy 108.949296 -294.400846)
			(xy 108.94331 -294.357897) (xy 108.942886 -294.336216) (xy 108.942886 -294.335962) (xy 108.943415 -294.310455)
			(xy 108.951592 -294.2601) (xy 108.967684 -294.211689) (xy 108.991279 -294.166459) (xy 109.006132 -294.145716)
			(xy 109.006386 -294.145462) (xy 109.010958 -294.139112) (xy 109.018832 -294.11676) (xy 109.020221 -294.112641)
			(xy 109.021754 -294.104087) (xy 109.02188 -294.099742) (xy 109.02188 -293.925498) (xy 109.021398 -293.911828)
			(xy 109.014068 -293.885486) (xy 109.000012 -293.862032) (xy 108.980239 -293.843146) (xy 108.956165 -293.830182)
			(xy 108.929515 -293.824067) (xy 108.902197 -293.82524) (xy 108.889038 -293.828978) (xy 108.865173 -293.836201)
			(xy 108.815924 -293.84398) (xy 108.790994 -293.844472) (xy 108.765984 -293.843981) (xy 108.716581 -293.836155)
			(xy 108.66901 -293.820698) (xy 108.624443 -293.797989) (xy 108.583977 -293.768588) (xy 108.548608 -293.733219)
			(xy 108.519208 -293.692752) (xy 108.4965 -293.648184) (xy 108.481043 -293.600613) (xy 108.473219 -293.55121)
			(xy 108.473219 -293.50119) (xy 108.481043 -293.451787) (xy 108.4965 -293.404216) (xy 108.519208 -293.359648)
			(xy 108.548608 -293.319181) (xy 108.583977 -293.283812) (xy 108.624443 -293.254411) (xy 108.66901 -293.231702)
			(xy 108.716581 -293.216245) (xy 108.765984 -293.208419) (xy 108.790994 -293.207948) (xy 108.815645 -293.20841)
			(xy 108.864359 -293.21601) (xy 108.911318 -293.231029) (xy 108.955401 -293.253108) (xy 108.995552 -293.281719)
			(xy 109.013498 -293.298626) (xy 109.016038 -293.301166) (xy 109.02188 -293.305484) (xy 109.03383 -293.313739)
			(xy 109.061052 -293.323826) (xy 109.090011 -293.325854) (xy 109.118373 -293.319659) (xy 109.14385 -293.305741)
			(xy 109.154468 -293.295832) (xy 110.019846 -292.430454) (xy 110.019846 -292.42004) (xy 110.084108 -292.42004)
			(xy 110.09249 -292.416992) (xy 110.118723 -292.408118) (xy 110.173261 -292.398538) (xy 110.228635 -292.398538)
			(xy 110.283173 -292.408118) (xy 110.309406 -292.416992) (xy 110.317788 -292.42004) (xy 110.362238 -292.42004)
			(xy 110.372304 -292.420471) (xy 110.390895 -292.4282) (xy 110.398306 -292.435026) (xy 111.028734 -293.065454)
			(xy 111.029242 -293.065962) (xy 111.036623 -293.072545) (xy 111.054922 -293.079998) (xy 111.064802 -293.08044)
			(xy 115.655852 -293.08044) (xy 115.665917 -293.080006) (xy 115.684502 -293.072271) (xy 115.69192 -293.065454)
			(xy 115.693698 -293.063676) (xy 115.693952 -293.063422) (xy 115.697762 -293.059358) (xy 116.009928 -292.747446)
			(xy 116.01545 -292.740914) (xy 116.02221 -292.725214) (xy 116.023136 -292.716712) (xy 116.023136 -292.519608)
			(xy 116.023136 -292.413182) (xy 116.023678 -292.403197) (xy 116.0314 -292.384773) (xy 116.038122 -292.377368)
			(xy 116.10848 -292.306756) (xy 116.108734 -292.306502) (xy 116.113052 -292.30193) (xy 116.113814 -292.301168)
			(xy 116.120629 -292.293825) (xy 116.128363 -292.275362) (xy 116.1288 -292.265354) (xy 116.1288 -292.221412)
			(xy 116.12866 -292.216522) (xy 116.126735 -292.206932) (xy 116.12499 -292.202362) (xy 116.127022 -292.175946)
			(xy 116.133351 -292.172078) (xy 116.14755 -292.167815) (xy 116.154962 -292.167564) (xy 116.226336 -292.167564)
			(xy 116.234527 -292.167249) (xy 116.250065 -292.162055) (xy 116.256816 -292.157404) (xy 116.260626 -292.15461)
			(xy 116.285772 -292.12921) (xy 116.286026 -292.12921) (xy 116.339112 -292.07587) (xy 116.342922 -292.07206)
			(xy 116.343684 -292.071552) (xy 116.41455 -292.00094) (xy 116.421896 -291.994133) (xy 116.440359 -291.986412)
			(xy 116.450364 -291.985954) (xy 116.548154 -291.985954) (xy 116.55679 -291.9857) (xy 116.825522 -291.9857)
			(xy 116.834943 -291.985259) (xy 116.852527 -291.978482) (xy 116.859812 -291.972492) (xy 116.86032 -291.971984)
			(xy 116.918232 -291.91712) (xy 116.92636 -291.899594) (xy 116.926868 -291.889688) (xy 116.928688 -291.864298)
			(xy 116.939388 -291.814535) (xy 116.957874 -291.76711) (xy 116.983674 -291.723233) (xy 117.016131 -291.684023)
			(xy 117.054416 -291.650481) (xy 117.097552 -291.623461) (xy 117.144441 -291.603653) (xy 117.193884 -291.591563)
			(xy 117.244622 -291.587498) (xy 117.29536 -291.591563) (xy 117.344803 -291.603653) (xy 117.391692 -291.623461)
			(xy 117.434828 -291.650481) (xy 117.473113 -291.684023) (xy 117.50557 -291.723233) (xy 117.53137 -291.76711)
			(xy 117.549856 -291.814535) (xy 117.560556 -291.864298) (xy 117.562376 -291.889688) (xy 117.562884 -291.899594)
			(xy 117.571012 -291.91712) (xy 117.62867 -291.97173) (xy 117.635987 -291.978123) (xy 117.654014 -291.985329)
			(xy 117.663722 -291.9857) (xy 117.765576 -291.9857) (xy 117.775 -291.985267) (xy 117.792595 -291.978502)
			(xy 117.799866 -291.972492) (xy 117.800374 -291.971984) (xy 117.858286 -291.91712) (xy 117.866414 -291.899594)
			(xy 117.866922 -291.889688) (xy 117.868633 -291.865569) (xy 117.878429 -291.818221) (xy 117.895274 -291.7729)
			(xy 117.918779 -291.730647) (xy 117.948404 -291.692436) (xy 117.983468 -291.659144) (xy 118.023163 -291.631538)
			(xy 118.066576 -291.610253) (xy 118.112709 -291.595778) (xy 118.160501 -291.588447) (xy 118.184676 -291.587936)
			(xy 118.209688 -291.588399) (xy 118.259098 -291.596222) (xy 118.306675 -291.611677) (xy 118.351249 -291.634386)
			(xy 118.391721 -291.663787) (xy 118.427096 -291.699159) (xy 118.456501 -291.739629) (xy 118.479213 -291.784201)
			(xy 118.494672 -291.831777) (xy 118.502499 -291.881186) (xy 118.502938 -291.906198) (xy 118.502453 -291.931135)
			(xy 118.502445 -291.931187) (xy 119.747266 -291.931187) (xy 119.747266 -291.881209) (xy 119.755085 -291.831846)
			(xy 119.770529 -291.784314) (xy 119.793219 -291.739782) (xy 119.822595 -291.699349) (xy 119.857935 -291.664009)
			(xy 119.898368 -291.634633) (xy 119.9429 -291.611943) (xy 119.990432 -291.596499) (xy 120.039795 -291.58868)
			(xy 120.089773 -291.58868) (xy 120.139136 -291.596499) (xy 120.186668 -291.611943) (xy 120.2312 -291.634633)
			(xy 120.271633 -291.664009) (xy 120.306973 -291.699349) (xy 120.336349 -291.739782) (xy 120.359039 -291.784314)
			(xy 120.374483 -291.831846) (xy 120.382302 -291.881209) (xy 120.382792 -291.906198) (xy 120.382302 -291.931187)
			(xy 120.68732 -291.931187) (xy 120.68732 -291.881209) (xy 120.695139 -291.831846) (xy 120.710583 -291.784314)
			(xy 120.733273 -291.739782) (xy 120.762649 -291.699349) (xy 120.797989 -291.664009) (xy 120.838422 -291.634633)
			(xy 120.882954 -291.611943) (xy 120.930486 -291.596499) (xy 120.979849 -291.58868) (xy 121.029827 -291.58868)
			(xy 121.07919 -291.596499) (xy 121.126722 -291.611943) (xy 121.171254 -291.634633) (xy 121.211687 -291.664009)
			(xy 121.247027 -291.699349) (xy 121.276403 -291.739782) (xy 121.299093 -291.784314) (xy 121.314537 -291.831846)
			(xy 121.322356 -291.881209) (xy 121.322846 -291.906198) (xy 121.322356 -291.931187) (xy 122.567174 -291.931187)
			(xy 122.567174 -291.881209) (xy 122.574993 -291.831846) (xy 122.590437 -291.784314) (xy 122.613127 -291.739782)
			(xy 122.642503 -291.699349) (xy 122.677843 -291.664009) (xy 122.718276 -291.634633) (xy 122.762808 -291.611943)
			(xy 122.81034 -291.596499) (xy 122.859703 -291.58868) (xy 122.909681 -291.58868) (xy 122.959044 -291.596499)
			(xy 123.006576 -291.611943) (xy 123.051108 -291.634633) (xy 123.091541 -291.664009) (xy 123.126881 -291.699349)
			(xy 123.156257 -291.739782) (xy 123.178947 -291.784314) (xy 123.194391 -291.831846) (xy 123.20221 -291.881209)
			(xy 123.2027 -291.906198) (xy 123.20221 -291.931187) (xy 123.507228 -291.931187) (xy 123.507228 -291.881209)
			(xy 123.515047 -291.831846) (xy 123.530491 -291.784314) (xy 123.553181 -291.739782) (xy 123.582557 -291.699349)
			(xy 123.617897 -291.664009) (xy 123.65833 -291.634633) (xy 123.702862 -291.611943) (xy 123.750394 -291.596499)
			(xy 123.799757 -291.58868) (xy 123.849735 -291.58868) (xy 123.899098 -291.596499) (xy 123.94663 -291.611943)
			(xy 123.991162 -291.634633) (xy 124.031595 -291.664009) (xy 124.066935 -291.699349) (xy 124.096311 -291.739782)
			(xy 124.119001 -291.784314) (xy 124.134445 -291.831846) (xy 124.142264 -291.881209) (xy 124.142754 -291.906198)
			(xy 124.142264 -291.931187) (xy 125.387336 -291.931187) (xy 125.387336 -291.881209) (xy 125.395155 -291.831846)
			(xy 125.410599 -291.784314) (xy 125.433289 -291.739782) (xy 125.462665 -291.699349) (xy 125.498005 -291.664009)
			(xy 125.538438 -291.634633) (xy 125.58297 -291.611943) (xy 125.630502 -291.596499) (xy 125.679865 -291.58868)
			(xy 125.729843 -291.58868) (xy 125.779206 -291.596499) (xy 125.826738 -291.611943) (xy 125.87127 -291.634633)
			(xy 125.911703 -291.664009) (xy 125.947043 -291.699349) (xy 125.976419 -291.739782) (xy 125.999109 -291.784314)
			(xy 126.014553 -291.831846) (xy 126.022372 -291.881209) (xy 126.022862 -291.906198) (xy 126.022372 -291.931187)
			(xy 126.327136 -291.931187) (xy 126.327136 -291.881209) (xy 126.334955 -291.831846) (xy 126.350399 -291.784314)
			(xy 126.373089 -291.739782) (xy 126.402465 -291.699349) (xy 126.437805 -291.664009) (xy 126.478238 -291.634633)
			(xy 126.52277 -291.611943) (xy 126.570302 -291.596499) (xy 126.619665 -291.58868) (xy 126.669643 -291.58868)
			(xy 126.719006 -291.596499) (xy 126.766538 -291.611943) (xy 126.81107 -291.634633) (xy 126.851503 -291.664009)
			(xy 126.886843 -291.699349) (xy 126.916219 -291.739782) (xy 126.938909 -291.784314) (xy 126.954353 -291.831846)
			(xy 126.962172 -291.881209) (xy 126.962662 -291.906198) (xy 126.962172 -291.931187) (xy 126.954353 -291.98055)
			(xy 126.938909 -292.028082) (xy 126.916219 -292.072614) (xy 126.886843 -292.113047) (xy 126.851503 -292.148387)
			(xy 126.81107 -292.177763) (xy 126.766538 -292.200453) (xy 126.719006 -292.215897) (xy 126.669643 -292.223716)
			(xy 126.619665 -292.223716) (xy 126.570302 -292.215897) (xy 126.52277 -292.200453) (xy 126.478238 -292.177763)
			(xy 126.437805 -292.148387) (xy 126.402465 -292.113047) (xy 126.373089 -292.072614) (xy 126.350399 -292.028082)
			(xy 126.334955 -291.98055) (xy 126.327136 -291.931187) (xy 126.022372 -291.931187) (xy 126.014553 -291.98055)
			(xy 125.999109 -292.028082) (xy 125.976419 -292.072614) (xy 125.947043 -292.113047) (xy 125.911703 -292.148387)
			(xy 125.87127 -292.177763) (xy 125.826738 -292.200453) (xy 125.779206 -292.215897) (xy 125.729843 -292.223716)
			(xy 125.679865 -292.223716) (xy 125.630502 -292.215897) (xy 125.58297 -292.200453) (xy 125.538438 -292.177763)
			(xy 125.498005 -292.148387) (xy 125.462665 -292.113047) (xy 125.433289 -292.072614) (xy 125.410599 -292.028082)
			(xy 125.395155 -291.98055) (xy 125.387336 -291.931187) (xy 124.142264 -291.931187) (xy 124.134445 -291.98055)
			(xy 124.119001 -292.028082) (xy 124.096311 -292.072614) (xy 124.066935 -292.113047) (xy 124.031595 -292.148387)
			(xy 123.991162 -292.177763) (xy 123.94663 -292.200453) (xy 123.899098 -292.215897) (xy 123.849735 -292.223716)
			(xy 123.799757 -292.223716) (xy 123.750394 -292.215897) (xy 123.702862 -292.200453) (xy 123.65833 -292.177763)
			(xy 123.617897 -292.148387) (xy 123.582557 -292.113047) (xy 123.553181 -292.072614) (xy 123.530491 -292.028082)
			(xy 123.515047 -291.98055) (xy 123.507228 -291.931187) (xy 123.20221 -291.931187) (xy 123.194391 -291.98055)
			(xy 123.178947 -292.028082) (xy 123.156257 -292.072614) (xy 123.126881 -292.113047) (xy 123.091541 -292.148387)
			(xy 123.051108 -292.177763) (xy 123.006576 -292.200453) (xy 122.959044 -292.215897) (xy 122.909681 -292.223716)
			(xy 122.859703 -292.223716) (xy 122.81034 -292.215897) (xy 122.762808 -292.200453) (xy 122.718276 -292.177763)
			(xy 122.677843 -292.148387) (xy 122.642503 -292.113047) (xy 122.613127 -292.072614) (xy 122.590437 -292.028082)
			(xy 122.574993 -291.98055) (xy 122.567174 -291.931187) (xy 121.322356 -291.931187) (xy 121.314537 -291.98055)
			(xy 121.299093 -292.028082) (xy 121.276403 -292.072614) (xy 121.247027 -292.113047) (xy 121.211687 -292.148387)
			(xy 121.171254 -292.177763) (xy 121.126722 -292.200453) (xy 121.07919 -292.215897) (xy 121.029827 -292.223716)
			(xy 120.979849 -292.223716) (xy 120.930486 -292.215897) (xy 120.882954 -292.200453) (xy 120.838422 -292.177763)
			(xy 120.797989 -292.148387) (xy 120.762649 -292.113047) (xy 120.733273 -292.072614) (xy 120.710583 -292.028082)
			(xy 120.695139 -291.98055) (xy 120.68732 -291.931187) (xy 120.382302 -291.931187) (xy 120.374483 -291.98055)
			(xy 120.359039 -292.028082) (xy 120.336349 -292.072614) (xy 120.306973 -292.113047) (xy 120.271633 -292.148387)
			(xy 120.2312 -292.177763) (xy 120.186668 -292.200453) (xy 120.139136 -292.215897) (xy 120.089773 -292.223716)
			(xy 120.039795 -292.223716) (xy 119.990432 -292.215897) (xy 119.9429 -292.200453) (xy 119.898368 -292.177763)
			(xy 119.857935 -292.148387) (xy 119.822595 -292.113047) (xy 119.793219 -292.072614) (xy 119.770529 -292.028082)
			(xy 119.755085 -291.98055) (xy 119.747266 -291.931187) (xy 118.502445 -291.931187) (xy 118.494673 -291.980399)
			(xy 118.479303 -292.027847) (xy 118.456719 -292.072315) (xy 118.427475 -292.112716) (xy 118.410228 -292.130734)
			(xy 118.400057 -292.141728) (xy 118.386028 -292.168175) (xy 118.380269 -292.197553) (xy 118.383275 -292.227338)
			(xy 118.394788 -292.254973) (xy 118.403878 -292.266878) (xy 118.40718 -292.270688) (xy 118.422166 -292.28542)
			(xy 118.429786 -292.293548) (xy 118.430548 -292.29431) (xy 118.497096 -292.360858) (xy 118.503898 -292.368206)
			(xy 118.51161 -292.386669) (xy 118.512082 -292.396672) (xy 118.512082 -292.49497) (xy 118.512336 -292.503098)
			(xy 118.512336 -292.741193) (xy 119.277112 -292.741193) (xy 119.277112 -292.691215) (xy 119.284931 -292.641852)
			(xy 119.300375 -292.59432) (xy 119.323065 -292.549788) (xy 119.352441 -292.509355) (xy 119.387781 -292.474015)
			(xy 119.428214 -292.444639) (xy 119.472746 -292.421949) (xy 119.520278 -292.406505) (xy 119.569641 -292.398686)
			(xy 119.619619 -292.398686) (xy 119.668982 -292.406505) (xy 119.716514 -292.421949) (xy 119.761046 -292.444639)
			(xy 119.801479 -292.474015) (xy 119.836819 -292.509355) (xy 119.866195 -292.549788) (xy 119.888885 -292.59432)
			(xy 119.904329 -292.641852) (xy 119.912148 -292.691215) (xy 119.912638 -292.716204) (xy 119.912148 -292.741193)
			(xy 120.217166 -292.741193) (xy 120.217166 -292.691215) (xy 120.224985 -292.641852) (xy 120.240429 -292.59432)
			(xy 120.263119 -292.549788) (xy 120.292495 -292.509355) (xy 120.327835 -292.474015) (xy 120.368268 -292.444639)
			(xy 120.4128 -292.421949) (xy 120.460332 -292.406505) (xy 120.509695 -292.398686) (xy 120.559673 -292.398686)
			(xy 120.609036 -292.406505) (xy 120.656568 -292.421949) (xy 120.7011 -292.444639) (xy 120.741533 -292.474015)
			(xy 120.776873 -292.509355) (xy 120.806249 -292.549788) (xy 120.828939 -292.59432) (xy 120.844383 -292.641852)
			(xy 120.852202 -292.691215) (xy 120.852692 -292.716204) (xy 120.852202 -292.741193) (xy 122.097274 -292.741193)
			(xy 122.097274 -292.691215) (xy 122.105093 -292.641852) (xy 122.120537 -292.59432) (xy 122.143227 -292.549788)
			(xy 122.172603 -292.509355) (xy 122.207943 -292.474015) (xy 122.248376 -292.444639) (xy 122.292908 -292.421949)
			(xy 122.34044 -292.406505) (xy 122.389803 -292.398686) (xy 122.439781 -292.398686) (xy 122.489144 -292.406505)
			(xy 122.536676 -292.421949) (xy 122.581208 -292.444639) (xy 122.621641 -292.474015) (xy 122.656981 -292.509355)
			(xy 122.686357 -292.549788) (xy 122.709047 -292.59432) (xy 122.724491 -292.641852) (xy 122.73231 -292.691215)
			(xy 122.7328 -292.716204) (xy 122.73231 -292.741193) (xy 123.037328 -292.741193) (xy 123.037328 -292.691215)
			(xy 123.045147 -292.641852) (xy 123.060591 -292.59432) (xy 123.083281 -292.549788) (xy 123.112657 -292.509355)
			(xy 123.147997 -292.474015) (xy 123.18843 -292.444639) (xy 123.232962 -292.421949) (xy 123.280494 -292.406505)
			(xy 123.329857 -292.398686) (xy 123.379835 -292.398686) (xy 123.429198 -292.406505) (xy 123.47673 -292.421949)
			(xy 123.521262 -292.444639) (xy 123.561695 -292.474015) (xy 123.597035 -292.509355) (xy 123.626411 -292.549788)
			(xy 123.649101 -292.59432) (xy 123.664545 -292.641852) (xy 123.672364 -292.691215) (xy 123.672854 -292.716204)
			(xy 123.672364 -292.741193) (xy 124.917182 -292.741193) (xy 124.917182 -292.691215) (xy 124.925001 -292.641852)
			(xy 124.940445 -292.59432) (xy 124.963135 -292.549788) (xy 124.992511 -292.509355) (xy 125.027851 -292.474015)
			(xy 125.068284 -292.444639) (xy 125.112816 -292.421949) (xy 125.160348 -292.406505) (xy 125.209711 -292.398686)
			(xy 125.259689 -292.398686) (xy 125.309052 -292.406505) (xy 125.356584 -292.421949) (xy 125.401116 -292.444639)
			(xy 125.441549 -292.474015) (xy 125.476889 -292.509355) (xy 125.506265 -292.549788) (xy 125.528955 -292.59432)
			(xy 125.544399 -292.641852) (xy 125.552218 -292.691215) (xy 125.552708 -292.716204) (xy 125.552218 -292.741193)
			(xy 125.857236 -292.741193) (xy 125.857236 -292.691215) (xy 125.865055 -292.641852) (xy 125.880499 -292.59432)
			(xy 125.903189 -292.549788) (xy 125.932565 -292.509355) (xy 125.967905 -292.474015) (xy 126.008338 -292.444639)
			(xy 126.05287 -292.421949) (xy 126.100402 -292.406505) (xy 126.149765 -292.398686) (xy 126.199743 -292.398686)
			(xy 126.249106 -292.406505) (xy 126.296638 -292.421949) (xy 126.34117 -292.444639) (xy 126.381603 -292.474015)
			(xy 126.416943 -292.509355) (xy 126.446319 -292.549788) (xy 126.469009 -292.59432) (xy 126.484453 -292.641852)
			(xy 126.492272 -292.691215) (xy 126.492762 -292.716204) (xy 126.492272 -292.741193) (xy 126.484453 -292.790556)
			(xy 126.469009 -292.838088) (xy 126.446319 -292.88262) (xy 126.416943 -292.923053) (xy 126.381603 -292.958393)
			(xy 126.34117 -292.987769) (xy 126.296638 -293.010459) (xy 126.249106 -293.025903) (xy 126.199743 -293.033722)
			(xy 126.149765 -293.033722) (xy 126.100402 -293.025903) (xy 126.05287 -293.010459) (xy 126.008338 -292.987769)
			(xy 125.967905 -292.958393) (xy 125.932565 -292.923053) (xy 125.903189 -292.88262) (xy 125.880499 -292.838088)
			(xy 125.865055 -292.790556) (xy 125.857236 -292.741193) (xy 125.552218 -292.741193) (xy 125.544399 -292.790556)
			(xy 125.528955 -292.838088) (xy 125.506265 -292.88262) (xy 125.476889 -292.923053) (xy 125.441549 -292.958393)
			(xy 125.401116 -292.987769) (xy 125.356584 -293.010459) (xy 125.309052 -293.025903) (xy 125.259689 -293.033722)
			(xy 125.209711 -293.033722) (xy 125.160348 -293.025903) (xy 125.112816 -293.010459) (xy 125.068284 -292.987769)
			(xy 125.027851 -292.958393) (xy 124.992511 -292.923053) (xy 124.963135 -292.88262) (xy 124.940445 -292.838088)
			(xy 124.925001 -292.790556) (xy 124.917182 -292.741193) (xy 123.672364 -292.741193) (xy 123.664545 -292.790556)
			(xy 123.649101 -292.838088) (xy 123.626411 -292.88262) (xy 123.597035 -292.923053) (xy 123.561695 -292.958393)
			(xy 123.521262 -292.987769) (xy 123.47673 -293.010459) (xy 123.429198 -293.025903) (xy 123.379835 -293.033722)
			(xy 123.329857 -293.033722) (xy 123.280494 -293.025903) (xy 123.232962 -293.010459) (xy 123.18843 -292.987769)
			(xy 123.147997 -292.958393) (xy 123.112657 -292.923053) (xy 123.083281 -292.88262) (xy 123.060591 -292.838088)
			(xy 123.045147 -292.790556) (xy 123.037328 -292.741193) (xy 122.73231 -292.741193) (xy 122.724491 -292.790556)
			(xy 122.709047 -292.838088) (xy 122.686357 -292.88262) (xy 122.656981 -292.923053) (xy 122.621641 -292.958393)
			(xy 122.581208 -292.987769) (xy 122.536676 -293.010459) (xy 122.489144 -293.025903) (xy 122.439781 -293.033722)
			(xy 122.389803 -293.033722) (xy 122.34044 -293.025903) (xy 122.292908 -293.010459) (xy 122.248376 -292.987769)
			(xy 122.207943 -292.958393) (xy 122.172603 -292.923053) (xy 122.143227 -292.88262) (xy 122.120537 -292.838088)
			(xy 122.105093 -292.790556) (xy 122.097274 -292.741193) (xy 120.852202 -292.741193) (xy 120.844383 -292.790556)
			(xy 120.828939 -292.838088) (xy 120.806249 -292.88262) (xy 120.776873 -292.923053) (xy 120.741533 -292.958393)
			(xy 120.7011 -292.987769) (xy 120.656568 -293.010459) (xy 120.609036 -293.025903) (xy 120.559673 -293.033722)
			(xy 120.509695 -293.033722) (xy 120.460332 -293.025903) (xy 120.4128 -293.010459) (xy 120.368268 -292.987769)
			(xy 120.327835 -292.958393) (xy 120.292495 -292.923053) (xy 120.263119 -292.88262) (xy 120.240429 -292.838088)
			(xy 120.224985 -292.790556) (xy 120.217166 -292.741193) (xy 119.912148 -292.741193) (xy 119.904329 -292.790556)
			(xy 119.888885 -292.838088) (xy 119.866195 -292.88262) (xy 119.836819 -292.923053) (xy 119.801479 -292.958393)
			(xy 119.761046 -292.987769) (xy 119.716514 -293.010459) (xy 119.668982 -293.025903) (xy 119.619619 -293.033722)
			(xy 119.569641 -293.033722) (xy 119.520278 -293.025903) (xy 119.472746 -293.010459) (xy 119.428214 -292.987769)
			(xy 119.387781 -292.958393) (xy 119.352441 -292.923053) (xy 119.323065 -292.88262) (xy 119.300375 -292.838088)
			(xy 119.284931 -292.790556) (xy 119.277112 -292.741193) (xy 118.512336 -292.741193) (xy 118.512336 -292.775894)
			(xy 118.51281 -292.785861) (xy 118.520383 -292.804301) (xy 118.527068 -292.811708) (xy 118.950994 -293.235634)
			(xy 118.981982 -293.241476) (xy 118.996206 -293.235126) (xy 119.016534 -293.226542) (xy 119.058967 -293.214442)
			(xy 119.102667 -293.208335) (xy 119.12473 -293.207948) (xy 119.149737 -293.208441) (xy 119.199136 -293.216269)
			(xy 119.246701 -293.231729) (xy 119.291263 -293.254438) (xy 119.331724 -293.283839) (xy 119.367087 -293.319207)
			(xy 119.396483 -293.359671) (xy 119.419187 -293.404236) (xy 119.43464 -293.451803) (xy 119.442462 -293.501203)
			(xy 119.442992 -293.52621) (xy 119.442487 -293.551199) (xy 119.747266 -293.551199) (xy 119.747266 -293.501221)
			(xy 119.755085 -293.451858) (xy 119.770529 -293.404326) (xy 119.793219 -293.359794) (xy 119.822595 -293.319361)
			(xy 119.857935 -293.284021) (xy 119.898368 -293.254645) (xy 119.9429 -293.231955) (xy 119.990432 -293.216511)
			(xy 120.039795 -293.208692) (xy 120.089773 -293.208692) (xy 120.139136 -293.216511) (xy 120.186668 -293.231955)
			(xy 120.2312 -293.254645) (xy 120.271633 -293.284021) (xy 120.306973 -293.319361) (xy 120.336349 -293.359794)
			(xy 120.359039 -293.404326) (xy 120.374483 -293.451858) (xy 120.382302 -293.501221) (xy 120.382792 -293.52621)
			(xy 120.382302 -293.551199) (xy 120.68732 -293.551199) (xy 120.68732 -293.501221) (xy 120.695139 -293.451858)
			(xy 120.710583 -293.404326) (xy 120.733273 -293.359794) (xy 120.762649 -293.319361) (xy 120.797989 -293.284021)
			(xy 120.838422 -293.254645) (xy 120.882954 -293.231955) (xy 120.930486 -293.216511) (xy 120.979849 -293.208692)
			(xy 121.029827 -293.208692) (xy 121.07919 -293.216511) (xy 121.126722 -293.231955) (xy 121.171254 -293.254645)
			(xy 121.211687 -293.284021) (xy 121.247027 -293.319361) (xy 121.276403 -293.359794) (xy 121.299093 -293.404326)
			(xy 121.314537 -293.451858) (xy 121.322356 -293.501221) (xy 121.322846 -293.52621) (xy 121.322356 -293.551199)
			(xy 121.62712 -293.551199) (xy 121.62712 -293.501221) (xy 121.634939 -293.451858) (xy 121.650383 -293.404326)
			(xy 121.673073 -293.359794) (xy 121.702449 -293.319361) (xy 121.737789 -293.284021) (xy 121.778222 -293.254645)
			(xy 121.822754 -293.231955) (xy 121.870286 -293.216511) (xy 121.919649 -293.208692) (xy 121.969627 -293.208692)
			(xy 122.01899 -293.216511) (xy 122.066522 -293.231955) (xy 122.111054 -293.254645) (xy 122.151487 -293.284021)
			(xy 122.186827 -293.319361) (xy 122.216203 -293.359794) (xy 122.238893 -293.404326) (xy 122.254337 -293.451858)
			(xy 122.262156 -293.501221) (xy 122.262646 -293.52621) (xy 122.262156 -293.551199) (xy 122.254337 -293.600562)
			(xy 122.238893 -293.648094) (xy 122.216203 -293.692626) (xy 122.186827 -293.733059) (xy 122.151487 -293.768399)
			(xy 122.111054 -293.797775) (xy 122.066522 -293.820465) (xy 122.01899 -293.835909) (xy 121.969627 -293.843728)
			(xy 121.919649 -293.843728) (xy 121.870286 -293.835909) (xy 121.822754 -293.820465) (xy 121.778222 -293.797775)
			(xy 121.737789 -293.768399) (xy 121.702449 -293.733059) (xy 121.673073 -293.692626) (xy 121.650383 -293.648094)
			(xy 121.634939 -293.600562) (xy 121.62712 -293.551199) (xy 121.322356 -293.551199) (xy 121.314537 -293.600562)
			(xy 121.299093 -293.648094) (xy 121.276403 -293.692626) (xy 121.247027 -293.733059) (xy 121.211687 -293.768399)
			(xy 121.171254 -293.797775) (xy 121.126722 -293.820465) (xy 121.07919 -293.835909) (xy 121.029827 -293.843728)
			(xy 120.979849 -293.843728) (xy 120.930486 -293.835909) (xy 120.882954 -293.820465) (xy 120.838422 -293.797775)
			(xy 120.797989 -293.768399) (xy 120.762649 -293.733059) (xy 120.733273 -293.692626) (xy 120.710583 -293.648094)
			(xy 120.695139 -293.600562) (xy 120.68732 -293.551199) (xy 120.382302 -293.551199) (xy 120.374483 -293.600562)
			(xy 120.359039 -293.648094) (xy 120.336349 -293.692626) (xy 120.306973 -293.733059) (xy 120.271633 -293.768399)
			(xy 120.2312 -293.797775) (xy 120.186668 -293.820465) (xy 120.139136 -293.835909) (xy 120.089773 -293.843728)
			(xy 120.039795 -293.843728) (xy 119.990432 -293.835909) (xy 119.9429 -293.820465) (xy 119.898368 -293.797775)
			(xy 119.857935 -293.768399) (xy 119.822595 -293.733059) (xy 119.793219 -293.692626) (xy 119.770529 -293.648094)
			(xy 119.755085 -293.600562) (xy 119.747266 -293.551199) (xy 119.442487 -293.551199) (xy 119.442443 -293.553362)
			(xy 119.433239 -293.60688) (xy 119.4151 -293.658065) (xy 119.388549 -293.705436) (xy 119.371872 -293.72687)
			(xy 119.366538 -293.733474) (xy 119.357648 -293.757858) (xy 119.356221 -293.762098) (xy 119.354688 -293.770911)
			(xy 119.3546 -293.775384) (xy 119.3546 -293.939976) (xy 119.355102 -293.953821) (xy 119.362611 -293.980477)
			(xy 119.377002 -294.004138) (xy 119.397217 -294.023065) (xy 119.421773 -294.035868) (xy 119.448865 -294.041608)
			(xy 119.476503 -294.039861) (xy 119.489728 -294.035734) (xy 119.515156 -294.027437) (xy 119.567888 -294.018499)
			(xy 119.59463 -294.017954) (xy 119.619636 -294.018447) (xy 119.669033 -294.026275) (xy 119.716597 -294.041733)
			(xy 119.761157 -294.064441) (xy 119.801616 -294.09384) (xy 119.836979 -294.129207) (xy 119.866374 -294.169669)
			(xy 119.889078 -294.214231) (xy 119.904532 -294.261796) (xy 119.912356 -294.311194) (xy 119.912356 -294.361205)
			(xy 120.217166 -294.361205) (xy 120.217166 -294.311227) (xy 120.224985 -294.261864) (xy 120.240429 -294.214332)
			(xy 120.263119 -294.1698) (xy 120.292495 -294.129367) (xy 120.327835 -294.094027) (xy 120.368268 -294.064651)
			(xy 120.4128 -294.041961) (xy 120.460332 -294.026517) (xy 120.509695 -294.018698) (xy 120.559673 -294.018698)
			(xy 120.609036 -294.026517) (xy 120.656568 -294.041961) (xy 120.7011 -294.064651) (xy 120.741533 -294.094027)
			(xy 120.776873 -294.129367) (xy 120.806249 -294.1698) (xy 120.828939 -294.214332) (xy 120.844383 -294.261864)
			(xy 120.852202 -294.311227) (xy 120.852692 -294.336216) (xy 120.852202 -294.361205) (xy 121.15722 -294.361205)
			(xy 121.15722 -294.311227) (xy 121.165039 -294.261864) (xy 121.180483 -294.214332) (xy 121.203173 -294.1698)
			(xy 121.232549 -294.129367) (xy 121.267889 -294.094027) (xy 121.308322 -294.064651) (xy 121.352854 -294.041961)
			(xy 121.400386 -294.026517) (xy 121.449749 -294.018698) (xy 121.499727 -294.018698) (xy 121.54909 -294.026517)
			(xy 121.596622 -294.041961) (xy 121.641154 -294.064651) (xy 121.681587 -294.094027) (xy 121.716927 -294.129367)
			(xy 121.746303 -294.1698) (xy 121.768993 -294.214332) (xy 121.784437 -294.261864) (xy 121.792256 -294.311227)
			(xy 121.792746 -294.336216) (xy 121.792256 -294.361205) (xy 121.784437 -294.410568) (xy 121.768993 -294.4581)
			(xy 121.746303 -294.502632) (xy 121.716927 -294.543065) (xy 121.681587 -294.578405) (xy 121.641154 -294.607781)
			(xy 121.596622 -294.630471) (xy 121.54909 -294.645915) (xy 121.499727 -294.653734) (xy 121.449749 -294.653734)
			(xy 121.400386 -294.645915) (xy 121.352854 -294.630471) (xy 121.308322 -294.607781) (xy 121.267889 -294.578405)
			(xy 121.232549 -294.543065) (xy 121.203173 -294.502632) (xy 121.180483 -294.4581) (xy 121.165039 -294.410568)
			(xy 121.15722 -294.361205) (xy 120.852202 -294.361205) (xy 120.844383 -294.410568) (xy 120.828939 -294.4581)
			(xy 120.806249 -294.502632) (xy 120.776873 -294.543065) (xy 120.741533 -294.578405) (xy 120.7011 -294.607781)
			(xy 120.656568 -294.630471) (xy 120.609036 -294.645915) (xy 120.559673 -294.653734) (xy 120.509695 -294.653734)
			(xy 120.460332 -294.645915) (xy 120.4128 -294.630471) (xy 120.368268 -294.607781) (xy 120.327835 -294.578405)
			(xy 120.292495 -294.543065) (xy 120.263119 -294.502632) (xy 120.240429 -294.4581) (xy 120.224985 -294.410568)
			(xy 120.217166 -294.361205) (xy 119.912356 -294.361205) (xy 119.912356 -294.361206) (xy 119.904532 -294.410604)
			(xy 119.889078 -294.458169) (xy 119.866374 -294.502731) (xy 119.836979 -294.543193) (xy 119.801616 -294.57856)
			(xy 119.761157 -294.607959) (xy 119.716597 -294.630667) (xy 119.669033 -294.646125) (xy 119.619636 -294.653953)
			(xy 119.59463 -294.654478) (xy 119.567199 -294.653884) (xy 119.513154 -294.644449) (xy 119.461521 -294.625904)
			(xy 119.437404 -294.612822) (xy 119.436896 -294.612568) (xy 119.431308 -294.60952) (xy 119.418862 -294.605964)
			(xy 119.407325 -294.603431) (xy 119.384166 -294.607937) (xy 119.374412 -294.6146) (xy 119.365014 -294.621712)
			(xy 119.3546 -294.642794) (xy 119.3546 -294.66286) (xy 119.354485 -294.667815) (xy 119.352573 -294.67754)
			(xy 119.35079 -294.682164) (xy 119.347488 -294.690038) (xy 119.345483 -294.694603) (xy 119.339988 -294.702922)
			(xy 119.336566 -294.706548) (xy 119.265446 -294.777668) (xy 119.265192 -294.777922) (xy 119.261382 -294.781986)
			(xy 118.981728 -295.061386) (xy 118.975666 -295.068556) (xy 118.968865 -295.086041) (xy 118.96852 -295.095422)
			(xy 118.96852 -295.171211) (xy 119.747266 -295.171211) (xy 119.747266 -295.121233) (xy 119.755085 -295.07187)
			(xy 119.770529 -295.024338) (xy 119.793219 -294.979806) (xy 119.822595 -294.939373) (xy 119.857935 -294.904033)
			(xy 119.898368 -294.874657) (xy 119.9429 -294.851967) (xy 119.990432 -294.836523) (xy 120.039795 -294.828704)
			(xy 120.089773 -294.828704) (xy 120.139136 -294.836523) (xy 120.186668 -294.851967) (xy 120.2312 -294.874657)
			(xy 120.271633 -294.904033) (xy 120.306973 -294.939373) (xy 120.336349 -294.979806) (xy 120.359039 -295.024338)
			(xy 120.374483 -295.07187) (xy 120.382302 -295.121233) (xy 120.382792 -295.146222) (xy 120.382302 -295.171211)
			(xy 120.374483 -295.220574) (xy 120.359039 -295.268106) (xy 120.336349 -295.312638) (xy 120.306973 -295.353071)
			(xy 120.271633 -295.388411) (xy 120.2312 -295.417787) (xy 120.186668 -295.440477) (xy 120.139136 -295.455921)
			(xy 120.089773 -295.46374) (xy 120.039795 -295.46374) (xy 119.990432 -295.455921) (xy 119.9429 -295.440477)
			(xy 119.898368 -295.417787) (xy 119.857935 -295.388411) (xy 119.822595 -295.353071) (xy 119.793219 -295.312638)
			(xy 119.770529 -295.268106) (xy 119.755085 -295.220574) (xy 119.747266 -295.171211) (xy 118.96852 -295.171211)
			(xy 118.96852 -295.843198) (xy 118.968977 -295.853076) (xy 118.976417 -295.871378) (xy 118.982998 -295.878758)
			(xy 118.983252 -295.879012) (xy 119.458994 -296.354754) (xy 119.459502 -296.355262) (xy 119.466886 -296.361836)
			(xy 119.485185 -296.369267) (xy 119.495062 -296.36974) (xy 120.25376 -296.36974) (xy 120.26736 -296.369273)
			(xy 120.293579 -296.362024) (xy 120.316955 -296.34811) (xy 120.335827 -296.328519) (xy 120.348857 -296.30464)
			(xy 120.355121 -296.278168) (xy 120.354173 -296.250982) (xy 120.346082 -296.22501) (xy 120.331421 -296.202096)
			(xy 120.321578 -296.192702) (xy 120.302142 -296.174436) (xy 120.269051 -296.13261) (xy 120.243386 -296.085857)
			(xy 120.225866 -296.035483) (xy 120.21698 -295.982895) (xy 120.216422 -295.956228) (xy 120.216913 -295.931219)
			(xy 120.224737 -295.881816) (xy 120.240194 -295.834246) (xy 120.262902 -295.789679) (xy 120.292302 -295.749214)
			(xy 120.32767 -295.713846) (xy 120.368135 -295.684446) (xy 120.412702 -295.661738) (xy 120.460272 -295.646281)
			(xy 120.509675 -295.638457) (xy 120.559693 -295.638457) (xy 120.609096 -295.646281) (xy 120.656666 -295.661738)
			(xy 120.701233 -295.684446) (xy 120.741698 -295.713846) (xy 120.777066 -295.749214) (xy 120.806466 -295.789679)
			(xy 120.829174 -295.834246) (xy 120.844631 -295.881816) (xy 120.852455 -295.931219) (xy 120.852946 -295.956228)
			(xy 120.852403 -295.982895) (xy 120.843513 -296.035482) (xy 120.825987 -296.085854) (xy 120.800314 -296.132602)
			(xy 120.767212 -296.17442) (xy 120.74779 -296.192702) (xy 120.737992 -296.202135) (xy 120.723343 -296.225038)
			(xy 120.715259 -296.250996) (xy 120.714314 -296.278167) (xy 120.720574 -296.304624) (xy 120.733595 -296.32849)
			(xy 120.752454 -296.348073) (xy 120.775813 -296.361984) (xy 120.802016 -296.369235) (xy 120.815608 -296.36974)
			(xy 121.136918 -296.36974) (xy 121.146985 -296.369312) (xy 121.165579 -296.361586) (xy 121.172986 -296.354754)
			(xy 121.227088 -296.300652) (xy 121.237442 -296.289515) (xy 121.251681 -296.262664) (xy 121.257402 -296.232815)
			(xy 121.254099 -296.202603) (xy 121.242065 -296.174694) (xy 121.232676 -296.16273) (xy 121.214876 -296.140959)
			(xy 121.186445 -296.092447) (xy 121.166977 -296.039694) (xy 121.157078 -295.984343) (xy 121.156476 -295.956228)
			(xy 121.156939 -295.931216) (xy 121.164761 -295.881809) (xy 121.180217 -295.834234) (xy 121.202926 -295.789662)
			(xy 121.232328 -295.749193) (xy 121.2677 -295.713822) (xy 121.308171 -295.68442) (xy 121.352743 -295.661713)
			(xy 121.400319 -295.646259) (xy 121.449726 -295.638438) (xy 121.474738 -295.637966) (xy 121.502855 -295.638562)
			(xy 121.558215 -295.648441) (xy 121.610973 -295.667904) (xy 121.659486 -295.696342) (xy 121.68124 -295.714166)
			(xy 121.69313 -295.723684) (xy 121.721064 -295.73579) (xy 121.751326 -295.739112) (xy 121.781221 -295.733354)
			(xy 121.808084 -295.71903) (xy 121.819162 -295.708578) (xy 122.491754 -295.035986) (xy 122.492262 -295.035478)
			(xy 122.498848 -295.028098) (xy 122.506308 -295.009799) (xy 122.50674 -294.999918) (xy 122.50674 -294.755824)
			(xy 122.506298 -294.742717) (xy 122.499552 -294.717384) (xy 122.486576 -294.694604) (xy 122.468226 -294.675881)
			(xy 122.445713 -294.662448) (xy 122.420521 -294.655193) (xy 122.407426 -294.654478) (xy 122.382794 -294.653445)
			(xy 122.334275 -294.64472) (xy 122.28768 -294.62862) (xy 122.244124 -294.60553) (xy 122.204648 -294.576002)
			(xy 122.170195 -294.540742) (xy 122.141589 -294.500592) (xy 122.119514 -294.456513) (xy 122.104498 -294.409558)
			(xy 122.096899 -294.360849) (xy 122.096899 -294.311551) (xy 122.104498 -294.262843) (xy 122.119514 -294.215888)
			(xy 122.141589 -294.171809) (xy 122.170195 -294.131659) (xy 122.204647 -294.096399) (xy 122.244124 -294.066871)
			(xy 122.28768 -294.043781) (xy 122.334274 -294.02768) (xy 122.382794 -294.018955) (xy 122.407426 -294.017954)
			(xy 122.420528 -294.017259) (xy 122.445736 -294.010018) (xy 122.468265 -293.996589) (xy 122.486626 -293.97786)
			(xy 122.499605 -293.955068) (xy 122.506343 -293.929721) (xy 122.50674 -293.916608) (xy 122.50674 -293.365682)
			(xy 122.507168 -293.355614) (xy 122.514891 -293.337018) (xy 122.521726 -293.329614) (xy 122.669554 -293.181786)
			(xy 122.676951 -293.174939) (xy 122.695551 -293.167211) (xy 122.705622 -293.1668) (xy 123.240038 -293.1668)
			(xy 123.250105 -293.16723) (xy 123.268699 -293.174954) (xy 123.276106 -293.181786) (xy 123.427236 -293.332916)
			(xy 123.437596 -293.342621) (xy 123.462403 -293.356398) (xy 123.490044 -293.362817) (xy 123.518384 -293.361382)
			(xy 123.545235 -293.352204) (xy 123.568524 -293.335992) (xy 123.577858 -293.325296) (xy 123.593055 -293.307289)
			(xy 123.627853 -293.275524) (xy 123.666957 -293.24924) (xy 123.709511 -293.229012) (xy 123.754583 -293.215283)
			(xy 123.801187 -293.208353) (xy 123.824746 -293.207948) (xy 123.849752 -293.208442) (xy 123.899147 -293.216272)
			(xy 123.94671 -293.231732) (xy 123.991269 -293.254442) (xy 124.031727 -293.283842) (xy 124.067088 -293.319208)
			(xy 124.096482 -293.35967) (xy 124.119185 -293.404233) (xy 124.134639 -293.451797) (xy 124.142462 -293.501194)
			(xy 124.142462 -293.551199) (xy 124.447282 -293.551199) (xy 124.447282 -293.501221) (xy 124.455101 -293.451858)
			(xy 124.470545 -293.404326) (xy 124.493235 -293.359794) (xy 124.522611 -293.319361) (xy 124.557951 -293.284021)
			(xy 124.598384 -293.254645) (xy 124.642916 -293.231955) (xy 124.690448 -293.216511) (xy 124.739811 -293.208692)
			(xy 124.789789 -293.208692) (xy 124.839152 -293.216511) (xy 124.886684 -293.231955) (xy 124.931216 -293.254645)
			(xy 124.971649 -293.284021) (xy 125.006989 -293.319361) (xy 125.036365 -293.359794) (xy 125.059055 -293.404326)
			(xy 125.074499 -293.451858) (xy 125.082318 -293.501221) (xy 125.082808 -293.52621) (xy 125.082318 -293.551199)
			(xy 125.387336 -293.551199) (xy 125.387336 -293.501221) (xy 125.395155 -293.451858) (xy 125.410599 -293.404326)
			(xy 125.433289 -293.359794) (xy 125.462665 -293.319361) (xy 125.498005 -293.284021) (xy 125.538438 -293.254645)
			(xy 125.58297 -293.231955) (xy 125.630502 -293.216511) (xy 125.679865 -293.208692) (xy 125.729843 -293.208692)
			(xy 125.779206 -293.216511) (xy 125.826738 -293.231955) (xy 125.87127 -293.254645) (xy 125.911703 -293.284021)
			(xy 125.947043 -293.319361) (xy 125.976419 -293.359794) (xy 125.999109 -293.404326) (xy 126.014553 -293.451858)
			(xy 126.022372 -293.501221) (xy 126.022862 -293.52621) (xy 126.022372 -293.551199) (xy 126.327136 -293.551199)
			(xy 126.327136 -293.501221) (xy 126.334955 -293.451858) (xy 126.350399 -293.404326) (xy 126.373089 -293.359794)
			(xy 126.402465 -293.319361) (xy 126.437805 -293.284021) (xy 126.478238 -293.254645) (xy 126.52277 -293.231955)
			(xy 126.570302 -293.216511) (xy 126.619665 -293.208692) (xy 126.669643 -293.208692) (xy 126.719006 -293.216511)
			(xy 126.766538 -293.231955) (xy 126.81107 -293.254645) (xy 126.851503 -293.284021) (xy 126.886843 -293.319361)
			(xy 126.916219 -293.359794) (xy 126.938909 -293.404326) (xy 126.954353 -293.451858) (xy 126.962172 -293.501221)
			(xy 126.962662 -293.52621) (xy 126.962172 -293.551199) (xy 126.954353 -293.600562) (xy 126.938909 -293.648094)
			(xy 126.916219 -293.692626) (xy 126.886843 -293.733059) (xy 126.851503 -293.768399) (xy 126.81107 -293.797775)
			(xy 126.766538 -293.820465) (xy 126.719006 -293.835909) (xy 126.669643 -293.843728) (xy 126.619665 -293.843728)
			(xy 126.570302 -293.835909) (xy 126.52277 -293.820465) (xy 126.478238 -293.797775) (xy 126.437805 -293.768399)
			(xy 126.402465 -293.733059) (xy 126.373089 -293.692626) (xy 126.350399 -293.648094) (xy 126.334955 -293.600562)
			(xy 126.327136 -293.551199) (xy 126.022372 -293.551199) (xy 126.014553 -293.600562) (xy 125.999109 -293.648094)
			(xy 125.976419 -293.692626) (xy 125.947043 -293.733059) (xy 125.911703 -293.768399) (xy 125.87127 -293.797775)
			(xy 125.826738 -293.820465) (xy 125.779206 -293.835909) (xy 125.729843 -293.843728) (xy 125.679865 -293.843728)
			(xy 125.630502 -293.835909) (xy 125.58297 -293.820465) (xy 125.538438 -293.797775) (xy 125.498005 -293.768399)
			(xy 125.462665 -293.733059) (xy 125.433289 -293.692626) (xy 125.410599 -293.648094) (xy 125.395155 -293.600562)
			(xy 125.387336 -293.551199) (xy 125.082318 -293.551199) (xy 125.074499 -293.600562) (xy 125.059055 -293.648094)
			(xy 125.036365 -293.692626) (xy 125.006989 -293.733059) (xy 124.971649 -293.768399) (xy 124.931216 -293.797775)
			(xy 124.886684 -293.820465) (xy 124.839152 -293.835909) (xy 124.789789 -293.843728) (xy 124.739811 -293.843728)
			(xy 124.690448 -293.835909) (xy 124.642916 -293.820465) (xy 124.598384 -293.797775) (xy 124.557951 -293.768399)
			(xy 124.522611 -293.733059) (xy 124.493235 -293.692626) (xy 124.470545 -293.648094) (xy 124.455101 -293.600562)
			(xy 124.447282 -293.551199) (xy 124.142462 -293.551199) (xy 124.142462 -293.551206) (xy 124.134639 -293.600603)
			(xy 124.119185 -293.648167) (xy 124.096482 -293.69273) (xy 124.067088 -293.733192) (xy 124.031727 -293.768558)
			(xy 123.991269 -293.797958) (xy 123.94671 -293.820668) (xy 123.899147 -293.836128) (xy 123.849752 -293.843958)
			(xy 123.824746 -293.844472) (xy 123.807331 -293.844223) (xy 123.772709 -293.840406) (xy 123.755658 -293.836852)
			(xy 123.740723 -293.834105) (xy 123.710469 -293.836507) (xy 123.682252 -293.847685) (xy 123.65856 -293.866654)
			(xy 123.64148 -293.891742) (xy 123.632517 -293.920738) (xy 123.63196 -293.935912) (xy 123.63196 -294.172894)
			(xy 123.634754 -294.184578) (xy 123.637548 -294.190166) (xy 123.637802 -294.19042) (xy 123.64894 -294.21309)
			(xy 123.664684 -294.261082) (xy 123.672631 -294.310961) (xy 123.673108 -294.336216) (xy 123.672624 -294.361205)
			(xy 123.977128 -294.361205) (xy 123.977128 -294.311227) (xy 123.984947 -294.261864) (xy 124.000391 -294.214332)
			(xy 124.023081 -294.1698) (xy 124.052457 -294.129367) (xy 124.087797 -294.094027) (xy 124.12823 -294.064651)
			(xy 124.172762 -294.041961) (xy 124.220294 -294.026517) (xy 124.269657 -294.018698) (xy 124.319635 -294.018698)
			(xy 124.368998 -294.026517) (xy 124.41653 -294.041961) (xy 124.461062 -294.064651) (xy 124.501495 -294.094027)
			(xy 124.536835 -294.129367) (xy 124.566211 -294.1698) (xy 124.588901 -294.214332) (xy 124.604345 -294.261864)
			(xy 124.612164 -294.311227) (xy 124.612654 -294.336216) (xy 124.612164 -294.361205) (xy 124.917182 -294.361205)
			(xy 124.917182 -294.311227) (xy 124.925001 -294.261864) (xy 124.940445 -294.214332) (xy 124.963135 -294.1698)
			(xy 124.992511 -294.129367) (xy 125.027851 -294.094027) (xy 125.068284 -294.064651) (xy 125.112816 -294.041961)
			(xy 125.160348 -294.026517) (xy 125.209711 -294.018698) (xy 125.259689 -294.018698) (xy 125.309052 -294.026517)
			(xy 125.356584 -294.041961) (xy 125.401116 -294.064651) (xy 125.441549 -294.094027) (xy 125.476889 -294.129367)
			(xy 125.506265 -294.1698) (xy 125.528955 -294.214332) (xy 125.544399 -294.261864) (xy 125.552218 -294.311227)
			(xy 125.552708 -294.336216) (xy 125.552218 -294.361205) (xy 125.857236 -294.361205) (xy 125.857236 -294.311227)
			(xy 125.865055 -294.261864) (xy 125.880499 -294.214332) (xy 125.903189 -294.1698) (xy 125.932565 -294.129367)
			(xy 125.967905 -294.094027) (xy 126.008338 -294.064651) (xy 126.05287 -294.041961) (xy 126.100402 -294.026517)
			(xy 126.149765 -294.018698) (xy 126.199743 -294.018698) (xy 126.249106 -294.026517) (xy 126.296638 -294.041961)
			(xy 126.34117 -294.064651) (xy 126.381603 -294.094027) (xy 126.416943 -294.129367) (xy 126.446319 -294.1698)
			(xy 126.469009 -294.214332) (xy 126.484453 -294.261864) (xy 126.492272 -294.311227) (xy 126.492762 -294.336216)
			(xy 126.492272 -294.361205) (xy 126.79729 -294.361205) (xy 126.79729 -294.311227) (xy 126.805109 -294.261864)
			(xy 126.820553 -294.214332) (xy 126.843243 -294.1698) (xy 126.872619 -294.129367) (xy 126.907959 -294.094027)
			(xy 126.948392 -294.064651) (xy 126.992924 -294.041961) (xy 127.040456 -294.026517) (xy 127.089819 -294.018698)
			(xy 127.139797 -294.018698) (xy 127.18916 -294.026517) (xy 127.236692 -294.041961) (xy 127.281224 -294.064651)
			(xy 127.321657 -294.094027) (xy 127.356997 -294.129367) (xy 127.386373 -294.1698) (xy 127.409063 -294.214332)
			(xy 127.424507 -294.261864) (xy 127.432326 -294.311227) (xy 127.432816 -294.336216) (xy 127.432326 -294.361205)
			(xy 127.737344 -294.361205) (xy 127.737344 -294.311227) (xy 127.745163 -294.261864) (xy 127.760607 -294.214332)
			(xy 127.783297 -294.1698) (xy 127.812673 -294.129367) (xy 127.848013 -294.094027) (xy 127.888446 -294.064651)
			(xy 127.932978 -294.041961) (xy 127.98051 -294.026517) (xy 128.029873 -294.018698) (xy 128.079851 -294.018698)
			(xy 128.129214 -294.026517) (xy 128.176746 -294.041961) (xy 128.221278 -294.064651) (xy 128.261711 -294.094027)
			(xy 128.297051 -294.129367) (xy 128.326427 -294.1698) (xy 128.349117 -294.214332) (xy 128.364561 -294.261864)
			(xy 128.37238 -294.311227) (xy 128.37287 -294.336216) (xy 128.37238 -294.361205) (xy 128.364561 -294.410568)
			(xy 128.349117 -294.4581) (xy 128.326427 -294.502632) (xy 128.297051 -294.543065) (xy 128.261711 -294.578405)
			(xy 128.221278 -294.607781) (xy 128.176746 -294.630471) (xy 128.129214 -294.645915) (xy 128.079851 -294.653734)
			(xy 128.029873 -294.653734) (xy 127.98051 -294.645915) (xy 127.932978 -294.630471) (xy 127.888446 -294.607781)
			(xy 127.848013 -294.578405) (xy 127.812673 -294.543065) (xy 127.783297 -294.502632) (xy 127.760607 -294.4581)
			(xy 127.745163 -294.410568) (xy 127.737344 -294.361205) (xy 127.432326 -294.361205) (xy 127.424507 -294.410568)
			(xy 127.409063 -294.4581) (xy 127.386373 -294.502632) (xy 127.356997 -294.543065) (xy 127.321657 -294.578405)
			(xy 127.281224 -294.607781) (xy 127.236692 -294.630471) (xy 127.18916 -294.645915) (xy 127.139797 -294.653734)
			(xy 127.089819 -294.653734) (xy 127.040456 -294.645915) (xy 126.992924 -294.630471) (xy 126.948392 -294.607781)
			(xy 126.907959 -294.578405) (xy 126.872619 -294.543065) (xy 126.843243 -294.502632) (xy 126.820553 -294.4581)
			(xy 126.805109 -294.410568) (xy 126.79729 -294.361205) (xy 126.492272 -294.361205) (xy 126.484453 -294.410568)
			(xy 126.469009 -294.4581) (xy 126.446319 -294.502632) (xy 126.416943 -294.543065) (xy 126.381603 -294.578405)
			(xy 126.34117 -294.607781) (xy 126.296638 -294.630471) (xy 126.249106 -294.645915) (xy 126.199743 -294.653734)
			(xy 126.149765 -294.653734) (xy 126.100402 -294.645915) (xy 126.05287 -294.630471) (xy 126.008338 -294.607781)
			(xy 125.967905 -294.578405) (xy 125.932565 -294.543065) (xy 125.903189 -294.502632) (xy 125.880499 -294.4581)
			(xy 125.865055 -294.410568) (xy 125.857236 -294.361205) (xy 125.552218 -294.361205) (xy 125.544399 -294.410568)
			(xy 125.528955 -294.4581) (xy 125.506265 -294.502632) (xy 125.476889 -294.543065) (xy 125.441549 -294.578405)
			(xy 125.401116 -294.607781) (xy 125.356584 -294.630471) (xy 125.309052 -294.645915) (xy 125.259689 -294.653734)
			(xy 125.209711 -294.653734) (xy 125.160348 -294.645915) (xy 125.112816 -294.630471) (xy 125.068284 -294.607781)
			(xy 125.027851 -294.578405) (xy 124.992511 -294.543065) (xy 124.963135 -294.502632) (xy 124.940445 -294.4581)
			(xy 124.925001 -294.410568) (xy 124.917182 -294.361205) (xy 124.612164 -294.361205) (xy 124.604345 -294.410568)
			(xy 124.588901 -294.4581) (xy 124.566211 -294.502632) (xy 124.536835 -294.543065) (xy 124.501495 -294.578405)
			(xy 124.461062 -294.607781) (xy 124.41653 -294.630471) (xy 124.368998 -294.645915) (xy 124.319635 -294.653734)
			(xy 124.269657 -294.653734) (xy 124.220294 -294.645915) (xy 124.172762 -294.630471) (xy 124.12823 -294.607781)
			(xy 124.087797 -294.578405) (xy 124.052457 -294.543065) (xy 124.023081 -294.502632) (xy 124.000391 -294.4581)
			(xy 123.984947 -294.410568) (xy 123.977128 -294.361205) (xy 123.672624 -294.361205) (xy 123.672619 -294.361468)
			(xy 123.664645 -294.411339) (xy 123.648916 -294.459332) (xy 123.637802 -294.482012) (xy 123.637548 -294.482266)
			(xy 123.634754 -294.487854) (xy 123.63196 -294.499538) (xy 123.63196 -295.171211) (xy 125.387336 -295.171211)
			(xy 125.387336 -295.121233) (xy 125.395155 -295.07187) (xy 125.410599 -295.024338) (xy 125.433289 -294.979806)
			(xy 125.462665 -294.939373) (xy 125.498005 -294.904033) (xy 125.538438 -294.874657) (xy 125.58297 -294.851967)
			(xy 125.630502 -294.836523) (xy 125.679865 -294.828704) (xy 125.729843 -294.828704) (xy 125.779206 -294.836523)
			(xy 125.826738 -294.851967) (xy 125.87127 -294.874657) (xy 125.911703 -294.904033) (xy 125.947043 -294.939373)
			(xy 125.976419 -294.979806) (xy 125.999109 -295.024338) (xy 126.014553 -295.07187) (xy 126.022372 -295.121233)
			(xy 126.022862 -295.146222) (xy 126.022372 -295.171211) (xy 128.207244 -295.171211) (xy 128.207244 -295.121233)
			(xy 128.215063 -295.07187) (xy 128.230507 -295.024338) (xy 128.253197 -294.979806) (xy 128.282573 -294.939373)
			(xy 128.317913 -294.904033) (xy 128.358346 -294.874657) (xy 128.402878 -294.851967) (xy 128.45041 -294.836523)
			(xy 128.499773 -294.828704) (xy 128.549751 -294.828704) (xy 128.599114 -294.836523) (xy 128.646646 -294.851967)
			(xy 128.691178 -294.874657) (xy 128.731611 -294.904033) (xy 128.766951 -294.939373) (xy 128.796327 -294.979806)
			(xy 128.819017 -295.024338) (xy 128.834461 -295.07187) (xy 128.84228 -295.121233) (xy 128.84277 -295.146222)
			(xy 128.84228 -295.171211) (xy 128.834461 -295.220574) (xy 128.819017 -295.268106) (xy 128.796327 -295.312638)
			(xy 128.766951 -295.353071) (xy 128.731611 -295.388411) (xy 128.691178 -295.417787) (xy 128.646646 -295.440477)
			(xy 128.599114 -295.455921) (xy 128.549751 -295.46374) (xy 128.499773 -295.46374) (xy 128.45041 -295.455921)
			(xy 128.402878 -295.440477) (xy 128.358346 -295.417787) (xy 128.317913 -295.388411) (xy 128.282573 -295.353071)
			(xy 128.253197 -295.312638) (xy 128.230507 -295.268106) (xy 128.215063 -295.220574) (xy 128.207244 -295.171211)
			(xy 126.022372 -295.171211) (xy 126.014553 -295.220574) (xy 125.999109 -295.268106) (xy 125.976419 -295.312638)
			(xy 125.947043 -295.353071) (xy 125.911703 -295.388411) (xy 125.87127 -295.417787) (xy 125.826738 -295.440477)
			(xy 125.779206 -295.455921) (xy 125.729843 -295.46374) (xy 125.679865 -295.46374) (xy 125.630502 -295.455921)
			(xy 125.58297 -295.440477) (xy 125.538438 -295.417787) (xy 125.498005 -295.388411) (xy 125.462665 -295.353071)
			(xy 125.433289 -295.312638) (xy 125.410599 -295.268106) (xy 125.395155 -295.220574) (xy 125.387336 -295.171211)
			(xy 123.63196 -295.171211) (xy 123.63196 -295.792906) (xy 123.634754 -295.80459) (xy 123.637548 -295.810178)
			(xy 123.637802 -295.810432) (xy 123.648736 -295.832683) (xy 123.66433 -295.879741) (xy 123.672426 -295.928651)
			(xy 123.673108 -295.953434) (xy 123.673108 -295.963594) (xy 123.680728 -295.981628) (xy 124.010674 -296.311574)
			(xy 124.011182 -296.312082) (xy 124.018566 -296.318657) (xy 124.036865 -296.326092) (xy 124.046742 -296.32656)
			(xy 124.109988 -296.32656) (xy 124.120008 -296.326142) (xy 124.138522 -296.318473) (xy 124.152688 -296.304299)
			(xy 124.160347 -296.28578) (xy 124.160788 -296.27576) (xy 124.160788 -296.262044) (xy 124.147326 -296.238676)
			(xy 124.135388 -296.231818) (xy 124.114978 -296.219542) (xy 124.077745 -296.189842) (xy 124.045355 -296.154924)
			(xy 124.018532 -296.115568) (xy 123.997874 -296.072653) (xy 123.983845 -296.027139) (xy 123.976756 -295.980042)
			(xy 123.976384 -295.956228) (xy 123.976875 -295.931219) (xy 123.984699 -295.881816) (xy 124.000156 -295.834246)
			(xy 124.022864 -295.789679) (xy 124.052264 -295.749214) (xy 124.087632 -295.713846) (xy 124.128097 -295.684446)
			(xy 124.172664 -295.661738) (xy 124.220234 -295.646281) (xy 124.269637 -295.638457) (xy 124.319655 -295.638457)
			(xy 124.369058 -295.646281) (xy 124.416628 -295.661738) (xy 124.461195 -295.684446) (xy 124.50166 -295.713846)
			(xy 124.537028 -295.749214) (xy 124.566428 -295.789679) (xy 124.589136 -295.834246) (xy 124.604593 -295.881816)
			(xy 124.612417 -295.931219) (xy 124.612908 -295.956228) (xy 124.612314 -295.983873) (xy 124.602766 -296.038333)
			(xy 124.58396 -296.090328) (xy 124.556462 -296.138296) (xy 124.539248 -296.159936) (xy 124.530404 -296.171324)
			(xy 124.518869 -296.197736) (xy 124.515172 -296.226318) (xy 124.519606 -296.254795) (xy 124.531819 -296.2809)
			(xy 124.550838 -296.302554) (xy 124.575149 -296.318033) (xy 124.602816 -296.326104) (xy 124.617226 -296.32656)
			(xy 125.852174 -296.32656) (xy 125.866587 -296.326063) (xy 125.894265 -296.318012) (xy 125.918589 -296.302545)
			(xy 125.93762 -296.280894) (xy 125.949839 -296.254787) (xy 125.954274 -296.226305) (xy 125.950569 -296.197718)
			(xy 125.939021 -296.171307) (xy 125.930152 -296.159936) (xy 125.912923 -296.138306) (xy 125.885423 -296.090335)
			(xy 125.866617 -296.038338) (xy 125.857068 -295.983875) (xy 125.856492 -295.956228) (xy 125.856983 -295.931219)
			(xy 125.864807 -295.881816) (xy 125.880264 -295.834246) (xy 125.902972 -295.789679) (xy 125.932372 -295.749214)
			(xy 125.96774 -295.713846) (xy 126.008205 -295.684446) (xy 126.052772 -295.661738) (xy 126.100342 -295.646281)
			(xy 126.149745 -295.638457) (xy 126.199763 -295.638457) (xy 126.249166 -295.646281) (xy 126.296736 -295.661738)
			(xy 126.341303 -295.684446) (xy 126.381768 -295.713846) (xy 126.417136 -295.749214) (xy 126.446536 -295.789679)
			(xy 126.469244 -295.834246) (xy 126.484701 -295.881816) (xy 126.492525 -295.931219) (xy 126.493016 -295.956228)
			(xy 126.492422 -295.983873) (xy 126.482874 -296.038333) (xy 126.464069 -296.090328) (xy 126.436571 -296.138296)
			(xy 126.419356 -296.159936) (xy 126.410512 -296.171324) (xy 126.398976 -296.197735) (xy 126.395278 -296.226317)
			(xy 126.399712 -296.254794) (xy 126.411925 -296.280899) (xy 126.430945 -296.302552) (xy 126.455256 -296.31803)
			(xy 126.482924 -296.326099) (xy 126.497334 -296.32656) (xy 126.792228 -296.32656) (xy 126.806646 -296.326069)
			(xy 126.834336 -296.318025) (xy 126.858672 -296.302559) (xy 126.877713 -296.280905) (xy 126.889938 -296.25479)
			(xy 126.894374 -296.226299) (xy 126.890665 -296.197703) (xy 126.879108 -296.171286) (xy 126.870206 -296.159936)
			(xy 126.852979 -296.138305) (xy 126.825483 -296.090333) (xy 126.80668 -296.038336) (xy 126.797132 -295.983874)
			(xy 126.796546 -295.956228) (xy 126.797037 -295.931219) (xy 126.804861 -295.881816) (xy 126.820318 -295.834246)
			(xy 126.843026 -295.789679) (xy 126.872426 -295.749214) (xy 126.907794 -295.713846) (xy 126.948259 -295.684446)
			(xy 126.992826 -295.661738) (xy 127.040396 -295.646281) (xy 127.089799 -295.638457) (xy 127.139817 -295.638457)
			(xy 127.18922 -295.646281) (xy 127.23679 -295.661738) (xy 127.281357 -295.684446) (xy 127.321822 -295.713846)
			(xy 127.35719 -295.749214) (xy 127.38659 -295.789679) (xy 127.409298 -295.834246) (xy 127.424755 -295.881816)
			(xy 127.432579 -295.931219) (xy 127.43307 -295.956228) (xy 127.432476 -295.983873) (xy 127.422927 -296.038332)
			(xy 127.404119 -296.090325) (xy 127.376619 -296.138291) (xy 127.35941 -296.159936) (xy 127.350569 -296.171327)
			(xy 127.339038 -296.19774) (xy 127.335343 -296.226323) (xy 127.339777 -296.254801) (xy 127.351988 -296.280907)
			(xy 127.371005 -296.302564) (xy 127.395313 -296.318049) (xy 127.422978 -296.326129) (xy 127.437388 -296.32656)
			(xy 127.732282 -296.32656) (xy 127.746694 -296.326062) (xy 127.77437 -296.31801) (xy 127.798692 -296.302542)
			(xy 127.817721 -296.280892) (xy 127.82994 -296.254786) (xy 127.834374 -296.226306) (xy 127.83067 -296.197721)
			(xy 127.819123 -296.171311) (xy 127.81026 -296.159936) (xy 127.793031 -296.138306) (xy 127.76553 -296.090336)
			(xy 127.746723 -296.038338) (xy 127.737174 -295.983875) (xy 127.7366 -295.956228) (xy 127.737088 -295.931216)
			(xy 127.744909 -295.881808) (xy 127.760363 -295.834232) (xy 127.783069 -295.789659) (xy 127.812468 -295.749186)
			(xy 127.847836 -295.71381) (xy 127.888302 -295.684403) (xy 127.932871 -295.661688) (xy 127.980444 -295.646225)
			(xy 128.02985 -295.638394) (xy 128.054862 -295.637966) (xy 128.081218 -295.638479) (xy 128.133212 -295.647158)
			(xy 128.183064 -295.664287) (xy 128.229413 -295.689395) (xy 128.27099 -295.721798) (xy 128.306661 -295.760608)
			(xy 128.335448 -295.804766) (xy 128.356566 -295.853064) (xy 128.363472 -295.878504) (xy 128.367156 -295.891413)
			(xy 128.380283 -295.914818) (xy 128.399056 -295.933995) (xy 128.422176 -295.947618) (xy 128.448048 -295.954746)
			(xy 128.474883 -295.954888) (xy 128.500828 -295.948033) (xy 128.524091 -295.934655) (xy 128.533906 -295.925494)
			(xy 129.095754 -295.363646) (xy 129.103153 -295.356803) (xy 129.121752 -295.349081) (xy 129.131822 -295.34866)
			(xy 129.6416 -295.34866) (xy 129.647545 -295.34847) (xy 129.659097 -295.345646) (xy 129.66446 -295.343072)
			(xy 129.689098 -295.330626) (xy 129.698242 -295.323006) (xy 129.701798 -295.31818) (xy 129.70256 -295.317418)
			(xy 129.704846 -295.314116) (xy 129.741047 -295.265212) (xy 129.818467 -295.171331) (xy 129.901363 -295.082247)
			(xy 129.989438 -294.99828) (xy 130.082377 -294.919731) (xy 130.179847 -294.84688) (xy 130.2815 -294.779989)
			(xy 130.38697 -294.719297) (xy 130.495882 -294.66502) (xy 130.551682 -294.640762) (xy 130.564704 -294.634669)
			(xy 130.586948 -294.616473) (xy 130.603243 -294.592801) (xy 130.612299 -294.565527) (xy 130.613398 -294.53681)
			(xy 130.606454 -294.508923) (xy 130.599688 -294.496236) (xy 130.586125 -294.471771) (xy 130.566872 -294.419256)
			(xy 130.557103 -294.364183) (xy 130.556508 -294.336216) (xy 130.557028 -294.309806) (xy 130.565747 -294.257711)
			(xy 130.58295 -294.20777) (xy 130.595116 -294.184324) (xy 130.603244 -294.169338) (xy 130.598418 -294.136318)
			(xy 130.466846 -294.004746) (xy 130.459734 -293.99738) (xy 130.440938 -293.98976) (xy 129.335784 -293.98976)
			(xy 129.321839 -293.990197) (xy 129.294991 -293.997752) (xy 129.27119 -294.012292) (xy 129.252215 -294.032732)
			(xy 129.239481 -294.057546) (xy 129.23394 -294.084881) (xy 129.236006 -294.112695) (xy 129.245523 -294.138911)
			(xy 129.253234 -294.150542) (xy 129.267299 -294.170926) (xy 129.289607 -294.215139) (xy 129.304783 -294.262278)
			(xy 129.312459 -294.311201) (xy 129.312924 -294.335962) (xy 129.312924 -294.336216) (xy 129.312433 -294.361225)
			(xy 129.304609 -294.410628) (xy 129.289152 -294.458198) (xy 129.266444 -294.502765) (xy 129.237044 -294.54323)
			(xy 129.201676 -294.578598) (xy 129.161211 -294.607998) (xy 129.116644 -294.630706) (xy 129.069074 -294.646163)
			(xy 129.019671 -294.653987) (xy 128.969653 -294.653987) (xy 128.92025 -294.646163) (xy 128.87268 -294.630706)
			(xy 128.828113 -294.607998) (xy 128.787648 -294.578598) (xy 128.75228 -294.54323) (xy 128.72288 -294.502765)
			(xy 128.700172 -294.458198) (xy 128.684715 -294.410628) (xy 128.676891 -294.361225) (xy 128.6764 -294.336216)
			(xy 128.6764 -294.335962) (xy 128.676894 -294.311204) (xy 128.684597 -294.262291) (xy 128.699765 -294.215155)
			(xy 128.722035 -294.170929) (xy 128.73609 -294.150542) (xy 128.743855 -294.138953) (xy 128.753351 -294.112732)
			(xy 128.755399 -294.08492) (xy 128.749845 -294.057591) (xy 128.737104 -294.032785) (xy 128.718126 -294.012351)
			(xy 128.694328 -293.997814) (xy 128.667483 -293.990258) (xy 128.65354 -293.98976) (xy 128.461262 -293.98976)
			(xy 128.451196 -293.989329) (xy 128.432605 -293.9816) (xy 128.425194 -293.974774) (xy 128.05029 -293.59987)
			(xy 128.039663 -293.589898) (xy 128.014095 -293.575937) (xy 127.985628 -293.569757) (xy 127.956573 -293.571859)
			(xy 127.929291 -293.582073) (xy 127.906 -293.599569) (xy 127.88859 -293.622926) (xy 127.883158 -293.636446)
			(xy 127.874363 -293.659019) (xy 127.850923 -293.701413) (xy 127.821324 -293.739762) (xy 127.786249 -293.773176)
			(xy 127.746512 -293.800882) (xy 127.703031 -293.82224) (xy 127.656814 -293.836754) (xy 127.60893 -293.844089)
			(xy 127.584708 -293.844472) (xy 127.559696 -293.844007) (xy 127.510287 -293.836183) (xy 127.46271 -293.820725)
			(xy 127.418137 -293.798015) (xy 127.377666 -293.768612) (xy 127.342293 -293.73324) (xy 127.312889 -293.692769)
			(xy 127.290178 -293.648197) (xy 127.274719 -293.600621) (xy 127.266893 -293.551212) (xy 127.266893 -293.501188)
			(xy 127.274719 -293.451779) (xy 127.290178 -293.404203) (xy 127.312889 -293.359631) (xy 127.342293 -293.31916)
			(xy 127.377666 -293.283788) (xy 127.418137 -293.254385) (xy 127.46271 -293.231675) (xy 127.510287 -293.216217)
			(xy 127.559696 -293.208393) (xy 127.584708 -293.207948) (xy 127.604083 -293.208233) (xy 127.642546 -293.212941)
			(xy 127.661416 -293.217346) (xy 127.676489 -293.220556) (xy 127.70724 -293.218768) (xy 127.736062 -293.207898)
			(xy 127.760336 -293.188935) (xy 127.777857 -293.1636) (xy 127.787033 -293.134196) (xy 127.787654 -293.118794)
			(xy 127.787654 -292.910514) (xy 127.785876 -292.897052) (xy 127.780542 -292.878256) (xy 127.777494 -292.872668)
			(xy 127.764616 -292.84867) (xy 127.746369 -292.79736) (xy 127.737149 -292.743688) (xy 127.7366 -292.716458)
			(xy 127.7366 -292.71595) (xy 127.737163 -292.688724) (xy 127.746424 -292.635064) (xy 127.76465 -292.583753)
			(xy 127.777494 -292.55974) (xy 127.780542 -292.554152) (xy 127.785876 -292.535356) (xy 127.787654 -292.521894)
			(xy 127.787654 -291.948362) (xy 127.787776 -291.943408) (xy 127.7897 -291.933689) (xy 127.791464 -291.929058)
			(xy 127.798068 -291.913564) (xy 127.800049 -291.908784) (xy 127.802225 -291.89867) (xy 127.802386 -291.893498)
			(xy 127.802386 -291.313616) (xy 127.802337 -291.309746) (xy 127.801185 -291.302092) (xy 127.8001 -291.298376)
			(xy 127.79375 -291.278564) (xy 127.788416 -291.270182) (xy 127.788162 -291.269674) (xy 127.786638 -291.267388)
			(xy 127.774803 -291.248122) (xy 127.756102 -291.206956) (xy 127.743418 -291.163557) (xy 127.737004 -291.118799)
			(xy 127.7366 -291.096192) (xy 127.737172 -291.068376) (xy 127.746834 -291.013589) (xy 127.765863 -290.961312)
			(xy 127.779272 -290.936934) (xy 127.782574 -290.931346) (xy 127.78613 -290.918392) (xy 127.788816 -290.906643)
			(xy 127.784187 -290.883026) (xy 127.77724 -290.87318) (xy 127.774192 -290.86937) (xy 127.505714 -290.600892)
			(xy 127.501765 -290.597045) (xy 127.49254 -290.591012) (xy 127.487426 -290.588954) (xy 127.485648 -290.588446)
			(xy 127.484632 -290.588192) (xy 127.46134 -290.579983) (xy 127.417425 -290.557392) (xy 127.377528 -290.528287)
			(xy 127.342608 -290.493366) (xy 127.313504 -290.453469) (xy 127.290914 -290.409553) (xy 127.282702 -290.386262)
			(xy 127.282448 -290.385246) (xy 127.28194 -290.383468) (xy 127.279839 -290.378376) (xy 127.273808 -290.369163)
			(xy 127.270002 -290.36518) (xy 126.928118 -290.023296) (xy 126.9214 -290.01606) (xy 126.913798 -289.997855)
			(xy 126.913386 -289.98799) (xy 126.913386 -289.755072) (xy 126.913229 -289.749838) (xy 126.911051 -289.739598)
			(xy 126.909068 -289.734752) (xy 126.897892 -289.709098) (xy 126.891034 -289.70224) (xy 126.873506 -289.684194)
			(xy 126.843794 -289.643599) (xy 126.820839 -289.598836) (xy 126.805211 -289.551019) (xy 126.797299 -289.501339)
			(xy 126.797301 -289.451033) (xy 126.805217 -289.401354) (xy 126.82085 -289.353538) (xy 126.843809 -289.308777)
			(xy 126.873524 -289.268185) (xy 126.891034 -289.25012) (xy 126.897892 -289.243262) (xy 126.909068 -289.217608)
			(xy 126.911067 -289.212767) (xy 126.913237 -289.202524) (xy 126.913386 -289.197288) (xy 126.913386 -289.049206)
			(xy 126.91268 -289.036475) (xy 126.900546 -289.014087) (xy 126.890272 -289.006534) (xy 126.820676 -288.961322)
			(xy 126.813432 -288.956982) (xy 126.797058 -288.952887) (xy 126.780242 -288.954342) (xy 126.772416 -288.957512)
			(xy 126.772162 -288.957512) (xy 126.752016 -288.965938) (xy 126.709994 -288.97781) (xy 126.666741 -288.983817)
			(xy 126.644908 -288.984182) (xy 126.639828 -288.984182) (xy 126.615091 -288.983332) (xy 126.566318 -288.974916)
			(xy 126.519438 -288.959046) (xy 126.475582 -288.936104) (xy 126.43581 -288.906646) (xy 126.401082 -288.871381)
			(xy 126.372236 -288.831163) (xy 126.34997 -288.786961) (xy 126.33482 -288.739843) (xy 126.327152 -288.690946)
			(xy 126.327152 -288.641453) (xy 126.33482 -288.592557) (xy 126.34997 -288.545439) (xy 126.372237 -288.501237)
			(xy 126.401083 -288.461018) (xy 126.435811 -288.425754) (xy 126.475583 -288.396295) (xy 126.519439 -288.373354)
			(xy 126.566319 -288.357484) (xy 126.615092 -288.349068) (xy 126.639828 -288.348166) (xy 126.644908 -288.348166)
			(xy 126.66674 -288.348548) (xy 126.709989 -288.354559) (xy 126.75201 -288.366428) (xy 126.772162 -288.374836)
			(xy 126.772416 -288.374836) (xy 126.78431 -288.379343) (xy 126.809632 -288.377337) (xy 126.820676 -288.371026)
			(xy 126.890272 -288.325814) (xy 126.897209 -288.320954) (xy 126.907637 -288.30762) (xy 126.913127 -288.291607)
			(xy 126.913386 -288.283142) (xy 126.913386 -288.135314) (xy 126.913233 -288.130079) (xy 126.911063 -288.119836)
			(xy 126.909068 -288.114994) (xy 126.897892 -288.08934) (xy 126.891034 -288.082482) (xy 126.873502 -288.064436)
			(xy 126.843784 -288.02384) (xy 126.820822 -287.979075) (xy 126.805188 -287.931255) (xy 126.797271 -287.881571)
			(xy 126.797269 -287.83126) (xy 126.805181 -287.781575) (xy 126.82081 -287.733754) (xy 126.843768 -287.688986)
			(xy 126.873482 -287.648387) (xy 126.891034 -287.630362) (xy 126.897892 -287.623504) (xy 126.909068 -287.59785)
			(xy 126.911071 -287.59301) (xy 126.913249 -287.582766) (xy 126.913386 -287.57753) (xy 126.913386 -286.515302)
			(xy 126.913232 -286.510068) (xy 126.91106 -286.499825) (xy 126.909068 -286.494982) (xy 126.897892 -286.469328)
			(xy 126.891034 -286.46247) (xy 126.873503 -286.444424) (xy 126.843787 -286.403828) (xy 126.820827 -286.359064)
			(xy 126.805195 -286.311245) (xy 126.79728 -286.261562) (xy 126.797278 -286.211252) (xy 126.805192 -286.161569)
			(xy 126.820822 -286.113749) (xy 126.84378 -286.068984) (xy 126.873494 -286.028387) (xy 126.891034 -286.01035)
			(xy 126.897892 -286.003492) (xy 126.909068 -285.977838) (xy 126.91107 -285.972998) (xy 126.913246 -285.962754)
			(xy 126.913386 -285.957518) (xy 126.913386 -285.809436) (xy 126.912687 -285.796701) (xy 126.900559 -285.774302)
			(xy 126.890272 -285.766764) (xy 126.820676 -285.721552) (xy 126.813432 -285.71721) (xy 126.797058 -285.713113)
			(xy 126.780241 -285.714568) (xy 126.772416 -285.717742) (xy 126.772162 -285.717742) (xy 126.752016 -285.726167)
			(xy 126.709993 -285.738038) (xy 126.666741 -285.744045) (xy 126.644908 -285.744412) (xy 126.639828 -285.744412)
			(xy 126.615089 -285.743562) (xy 126.566311 -285.735145) (xy 126.519427 -285.719273) (xy 126.475567 -285.69633)
			(xy 126.435791 -285.666869) (xy 126.401059 -285.631601) (xy 126.372211 -285.591379) (xy 126.349942 -285.547172)
			(xy 126.33479 -285.50005) (xy 126.327122 -285.451149) (xy 126.327122 -285.401651) (xy 126.33479 -285.35275)
			(xy 126.349942 -285.305628) (xy 126.372211 -285.261422) (xy 126.401059 -285.221199) (xy 126.435791 -285.185931)
			(xy 126.475567 -285.15647) (xy 126.519427 -285.133527) (xy 126.566311 -285.117655) (xy 126.615089 -285.109238)
			(xy 126.639828 -285.108396) (xy 126.644908 -285.108396) (xy 126.66674 -285.108778) (xy 126.709989 -285.11479)
			(xy 126.75201 -285.126659) (xy 126.772162 -285.135066) (xy 126.772416 -285.135066) (xy 126.78431 -285.139571)
			(xy 126.809632 -285.137567) (xy 126.820676 -285.131256) (xy 126.890272 -285.086044) (xy 126.897201 -285.081181)
			(xy 126.907611 -285.067844) (xy 126.913079 -285.051833) (xy 126.913386 -285.043372) (xy 126.913386 -284.89529)
			(xy 126.91323 -284.890056) (xy 126.911056 -284.879814) (xy 126.909068 -284.87497) (xy 126.897892 -284.849316)
			(xy 126.891034 -284.842458) (xy 126.873504 -284.824412) (xy 126.84379 -284.783817) (xy 126.820832 -284.739053)
			(xy 126.805201 -284.691234) (xy 126.797287 -284.641553) (xy 126.797288 -284.591245) (xy 126.805202 -284.541563)
			(xy 126.820833 -284.493745) (xy 126.843791 -284.448981) (xy 126.873506 -284.408386) (xy 126.891034 -284.390338)
			(xy 126.897892 -284.38348) (xy 126.909068 -284.357826) (xy 126.911069 -284.352986) (xy 126.913242 -284.342742)
			(xy 126.913386 -284.337506) (xy 126.913386 -283.275278) (xy 126.913229 -283.270044) (xy 126.911053 -283.259803)
			(xy 126.909068 -283.254958) (xy 126.897892 -283.229304) (xy 126.891034 -283.222446) (xy 126.87397 -283.204924)
			(xy 126.844888 -283.165601) (xy 126.822169 -283.122289) (xy 126.806347 -283.076011) (xy 126.801626 -283.052012)
			(xy 126.800356 -283.044646) (xy 126.797054 -283.037788) (xy 126.795105 -283.03417) (xy 126.790261 -283.027532)
			(xy 126.787402 -283.02458) (xy 126.672594 -282.909772) (xy 126.668115 -282.905532) (xy 126.657585 -282.899116)
			(xy 126.651766 -282.897072) (xy 126.642935 -282.894739) (xy 126.62471 -282.895773) (xy 126.616206 -282.899104)
			(xy 126.531878 -282.935934) (xy 126.522762 -282.94041) (xy 126.508757 -282.955094) (xy 126.50149 -282.974041)
			(xy 126.501398 -282.984194) (xy 126.501398 -282.98775) (xy 126.501652 -282.996132) (xy 126.501652 -282.99664)
			(xy 126.50113 -283.022314) (xy 126.493063 -283.073025) (xy 126.477166 -283.121851) (xy 126.453828 -283.167591)
			(xy 126.423625 -283.209118) (xy 126.3873 -283.245411) (xy 126.345747 -283.275578) (xy 126.299987 -283.298875)
			(xy 126.251147 -283.31473) (xy 126.200429 -283.322753) (xy 126.174754 -283.323284) (xy 126.14907 -283.322777)
			(xy 126.098334 -283.314735) (xy 126.049482 -283.298855) (xy 126.003714 -283.27553) (xy 125.962158 -283.245332)
			(xy 125.925838 -283.209007) (xy 125.895646 -283.167447) (xy 125.872327 -283.121676) (xy 125.856455 -283.072821)
			(xy 125.84842 -283.022084) (xy 125.84842 -282.970716) (xy 125.856455 -282.919979) (xy 125.872327 -282.871124)
			(xy 125.895646 -282.825353) (xy 125.925838 -282.783793) (xy 125.962158 -282.747468) (xy 126.003714 -282.71727)
			(xy 126.049482 -282.693945) (xy 126.098334 -282.678065) (xy 126.14907 -282.670023) (xy 126.174754 -282.669488)
			(xy 126.201622 -282.670034) (xy 126.254634 -282.678817) (xy 126.305501 -282.696139) (xy 126.32944 -282.70835)
			(xy 126.334774 -282.711144) (xy 126.346712 -282.714446) (xy 126.358157 -282.716872) (xy 126.381065 -282.712255)
			(xy 126.390654 -282.705556) (xy 126.400306 -282.69819) (xy 126.410466 -282.677362) (xy 126.410466 -282.626562)
			(xy 126.405386 -282.621482) (xy 126.405386 -282.421076) (xy 126.405329 -282.416802) (xy 126.403928 -282.408372)
			(xy 126.402592 -282.404312) (xy 126.39548 -282.3845) (xy 126.390654 -282.37815) (xy 126.375541 -282.357305)
			(xy 126.351544 -282.311756) (xy 126.33519 -282.262939) (xy 126.326906 -282.212126) (xy 126.326908 -282.160642)
			(xy 126.335197 -282.10983) (xy 126.351556 -282.061014) (xy 126.375559 -282.015468) (xy 126.390654 -281.99461)
			(xy 126.39548 -281.98826) (xy 126.402592 -281.968448) (xy 126.403894 -281.964379) (xy 126.405304 -281.955955)
			(xy 126.405386 -281.951684) (xy 126.405386 -281.783028) (xy 126.404747 -281.771044) (xy 126.393884 -281.749684)
			(xy 126.384558 -281.742134) (xy 126.309882 -281.687778) (xy 126.28626 -281.683968) (xy 126.274576 -281.687778)
			(xy 126.250327 -281.695034) (xy 126.200315 -281.702811) (xy 126.175008 -281.703272) (xy 126.174754 -281.703272)
			(xy 126.149071 -281.702765) (xy 126.098337 -281.694723) (xy 126.049486 -281.678844) (xy 126.00372 -281.65552)
			(xy 125.962166 -281.625323) (xy 125.925847 -281.588999) (xy 125.895656 -281.547441) (xy 125.872338 -281.501671)
			(xy 125.856466 -281.452818) (xy 125.848432 -281.402083) (xy 125.848432 -281.350717) (xy 125.856466 -281.299982)
			(xy 125.872338 -281.251129) (xy 125.895656 -281.205359) (xy 125.925847 -281.163801) (xy 125.962166 -281.127477)
			(xy 126.00372 -281.09728) (xy 126.049486 -281.073956) (xy 126.098337 -281.058077) (xy 126.149071 -281.050035)
			(xy 126.174754 -281.049476) (xy 126.175008 -281.049476) (xy 126.200314 -281.049951) (xy 126.250324 -281.057729)
			(xy 126.274576 -281.06497) (xy 126.28626 -281.06878) (xy 126.309882 -281.06497) (xy 126.384558 -281.010614)
			(xy 126.393819 -281.003009) (xy 126.404681 -280.981683) (xy 126.405386 -280.96972) (xy 126.405386 -280.801064)
			(xy 126.405328 -280.796791) (xy 126.403925 -280.788361) (xy 126.402592 -280.7843) (xy 126.39548 -280.764488)
			(xy 126.390654 -280.758138) (xy 126.375542 -280.737293) (xy 126.351546 -280.691745) (xy 126.335194 -280.642928)
			(xy 126.326912 -280.592116) (xy 126.326916 -280.540633) (xy 126.335207 -280.489822) (xy 126.351566 -280.441008)
			(xy 126.37557 -280.395463) (xy 126.390654 -280.374598) (xy 126.39548 -280.368248) (xy 126.402592 -280.348436)
			(xy 126.403893 -280.344367) (xy 126.405301 -280.335943) (xy 126.405386 -280.331672) (xy 126.405386 -280.14168)
			(xy 126.39421 -280.119836) (xy 126.384304 -280.112724) (xy 126.322836 -280.068274) (xy 126.316207 -280.063864)
			(xy 126.301073 -280.058942) (xy 126.293118 -280.058622) (xy 126.275592 -280.058622) (xy 126.26848 -280.060908)
			(xy 126.245775 -280.067292) (xy 126.199099 -280.074047) (xy 126.175516 -280.07437) (xy 126.174754 -280.07437)
			(xy 126.14977 -280.073876) (xy 126.100419 -280.066053) (xy 126.052898 -280.050607) (xy 126.008379 -280.027917)
			(xy 125.967957 -279.998544) (xy 125.932627 -279.963208) (xy 125.903259 -279.922782) (xy 125.880576 -279.878259)
			(xy 125.865136 -279.830737) (xy 125.85732 -279.781384) (xy 125.85732 -279.731416) (xy 125.865136 -279.682063)
			(xy 125.880576 -279.634541) (xy 125.903259 -279.590018) (xy 125.932627 -279.549592) (xy 125.967957 -279.514256)
			(xy 126.008379 -279.484883) (xy 126.052898 -279.462193) (xy 126.100419 -279.446747) (xy 126.14977 -279.438924)
			(xy 126.174754 -279.438354) (xy 126.202566 -279.438905) (xy 126.257351 -279.448531) (xy 126.309629 -279.467534)
			(xy 126.357808 -279.495334) (xy 126.379478 -279.512776) (xy 126.386082 -279.518364) (xy 126.418594 -279.530556)
			(xy 126.44882 -279.530556) (xy 126.458663 -279.53003) (xy 126.476842 -279.522462) (xy 126.484126 -279.515824)
			(xy 126.898654 -279.101296) (xy 126.905364 -279.094056) (xy 126.912954 -279.075852) (xy 126.913386 -279.06599)
			(xy 126.913386 -278.415242) (xy 126.913226 -278.410009) (xy 126.911043 -278.399771) (xy 126.909068 -278.394922)
			(xy 126.897892 -278.369268) (xy 126.891034 -278.36241) (xy 126.8735 -278.344364) (xy 126.843777 -278.303768)
			(xy 126.820811 -278.259001) (xy 126.805173 -278.211179) (xy 126.797253 -278.161492) (xy 126.797247 -278.111178)
			(xy 126.805157 -278.06149) (xy 126.820784 -278.013664) (xy 126.84374 -277.968892) (xy 126.873454 -277.928289)
			(xy 126.891034 -277.91029) (xy 126.897892 -277.903432) (xy 126.909068 -277.877778) (xy 126.911074 -277.872939)
			(xy 126.913258 -277.862695) (xy 126.913386 -277.857458) (xy 126.913386 -277.709376) (xy 126.912696 -277.696636)
			(xy 126.900577 -277.674222) (xy 126.890272 -277.666704) (xy 126.820676 -277.621492) (xy 126.813433 -277.617147)
			(xy 126.797058 -277.613047) (xy 126.78024 -277.614504) (xy 126.772416 -277.617682) (xy 126.772162 -277.617682)
			(xy 126.752016 -277.626108) (xy 126.709994 -277.637982) (xy 126.666742 -277.64399) (xy 126.644908 -277.644352)
			(xy 126.639828 -277.644352) (xy 126.615086 -277.643502) (xy 126.566302 -277.635084) (xy 126.519411 -277.619211)
			(xy 126.475546 -277.596265) (xy 126.435765 -277.5668) (xy 126.401029 -277.531528) (xy 126.372177 -277.4913)
			(xy 126.349905 -277.447088) (xy 126.334751 -277.39996) (xy 126.327082 -277.351053) (xy 126.327082 -277.301548)
			(xy 126.334751 -277.252641) (xy 126.349904 -277.205513) (xy 126.372176 -277.161301) (xy 126.401028 -277.121073)
			(xy 126.435764 -277.085801) (xy 126.475545 -277.056336) (xy 126.51941 -277.03339) (xy 126.566301 -277.017516)
			(xy 126.615084 -277.009098) (xy 126.639828 -277.008336) (xy 126.644908 -277.008336) (xy 126.66674 -277.008717)
			(xy 126.709989 -277.014729) (xy 126.752011 -277.026596) (xy 126.772162 -277.035006) (xy 126.772416 -277.035006)
			(xy 126.78431 -277.039514) (xy 126.809632 -277.037508) (xy 126.820676 -277.031196) (xy 126.890272 -276.985984)
			(xy 126.897206 -276.981123) (xy 126.907626 -276.967787) (xy 126.913106 -276.951775) (xy 126.913386 -276.943312)
			(xy 126.913386 -276.79523) (xy 126.913224 -276.789997) (xy 126.91104 -276.77976) (xy 126.909068 -276.77491)
			(xy 126.897892 -276.749256) (xy 126.891034 -276.742398) (xy 126.873501 -276.724352) (xy 126.84378 -276.683756)
			(xy 126.820816 -276.63899) (xy 126.80518 -276.591169) (xy 126.797261 -276.541483) (xy 126.797257 -276.49117)
			(xy 126.805167 -276.441483) (xy 126.820795 -276.39366) (xy 126.843752 -276.34889) (xy 126.873466 -276.308288)
			(xy 126.891034 -276.290278) (xy 126.897892 -276.28342) (xy 126.909068 -276.257766) (xy 126.911073 -276.252926)
			(xy 126.913254 -276.242683) (xy 126.913386 -276.237446) (xy 126.913386 -275.175218) (xy 126.913233 -275.169983)
			(xy 126.911064 -275.159739) (xy 126.909068 -275.154898) (xy 126.897892 -275.129244) (xy 126.891034 -275.122386)
			(xy 126.873502 -275.10434) (xy 126.843783 -275.063744) (xy 126.820821 -275.018979) (xy 126.805186 -274.971158)
			(xy 126.797269 -274.921474) (xy 126.797266 -274.871163) (xy 126.805177 -274.821477) (xy 126.820806 -274.773655)
			(xy 126.843764 -274.728887) (xy 126.873478 -274.688288) (xy 126.891034 -274.670266) (xy 126.897892 -274.663408)
			(xy 126.909068 -274.637754) (xy 126.911072 -274.632914) (xy 126.913251 -274.62267) (xy 126.913386 -274.617434)
			(xy 126.913386 -274.469352) (xy 126.91269 -274.456615) (xy 126.900567 -274.43421) (xy 126.890272 -274.42668)
			(xy 126.820676 -274.381468) (xy 126.813433 -274.377124) (xy 126.797058 -274.373026) (xy 126.780241 -274.374482)
			(xy 126.772416 -274.377658) (xy 126.772162 -274.377658) (xy 126.752017 -274.386085) (xy 126.709994 -274.397959)
			(xy 126.666742 -274.403968) (xy 126.644908 -274.404328) (xy 126.639828 -274.404328) (xy 126.615088 -274.403478)
			(xy 126.566308 -274.395061) (xy 126.51942 -274.379189) (xy 126.475558 -274.356244) (xy 126.43578 -274.326781)
			(xy 126.401047 -274.291512) (xy 126.372197 -274.251287) (xy 126.349927 -274.207079) (xy 126.334774 -274.159954)
			(xy 126.327106 -274.111051) (xy 126.327106 -274.06155) (xy 126.334774 -274.012647) (xy 126.349927 -273.965522)
			(xy 126.372197 -273.921313) (xy 126.401046 -273.881089) (xy 126.43578 -273.845819) (xy 126.475558 -273.816356)
			(xy 126.51942 -273.793412) (xy 126.566307 -273.777539) (xy 126.615087 -273.769122) (xy 126.639828 -273.768312)
			(xy 126.644908 -273.768312) (xy 126.66674 -273.768693) (xy 126.70999 -273.774704) (xy 126.752011 -273.786571)
			(xy 126.772162 -273.794982) (xy 126.772416 -273.794982) (xy 126.784309 -273.799492) (xy 126.809632 -273.797484)
			(xy 126.820676 -273.791172) (xy 126.890272 -273.74596) (xy 126.897203 -273.741098) (xy 126.907617 -273.727761)
			(xy 126.91309 -273.71175) (xy 126.913386 -273.703288) (xy 126.913386 -273.555206) (xy 126.913232 -273.549971)
			(xy 126.911061 -273.539728) (xy 126.909068 -273.534886) (xy 126.897892 -273.509232) (xy 126.891034 -273.502374)
			(xy 126.873503 -273.484328) (xy 126.843786 -273.443733) (xy 126.820825 -273.398968) (xy 126.805192 -273.351148)
			(xy 126.797276 -273.301465) (xy 126.797275 -273.251155) (xy 126.805188 -273.201471) (xy 126.820818 -273.153651)
			(xy 126.843775 -273.108884) (xy 126.87349 -273.068287) (xy 126.891034 -273.050254) (xy 126.897892 -273.043396)
			(xy 126.909068 -273.017742) (xy 126.911071 -273.012902) (xy 126.913247 -273.002658) (xy 126.913386 -272.997422)
			(xy 126.913386 -271.935194) (xy 126.913231 -271.92996) (xy 126.911058 -271.919718) (xy 126.909068 -271.914874)
			(xy 126.897892 -271.88922) (xy 126.891034 -271.882362) (xy 126.873504 -271.864316) (xy 126.843789 -271.823721)
			(xy 126.82083 -271.778956) (xy 126.805199 -271.731138) (xy 126.797285 -271.681456) (xy 126.797285 -271.631147)
			(xy 126.805198 -271.581465) (xy 126.820829 -271.533646) (xy 126.843788 -271.488882) (xy 126.873502 -271.448286)
			(xy 126.891034 -271.430242) (xy 126.897892 -271.423384) (xy 126.909068 -271.39773) (xy 126.91107 -271.39289)
			(xy 126.913243 -271.382646) (xy 126.913386 -271.37741) (xy 126.913386 -271.229328) (xy 126.912685 -271.216594)
			(xy 126.900556 -271.194198) (xy 126.890272 -271.186656) (xy 126.820676 -271.141444) (xy 126.813432 -271.137102)
			(xy 126.797058 -271.133006) (xy 126.780241 -271.134461) (xy 126.772416 -271.137634) (xy 126.772162 -271.137634)
			(xy 126.752016 -271.146059) (xy 126.709994 -271.157931) (xy 126.666741 -271.163937) (xy 126.644908 -271.164304)
			(xy 126.639828 -271.164304) (xy 126.61509 -271.163454) (xy 126.566313 -271.155037) (xy 126.51943 -271.139166)
			(xy 126.475571 -271.116223) (xy 126.435796 -271.086763) (xy 126.401065 -271.051496) (xy 126.372218 -271.011274)
			(xy 126.349949 -270.967069) (xy 126.334798 -270.919948) (xy 126.32713 -270.871048) (xy 126.32713 -270.821551)
			(xy 126.334798 -270.772652) (xy 126.349949 -270.725531) (xy 126.372218 -270.681326) (xy 126.401065 -270.641104)
			(xy 126.435796 -270.605837) (xy 126.475571 -270.576377) (xy 126.51943 -270.553434) (xy 126.566313 -270.537563)
			(xy 126.61509 -270.529146) (xy 126.639828 -270.528288) (xy 126.644908 -270.528288) (xy 126.66674 -270.52867)
			(xy 126.709989 -270.534682) (xy 126.75201 -270.546551) (xy 126.772162 -270.554958) (xy 126.772416 -270.554958)
			(xy 126.78431 -270.559464) (xy 126.809632 -270.557459) (xy 126.820676 -270.551148) (xy 126.890272 -270.505936)
			(xy 126.8972 -270.501073) (xy 126.907608 -270.487735) (xy 126.913074 -270.471724) (xy 126.913386 -270.463264)
			(xy 126.913386 -270.315182) (xy 126.91323 -270.309948) (xy 126.911054 -270.299707) (xy 126.909068 -270.294862)
			(xy 126.897892 -270.269208) (xy 126.891034 -270.26235) (xy 126.873505 -270.244304) (xy 126.843792 -270.203709)
			(xy 126.820835 -270.158945) (xy 126.805205 -270.111128) (xy 126.797293 -270.061447) (xy 126.797294 -270.011139)
			(xy 126.805209 -269.961459) (xy 126.82084 -269.913642) (xy 126.843799 -269.868879) (xy 126.873514 -269.828285)
			(xy 126.891034 -269.81023) (xy 126.897892 -269.803372) (xy 126.909068 -269.777718) (xy 126.911068 -269.772878)
			(xy 126.91324 -269.762634) (xy 126.913386 -269.757398) (xy 126.913386 -268.69517) (xy 126.913228 -268.689936)
			(xy 126.911051 -268.679696) (xy 126.909068 -268.67485) (xy 126.897892 -268.649196) (xy 126.891034 -268.642338)
			(xy 126.873506 -268.624292) (xy 126.843795 -268.583697) (xy 126.820839 -268.538934) (xy 126.805212 -268.491117)
			(xy 126.7973 -268.441437) (xy 126.797303 -268.391132) (xy 126.805219 -268.341452) (xy 126.820851 -268.293637)
			(xy 126.843811 -268.248876) (xy 126.873526 -268.208284) (xy 126.891034 -268.190218) (xy 126.897892 -268.18336)
			(xy 126.909068 -268.157706) (xy 126.911067 -268.152865) (xy 126.913236 -268.142622) (xy 126.913386 -268.137386)
			(xy 126.913386 -267.989304) (xy 126.91268 -267.976573) (xy 126.900545 -267.954186) (xy 126.890272 -267.946632)
			(xy 126.820676 -267.90142) (xy 126.813432 -267.89708) (xy 126.797058 -267.892986) (xy 126.780242 -267.89444)
			(xy 126.772416 -267.89761) (xy 126.772162 -267.89761) (xy 126.752016 -267.906036) (xy 126.709994 -267.917908)
			(xy 126.666741 -267.923915) (xy 126.644908 -267.92428) (xy 126.639828 -267.92428) (xy 126.614926 -267.923422)
			(xy 126.565833 -267.914914) (xy 126.518668 -267.898854) (xy 126.474584 -267.875635) (xy 126.434661 -267.845826)
			(xy 126.399875 -267.810155) (xy 126.371078 -267.769495) (xy 126.348974 -267.724842) (xy 126.334104 -267.677288)
			(xy 126.326833 -267.627997) (xy 126.327337 -267.578176) (xy 126.335605 -267.529042) (xy 126.351434 -267.481799)
			(xy 126.374437 -267.437602) (xy 126.388876 -267.417296) (xy 126.403262 -267.398558) (xy 126.436651 -267.36514)
			(xy 126.474616 -267.337029) (xy 126.516323 -267.314845) (xy 126.560852 -267.299075) (xy 126.583948 -267.294106)
			(xy 126.590545 -267.292582) (xy 126.602653 -267.286537) (xy 126.607824 -267.282168) (xy 126.608078 -267.282168)
			(xy 126.613105 -267.277438) (xy 126.620574 -267.265838) (xy 126.62281 -267.259308) (xy 126.630684 -267.233654)
			(xy 126.630684 -267.233146) (xy 126.64821 -267.175488) (xy 126.648464 -267.17498) (xy 126.652274 -267.161264)
			(xy 126.64567 -267.134594) (xy 126.63551 -267.124688) (xy 126.536958 -267.026136) (xy 126.529626 -267.019422)
			(xy 126.511324 -267.011712) (xy 126.501398 -267.01115) (xy 126.421896 -267.010388) (xy 126.403608 -267.0175)
			(xy 126.396242 -267.024612) (xy 126.378339 -267.041374) (xy 126.338338 -267.069746) (xy 126.294455 -267.091641)
			(xy 126.247731 -267.10654) (xy 126.199275 -267.114091) (xy 126.174754 -267.114528) (xy 126.149748 -267.114034)
			(xy 126.100353 -267.106203) (xy 126.052791 -267.090742) (xy 126.008234 -267.068032) (xy 125.967777 -267.03863)
			(xy 125.932418 -267.003262) (xy 125.903027 -266.962798) (xy 125.880327 -266.918235) (xy 125.864878 -266.870669)
			(xy 125.85706 -266.821272) (xy 125.856492 -266.796266) (xy 125.856492 -266.795504) (xy 125.856595 -266.785058)
			(xy 125.857993 -266.764214) (xy 125.859286 -266.753848) (xy 125.86081 -266.742672) (xy 125.85446 -266.721844)
			(xy 125.830838 -266.69492) (xy 125.798072 -266.657836) (xy 125.790706 -266.649454) (xy 125.770894 -266.640564)
			(xy 125.63856 -266.640564) (xy 125.618748 -266.649454) (xy 125.611382 -266.657836) (xy 125.578616 -266.69492)
			(xy 125.554994 -266.721844) (xy 125.548644 -266.742672) (xy 125.550168 -266.753848) (xy 125.551494 -266.764402)
			(xy 125.552895 -266.785629) (xy 125.552962 -266.796266) (xy 125.552515 -266.820745) (xy 125.54502 -266.869126)
			(xy 125.530203 -266.915788) (xy 125.508412 -266.95963) (xy 125.480163 -266.999616) (xy 125.446122 -267.034802)
			(xy 125.407092 -267.064359) (xy 125.363996 -267.087588) (xy 125.31785 -267.103941) (xy 125.293882 -267.10894)
			(xy 125.293374 -267.10894) (xy 125.281928 -267.111779) (xy 125.263208 -267.126077) (xy 125.252783 -267.147199)
			(xy 125.252226 -267.158978) (xy 125.252226 -267.756386) (xy 125.251972 -267.757656) (xy 125.251972 -267.773912)
			(xy 125.222508 -267.803376) (xy 125.07595 -267.803376) (xy 125.070292 -267.803562) (xy 125.059269 -267.806133)
			(xy 125.054106 -267.808456) (xy 125.026166 -267.821664) (xy 125.019054 -267.829792) (xy 125.002544 -267.847572)
			(xy 124.98832 -267.861288) (xy 124.988066 -267.861542) (xy 124.984002 -267.865098) (xy 124.972572 -267.873988)
			(xy 124.950143 -267.890644) (xy 124.900964 -267.917138) (xy 124.848099 -267.935187) (xy 124.792986 -267.944298)
			(xy 124.765054 -267.944854) (xy 124.7648 -267.944854) (xy 124.738193 -267.944359) (xy 124.685634 -267.936034)
			(xy 124.635024 -267.919589) (xy 124.58761 -267.895429) (xy 124.54456 -267.864149) (xy 124.506933 -267.826519)
			(xy 124.475656 -267.783466) (xy 124.4515 -267.73605) (xy 124.435059 -267.685439) (xy 124.426739 -267.632879)
			(xy 124.426218 -267.606272) (xy 124.426793 -267.57744) (xy 124.436547 -267.520607) (xy 124.455787 -267.466247)
			(xy 124.483955 -267.415932) (xy 124.501656 -267.393166) (xy 124.506736 -267.386816) (xy 124.514102 -267.367766)
			(xy 124.516388 -267.35913) (xy 124.518928 -267.345414) (xy 124.519182 -267.34135) (xy 124.520243 -267.320782)
			(xy 124.52928 -267.280607) (xy 124.545851 -267.242909) (xy 124.569341 -267.209087) (xy 124.598878 -267.180394)
			(xy 124.633368 -267.157896) (xy 124.671531 -267.142427) (xy 124.711952 -267.13456) (xy 124.732542 -267.134086)
			(xy 124.733304 -267.13434) (xy 124.89053 -267.13434) (xy 124.901662 -267.133714) (xy 124.921815 -267.124232)
			(xy 124.929392 -267.116052) (xy 124.933202 -267.11148) (xy 124.962158 -267.056108) (xy 124.976128 -267.029692)
			(xy 124.979896 -267.02173) (xy 124.982316 -267.004296) (xy 124.97867 -266.987076) (xy 124.97435 -266.9794)
			(xy 124.97308 -266.977368) (xy 124.972064 -266.976098) (xy 124.965206 -266.965684) (xy 124.964698 -266.964668)
			(xy 124.963682 -266.96289) (xy 124.948912 -266.937675) (xy 124.927856 -266.883171) (xy 124.917127 -266.825734)
			(xy 124.916438 -266.79652) (xy 124.916438 -266.796012) (xy 124.916438 -266.791948) (xy 124.916438 -266.788392)
			(xy 124.918978 -266.754864) (xy 124.919232 -266.75334) (xy 124.919486 -266.750546) (xy 124.919813 -266.740391)
			(xy 124.913403 -266.721128) (xy 124.90704 -266.713208) (xy 124.890784 -266.69492) (xy 124.858018 -266.657836)
			(xy 124.850652 -266.649454) (xy 124.83084 -266.640564) (xy 124.698506 -266.640564) (xy 124.678694 -266.649454)
			(xy 124.671328 -266.657836) (xy 124.638562 -266.69492) (xy 124.61494 -266.721844) (xy 124.60859 -266.742672)
			(xy 124.610114 -266.753848) (xy 124.611439 -266.764402) (xy 124.612841 -266.785629) (xy 124.612908 -266.796266)
			(xy 124.612417 -266.821275) (xy 124.604593 -266.870678) (xy 124.589136 -266.918248) (xy 124.566428 -266.962815)
			(xy 124.537028 -267.00328) (xy 124.50166 -267.038648) (xy 124.461195 -267.068048) (xy 124.416628 -267.090756)
			(xy 124.369058 -267.106213) (xy 124.319655 -267.114037) (xy 124.269637 -267.114037) (xy 124.220234 -267.106213)
			(xy 124.172664 -267.090756) (xy 124.128097 -267.068048) (xy 124.087632 -267.038648) (xy 124.052264 -267.00328)
			(xy 124.022864 -266.962815) (xy 124.000156 -266.918248) (xy 123.984699 -266.870678) (xy 123.976875 -266.821275)
			(xy 123.976384 -266.796266) (xy 123.976417 -266.785824) (xy 123.977686 -266.764979) (xy 123.978924 -266.75461)
			(xy 123.979178 -266.75334) (xy 123.979432 -266.750546) (xy 123.979759 -266.74039) (xy 123.973354 -266.721124)
			(xy 123.966986 -266.713208) (xy 123.95073 -266.69492) (xy 123.917964 -266.657836) (xy 123.910598 -266.649454)
			(xy 123.890786 -266.640564) (xy 123.758706 -266.640564) (xy 123.738894 -266.649454) (xy 123.731528 -266.657836)
			(xy 123.698762 -266.69492) (xy 123.67514 -266.721844) (xy 123.66879 -266.742672) (xy 123.670314 -266.753848)
			(xy 123.671639 -266.764402) (xy 123.673041 -266.785629) (xy 123.673108 -266.796266) (xy 123.672617 -266.821974)
			(xy 123.664354 -266.872721) (xy 123.648036 -266.921478) (xy 123.62409 -266.966976) (xy 123.593138 -267.008031)
			(xy 123.555986 -267.043574) (xy 123.513601 -267.072679) (xy 123.467088 -267.094589) (xy 123.417656 -267.108732)
			(xy 123.392184 -267.112242) (xy 123.383003 -267.113698) (xy 123.366514 -267.122249) (xy 123.354168 -267.136127)
			(xy 123.347596 -267.153499) (xy 123.347226 -267.162788) (xy 123.347226 -267.756386) (xy 123.346972 -267.757656)
			(xy 123.346972 -267.773912) (xy 123.317508 -267.803376) (xy 123.167648 -267.803376) (xy 123.162272 -267.803535)
			(xy 123.151766 -267.805835) (xy 123.14682 -267.807948) (xy 123.12015 -267.819886) (xy 123.113038 -267.82776)
			(xy 123.107196 -267.83411) (xy 123.082304 -267.856462) (xy 123.082304 -267.86332) (xy 123.072398 -267.86332)
			(xy 123.059698 -267.871702) (xy 123.040126 -267.884128) (xy 122.99814 -267.903783) (xy 122.95374 -267.917118)
			(xy 122.907872 -267.92385) (xy 122.884692 -267.92428) (xy 122.859702 -267.923814) (xy 122.810338 -267.915994)
			(xy 122.762804 -267.900548) (xy 122.718273 -267.877855) (xy 122.67784 -267.848476) (xy 122.642501 -267.813133)
			(xy 122.613126 -267.772696) (xy 122.590438 -267.728162) (xy 122.574997 -267.680627) (xy 122.567183 -267.631262)
			(xy 122.566684 -267.606272) (xy 122.567224 -267.579618) (xy 122.576123 -267.527058) (xy 122.593682 -267.476725)
			(xy 122.606054 -267.45311) (xy 122.607578 -267.450062) (xy 122.610626 -267.442696) (xy 122.612188 -267.438287)
			(xy 122.613851 -267.429084) (xy 122.613928 -267.424408) (xy 122.613928 -267.348716) (xy 122.614314 -267.327683)
			(xy 122.622348 -267.286396) (xy 122.638305 -267.247478) (xy 122.661568 -267.212435) (xy 122.691238 -267.182622)
			(xy 122.726169 -267.15919) (xy 122.765009 -267.143045) (xy 122.806257 -267.134813) (xy 122.827288 -267.13434)
			(xy 123.010422 -267.13434) (xy 123.018909 -267.134031) (xy 123.034949 -267.128478) (xy 123.048273 -267.117963)
			(xy 123.053094 -267.110972) (xy 123.054872 -267.108178) (xy 123.102878 -267.017246) (xy 123.1011 -266.989052)
			(xy 123.092972 -266.977368) (xy 123.079669 -266.957321) (xy 123.058608 -266.914067) (xy 123.044293 -266.868136)
			(xy 123.037052 -266.820575) (xy 123.036584 -266.79652) (xy 123.036584 -266.796266) (xy 123.036657 -266.785566)
			(xy 123.038053 -266.764212) (xy 123.039378 -266.753594) (xy 123.040902 -266.742418) (xy 123.034552 -266.721336)
			(xy 123.01093 -266.69492) (xy 122.978164 -266.657836) (xy 122.970798 -266.649454) (xy 122.950986 -266.640564)
			(xy 121.878598 -266.640564) (xy 121.858786 -266.649454) (xy 121.85142 -266.657836) (xy 121.818654 -266.69492)
			(xy 121.795032 -266.721844) (xy 121.788682 -266.742672) (xy 121.790206 -266.753848) (xy 121.791531 -266.764402)
			(xy 121.792933 -266.785629) (xy 121.793 -266.796266) (xy 121.792493 -266.821832) (xy 121.784322 -266.872308)
			(xy 121.768184 -266.920827) (xy 121.744494 -266.966141) (xy 121.713864 -267.007083) (xy 121.67708 -267.0426)
			(xy 121.635089 -267.071778) (xy 121.588973 -267.093866) (xy 121.539919 -267.108294) (xy 121.514616 -267.111988)
			(xy 121.506234 -267.113004) (xy 121.476516 -267.127482) (xy 121.470166 -267.13434) (xy 121.45645 -267.148564)
			(xy 121.449972 -267.155917) (xy 121.442664 -267.17408) (xy 121.442226 -267.18387) (xy 121.442226 -267.756386)
			(xy 121.441972 -267.757656) (xy 121.441972 -267.773912) (xy 121.412508 -267.803376) (xy 121.28754 -267.803376)
			(xy 121.282164 -267.803536) (xy 121.271659 -267.805837) (xy 121.266712 -267.807948) (xy 121.240804 -267.819632)
			(xy 121.2342 -267.826744) (xy 121.216053 -267.844838) (xy 121.175049 -267.875571) (xy 121.129655 -267.899343)
			(xy 121.08104 -267.915543) (xy 121.030459 -267.923751) (xy 121.004838 -267.92428) (xy 120.980116 -267.923806)
			(xy 120.931269 -267.916146) (xy 120.884196 -267.90102) (xy 120.840031 -267.878792) (xy 120.799837 -267.849997)
			(xy 120.764582 -267.81533) (xy 120.735116 -267.775625) (xy 120.712149 -267.731839) (xy 120.696234 -267.685027)
			(xy 120.687755 -267.636316) (xy 120.68683 -267.611606) (xy 120.68683 -267.606018) (xy 120.687464 -267.57846)
			(xy 120.697049 -267.524181) (xy 120.70588 -267.498068) (xy 120.70588 -267.497814) (xy 120.708928 -267.489178)
			(xy 120.708928 -267.348716) (xy 120.709314 -267.327683) (xy 120.717348 -267.286396) (xy 120.733305 -267.247478)
			(xy 120.756568 -267.212435) (xy 120.786238 -267.182622) (xy 120.821169 -267.15919) (xy 120.860009 -267.143045)
			(xy 120.901257 -267.134813) (xy 120.922288 -267.13434) (xy 121.126504 -267.13434) (xy 121.136522 -267.134761)
			(xy 121.15503 -267.142433) (xy 121.169192 -267.156607) (xy 121.176848 -267.175122) (xy 121.177304 -267.18514)
			(xy 121.177304 -267.194284) (xy 121.349008 -267.194284) (xy 121.359027 -267.193863) (xy 121.377539 -267.186191)
			(xy 121.391705 -267.172018) (xy 121.399368 -267.153503) (xy 121.399808 -267.143484) (xy 121.399808 -267.127228)
			(xy 121.38152 -267.101066) (xy 121.366534 -267.095478) (xy 121.343779 -267.086781) (xy 121.301011 -267.063464)
			(xy 121.262302 -267.033894) (xy 121.228559 -266.998763) (xy 121.200572 -266.958894) (xy 121.178997 -266.915222)
			(xy 121.164339 -266.868768) (xy 121.156941 -266.820622) (xy 121.156476 -266.796266) (xy 121.156476 -266.795504)
			(xy 121.156579 -266.785058) (xy 121.157977 -266.764214) (xy 121.15927 -266.753848) (xy 121.160794 -266.742672)
			(xy 121.154444 -266.721844) (xy 121.130822 -266.69492) (xy 121.098056 -266.657836) (xy 121.09069 -266.649454)
			(xy 121.070878 -266.640564) (xy 120.938544 -266.640564) (xy 120.918732 -266.649454) (xy 120.911366 -266.657836)
			(xy 120.8786 -266.69492) (xy 120.854978 -266.721844) (xy 120.848628 -266.742672) (xy 120.850152 -266.753848)
			(xy 120.851477 -266.764402) (xy 120.852878 -266.785629) (xy 120.852946 -266.796266) (xy 120.852455 -266.821275)
			(xy 120.844631 -266.870678) (xy 120.829174 -266.918248) (xy 120.806466 -266.962815) (xy 120.777066 -267.00328)
			(xy 120.741698 -267.038648) (xy 120.701233 -267.068048) (xy 120.656666 -267.090756) (xy 120.609096 -267.106213)
			(xy 120.559693 -267.114037) (xy 120.509675 -267.114037) (xy 120.460272 -267.106213) (xy 120.412702 -267.090756)
			(xy 120.368135 -267.068048) (xy 120.32767 -267.038648) (xy 120.292302 -267.00328) (xy 120.262902 -266.962815)
			(xy 120.240194 -266.918248) (xy 120.224737 -266.870678) (xy 120.216913 -266.821275) (xy 120.216422 -266.796266)
			(xy 120.216455 -266.785824) (xy 120.217725 -266.764979) (xy 120.218962 -266.75461) (xy 120.219216 -266.75334)
			(xy 120.21947 -266.750546) (xy 120.219796 -266.740391) (xy 120.213385 -266.721129) (xy 120.207024 -266.713208)
			(xy 120.190768 -266.69492) (xy 120.158002 -266.657836) (xy 120.150636 -266.649454) (xy 120.130824 -266.640564)
			(xy 119.99849 -266.640564) (xy 119.978678 -266.649454) (xy 119.971312 -266.657836) (xy 119.938546 -266.69492)
			(xy 119.914924 -266.721844) (xy 119.908574 -266.742672) (xy 119.910098 -266.753848) (xy 119.911423 -266.764402)
			(xy 119.912825 -266.785629) (xy 119.912892 -266.796266) (xy 119.912434 -266.820896) (xy 119.90485 -266.869568)
			(xy 119.889858 -266.916491) (xy 119.867816 -266.960544) (xy 119.839251 -267.000675) (xy 119.804844 -267.035926)
			(xy 119.765417 -267.065456) (xy 119.721911 -267.088559) (xy 119.69877 -267.097002) (xy 119.698516 -267.097002)
			(xy 119.697754 -267.097256) (xy 119.69068 -267.100082) (xy 119.678527 -267.109256) (xy 119.673878 -267.11529)
			(xy 119.673878 -267.115544) (xy 119.669494 -267.122116) (xy 119.664568 -267.137116) (xy 119.664226 -267.145008)
			(xy 119.664226 -267.756386) (xy 119.663972 -267.757656) (xy 119.663972 -267.773912) (xy 119.634508 -267.803376)
			(xy 119.446548 -267.803376) (xy 119.437043 -267.804505) (xy 119.419816 -267.812817) (xy 119.406792 -267.826827)
			(xy 119.399757 -267.844614) (xy 119.399304 -267.854176) (xy 119.399304 -267.86332) (xy 119.33428 -267.86332)
			(xy 119.330473 -267.863386) (xy 119.322947 -267.864534) (xy 119.319294 -267.865606) (xy 119.300244 -267.871448)
			(xy 119.294656 -267.875258) (xy 119.275495 -267.886892) (xy 119.2346 -267.905244) (xy 119.191531 -267.917668)
			(xy 119.147143 -267.923915) (xy 119.12473 -267.92428) (xy 119.100314 -267.923836) (xy 119.052055 -267.916373)
			(xy 119.005505 -267.901617) (xy 118.961759 -267.879915) (xy 118.921847 -267.851779) (xy 118.886707 -267.81787)
			(xy 118.857166 -267.778986) (xy 118.833919 -267.736042) (xy 118.817514 -267.690048) (xy 118.808335 -267.642085)
			(xy 118.806976 -267.617702) (xy 118.806722 -267.611098) (xy 118.806722 -267.606272) (xy 118.807255 -267.580092)
			(xy 118.815824 -267.528437) (xy 118.832727 -267.47888) (xy 118.857509 -267.432756) (xy 118.889502 -267.391306)
			(xy 118.908322 -267.3731) (xy 118.91518 -267.36675) (xy 118.931436 -267.33373) (xy 118.932198 -267.32484)
			(xy 118.934724 -267.30547) (xy 118.9459 -267.268044) (xy 118.963695 -267.233274) (xy 118.987517 -267.202321)
			(xy 119.01657 -267.176215) (xy 119.049887 -267.155828) (xy 119.086355 -267.14184) (xy 119.124759 -267.134717)
			(xy 119.144288 -267.13434) (xy 119.250206 -267.13434) (xy 119.258695 -267.134034) (xy 119.274738 -267.128484)
			(xy 119.288066 -267.11797) (xy 119.292878 -267.110972) (xy 119.294656 -267.108178) (xy 119.342662 -267.017246)
			(xy 119.340884 -266.989052) (xy 119.332756 -266.977368) (xy 119.31945 -266.957323) (xy 119.298383 -266.914069)
			(xy 119.284065 -266.868138) (xy 119.276821 -266.820576) (xy 119.276368 -266.79652) (xy 119.276368 -266.796266)
			(xy 119.276441 -266.785566) (xy 119.277837 -266.764212) (xy 119.279162 -266.753594) (xy 119.280686 -266.742418)
			(xy 119.274336 -266.721336) (xy 119.250714 -266.69492) (xy 119.217948 -266.657836) (xy 119.210582 -266.649454)
			(xy 119.19077 -266.640564) (xy 118.118636 -266.640564) (xy 118.098824 -266.649454) (xy 118.091458 -266.657836)
			(xy 118.058692 -266.69492) (xy 118.03507 -266.721844) (xy 118.02872 -266.742672) (xy 118.030244 -266.753848)
			(xy 118.031569 -266.764402) (xy 118.03297 -266.785629) (xy 118.033038 -266.796266) (xy 118.032575 -266.821278)
			(xy 118.024754 -266.870687) (xy 118.009299 -266.918264) (xy 117.986591 -266.962838) (xy 117.957189 -267.003309)
			(xy 117.921817 -267.038682) (xy 117.881346 -267.068086) (xy 117.836774 -267.090795) (xy 117.789197 -267.106252)
			(xy 117.739788 -267.114075) (xy 117.714776 -267.114528) (xy 117.691642 -267.114073) (xy 117.645869 -267.107315)
			(xy 117.62359 -267.101066) (xy 117.616478 -267.099034) (xy 117.608858 -267.099034) (xy 117.598858 -267.09953)
			(xy 117.580387 -267.107198) (xy 117.566255 -267.121351) (xy 117.558615 -267.139834) (xy 117.558058 -267.149834)
			(xy 117.558058 -267.17498) (xy 117.558433 -267.18482) (xy 117.565916 -267.203017) (xy 117.579817 -267.216941)
			(xy 117.598003 -267.224451) (xy 117.607842 -267.224764) (xy 117.77218 -267.224764) (xy 117.793008 -267.224764)
			(xy 117.82298 -267.254736) (xy 117.82298 -267.273024) (xy 117.82298 -267.783564) (xy 117.82298 -267.804392)
			(xy 117.793008 -267.834364) (xy 117.77472 -267.834364) (xy 117.607842 -267.834364) (xy 117.59805 -267.834883)
			(xy 117.579973 -267.842426) (xy 117.566123 -267.856278) (xy 117.558582 -267.874356) (xy 117.558058 -267.884148)
			(xy 117.558058 -267.894308) (xy 117.395498 -267.894308) (xy 117.385084 -267.895324) (xy 117.370352 -267.898372)
			(xy 117.36578 -267.90015) (xy 117.364002 -267.900912) (xy 117.335835 -267.911592) (xy 117.276764 -267.923361)
			(xy 117.246654 -267.92428) (xy 117.24005 -267.92428) (xy 117.215296 -267.923453) (xy 117.166482 -267.915076)
			(xy 117.119557 -267.899232) (xy 117.075655 -267.876305) (xy 117.035839 -267.846849) (xy 117.001071 -267.811576)
			(xy 116.972191 -267.77134) (xy 116.949899 -267.727113) (xy 116.934732 -267.679965) (xy 116.927058 -267.631036)
			(xy 116.926614 -267.606272) (xy 116.927158 -267.579619) (xy 116.936052 -267.527059) (xy 116.953585 -267.476719)
			(xy 116.979267 -267.430007) (xy 117.012378 -267.388231) (xy 117.051992 -267.352561) (xy 117.074188 -267.337794)
			(xy 117.081046 -267.333476) (xy 117.101112 -267.309092) (xy 117.10416 -267.301472) (xy 117.112334 -267.281695)
			(xy 117.135348 -267.245626) (xy 117.165082 -267.214861) (xy 117.200345 -267.190631) (xy 117.239727 -267.173907)
			(xy 117.28165 -267.165358) (xy 117.303042 -267.16482) (xy 117.393974 -267.16482) (xy 117.403605 -267.164344)
			(xy 117.421479 -267.157147) (xy 117.435469 -267.143897) (xy 117.439948 -267.135356) (xy 117.474238 -267.061696)
			(xy 117.483329 -267.053272) (xy 117.506896 -267.04569) (xy 117.519196 -267.047218) (xy 117.500443 -267.032056)
			(xy 117.467297 -266.997029) (xy 117.439821 -266.957399) (xy 117.418644 -266.914074) (xy 117.404253 -266.868049)
			(xy 117.396976 -266.820378) (xy 117.396514 -266.796266) (xy 117.396514 -266.795504) (xy 117.396617 -266.785058)
			(xy 117.398015 -266.764214) (xy 117.399308 -266.753848) (xy 117.400832 -266.742672) (xy 117.394482 -266.721844)
			(xy 117.37086 -266.69492) (xy 117.338094 -266.657836) (xy 117.330728 -266.649454) (xy 117.310916 -266.640564)
			(xy 117.178582 -266.640564) (xy 117.15877 -266.649454) (xy 117.151404 -266.657836) (xy 117.118638 -266.69492)
			(xy 117.095016 -266.721844) (xy 117.088666 -266.742672) (xy 117.09019 -266.753848) (xy 117.091515 -266.764402)
			(xy 117.092917 -266.785629) (xy 117.092984 -266.796266) (xy 117.092493 -266.821275) (xy 117.084669 -266.870678)
			(xy 117.069212 -266.918248) (xy 117.046504 -266.962815) (xy 117.017104 -267.00328) (xy 116.981736 -267.038648)
			(xy 116.941271 -267.068048) (xy 116.896704 -267.090756) (xy 116.849134 -267.106213) (xy 116.799731 -267.114037)
			(xy 116.749713 -267.114037) (xy 116.70031 -267.106213) (xy 116.65274 -267.090756) (xy 116.608173 -267.068048)
			(xy 116.567708 -267.038648) (xy 116.53234 -267.00328) (xy 116.50294 -266.962815) (xy 116.480232 -266.918248)
			(xy 116.464775 -266.870678) (xy 116.456951 -266.821275) (xy 116.45646 -266.796266) (xy 116.456493 -266.785824)
			(xy 116.457763 -266.764979) (xy 116.459 -266.75461) (xy 116.459254 -266.75334) (xy 116.459508 -266.750546)
			(xy 116.459835 -266.740391) (xy 116.453427 -266.721126) (xy 116.447062 -266.713208) (xy 116.430806 -266.69492)
			(xy 116.39804 -266.657836) (xy 116.390674 -266.649454) (xy 116.370862 -266.640564) (xy 116.238528 -266.640564)
			(xy 116.218716 -266.649454) (xy 116.21135 -266.657836) (xy 116.178584 -266.69492) (xy 116.154962 -266.721844)
			(xy 116.148612 -266.742672) (xy 116.150136 -266.753848) (xy 116.151461 -266.764402) (xy 116.152863 -266.785629)
			(xy 116.15293 -266.796266) (xy 116.152467 -266.821278) (xy 116.144646 -266.870687) (xy 116.129191 -266.918263)
			(xy 116.106483 -266.962836) (xy 116.07708 -267.003307) (xy 116.041708 -267.038679) (xy 116.001238 -267.068082)
			(xy 115.956665 -267.09079) (xy 115.909089 -267.106246) (xy 115.85968 -267.114067) (xy 115.834668 -267.114528)
			(xy 115.807927 -267.113978) (xy 115.755196 -267.105038) (xy 115.729766 -267.096748) (xy 115.725956 -267.095478)
			(xy 115.718082 -267.093954) (xy 115.706967 -267.092567) (xy 115.68536 -267.098371) (xy 115.676426 -267.10513)
			(xy 115.66779 -267.112242) (xy 115.658138 -267.132562) (xy 115.658138 -267.17498) (xy 115.658515 -267.184814)
			(xy 115.666 -267.202997) (xy 115.679904 -267.216901) (xy 115.698088 -267.224386) (xy 115.707922 -267.224764)
			(xy 115.87226 -267.224764) (xy 115.893088 -267.224764) (xy 115.92306 -267.254736) (xy 115.92306 -267.273024)
			(xy 115.92306 -267.783564) (xy 115.92306 -267.804392) (xy 115.893088 -267.834364) (xy 115.8748 -267.834364)
			(xy 115.707922 -267.834364) (xy 115.698133 -267.834886) (xy 115.680062 -267.842433) (xy 115.666218 -267.856284)
			(xy 115.658681 -267.874359) (xy 115.658138 -267.884148) (xy 115.658138 -267.894308) (xy 115.515644 -267.894308)
			(xy 115.50523 -267.895324) (xy 115.490498 -267.898372) (xy 115.485926 -267.90015) (xy 115.484148 -267.900912)
			(xy 115.45598 -267.911587) (xy 115.396909 -267.923347) (xy 115.3668 -267.92428) (xy 115.360196 -267.92428)
			(xy 115.335439 -267.923456) (xy 115.28662 -267.915085) (xy 115.239689 -267.899245) (xy 115.195781 -267.87632)
			(xy 115.155959 -267.846865) (xy 115.121185 -267.811592) (xy 115.0923 -267.771354) (xy 115.070004 -267.727124)
			(xy 115.054834 -267.679972) (xy 115.047159 -267.631038) (xy 115.04676 -267.606272) (xy 115.047215 -267.581751)
			(xy 115.054743 -267.533289) (xy 115.069616 -267.486556) (xy 115.091483 -267.442658) (xy 115.119826 -267.402634)
			(xy 115.153973 -267.367433) (xy 115.173252 -267.352272) (xy 115.18011 -267.347192) (xy 115.197382 -267.321538)
			(xy 115.199668 -267.314426) (xy 115.202716 -267.305282) (xy 115.20297 -267.30452) (xy 115.203478 -267.303504)
			(xy 115.21153 -267.283482) (xy 115.234427 -267.246913) (xy 115.264199 -267.215684) (xy 115.299633 -267.191067)
			(xy 115.339288 -267.174064) (xy 115.381549 -267.165367) (xy 115.403122 -267.16482) (xy 115.528598 -267.16482)
			(xy 115.55349 -267.148818) (xy 115.55984 -267.135356) (xy 115.59413 -267.061696) (xy 115.603221 -267.053271)
			(xy 115.626788 -267.045685) (xy 115.639088 -267.047218) (xy 115.620335 -267.032056) (xy 115.587191 -266.997029)
			(xy 115.559715 -266.957398) (xy 115.538539 -266.914074) (xy 115.524147 -266.868048) (xy 115.516871 -266.820378)
			(xy 115.516406 -266.796266) (xy 115.516406 -266.795504) (xy 115.516509 -266.785058) (xy 115.517907 -266.764214)
			(xy 115.5192 -266.753848) (xy 115.520724 -266.742672) (xy 115.514374 -266.721844) (xy 115.490752 -266.69492)
			(xy 115.457986 -266.657836) (xy 115.45062 -266.649454) (xy 115.430808 -266.640564) (xy 114.358674 -266.640564)
			(xy 114.338862 -266.649454) (xy 114.331496 -266.657836) (xy 114.29873 -266.69492) (xy 114.275108 -266.721844)
			(xy 114.268758 -266.742672) (xy 114.270282 -266.753848) (xy 114.271608 -266.764402) (xy 114.273009 -266.785629)
			(xy 114.273076 -266.796266) (xy 114.272613 -266.821279) (xy 114.264792 -266.870691) (xy 114.249338 -266.91827)
			(xy 114.22663 -266.962846) (xy 114.197229 -267.003321) (xy 114.161857 -267.038698) (xy 114.121387 -267.068105)
			(xy 114.076815 -267.09082) (xy 114.029237 -267.106281) (xy 113.979827 -267.11411) (xy 113.954814 -267.114528)
			(xy 113.954306 -267.114528) (xy 113.932796 -267.114159) (xy 113.890173 -267.10833) (xy 113.848725 -267.096804)
			(xy 113.82883 -267.08862) (xy 113.819178 -267.084556) (xy 113.808764 -267.084556) (xy 113.798758 -267.08505)
			(xy 113.780271 -267.092714) (xy 113.766119 -267.106864) (xy 113.758451 -267.12535) (xy 113.757964 -267.135356)
			(xy 113.757964 -267.179806) (xy 113.759309 -267.188896) (xy 113.767597 -267.205278) (xy 113.781201 -267.217607)
			(xy 113.798316 -267.22425) (xy 113.807494 -267.224764) (xy 113.971832 -267.224764) (xy 113.993168 -267.224764)
			(xy 114.022632 -267.254736) (xy 114.022632 -267.270738) (xy 114.022886 -267.272008) (xy 114.022886 -267.78712)
			(xy 114.022632 -267.78839) (xy 114.022632 -267.804392) (xy 113.993168 -267.834364) (xy 113.974372 -267.834364)
			(xy 113.807494 -267.834364) (xy 113.798317 -267.834828) (xy 113.781214 -267.8415) (xy 113.767628 -267.853847)
			(xy 113.759357 -267.870237) (xy 113.757964 -267.879322) (xy 113.757964 -267.894308) (xy 113.635536 -267.894308)
			(xy 113.625122 -267.895324) (xy 113.61039 -267.898372) (xy 113.605818 -267.90015) (xy 113.60404 -267.900912)
			(xy 113.575872 -267.911586) (xy 113.516801 -267.923344) (xy 113.486692 -267.92428) (xy 113.480088 -267.92428)
			(xy 113.455332 -267.923456) (xy 113.406513 -267.915083) (xy 113.359583 -267.899242) (xy 113.315677 -267.876317)
			(xy 113.275855 -267.846862) (xy 113.241082 -267.811589) (xy 113.212199 -267.771351) (xy 113.189903 -267.727122)
			(xy 113.174734 -267.679971) (xy 113.167059 -267.631038) (xy 113.166652 -267.606272) (xy 113.167191 -267.579588)
			(xy 113.176089 -267.526966) (xy 113.193648 -267.476569) (xy 113.219376 -267.429811) (xy 113.252548 -267.388005)
			(xy 113.272062 -267.369798) (xy 113.278412 -267.36421) (xy 113.293398 -267.337032) (xy 113.295176 -267.32992)
			(xy 113.295176 -267.329666) (xy 113.300283 -267.30985) (xy 113.317011 -267.272509) (xy 113.340546 -267.239037)
			(xy 113.370024 -267.210661) (xy 113.404368 -267.188419) (xy 113.44232 -267.173126) (xy 113.482489 -267.165342)
			(xy 113.502948 -267.16482) (xy 113.648744 -267.16482) (xy 113.673636 -267.148818) (xy 113.679986 -267.135356)
			(xy 113.714276 -267.061696) (xy 113.723364 -267.05326) (xy 113.746935 -267.045649) (xy 113.759234 -267.047218)
			(xy 113.740484 -267.032054) (xy 113.707345 -266.997025) (xy 113.679874 -266.957394) (xy 113.658702 -266.91407)
			(xy 113.644313 -266.868045) (xy 113.637038 -266.820377) (xy 113.636552 -266.796266) (xy 113.636552 -266.795504)
			(xy 113.636655 -266.785058) (xy 113.638053 -266.764214) (xy 113.639346 -266.753848) (xy 113.64087 -266.742672)
			(xy 113.63452 -266.721844) (xy 113.610898 -266.69492) (xy 113.578132 -266.657836) (xy 113.570766 -266.649454)
			(xy 113.550954 -266.640564) (xy 110.604808 -266.640564) (xy 110.584996 -266.649454) (xy 110.57763 -266.657836)
			(xy 110.544864 -266.69492) (xy 110.521242 -266.721844) (xy 110.514892 -266.742672) (xy 110.516416 -266.753848)
			(xy 110.517741 -266.764402) (xy 110.519143 -266.785629) (xy 110.51921 -266.796266) (xy 110.518722 -266.821278)
			(xy 110.510902 -266.870688) (xy 110.495449 -266.918266) (xy 110.472744 -266.96284) (xy 110.443345 -267.003315)
			(xy 110.407977 -267.038692) (xy 110.36751 -267.068101) (xy 110.322941 -267.090818) (xy 110.275368 -267.106283)
			(xy 110.22596 -267.114116) (xy 110.200948 -267.114528) (xy 110.179667 -267.114174) (xy 110.137489 -267.108459)
			(xy 110.096456 -267.097152) (xy 110.076742 -267.089128) (xy 110.071662 -267.087096) (xy 110.061502 -267.085064)
			(xy 110.050348 -267.083562) (xy 110.028599 -267.089236) (xy 110.019592 -267.095986) (xy 110.010956 -267.103098)
			(xy 110.001304 -267.123672) (xy 110.001304 -267.173964) (xy 110.001717 -267.18399) (xy 110.009381 -267.202518)
			(xy 110.023555 -267.216701) (xy 110.042078 -267.224376) (xy 110.052104 -267.224764) (xy 110.215172 -267.224764)
			(xy 110.236508 -267.224764) (xy 110.265972 -267.254736) (xy 110.265972 -267.804392) (xy 110.236508 -267.834364)
			(xy 110.217712 -267.834364) (xy 110.052104 -267.834364) (xy 110.042093 -267.834851) (xy 110.023594 -267.842508)
			(xy 110.009431 -267.85666) (xy 110.001759 -267.875154) (xy 110.001304 -267.885164) (xy 110.001304 -267.894308)
			(xy 109.866176 -267.894308) (xy 109.856524 -267.898372) (xy 109.836626 -267.90655) (xy 109.79518 -267.918076)
			(xy 109.752557 -267.923909) (xy 109.731048 -267.92428) (xy 109.706055 -267.923819) (xy 109.656684 -267.916005)
			(xy 109.609143 -267.900564) (xy 109.564604 -267.877875) (xy 109.524163 -267.848496) (xy 109.488817 -267.813152)
			(xy 109.459436 -267.772713) (xy 109.436744 -267.728175) (xy 109.421299 -267.680635) (xy 109.413483 -267.631265)
			(xy 109.41304 -267.606272) (xy 109.413559 -267.57982) (xy 109.4223 -267.527644) (xy 109.439554 -267.477634)
			(xy 109.464845 -267.431168) (xy 109.497475 -267.389526) (xy 109.516672 -267.371322) (xy 109.522768 -267.365988)
			(xy 109.535722 -267.34262) (xy 109.5375 -267.335) (xy 109.542203 -267.31469) (xy 109.558386 -267.276277)
			(xy 109.581715 -267.241733) (xy 109.611302 -267.212372) (xy 109.646024 -267.18931) (xy 109.68456 -267.173422)
			(xy 109.725447 -267.165313) (xy 109.746288 -267.16482) (xy 109.877098 -267.16482) (xy 109.886681 -267.164405)
			(xy 109.904515 -267.157377) (xy 109.918554 -267.144326) (xy 109.923072 -267.135864) (xy 109.962442 -267.05306)
			(xy 109.966158 -267.044167) (xy 109.967358 -267.024946) (xy 109.961422 -267.006625) (xy 109.955584 -266.998958)
			(xy 109.938523 -266.977399) (xy 109.911307 -266.929636) (xy 109.892696 -266.877908) (xy 109.883245 -266.823753)
			(xy 109.882686 -266.796266) (xy 109.882686 -266.795504) (xy 109.882789 -266.785058) (xy 109.884187 -266.764214)
			(xy 109.88548 -266.753848) (xy 109.887004 -266.742672) (xy 109.880654 -266.721844) (xy 109.857032 -266.69492)
			(xy 109.824266 -266.657836) (xy 109.8169 -266.649454) (xy 109.797088 -266.640564) (xy 109.665008 -266.640564)
			(xy 109.645196 -266.649454) (xy 109.63783 -266.657836) (xy 109.605064 -266.69492) (xy 109.581442 -266.721844)
			(xy 109.575092 -266.742672) (xy 109.576616 -266.753848) (xy 109.577941 -266.764402) (xy 109.579343 -266.785629)
			(xy 109.57941 -266.796266) (xy 109.578919 -266.821275) (xy 109.571095 -266.870678) (xy 109.555638 -266.918248)
			(xy 109.53293 -266.962815) (xy 109.50353 -267.00328) (xy 109.468162 -267.038648) (xy 109.427697 -267.068048)
			(xy 109.38313 -267.090756) (xy 109.33556 -267.106213) (xy 109.286157 -267.114037) (xy 109.236139 -267.114037)
			(xy 109.186736 -267.106213) (xy 109.139166 -267.090756) (xy 109.094599 -267.068048) (xy 109.054134 -267.038648)
			(xy 109.018766 -267.00328) (xy 108.989366 -266.962815) (xy 108.966658 -266.918248) (xy 108.951201 -266.870678)
			(xy 108.943377 -266.821275) (xy 108.942886 -266.796266) (xy 108.942919 -266.785824) (xy 108.944188 -266.764979)
			(xy 108.945426 -266.75461) (xy 108.94568 -266.75334) (xy 108.945934 -266.750546) (xy 108.946261 -266.74039)
			(xy 108.939856 -266.721124) (xy 108.933488 -266.713208) (xy 108.917232 -266.69492) (xy 108.884466 -266.657836)
			(xy 108.8771 -266.649454) (xy 108.857288 -266.640564) (xy 107.7849 -266.640564) (xy 107.765088 -266.649454)
			(xy 107.757722 -266.657836) (xy 107.724956 -266.69492) (xy 107.701334 -266.721844) (xy 107.694984 -266.742672)
			(xy 107.696508 -266.753848) (xy 107.697833 -266.764402) (xy 107.699235 -266.785629) (xy 107.699302 -266.796266)
			(xy 107.698811 -266.821275) (xy 107.690987 -266.870678) (xy 107.67553 -266.918248) (xy 107.652822 -266.962815)
			(xy 107.623422 -267.00328) (xy 107.588054 -267.038648) (xy 107.547589 -267.068048) (xy 107.503022 -267.090756)
			(xy 107.455452 -267.106213) (xy 107.406049 -267.114037) (xy 107.356031 -267.114037) (xy 107.306628 -267.106213)
			(xy 107.259058 -267.090756) (xy 107.214491 -267.068048) (xy 107.174026 -267.038648) (xy 107.138658 -267.00328)
			(xy 107.109258 -266.962815) (xy 107.08655 -266.918248) (xy 107.071093 -266.870678) (xy 107.063269 -266.821275)
			(xy 107.062778 -266.796266) (xy 107.062811 -266.785824) (xy 107.064081 -266.764979) (xy 107.065318 -266.75461)
			(xy 107.065572 -266.75334) (xy 107.065826 -266.750546) (xy 107.066153 -266.74039) (xy 107.059748 -266.721124)
			(xy 107.05338 -266.713208) (xy 107.037124 -266.69492) (xy 107.004358 -266.657836) (xy 106.996992 -266.649454)
			(xy 106.97718 -266.640564) (xy 106.844846 -266.640564) (xy 106.825034 -266.649454) (xy 106.817668 -266.657836)
			(xy 106.784902 -266.69492) (xy 106.76128 -266.721844) (xy 106.75493 -266.742672) (xy 106.756454 -266.753848)
			(xy 106.757779 -266.764402) (xy 106.75918 -266.785629) (xy 106.759248 -266.796266) (xy 106.758757 -266.821275)
			(xy 106.750933 -266.870678) (xy 106.735476 -266.918248) (xy 106.712768 -266.962815) (xy 106.683368 -267.00328)
			(xy 106.648 -267.038648) (xy 106.607535 -267.068048) (xy 106.562968 -267.090756) (xy 106.515398 -267.106213)
			(xy 106.465995 -267.114037) (xy 106.415977 -267.114037) (xy 106.366574 -267.106213) (xy 106.319004 -267.090756)
			(xy 106.274437 -267.068048) (xy 106.233972 -267.038648) (xy 106.198604 -267.00328) (xy 106.169204 -266.962815)
			(xy 106.146496 -266.918248) (xy 106.131039 -266.870678) (xy 106.123215 -266.821275) (xy 106.122724 -266.796266)
			(xy 106.122757 -266.785824) (xy 106.124027 -266.764979) (xy 106.125264 -266.75461) (xy 106.125518 -266.75334)
			(xy 106.125772 -266.750546) (xy 106.126098 -266.740391) (xy 106.119688 -266.721129) (xy 106.113326 -266.713208)
			(xy 106.09707 -266.69492) (xy 106.064304 -266.657836) (xy 106.056938 -266.649454) (xy 106.037126 -266.640564)
			(xy 105.904792 -266.640564) (xy 105.88498 -266.649454) (xy 105.877614 -266.657836) (xy 105.844848 -266.69492)
			(xy 105.821226 -266.721844) (xy 105.814876 -266.742672) (xy 105.8164 -266.753848) (xy 105.817725 -266.764402)
			(xy 105.819127 -266.785629) (xy 105.819194 -266.796266) (xy 105.818703 -266.821275) (xy 105.810879 -266.870678)
			(xy 105.795422 -266.918248) (xy 105.772714 -266.962815) (xy 105.743314 -267.00328) (xy 105.707946 -267.038648)
			(xy 105.667481 -267.068048) (xy 105.622914 -267.090756) (xy 105.575344 -267.106213) (xy 105.525941 -267.114037)
			(xy 105.475923 -267.114037) (xy 105.42652 -267.106213) (xy 105.37895 -267.090756) (xy 105.334383 -267.068048)
			(xy 105.293918 -267.038648) (xy 105.25855 -267.00328) (xy 105.22915 -266.962815) (xy 105.206442 -266.918248)
			(xy 105.190985 -266.870678) (xy 105.183161 -266.821275) (xy 105.18267 -266.796266) (xy 105.182703 -266.785824)
			(xy 105.183973 -266.764979) (xy 105.18521 -266.75461) (xy 105.185464 -266.75334) (xy 105.185718 -266.750546)
			(xy 105.186045 -266.74039) (xy 105.179639 -266.721125) (xy 105.173272 -266.713208) (xy 105.157016 -266.69492)
			(xy 105.12425 -266.657836) (xy 105.116884 -266.649454) (xy 105.097072 -266.640564) (xy 104.024938 -266.640564)
			(xy 104.005126 -266.649454) (xy 103.99776 -266.657836) (xy 103.964994 -266.69492) (xy 103.941372 -266.721844)
			(xy 103.935022 -266.742672) (xy 103.936546 -266.753848) (xy 103.937871 -266.764402) (xy 103.939272 -266.785629)
			(xy 103.93934 -266.796266) (xy 103.938849 -266.821275) (xy 103.931025 -266.870678) (xy 103.915568 -266.918248)
			(xy 103.89286 -266.962815) (xy 103.86346 -267.00328) (xy 103.828092 -267.038648) (xy 103.787627 -267.068048)
			(xy 103.74306 -267.090756) (xy 103.69549 -267.106213) (xy 103.646087 -267.114037) (xy 103.596069 -267.114037)
			(xy 103.546666 -267.106213) (xy 103.499096 -267.090756) (xy 103.454529 -267.068048) (xy 103.414064 -267.038648)
			(xy 103.378696 -267.00328) (xy 103.349296 -266.962815) (xy 103.326588 -266.918248) (xy 103.311131 -266.870678)
			(xy 103.303307 -266.821275) (xy 103.302816 -266.796266) (xy 103.302849 -266.785824) (xy 103.304119 -266.764979)
			(xy 103.305356 -266.75461) (xy 103.30561 -266.75334) (xy 103.305864 -266.750546) (xy 103.30619 -266.740391)
			(xy 103.299778 -266.72113) (xy 103.293418 -266.713208) (xy 103.277162 -266.69492) (xy 103.244396 -266.657836)
			(xy 103.23703 -266.649454) (xy 103.217218 -266.640564) (xy 103.084884 -266.640564) (xy 103.065072 -266.649454)
			(xy 103.057706 -266.657836) (xy 103.02494 -266.69492) (xy 103.001318 -266.721844) (xy 102.994968 -266.742672)
			(xy 102.996492 -266.753848) (xy 102.997817 -266.764402) (xy 102.999219 -266.785629) (xy 102.999286 -266.796266)
			(xy 102.998795 -266.821275) (xy 102.990971 -266.870678) (xy 102.975514 -266.918248) (xy 102.952806 -266.962815)
			(xy 102.923406 -267.00328) (xy 102.888038 -267.038648) (xy 102.847573 -267.068048) (xy 102.803006 -267.090756)
			(xy 102.755436 -267.106213) (xy 102.706033 -267.114037) (xy 102.656015 -267.114037) (xy 102.606612 -267.106213)
			(xy 102.559042 -267.090756) (xy 102.514475 -267.068048) (xy 102.47401 -267.038648) (xy 102.438642 -267.00328)
			(xy 102.409242 -266.962815) (xy 102.386534 -266.918248) (xy 102.371077 -266.870678) (xy 102.363253 -266.821275)
			(xy 102.362762 -266.796266) (xy 102.362795 -266.785824) (xy 102.364065 -266.764979) (xy 102.365302 -266.75461)
			(xy 102.365556 -266.75334) (xy 102.36581 -266.750546) (xy 102.366137 -266.740391) (xy 102.35973 -266.721126)
			(xy 102.353364 -266.713208) (xy 102.337108 -266.69492) (xy 102.304342 -266.657836) (xy 102.296976 -266.649454)
			(xy 102.277164 -266.640564) (xy 102.14483 -266.640564) (xy 102.125018 -266.649454) (xy 102.117652 -266.657836)
			(xy 102.084886 -266.69492) (xy 102.061264 -266.721844) (xy 102.054914 -266.742672) (xy 102.056438 -266.753848)
			(xy 102.057763 -266.764402) (xy 102.059165 -266.785629) (xy 102.059232 -266.796266) (xy 102.058741 -266.821275)
			(xy 102.050917 -266.870678) (xy 102.03546 -266.918248) (xy 102.012752 -266.962815) (xy 101.983352 -267.00328)
			(xy 101.947984 -267.038648) (xy 101.907519 -267.068048) (xy 101.862952 -267.090756) (xy 101.815382 -267.106213)
			(xy 101.765979 -267.114037) (xy 101.715961 -267.114037) (xy 101.666558 -267.106213) (xy 101.618988 -267.090756)
			(xy 101.574421 -267.068048) (xy 101.533956 -267.038648) (xy 101.498588 -267.00328) (xy 101.469188 -266.962815)
			(xy 101.44648 -266.918248) (xy 101.431023 -266.870678) (xy 101.423199 -266.821275) (xy 101.422708 -266.796266)
			(xy 101.422741 -266.785824) (xy 101.424011 -266.764979) (xy 101.425248 -266.75461) (xy 101.425502 -266.75334)
			(xy 101.425756 -266.750546) (xy 101.426083 -266.74039) (xy 101.419681 -266.721122) (xy 101.41331 -266.713208)
			(xy 101.397054 -266.69492) (xy 101.364288 -266.657836) (xy 101.356922 -266.649454) (xy 101.33711 -266.640564)
			(xy 100.264976 -266.640564) (xy 100.245164 -266.649454) (xy 100.237798 -266.657836) (xy 100.205032 -266.69492)
			(xy 100.18141 -266.721844) (xy 100.17506 -266.742672) (xy 100.176584 -266.753848) (xy 100.17791 -266.764402)
			(xy 100.179311 -266.785629) (xy 100.179378 -266.796266) (xy 100.178886 -266.821544) (xy 100.170884 -266.871464)
			(xy 100.15509 -266.91949) (xy 100.131902 -266.964416) (xy 100.101904 -267.005111) (xy 100.06585 -267.040553)
			(xy 100.024646 -267.069848) (xy 99.979329 -267.092262) (xy 99.931038 -267.107229) (xy 99.906074 -267.111226)
			(xy 99.90582 -267.111226) (xy 99.896887 -267.112913) (xy 99.880962 -267.121656) (xy 99.869087 -267.135406)
			(xy 99.862755 -267.152434) (xy 99.862386 -267.161518) (xy 99.862386 -267.606272) (xy 100.013008 -267.606272)
			(xy 100.013585 -267.579048) (xy 100.022839 -267.525394) (xy 100.041105 -267.474103) (xy 100.067849 -267.426678)
			(xy 100.102287 -267.384506) (xy 100.122482 -267.366242) (xy 100.128622 -267.360426) (xy 100.137038 -267.345769)
			(xy 100.138992 -267.33754) (xy 100.143464 -267.316991) (xy 100.159419 -267.278087) (xy 100.18267 -267.243051)
			(xy 100.21232 -267.213235) (xy 100.247224 -267.189787) (xy 100.286038 -267.173612) (xy 100.327264 -267.165335)
			(xy 100.348288 -267.16482) (xy 100.603304 -267.16482) (xy 100.603304 -267.173964) (xy 100.603849 -267.183958)
			(xy 100.611526 -267.202416) (xy 100.625657 -267.216556) (xy 100.64411 -267.224245) (xy 100.654104 -267.224764)
			(xy 100.817172 -267.224764) (xy 100.827173 -267.22531) (xy 100.845658 -267.232954) (xy 100.859811 -267.247088)
			(xy 100.867477 -267.265563) (xy 100.867972 -267.275564) (xy 100.867972 -267.606272) (xy 101.893116 -267.606272)
			(xy 101.893682 -267.579998) (xy 101.902359 -267.528171) (xy 101.910388 -267.503148) (xy 101.912928 -267.49502)
			(xy 101.912928 -267.379704) (xy 101.913266 -267.358639) (xy 101.921229 -267.317275) (xy 101.937142 -267.278273)
			(xy 101.96039 -267.243145) (xy 101.99007 -267.213253) (xy 102.025031 -267.189757) (xy 102.06392 -267.173567)
			(xy 102.105226 -267.165311) (xy 102.126288 -267.16482) (xy 102.381304 -267.16482) (xy 102.381304 -267.173964)
			(xy 102.381849 -267.183958) (xy 102.389526 -267.202416) (xy 102.403657 -267.216556) (xy 102.42211 -267.224245)
			(xy 102.432104 -267.224764) (xy 102.595172 -267.224764) (xy 102.605173 -267.22531) (xy 102.623658 -267.232954)
			(xy 102.637811 -267.247088) (xy 102.645477 -267.265563) (xy 102.645972 -267.275564) (xy 102.645972 -267.606272)
			(xy 103.77297 -267.606272) (xy 103.773484 -267.579767) (xy 103.782272 -267.52749) (xy 103.799601 -267.477392)
			(xy 103.811832 -267.453872) (xy 103.815134 -267.44803) (xy 103.817928 -267.436092) (xy 103.817928 -267.379958)
			(xy 103.817928 -267.379704) (xy 103.818266 -267.358639) (xy 103.826229 -267.317275) (xy 103.842142 -267.278273)
			(xy 103.86539 -267.243145) (xy 103.89507 -267.213253) (xy 103.930031 -267.189757) (xy 103.96892 -267.173567)
			(xy 104.010226 -267.165311) (xy 104.031288 -267.16482) (xy 104.286304 -267.16482) (xy 104.286304 -267.173964)
			(xy 104.286849 -267.183958) (xy 104.294526 -267.202416) (xy 104.308657 -267.216556) (xy 104.32711 -267.224245)
			(xy 104.337104 -267.224764) (xy 104.500172 -267.224764) (xy 104.510173 -267.22531) (xy 104.528658 -267.232954)
			(xy 104.542811 -267.247088) (xy 104.550477 -267.265563) (xy 104.550972 -267.275564) (xy 104.550972 -267.606272)
			(xy 105.653078 -267.606272) (xy 105.65357 -267.581354) (xy 105.661352 -267.532131) (xy 105.676723 -267.484725)
			(xy 105.699304 -267.440299) (xy 105.71353 -267.419836) (xy 105.718102 -267.413486) (xy 105.722928 -267.398246)
			(xy 105.722928 -267.379958) (xy 105.722928 -267.379704) (xy 105.723266 -267.358639) (xy 105.731229 -267.317275)
			(xy 105.747142 -267.278273) (xy 105.77039 -267.243145) (xy 105.80007 -267.213253) (xy 105.835031 -267.189757)
			(xy 105.87392 -267.173567) (xy 105.915226 -267.165311) (xy 105.936288 -267.16482) (xy 106.191304 -267.16482)
			(xy 106.191304 -267.173964) (xy 106.191849 -267.183958) (xy 106.199526 -267.202416) (xy 106.213657 -267.216556)
			(xy 106.23211 -267.224245) (xy 106.242104 -267.224764) (xy 106.405172 -267.224764) (xy 106.415173 -267.22531)
			(xy 106.433658 -267.232954) (xy 106.447811 -267.247088) (xy 106.455477 -267.265563) (xy 106.455972 -267.275564)
			(xy 106.455972 -267.606272) (xy 107.532932 -267.606272) (xy 107.533331 -267.582796) (xy 107.540248 -267.536355)
			(xy 107.553927 -267.491439) (xy 107.574069 -267.449027) (xy 107.600237 -267.410042) (xy 107.615736 -267.392404)
			(xy 107.62116 -267.385982) (xy 107.627771 -267.370534) (xy 107.62869 -267.362178) (xy 107.630597 -267.342316)
			(xy 107.640959 -267.303785) (xy 107.658291 -267.267846) (xy 107.681992 -267.235748) (xy 107.711238 -267.208606)
			(xy 107.745012 -267.187363) (xy 107.782143 -267.172757) (xy 107.821339 -267.165295) (xy 107.841288 -267.16482)
			(xy 108.096304 -267.16482) (xy 108.096304 -267.173964) (xy 108.096849 -267.183958) (xy 108.104526 -267.202416)
			(xy 108.118657 -267.216556) (xy 108.13711 -267.224245) (xy 108.147104 -267.224764) (xy 108.310172 -267.224764)
			(xy 108.320173 -267.22531) (xy 108.338658 -267.232954) (xy 108.352811 -267.247088) (xy 108.360477 -267.265563)
			(xy 108.360972 -267.275564) (xy 108.360972 -267.783564) (xy 108.36055 -267.793586) (xy 108.352887 -267.812108)
			(xy 108.338715 -267.826282) (xy 108.320194 -267.833949) (xy 108.310172 -267.834364) (xy 108.096304 -267.834364)
			(xy 108.096304 -267.843508) (xy 108.095818 -267.853516) (xy 108.088157 -267.872007) (xy 108.074003 -267.886159)
			(xy 108.055512 -267.893819) (xy 108.045504 -267.894308) (xy 107.986322 -267.894308) (xy 107.97667 -267.898372)
			(xy 107.956728 -267.906553) (xy 107.915199 -267.918093) (xy 107.872491 -267.923919) (xy 107.85094 -267.92428)
			(xy 107.825949 -267.923806) (xy 107.77658 -267.915992) (xy 107.729042 -267.900551) (xy 107.684506 -267.877862)
			(xy 107.644068 -267.848484) (xy 107.608724 -267.813141) (xy 107.579345 -267.772704) (xy 107.556654 -267.728169)
			(xy 107.541211 -267.680632) (xy 107.533395 -267.631263) (xy 107.532932 -267.606272) (xy 106.455972 -267.606272)
			(xy 106.455972 -267.783564) (xy 106.45555 -267.793586) (xy 106.447887 -267.812108) (xy 106.433715 -267.826282)
			(xy 106.415194 -267.833949) (xy 106.405172 -267.834364) (xy 106.192828 -267.834364) (xy 106.191304 -267.835888)
			(xy 106.191304 -267.843508) (xy 106.190818 -267.853516) (xy 106.183157 -267.872007) (xy 106.169003 -267.886159)
			(xy 106.150512 -267.893819) (xy 106.140504 -267.894308) (xy 106.106468 -267.894308) (xy 106.096816 -267.898372)
			(xy 106.076881 -267.906569) (xy 106.035348 -267.918103) (xy 105.992638 -267.923922) (xy 105.971086 -267.92428)
			(xy 105.946093 -267.923856) (xy 105.896723 -267.916034) (xy 105.849184 -267.900585) (xy 105.804647 -267.87789)
			(xy 105.76421 -267.848506) (xy 105.728867 -267.813158) (xy 105.699488 -267.772717) (xy 105.676798 -267.728177)
			(xy 105.661356 -267.680636) (xy 105.65354 -267.631265) (xy 105.653078 -267.606272) (xy 104.550972 -267.606272)
			(xy 104.550972 -267.783564) (xy 104.55055 -267.793586) (xy 104.542887 -267.812108) (xy 104.528715 -267.826282)
			(xy 104.510194 -267.833949) (xy 104.500172 -267.834364) (xy 104.332532 -267.834364) (xy 104.32345 -267.834685)
			(xy 104.3064 -267.840936) (xy 104.299258 -267.846556) (xy 104.286304 -267.857224) (xy 104.286304 -267.864336)
			(xy 104.256332 -267.894308) (xy 104.22636 -267.894308) (xy 104.216708 -267.898372) (xy 104.196774 -267.906572)
			(xy 104.15524 -267.918105) (xy 104.11253 -267.923923) (xy 104.090978 -267.92428) (xy 104.065985 -267.923864)
			(xy 104.016614 -267.916041) (xy 103.969075 -267.900591) (xy 103.924539 -267.877894) (xy 103.884101 -267.848509)
			(xy 103.848758 -267.813161) (xy 103.81938 -267.772718) (xy 103.79669 -267.728178) (xy 103.781248 -267.680637)
			(xy 103.773432 -267.631265) (xy 103.77297 -267.606272) (xy 102.645972 -267.606272) (xy 102.645972 -267.783564)
			(xy 102.64555 -267.793586) (xy 102.637887 -267.812108) (xy 102.623715 -267.826282) (xy 102.605194 -267.833949)
			(xy 102.595172 -267.834364) (xy 102.452678 -267.834364) (xy 102.443598 -267.834707) (xy 102.426548 -267.840943)
			(xy 102.419404 -267.846556) (xy 102.410356 -267.854285) (xy 102.391284 -267.868522) (xy 102.381304 -267.875004)
			(xy 102.381304 -267.894308) (xy 102.346506 -267.894308) (xy 102.336854 -267.898372) (xy 102.316914 -267.906558)
			(xy 102.275384 -267.918096) (xy 102.232676 -267.92392) (xy 102.211124 -267.92428) (xy 102.183114 -267.923711)
			(xy 102.127952 -267.913954) (xy 102.075353 -267.894683) (xy 102.05085 -267.8811) (xy 102.044754 -267.878052)
			(xy 102.02689 -267.870193) (xy 101.994172 -267.848919) (xy 101.965863 -267.822057) (xy 101.942902 -267.7905)
			(xy 101.926054 -267.755299) (xy 101.920548 -267.736574) (xy 101.918262 -267.730224) (xy 101.910304 -267.71054)
			(xy 101.899111 -267.669583) (xy 101.893467 -267.627501) (xy 101.893116 -267.606272) (xy 100.867972 -267.606272)
			(xy 100.867972 -267.783564) (xy 100.86755 -267.793586) (xy 100.859887 -267.812108) (xy 100.845715 -267.826282)
			(xy 100.827194 -267.833949) (xy 100.817172 -267.834364) (xy 100.603304 -267.834364) (xy 100.603304 -267.843508)
			(xy 100.602818 -267.853516) (xy 100.595157 -267.872007) (xy 100.581003 -267.886159) (xy 100.562512 -267.893819)
			(xy 100.552504 -267.894308) (xy 100.466398 -267.894308) (xy 100.456746 -267.898372) (xy 100.436807 -267.90656)
			(xy 100.395276 -267.918097) (xy 100.352568 -267.92392) (xy 100.331016 -267.92428) (xy 100.306024 -267.923829)
			(xy 100.256655 -267.916011) (xy 100.209116 -267.900566) (xy 100.16458 -267.877874) (xy 100.124142 -267.848494)
			(xy 100.088798 -267.813149) (xy 100.059419 -267.77271) (xy 100.036729 -267.728173) (xy 100.021286 -267.680634)
			(xy 100.01347 -267.631264) (xy 100.013008 -267.606272) (xy 99.862386 -267.606272) (xy 99.862386 -267.63599)
			(xy 99.861846 -267.645825) (xy 99.854252 -267.66398) (xy 99.847654 -267.671296) (xy 99.701096 -267.817854)
			(xy 99.697032 -267.827252) (xy 99.697032 -267.827506) (xy 99.690853 -267.841237) (xy 99.672491 -267.865089)
			(xy 99.648548 -267.883334) (xy 99.634802 -267.889482) (xy 99.625404 -267.893546) (xy 99.369118 -268.149832)
			(xy 99.361881 -268.156548) (xy 99.343676 -268.16415) (xy 99.333812 -268.164564) (xy 98.611436 -268.164564)
			(xy 98.599909 -268.165122) (xy 98.579169 -268.17519) (xy 98.571558 -268.183868) (xy 98.523552 -268.244574)
			(xy 98.518524 -268.251457) (xy 98.512942 -268.267552) (xy 98.51263 -268.27607) (xy 98.51263 -268.289532)
			(xy 98.5139 -268.29512) (xy 98.515932 -268.305026) (xy 98.521371 -268.332518) (xy 98.527229 -268.388256)
			(xy 98.527616 -268.416278) (xy 99.543108 -268.416278) (xy 99.543577 -268.391111) (xy 99.551528 -268.341407)
			(xy 99.567212 -268.293578) (xy 99.590237 -268.248818) (xy 99.620027 -268.208245) (xy 99.637596 -268.190218)
			(xy 99.640664 -268.186998) (xy 99.645774 -268.179721) (xy 99.647756 -268.17574) (xy 99.656806 -268.157845)
			(xy 99.680447 -268.125463) (xy 99.709716 -268.098061) (xy 99.743585 -268.076605) (xy 99.780864 -268.061846)
			(xy 99.820242 -268.054305) (xy 99.840288 -268.05382) (xy 100.095304 -268.05382) (xy 100.095304 -268.062964)
			(xy 100.095849 -268.072958) (xy 100.103526 -268.091416) (xy 100.117657 -268.105556) (xy 100.13611 -268.113245)
			(xy 100.146104 -268.113764) (xy 100.309172 -268.113764) (xy 100.319173 -268.11431) (xy 100.337658 -268.121954)
			(xy 100.351811 -268.136088) (xy 100.359477 -268.154563) (xy 100.359972 -268.164564) (xy 100.359972 -268.416278)
			(xy 101.422962 -268.416278) (xy 101.423468 -268.390697) (xy 101.431675 -268.340196) (xy 101.447859 -268.29166)
			(xy 101.4716 -268.24634) (xy 101.502289 -268.205402) (xy 101.539134 -268.169904) (xy 101.559868 -268.154912)
			(xy 101.563364 -268.152347) (xy 101.569491 -268.146213) (xy 101.57206 -268.14272) (xy 101.584253 -268.126571)
			(xy 101.613655 -268.098775) (xy 101.647752 -268.076993) (xy 101.685332 -268.062) (xy 101.725059 -268.054328)
			(xy 101.745288 -268.05382) (xy 102.000304 -268.05382) (xy 102.000304 -268.062964) (xy 102.000849 -268.072958)
			(xy 102.008526 -268.091416) (xy 102.022657 -268.105556) (xy 102.04111 -268.113245) (xy 102.051104 -268.113764)
			(xy 102.214172 -268.113764) (xy 102.224173 -268.11431) (xy 102.242658 -268.121954) (xy 102.256811 -268.136088)
			(xy 102.264477 -268.154563) (xy 102.264972 -268.164564) (xy 102.264972 -268.416278) (xy 103.30307 -268.416278)
			(xy 103.303582 -268.3909) (xy 103.311661 -268.340789) (xy 103.327594 -268.292598) (xy 103.350977 -268.247548)
			(xy 103.381217 -268.206782) (xy 103.417546 -268.171335) (xy 103.459043 -268.142107) (xy 103.481632 -268.130528)
			(xy 103.485649 -268.128446) (xy 103.492932 -268.12308) (xy 103.49611 -268.11986) (xy 103.511389 -268.104633)
			(xy 103.546834 -268.080062) (xy 103.586481 -268.063084) (xy 103.628724 -268.054388) (xy 103.650288 -268.05382)
			(xy 103.905304 -268.05382) (xy 103.905304 -268.062964) (xy 103.905849 -268.072958) (xy 103.913526 -268.091416)
			(xy 103.927657 -268.105556) (xy 103.94611 -268.113245) (xy 103.956104 -268.113764) (xy 104.119172 -268.113764)
			(xy 104.129173 -268.11431) (xy 104.147658 -268.121954) (xy 104.161811 -268.136088) (xy 104.169477 -268.154563)
			(xy 104.169972 -268.164564) (xy 104.169972 -268.416278) (xy 105.182924 -268.416278) (xy 105.18344 -268.391477)
			(xy 105.191144 -268.342478) (xy 105.206362 -268.295268) (xy 105.228724 -268.250994) (xy 105.257688 -268.210728)
			(xy 105.292553 -268.175446) (xy 105.332473 -268.146006) (xy 105.376479 -268.123119) (xy 105.39984 -268.11478)
			(xy 105.404411 -268.113094) (xy 105.412853 -268.108236) (xy 105.416604 -268.105128) (xy 105.431227 -268.09317)
			(xy 105.463805 -268.074056) (xy 105.49923 -268.060949) (xy 105.536403 -268.054256) (xy 105.555288 -268.05382)
			(xy 105.810304 -268.05382) (xy 105.810304 -268.062964) (xy 105.810849 -268.072958) (xy 105.818526 -268.091416)
			(xy 105.832657 -268.105556) (xy 105.85111 -268.113245) (xy 105.861104 -268.113764) (xy 106.024172 -268.113764)
			(xy 106.034173 -268.11431) (xy 106.052658 -268.121954) (xy 106.066811 -268.136088) (xy 106.074477 -268.154563)
			(xy 106.074972 -268.164564) (xy 106.074972 -268.416278) (xy 107.063032 -268.416278) (xy 107.063459 -268.392607)
			(xy 107.070438 -268.345784) (xy 107.084297 -268.300517) (xy 107.104729 -268.257813) (xy 107.117642 -268.23797)
			(xy 107.120264 -268.234005) (xy 107.1241 -268.225308) (xy 107.125262 -268.220698) (xy 107.130228 -268.200708)
			(xy 107.146751 -268.162983) (xy 107.170195 -268.129121) (xy 107.199691 -268.100378) (xy 107.234146 -268.077818)
			(xy 107.272286 -268.062275) (xy 107.312696 -268.054327) (xy 107.333288 -268.05382) (xy 107.588304 -268.05382)
			(xy 107.588304 -268.062964) (xy 107.588849 -268.072958) (xy 107.596526 -268.091416) (xy 107.610657 -268.105556)
			(xy 107.62911 -268.113245) (xy 107.639104 -268.113764) (xy 107.802172 -268.113764) (xy 107.812173 -268.11431)
			(xy 107.830658 -268.121954) (xy 107.844811 -268.136088) (xy 107.852477 -268.154563) (xy 107.852972 -268.164564)
			(xy 107.852972 -268.416278) (xy 108.94314 -268.416278) (xy 108.943584 -268.391578) (xy 108.951244 -268.342775)
			(xy 108.966362 -268.295745) (xy 108.988573 -268.251619) (xy 109.017342 -268.211461) (xy 109.034326 -268.19352)
			(xy 109.037341 -268.1903) (xy 109.042317 -268.183016) (xy 109.044232 -268.179042) (xy 109.053018 -268.160674)
			(xy 109.076562 -268.127458) (xy 109.105974 -268.099306) (xy 109.140188 -268.077236) (xy 109.177963 -268.062049)
			(xy 109.217932 -268.054295) (xy 109.238288 -268.05382) (xy 109.493304 -268.05382) (xy 109.493304 -268.059662)
			(xy 111.689896 -268.059662) (xy 111.689896 -267.8049) (xy 111.69904 -267.8049) (xy 111.70905 -267.804445)
			(xy 111.727543 -267.796772) (xy 111.741694 -267.782609) (xy 111.749353 -267.764111) (xy 111.74984 -267.7541)
			(xy 111.74984 -267.590524) (xy 111.75024 -267.580499) (xy 111.75791 -267.561975) (xy 111.772089 -267.547801)
			(xy 111.790615 -267.540137) (xy 111.80064 -267.539724) (xy 112.308132 -267.539724) (xy 112.318145 -267.540162)
			(xy 112.336642 -267.547837) (xy 112.350794 -267.562005) (xy 112.358449 -267.580511) (xy 112.358932 -267.590524)
			(xy 112.358932 -267.8049) (xy 112.368076 -267.8049) (xy 112.37807 -267.805439) (xy 112.396528 -267.813119)
			(xy 112.410667 -267.827252) (xy 112.418356 -267.845706) (xy 112.418876 -267.8557) (xy 112.418876 -268.059662)
			(xy 112.41844 -268.079719) (xy 112.410954 -268.119128) (xy 112.396236 -268.156445) (xy 112.374807 -268.190355)
			(xy 112.34742 -268.219665) (xy 112.3315 -268.231874) (xy 112.323118 -268.239494) (xy 112.304546 -268.260049)
			(xy 112.262164 -268.295717) (xy 112.21477 -268.324393) (xy 112.163507 -268.345384) (xy 112.109613 -268.358185)
			(xy 112.054386 -268.362487) (xy 111.999159 -268.358185) (xy 111.945265 -268.345384) (xy 111.894002 -268.324393)
			(xy 111.846608 -268.295717) (xy 111.804226 -268.260049) (xy 111.785654 -268.239494) (xy 111.777272 -268.231874)
			(xy 111.761385 -268.219628) (xy 111.734006 -268.190322) (xy 111.712578 -268.156419) (xy 111.697857 -268.119113)
			(xy 111.690358 -268.079715) (xy 111.689896 -268.059662) (xy 109.493304 -268.059662) (xy 109.493304 -268.062964)
			(xy 109.493849 -268.072958) (xy 109.501526 -268.091416) (xy 109.515657 -268.105556) (xy 109.53411 -268.113245)
			(xy 109.544104 -268.113764) (xy 109.707172 -268.113764) (xy 109.717173 -268.11431) (xy 109.735658 -268.121954)
			(xy 109.749811 -268.136088) (xy 109.757477 -268.154563) (xy 109.757972 -268.164564) (xy 109.757972 -268.416278)
			(xy 113.636806 -268.416278) (xy 113.637303 -268.39035) (xy 113.645706 -268.339179) (xy 113.662304 -268.29005)
			(xy 113.686655 -268.244267) (xy 113.718113 -268.203043) (xy 113.736628 -268.184884) (xy 113.73975 -268.181809)
			(xy 113.744984 -268.174783) (xy 113.747042 -268.170914) (xy 113.756262 -268.153607) (xy 113.78007 -268.122451)
			(xy 113.80916 -268.096158) (xy 113.842556 -268.07561) (xy 113.87914 -268.061497) (xy 113.917683 -268.054291)
			(xy 113.937288 -268.05382) (xy 114.192304 -268.05382) (xy 114.192304 -268.062964) (xy 114.192849 -268.072958)
			(xy 114.200526 -268.091416) (xy 114.214657 -268.105556) (xy 114.23311 -268.113245) (xy 114.243104 -268.113764)
			(xy 114.406172 -268.113764) (xy 114.416173 -268.11431) (xy 114.434658 -268.121954) (xy 114.448811 -268.136088)
			(xy 114.456477 -268.154563) (xy 114.456972 -268.164564) (xy 114.456972 -268.416278) (xy 115.51666 -268.416278)
			(xy 115.517196 -268.390131) (xy 115.525755 -268.338541) (xy 115.542638 -268.289047) (xy 115.567391 -268.242982)
			(xy 115.599346 -268.201586) (xy 115.637643 -268.165976) (xy 115.659154 -268.151102) (xy 115.662771 -268.148625)
			(xy 115.669154 -268.142617) (xy 115.671854 -268.139164) (xy 115.684035 -268.123578) (xy 115.713196 -268.096851)
			(xy 115.74678 -268.075951) (xy 115.783638 -268.061594) (xy 115.82251 -268.054271) (xy 115.842288 -268.05382)
			(xy 116.097304 -268.05382) (xy 116.097304 -268.062964) (xy 116.097849 -268.072958) (xy 116.105526 -268.091416)
			(xy 116.119657 -268.105556) (xy 116.13811 -268.113245) (xy 116.148104 -268.113764) (xy 116.311172 -268.113764)
			(xy 116.321173 -268.11431) (xy 116.339658 -268.121954) (xy 116.353811 -268.136088) (xy 116.361477 -268.154563)
			(xy 116.361972 -268.164564) (xy 116.361972 -268.416278) (xy 117.396768 -268.416278) (xy 117.39729 -268.390476)
			(xy 117.405639 -268.339552) (xy 117.422098 -268.290644) (xy 117.446235 -268.245033) (xy 117.477417 -268.203916)
			(xy 117.514827 -268.168371) (xy 117.557483 -268.13933) (xy 117.580664 -268.127988) (xy 117.584736 -268.125981)
			(xy 117.592153 -268.12075) (xy 117.595396 -268.117574) (xy 117.610606 -268.102856) (xy 117.645637 -268.079118)
			(xy 117.684653 -268.062735) (xy 117.72613 -268.054349) (xy 117.747288 -268.05382) (xy 118.002304 -268.05382)
			(xy 118.002304 -268.062964) (xy 118.002849 -268.072958) (xy 118.010526 -268.091416) (xy 118.024657 -268.105556)
			(xy 118.04311 -268.113245) (xy 118.053104 -268.113764) (xy 118.216172 -268.113764) (xy 118.226173 -268.11431)
			(xy 118.244658 -268.121954) (xy 118.258811 -268.136088) (xy 118.266477 -268.154563) (xy 118.266972 -268.164564)
			(xy 118.266972 -268.416278) (xy 119.276622 -268.416278) (xy 119.277095 -268.391025) (xy 119.285065 -268.34115)
			(xy 119.300802 -268.293157) (xy 119.311928 -268.270482) (xy 119.311928 -268.268958) (xy 119.312244 -268.247877)
			(xy 119.32017 -268.206473) (xy 119.336061 -268.167428) (xy 119.359299 -268.132256) (xy 119.388984 -268.102324)
			(xy 119.423961 -268.078795) (xy 119.462874 -268.062581) (xy 119.50421 -268.054312) (xy 119.525288 -268.05382)
			(xy 119.780304 -268.05382) (xy 119.780304 -268.062964) (xy 119.780849 -268.072958) (xy 119.788526 -268.091416)
			(xy 119.802657 -268.105556) (xy 119.82111 -268.113245) (xy 119.831104 -268.113764) (xy 119.994172 -268.113764)
			(xy 120.004173 -268.11431) (xy 120.022658 -268.121954) (xy 120.036811 -268.136088) (xy 120.044477 -268.154563)
			(xy 120.044972 -268.164564) (xy 120.044972 -268.416278) (xy 121.15673 -268.416278) (xy 121.157199 -268.391645)
			(xy 121.164754 -268.342961) (xy 121.179725 -268.296025) (xy 121.201754 -268.251959) (xy 121.215658 -268.23162)
			(xy 121.21831 -268.227785) (xy 121.222271 -268.219345) (xy 121.223532 -268.214856) (xy 121.228955 -268.195427)
			(xy 121.246053 -268.1589) (xy 121.269694 -268.126224) (xy 121.29904 -268.098556) (xy 121.33305 -268.076879)
			(xy 121.370521 -268.061958) (xy 121.410123 -268.054324) (xy 121.430288 -268.05382) (xy 121.685304 -268.05382)
			(xy 121.685304 -268.062964) (xy 121.685849 -268.072958) (xy 121.693526 -268.091416) (xy 121.707657 -268.105556)
			(xy 121.72611 -268.113245) (xy 121.736104 -268.113764) (xy 121.899172 -268.113764) (xy 121.909173 -268.11431)
			(xy 121.927658 -268.121954) (xy 121.941811 -268.136088) (xy 121.949477 -268.154563) (xy 121.949972 -268.164564)
			(xy 121.949972 -268.416278) (xy 123.036838 -268.416278) (xy 123.037325 -268.390822) (xy 123.045446 -268.340561)
			(xy 123.061476 -268.292238) (xy 123.085007 -268.247089) (xy 123.115434 -268.20627) (xy 123.133358 -268.188186)
			(xy 123.136412 -268.185026) (xy 123.141517 -268.177874) (xy 123.143518 -268.173962) (xy 123.152592 -268.156256)
			(xy 123.176325 -268.124327) (xy 123.205554 -268.097338) (xy 123.23927 -268.076221) (xy 123.276311 -268.061704)
			(xy 123.315397 -268.054289) (xy 123.335288 -268.05382) (xy 123.590304 -268.05382) (xy 123.590304 -268.062964)
			(xy 123.590849 -268.072958) (xy 123.598526 -268.091416) (xy 123.612657 -268.105556) (xy 123.63111 -268.113245)
			(xy 123.641104 -268.113764) (xy 123.804172 -268.113764) (xy 123.814173 -268.11431) (xy 123.832658 -268.121954)
			(xy 123.846811 -268.136088) (xy 123.854477 -268.154563) (xy 123.854972 -268.164564) (xy 123.854972 -268.482356)
			(xy 124.858989 -268.482356) (xy 124.861086 -268.441436) (xy 124.870943 -268.401666) (xy 124.888197 -268.364503)
			(xy 124.912218 -268.331308) (xy 124.926852 -268.316964) (xy 124.93082 -268.313036) (xy 124.9371 -268.303808)
			(xy 124.939298 -268.298676) (xy 124.94851 -268.276836) (xy 124.972365 -268.23588) (xy 125.002037 -268.19892)
			(xy 125.036869 -268.166777) (xy 125.076088 -268.140163) (xy 125.118824 -268.119668) (xy 125.16413 -268.105747)
			(xy 125.211002 -268.098708) (xy 125.2347 -268.09827) (xy 125.253353 -268.098511) (xy 125.290407 -268.102843)
			(xy 125.308614 -268.106906) (xy 125.312169 -268.107757) (xy 125.319438 -268.108516) (xy 125.323092 -268.10843)
			(xy 125.342689 -268.107836) (xy 125.381563 -268.112888) (xy 125.41886 -268.124955) (xy 125.453325 -268.143632)
			(xy 125.483799 -268.16829) (xy 125.509257 -268.198099) (xy 125.519434 -268.214856) (xy 125.646942 -268.435582)
			(xy 125.639068 -268.440154) (xy 125.630655 -268.445578) (xy 125.618495 -268.461452) (xy 125.61333 -268.48077)
			(xy 125.615947 -268.500594) (xy 125.620526 -268.509496) (xy 125.70206 -268.65072) (xy 125.706656 -268.659613)
			(xy 125.70927 -268.679442) (xy 125.704099 -268.698762) (xy 125.691931 -268.714635) (xy 125.683518 -268.720062)
			(xy 125.24359 -268.974062) (xy 125.234691 -268.978646) (xy 125.214866 -268.981263) (xy 125.195548 -268.976096)
			(xy 125.179675 -268.963932) (xy 125.174248 -268.95552) (xy 125.06706 -268.769846) (xy 125.058932 -268.774672)
			(xy 125.050016 -268.77927) (xy 125.03014 -268.781852) (xy 125.010794 -268.776617) (xy 124.994933 -268.764365)
			(xy 124.98959 -268.755876) (xy 124.88799 -268.5796) (xy 124.878093 -268.561658) (xy 124.864728 -268.522925)
			(xy 124.858989 -268.482356) (xy 123.854972 -268.482356) (xy 123.854972 -268.672564) (xy 123.85455 -268.682586)
			(xy 123.846887 -268.701108) (xy 123.832715 -268.715282) (xy 123.814194 -268.722949) (xy 123.804172 -268.723364)
			(xy 123.590304 -268.723364) (xy 123.590304 -268.732508) (xy 123.589818 -268.742516) (xy 123.582157 -268.761007)
			(xy 123.568003 -268.775159) (xy 123.549512 -268.782819) (xy 123.539504 -268.783308) (xy 123.335288 -268.783308)
			(xy 123.314775 -268.782806) (xy 123.274515 -268.774916) (xy 123.236501 -268.759484) (xy 123.202132 -268.73708)
			(xy 123.172672 -268.708527) (xy 123.149205 -268.674875) (xy 123.14047 -268.656308) (xy 123.138448 -268.652084)
			(xy 123.133078 -268.644414) (xy 123.129802 -268.641068) (xy 123.112497 -268.623055) (xy 123.083177 -268.582619)
			(xy 123.060534 -268.538098) (xy 123.045123 -268.490587) (xy 123.037324 -268.441252) (xy 123.036838 -268.416278)
			(xy 121.949972 -268.416278) (xy 121.949972 -268.672564) (xy 121.94955 -268.682586) (xy 121.941887 -268.701108)
			(xy 121.927715 -268.715282) (xy 121.909194 -268.722949) (xy 121.899172 -268.723364) (xy 121.685304 -268.723364)
			(xy 121.685304 -268.732508) (xy 121.684818 -268.742516) (xy 121.677157 -268.761007) (xy 121.663003 -268.775159)
			(xy 121.644512 -268.782819) (xy 121.634504 -268.783308) (xy 121.430288 -268.783308) (xy 121.409706 -268.782811)
			(xy 121.369305 -268.774916) (xy 121.331168 -268.759422) (xy 121.296709 -268.736904) (xy 121.267206 -268.708196)
			(xy 121.243755 -268.674365) (xy 121.227225 -268.636665) (xy 121.222262 -268.616684) (xy 121.221033 -268.611946)
			(xy 121.217077 -268.602994) (xy 121.214388 -268.598904) (xy 121.200786 -268.578728) (xy 121.179244 -268.535099)
			(xy 121.164598 -268.488697) (xy 121.157191 -268.440607) (xy 121.15673 -268.416278) (xy 120.044972 -268.416278)
			(xy 120.044972 -268.672564) (xy 120.04455 -268.682586) (xy 120.036887 -268.701108) (xy 120.022715 -268.715282)
			(xy 120.004194 -268.722949) (xy 119.994172 -268.723364) (xy 119.780304 -268.723364) (xy 119.780304 -268.732508)
			(xy 119.779818 -268.742516) (xy 119.772157 -268.761007) (xy 119.758003 -268.775159) (xy 119.739512 -268.782819)
			(xy 119.729504 -268.783308) (xy 119.525288 -268.783308) (xy 119.504206 -268.782887) (xy 119.462861 -268.774615)
			(xy 119.423942 -268.758394) (xy 119.38896 -268.734855) (xy 119.359274 -268.704912) (xy 119.336038 -268.669728)
			(xy 119.320153 -268.63067) (xy 119.312239 -268.589256) (xy 119.311928 -268.56817) (xy 119.311928 -268.562074)
			(xy 119.300791 -268.539402) (xy 119.285037 -268.491413) (xy 119.277085 -268.441533) (xy 119.276622 -268.416278)
			(xy 118.266972 -268.416278) (xy 118.266972 -268.672564) (xy 118.26655 -268.682586) (xy 118.258887 -268.701108)
			(xy 118.244715 -268.715282) (xy 118.226194 -268.722949) (xy 118.216172 -268.723364) (xy 118.002304 -268.723364)
			(xy 118.002304 -268.732508) (xy 118.001818 -268.742516) (xy 117.994157 -268.761007) (xy 117.980003 -268.775159)
			(xy 117.961512 -268.782819) (xy 117.951504 -268.783308) (xy 117.747288 -268.783308) (xy 117.724967 -268.782816)
			(xy 117.681297 -268.773549) (xy 117.64051 -268.755404) (xy 117.604388 -268.729172) (xy 117.589046 -268.71295)
			(xy 117.585781 -268.709509) (xy 117.578247 -268.703749) (xy 117.57406 -268.70152) (xy 117.551605 -268.689885)
			(xy 117.510378 -268.660599) (xy 117.474301 -268.625162) (xy 117.444282 -268.584465) (xy 117.421077 -268.539532)
			(xy 117.405271 -268.491495) (xy 117.397261 -268.441563) (xy 117.396768 -268.416278) (xy 116.361972 -268.416278)
			(xy 116.361972 -268.672564) (xy 116.36155 -268.682586) (xy 116.353887 -268.701108) (xy 116.339715 -268.715282)
			(xy 116.321194 -268.722949) (xy 116.311172 -268.723364) (xy 116.097304 -268.723364) (xy 116.097304 -268.732508)
			(xy 116.096818 -268.742516) (xy 116.089157 -268.761007) (xy 116.075003 -268.775159) (xy 116.056512 -268.782819)
			(xy 116.046504 -268.783308) (xy 115.842288 -268.783308) (xy 115.82162 -268.78278) (xy 115.781064 -268.774777)
			(xy 115.742795 -268.759147) (xy 115.708233 -268.73647) (xy 115.678659 -268.707588) (xy 115.66652 -268.690852)
			(xy 115.663876 -268.687131) (xy 115.657491 -268.68061) (xy 115.65382 -268.677898) (xy 115.633071 -268.662874)
			(xy 115.596154 -268.627365) (xy 115.565403 -268.5864) (xy 115.541613 -268.541037) (xy 115.525399 -268.492448)
			(xy 115.51718 -268.441889) (xy 115.51666 -268.416278) (xy 114.456972 -268.416278) (xy 114.456972 -268.672564)
			(xy 114.45655 -268.682586) (xy 114.448887 -268.701108) (xy 114.434715 -268.715282) (xy 114.416194 -268.722949)
			(xy 114.406172 -268.723364) (xy 114.192304 -268.723364) (xy 114.192304 -268.732508) (xy 114.191818 -268.742516)
			(xy 114.184157 -268.761007) (xy 114.170003 -268.775159) (xy 114.151512 -268.782819) (xy 114.141504 -268.783308)
			(xy 113.937288 -268.783308) (xy 113.917043 -268.782852) (xy 113.877284 -268.775195) (xy 113.839683 -268.760177)
			(xy 113.805589 -268.738337) (xy 113.776225 -268.710459) (xy 113.752646 -268.677543) (xy 113.74374 -268.659356)
			(xy 113.741714 -268.655135) (xy 113.736347 -268.647463) (xy 113.733072 -268.644116) (xy 113.715176 -268.626057)
			(xy 113.684834 -268.585262) (xy 113.661374 -268.540157) (xy 113.645395 -268.491892) (xy 113.637304 -268.441699)
			(xy 113.636806 -268.416278) (xy 109.757972 -268.416278) (xy 109.757972 -268.672564) (xy 109.75755 -268.682586)
			(xy 109.749887 -268.701108) (xy 109.735715 -268.715282) (xy 109.717194 -268.722949) (xy 109.707172 -268.723364)
			(xy 109.493304 -268.723364) (xy 109.493304 -268.732508) (xy 109.492818 -268.742516) (xy 109.485157 -268.761007)
			(xy 109.471003 -268.775159) (xy 109.452512 -268.782819) (xy 109.442504 -268.783308) (xy 109.238288 -268.783308)
			(xy 109.217312 -268.782829) (xy 109.176162 -268.774663) (xy 109.137403 -268.75861) (xy 109.10253 -268.735289)
			(xy 109.07289 -268.705601) (xy 109.049626 -268.67069) (xy 109.041184 -268.651482) (xy 109.039289 -268.647222)
			(xy 109.034174 -268.639426) (xy 109.031024 -268.635988) (xy 109.014593 -268.618134) (xy 108.986826 -268.578344)
			(xy 108.965429 -268.534797) (xy 108.950899 -268.488503) (xy 108.943574 -268.440539) (xy 108.94314 -268.416278)
			(xy 107.852972 -268.416278) (xy 107.852972 -268.672564) (xy 107.85255 -268.682586) (xy 107.844887 -268.701108)
			(xy 107.830715 -268.715282) (xy 107.812194 -268.722949) (xy 107.802172 -268.723364) (xy 107.588304 -268.723364)
			(xy 107.588304 -268.732508) (xy 107.587818 -268.742516) (xy 107.580157 -268.761007) (xy 107.566003 -268.775159)
			(xy 107.547512 -268.782819) (xy 107.537504 -268.783308) (xy 107.333288 -268.783308) (xy 107.312283 -268.782891)
			(xy 107.271083 -268.774691) (xy 107.232282 -268.75859) (xy 107.197381 -268.735209) (xy 107.167727 -268.705454)
			(xy 107.144466 -268.670473) (xy 107.128498 -268.631617) (xy 107.123992 -268.611096) (xy 107.122946 -268.606242)
			(xy 107.119238 -268.597032) (xy 107.116626 -268.592808) (xy 107.10399 -268.5731) (xy 107.08398 -268.530779)
			(xy 107.070376 -268.485986) (xy 107.063472 -268.439684) (xy 107.063032 -268.416278) (xy 106.074972 -268.416278)
			(xy 106.074972 -268.672564) (xy 106.07455 -268.682586) (xy 106.066887 -268.701108) (xy 106.052715 -268.715282)
			(xy 106.034194 -268.722949) (xy 106.024172 -268.723364) (xy 105.810304 -268.723364) (xy 105.810304 -268.732508)
			(xy 105.809818 -268.742516) (xy 105.802157 -268.761007) (xy 105.788003 -268.775159) (xy 105.769512 -268.782819)
			(xy 105.759504 -268.783308) (xy 105.555288 -268.783308) (xy 105.535282 -268.782818) (xy 105.495981 -268.775296)
			(xy 105.458767 -268.760593) (xy 105.424938 -268.739221) (xy 105.41 -268.725904) (xy 105.406138 -268.722464)
			(xy 105.397304 -268.717088) (xy 105.392474 -268.715236) (xy 105.369757 -268.706551) (xy 105.327101 -268.683188)
			(xy 105.288498 -268.653604) (xy 105.254849 -268.618488) (xy 105.226939 -268.578659) (xy 105.205416 -268.535046)
			(xy 105.190784 -268.488664) (xy 105.183384 -268.440596) (xy 105.182924 -268.416278) (xy 104.169972 -268.416278)
			(xy 104.169972 -268.672564) (xy 104.16955 -268.682586) (xy 104.161887 -268.701108) (xy 104.147715 -268.715282)
			(xy 104.129194 -268.722949) (xy 104.119172 -268.723364) (xy 103.905304 -268.723364) (xy 103.905304 -268.732508)
			(xy 103.904818 -268.742516) (xy 103.897157 -268.761007) (xy 103.883003 -268.775159) (xy 103.864512 -268.782819)
			(xy 103.854504 -268.783308) (xy 103.650288 -268.783308) (xy 103.627581 -268.782665) (xy 103.583203 -268.773005)
			(xy 103.54186 -268.754206) (xy 103.505409 -268.727114) (xy 103.490014 -268.71041) (xy 103.486784 -268.70688)
			(xy 103.479241 -268.700995) (xy 103.475028 -268.698726) (xy 103.453165 -268.686898) (xy 103.413097 -268.657482)
			(xy 103.378096 -268.622188) (xy 103.349014 -268.581878) (xy 103.32656 -268.537532) (xy 103.31128 -268.490232)
			(xy 103.303548 -268.441131) (xy 103.30307 -268.416278) (xy 102.264972 -268.416278) (xy 102.264972 -268.672564)
			(xy 102.26455 -268.682586) (xy 102.256887 -268.701108) (xy 102.242715 -268.715282) (xy 102.224194 -268.722949)
			(xy 102.214172 -268.723364) (xy 102.000304 -268.723364) (xy 102.000304 -268.732508) (xy 101.999818 -268.742516)
			(xy 101.992157 -268.761007) (xy 101.978003 -268.775159) (xy 101.959512 -268.782819) (xy 101.949504 -268.783308)
			(xy 101.745288 -268.783308) (xy 101.72418 -268.782798) (xy 101.682799 -268.774433) (xy 101.643864 -268.75811)
			(xy 101.60889 -268.734464) (xy 101.579236 -268.704414) (xy 101.567234 -268.687042) (xy 101.564593 -268.683264)
			(xy 101.558206 -268.67662) (xy 101.554534 -268.673834) (xy 101.534546 -268.658753) (xy 101.49908 -268.623412)
			(xy 101.469591 -268.582949) (xy 101.446809 -268.538364) (xy 101.431296 -268.49076) (xy 101.423437 -268.441312)
			(xy 101.422962 -268.416278) (xy 100.359972 -268.416278) (xy 100.359972 -268.672564) (xy 100.35955 -268.682586)
			(xy 100.351887 -268.701108) (xy 100.337715 -268.715282) (xy 100.319194 -268.722949) (xy 100.309172 -268.723364)
			(xy 100.095304 -268.723364) (xy 100.095304 -268.732508) (xy 100.094818 -268.742516) (xy 100.087157 -268.761007)
			(xy 100.073003 -268.775159) (xy 100.054512 -268.782819) (xy 100.044504 -268.783308) (xy 99.840288 -268.783308)
			(xy 99.819616 -268.782776) (xy 99.779055 -268.774763) (xy 99.740792 -268.759096) (xy 99.706259 -268.736361)
			(xy 99.676745 -268.707406) (xy 99.653352 -268.673315) (xy 99.644708 -268.65453) (xy 99.642751 -268.650259)
			(xy 99.637504 -268.642466) (xy 99.634294 -268.639036) (xy 99.617314 -268.621092) (xy 99.58854 -268.580938)
			(xy 99.566331 -268.536813) (xy 99.551221 -268.489782) (xy 99.543576 -268.440978) (xy 99.543108 -268.416278)
			(xy 98.527616 -268.416278) (xy 98.527616 -268.43609) (xy 98.527362 -268.440408) (xy 98.525584 -268.46276)
			(xy 98.522356 -268.495135) (xy 98.509175 -268.558849) (xy 98.488519 -268.620548) (xy 98.460682 -268.679356)
			(xy 98.426058 -268.734442) (xy 98.385136 -268.785025) (xy 98.338496 -268.830391) (xy 98.286799 -268.869896)
			(xy 98.230775 -268.902982) (xy 98.171218 -268.929179) (xy 98.108972 -268.948118) (xy 98.07702 -268.95425)
			(xy 98.058224 -268.957552) (xy 98.054414 -268.95806) (xy 98.023172 -268.961362) (xy 98.002852 -268.974316)
			(xy 97.996502 -268.98473) (xy 97.966873 -269.033202) (xy 97.899179 -269.124443) (xy 97.861374 -269.166848)
			(xy 97.855024 -269.173706) (xy 97.841562 -269.207742) (xy 97.841816 -269.217902) (xy 97.841816 -269.224506)
			(xy 97.841816 -269.226284) (xy 99.072954 -269.226284) (xy 99.073467 -269.201296) (xy 99.081287 -269.151936)
			(xy 99.096731 -269.104407) (xy 99.119419 -269.059879) (xy 99.148794 -269.019447) (xy 99.18413 -268.984108)
			(xy 99.22456 -268.954731) (xy 99.269087 -268.932039) (xy 99.316615 -268.916592) (xy 99.365974 -268.908769)
			(xy 99.390962 -268.908276) (xy 99.414143 -268.908704) (xy 99.460012 -268.915447) (xy 99.504411 -268.928796)
			(xy 99.525582 -268.938248) (xy 99.535742 -268.94282) (xy 99.557332 -268.94282) (xy 99.587304 -268.972792)
			(xy 99.587304 -268.976094) (xy 99.60356 -268.98981) (xy 99.610742 -268.995817) (xy 99.628237 -269.00246)
			(xy 99.637596 -269.002764) (xy 99.801172 -269.002764) (xy 99.811173 -269.00331) (xy 99.829658 -269.010954)
			(xy 99.843811 -269.025088) (xy 99.851477 -269.043563) (xy 99.851972 -269.053564) (xy 99.851972 -269.226284)
			(xy 101.893116 -269.226284) (xy 101.893542 -269.201291) (xy 101.901364 -269.151921) (xy 101.916813 -269.104383)
			(xy 101.939509 -269.059846) (xy 101.968892 -269.019409) (xy 102.004239 -268.984066) (xy 102.044681 -268.954688)
			(xy 102.08922 -268.931998) (xy 102.13676 -268.916554) (xy 102.186131 -268.908739) (xy 102.211124 -268.908276)
			(xy 102.234305 -268.908718) (xy 102.280173 -268.915455) (xy 102.324573 -268.928799) (xy 102.345744 -268.938248)
			(xy 102.355904 -268.94282) (xy 102.508304 -268.94282) (xy 102.508304 -268.951964) (xy 102.508849 -268.961958)
			(xy 102.516526 -268.980416) (xy 102.530657 -268.994556) (xy 102.54911 -269.002245) (xy 102.559104 -269.002764)
			(xy 102.722172 -269.002764) (xy 102.732173 -269.00331) (xy 102.750658 -269.010954) (xy 102.764811 -269.025088)
			(xy 102.772477 -269.043563) (xy 102.772972 -269.053564) (xy 102.772972 -269.226284) (xy 104.713024 -269.226284)
			(xy 104.713442 -269.201291) (xy 104.721264 -269.15192) (xy 104.736714 -269.104381) (xy 104.75941 -269.059844)
			(xy 104.788794 -269.019406) (xy 104.824143 -268.984063) (xy 104.864585 -268.954685) (xy 104.909125 -268.931995)
			(xy 104.956667 -268.916553) (xy 105.006039 -268.908738) (xy 105.031032 -268.908276) (xy 105.054213 -268.908715)
			(xy 105.100082 -268.915454) (xy 105.144481 -268.928798) (xy 105.165652 -268.938248) (xy 105.175812 -268.94282)
			(xy 105.302304 -268.94282) (xy 105.302304 -268.951964) (xy 105.302849 -268.961958) (xy 105.310526 -268.980416)
			(xy 105.324657 -268.994556) (xy 105.34311 -269.002245) (xy 105.353104 -269.002764) (xy 105.516172 -269.002764)
			(xy 105.526173 -269.00331) (xy 105.544658 -269.010954) (xy 105.558811 -269.025088) (xy 105.566477 -269.043563)
			(xy 105.566972 -269.053564) (xy 105.566972 -269.561564) (xy 107.3658 -269.561564) (xy 107.3658 -269.053564)
			(xy 107.366259 -269.043554) (xy 107.37393 -269.025061) (xy 107.388092 -269.01091) (xy 107.40659 -269.003251)
			(xy 107.4166 -269.002764) (xy 107.624626 -269.002764) (xy 107.630468 -268.996922) (xy 107.630468 -268.99362)
			(xy 107.630953 -268.983623) (xy 107.638661 -268.965169) (xy 107.65281 -268.951034) (xy 107.671271 -268.943343)
			(xy 107.681268 -268.94282) (xy 107.70616 -268.94282) (xy 107.71632 -268.938248) (xy 107.737497 -268.928815)
			(xy 107.781898 -268.915482) (xy 107.827761 -268.908718) (xy 107.85094 -268.908276) (xy 107.875929 -268.908745)
			(xy 107.925292 -268.916569) (xy 107.972824 -268.932018) (xy 108.017354 -268.954711) (xy 108.057786 -268.98409)
			(xy 108.093125 -269.019432) (xy 108.122501 -269.059867) (xy 108.145191 -269.104398) (xy 108.160636 -269.151931)
			(xy 108.168457 -269.201294) (xy 108.168948 -269.226284) (xy 108.474759 -269.226284) (xy 108.478854 -269.175556)
			(xy 108.491033 -269.126142) (xy 108.510981 -269.079322) (xy 108.538182 -269.036308) (xy 108.57193 -268.998214)
			(xy 108.611352 -268.966027) (xy 108.655426 -268.940581) (xy 108.703012 -268.922534) (xy 108.752876 -268.912354)
			(xy 108.803728 -268.910305) (xy 108.854249 -268.916439) (xy 108.903133 -268.930599) (xy 108.949112 -268.952416)
			(xy 108.990996 -268.981326) (xy 109.0277 -269.016581) (xy 109.058273 -269.057267) (xy 109.081924 -269.10233)
			(xy 109.09804 -269.150604) (xy 109.106204 -269.200838) (xy 109.106716 -269.226284) (xy 109.414813 -269.226284)
			(xy 109.418908 -269.175556) (xy 109.431087 -269.126142) (xy 109.451035 -269.079322) (xy 109.478236 -269.036308)
			(xy 109.511984 -268.998214) (xy 109.551406 -268.966027) (xy 109.59548 -268.940581) (xy 109.643066 -268.922534)
			(xy 109.69293 -268.912354) (xy 109.743782 -268.910305) (xy 109.794303 -268.916439) (xy 109.843187 -268.930599)
			(xy 109.889166 -268.952416) (xy 109.93105 -268.981326) (xy 109.967754 -269.016581) (xy 109.998327 -269.057267)
			(xy 110.021978 -269.10233) (xy 110.038094 -269.150604) (xy 110.046258 -269.200838) (xy 110.04677 -269.226284)
			(xy 110.046267 -269.251273) (xy 110.353584 -269.251273) (xy 110.353584 -269.201295) (xy 110.361403 -269.151932)
			(xy 110.376847 -269.1044) (xy 110.399537 -269.059868) (xy 110.428913 -269.019435) (xy 110.464253 -268.984095)
			(xy 110.504686 -268.954719) (xy 110.549218 -268.932029) (xy 110.59675 -268.916585) (xy 110.646113 -268.908766)
			(xy 110.696091 -268.908766) (xy 110.745454 -268.916585) (xy 110.792986 -268.932029) (xy 110.837518 -268.954719)
			(xy 110.877951 -268.984095) (xy 110.913291 -269.019435) (xy 110.942667 -269.059868) (xy 110.965357 -269.1044)
			(xy 110.980801 -269.151932) (xy 110.98862 -269.201295) (xy 110.98911 -269.226284) (xy 110.98862 -269.251273)
			(xy 113.167142 -269.251273) (xy 113.167142 -269.201295) (xy 113.174961 -269.151932) (xy 113.190405 -269.1044)
			(xy 113.213095 -269.059868) (xy 113.242471 -269.019435) (xy 113.277811 -268.984095) (xy 113.318244 -268.954719)
			(xy 113.362776 -268.932029) (xy 113.410308 -268.916585) (xy 113.459671 -268.908766) (xy 113.509649 -268.908766)
			(xy 113.559012 -268.916585) (xy 113.606544 -268.932029) (xy 113.651076 -268.954719) (xy 113.691509 -268.984095)
			(xy 113.726849 -269.019435) (xy 113.756225 -269.059868) (xy 113.778915 -269.1044) (xy 113.794359 -269.151932)
			(xy 113.802178 -269.201295) (xy 113.802668 -269.226284) (xy 114.108479 -269.226284) (xy 114.112574 -269.175556)
			(xy 114.124753 -269.126142) (xy 114.144701 -269.079322) (xy 114.171902 -269.036308) (xy 114.20565 -268.998214)
			(xy 114.245072 -268.966027) (xy 114.289146 -268.940581) (xy 114.336732 -268.922534) (xy 114.386596 -268.912354)
			(xy 114.437448 -268.910305) (xy 114.487969 -268.916439) (xy 114.536853 -268.930599) (xy 114.582832 -268.952416)
			(xy 114.624716 -268.981326) (xy 114.66142 -269.016581) (xy 114.691993 -269.057267) (xy 114.715644 -269.10233)
			(xy 114.73176 -269.150604) (xy 114.739924 -269.200838) (xy 114.740436 -269.226284) (xy 115.048533 -269.226284)
			(xy 115.052628 -269.175556) (xy 115.064807 -269.126142) (xy 115.084755 -269.079322) (xy 115.111956 -269.036308)
			(xy 115.145704 -268.998214) (xy 115.185126 -268.966027) (xy 115.2292 -268.940581) (xy 115.276786 -268.922534)
			(xy 115.32665 -268.912354) (xy 115.377502 -268.910305) (xy 115.428023 -268.916439) (xy 115.476907 -268.930599)
			(xy 115.522886 -268.952416) (xy 115.56477 -268.981326) (xy 115.601474 -269.016581) (xy 115.632047 -269.057267)
			(xy 115.655698 -269.10233) (xy 115.671814 -269.150604) (xy 115.679978 -269.200838) (xy 115.68049 -269.226284)
			(xy 115.986814 -269.226284) (xy 115.987242 -269.201291) (xy 115.995064 -269.151922) (xy 116.010513 -269.104383)
			(xy 116.033208 -269.059847) (xy 116.062591 -269.01941) (xy 116.097939 -268.984067) (xy 116.13838 -268.954688)
			(xy 116.182918 -268.931998) (xy 116.230459 -268.916555) (xy 116.279829 -268.908739) (xy 116.304822 -268.908276)
			(xy 116.328003 -268.908718) (xy 116.373871 -268.915456) (xy 116.418271 -268.928799) (xy 116.439442 -268.938248)
			(xy 116.449602 -268.94282) (xy 116.605304 -268.94282) (xy 116.605304 -268.951964) (xy 116.605849 -268.961958)
			(xy 116.613526 -268.980416) (xy 116.627657 -268.994556) (xy 116.64611 -269.002245) (xy 116.656104 -269.002764)
			(xy 116.819172 -269.002764) (xy 116.829173 -269.00331) (xy 116.847658 -269.010954) (xy 116.861811 -269.025088)
			(xy 116.869477 -269.043563) (xy 116.869972 -269.053564) (xy 116.869972 -269.561564) (xy 118.6688 -269.561564)
			(xy 118.6688 -269.053564) (xy 118.669259 -269.043554) (xy 118.67693 -269.025061) (xy 118.691092 -269.01091)
			(xy 118.70959 -269.003251) (xy 118.7196 -269.002764) (xy 118.878096 -269.002764) (xy 118.887431 -269.002338)
			(xy 118.904883 -268.995706) (xy 118.912132 -268.98981) (xy 118.916196 -268.986254) (xy 118.924059 -268.978685)
			(xy 118.933009 -268.958804) (xy 118.933468 -268.9479) (xy 118.933468 -268.94282) (xy 118.97995 -268.94282)
			(xy 118.99011 -268.938248) (xy 119.011289 -268.928818) (xy 119.055689 -268.915484) (xy 119.101551 -268.908719)
			(xy 119.12473 -268.908276) (xy 119.149719 -268.908755) (xy 119.199082 -268.916577) (xy 119.246613 -268.932024)
			(xy 119.291143 -268.954716) (xy 119.331575 -268.984094) (xy 119.366915 -269.019435) (xy 119.396291 -269.059869)
			(xy 119.418981 -269.1044) (xy 119.434426 -269.151932) (xy 119.442247 -269.201295) (xy 119.442738 -269.226284)
			(xy 119.442244 -269.251537) (xy 119.434282 -269.30141) (xy 119.418554 -269.349403) (xy 119.407432 -269.37208)
			(xy 119.404638 -269.377668) (xy 119.401844 -269.389098) (xy 119.401844 -269.457424) (xy 119.40156 -269.478491)
			(xy 119.393591 -269.51986) (xy 119.37767 -269.558865) (xy 119.375883 -269.561564) (xy 121.5898 -269.561564)
			(xy 121.5898 -269.053564) (xy 121.590259 -269.043554) (xy 121.59793 -269.025061) (xy 121.612092 -269.01091)
			(xy 121.63059 -269.003251) (xy 121.6406 -269.002764) (xy 121.698004 -269.002764) (xy 121.707339 -269.002342)
			(xy 121.724792 -268.995707) (xy 121.73204 -268.98981) (xy 121.749624 -268.974519) (xy 121.788451 -268.948753)
			(xy 121.830624 -268.928931) (xy 121.875238 -268.915478) (xy 121.921339 -268.908681) (xy 121.944638 -268.908276)
			(xy 121.967819 -268.908713) (xy 122.013688 -268.915453) (xy 122.058087 -268.928798) (xy 122.079258 -268.938248)
			(xy 122.089418 -268.94282) (xy 122.109484 -268.94282) (xy 122.130545 -268.943338) (xy 122.17185 -268.95159)
			(xy 122.210737 -268.967775) (xy 122.245699 -268.991267) (xy 122.275379 -269.021155) (xy 122.298626 -269.05628)
			(xy 122.31454 -269.095279) (xy 122.322503 -269.13664) (xy 122.322844 -269.157704) (xy 122.322844 -269.457424)
			(xy 122.32256 -269.478491) (xy 122.314591 -269.51986) (xy 122.29867 -269.558865) (xy 122.275415 -269.593995)
			(xy 122.245727 -269.623886) (xy 122.210757 -269.647381) (xy 122.171862 -269.663569) (xy 122.130549 -269.671821)
			(xy 122.109484 -269.672308) (xy 121.854468 -269.672308) (xy 121.854468 -269.663164) (xy 121.85409 -269.653119)
			(xy 121.846494 -269.634529) (xy 121.832298 -269.620324) (xy 121.813713 -269.612716) (xy 121.803668 -269.612364)
			(xy 121.6406 -269.612364) (xy 121.630574 -269.61198) (xy 121.61205 -269.604303) (xy 121.597877 -269.590119)
			(xy 121.590213 -269.57159) (xy 121.5898 -269.561564) (xy 119.375883 -269.561564) (xy 119.354415 -269.593995)
			(xy 119.324727 -269.623886) (xy 119.289757 -269.647381) (xy 119.250862 -269.663569) (xy 119.209549 -269.671821)
			(xy 119.188484 -269.672308) (xy 118.933468 -269.672308) (xy 118.933468 -269.663164) (xy 118.93309 -269.653119)
			(xy 118.925494 -269.634529) (xy 118.911298 -269.620324) (xy 118.892713 -269.612716) (xy 118.882668 -269.612364)
			(xy 118.7196 -269.612364) (xy 118.709574 -269.61198) (xy 118.69105 -269.604303) (xy 118.676877 -269.590119)
			(xy 118.669213 -269.57159) (xy 118.6688 -269.561564) (xy 116.869972 -269.561564) (xy 116.86955 -269.571586)
			(xy 116.861887 -269.590108) (xy 116.847715 -269.604282) (xy 116.829194 -269.611949) (xy 116.819172 -269.612364)
			(xy 116.656104 -269.612364) (xy 116.646101 -269.612891) (xy 116.627616 -269.620542) (xy 116.613464 -269.634683)
			(xy 116.605798 -269.653161) (xy 116.605304 -269.663164) (xy 116.605304 -269.68958) (xy 116.605736 -269.6996)
			(xy 116.6134 -269.718118) (xy 116.627569 -269.732291) (xy 116.646084 -269.739961) (xy 116.656104 -269.74038)
			(xy 116.664486 -269.74038) (xy 116.67236 -269.73784) (xy 116.697183 -269.729795) (xy 116.748634 -269.721114)
			(xy 116.774722 -269.720568) (xy 116.79953 -269.721088) (xy 116.848533 -269.728853) (xy 116.895719 -269.744188)
			(xy 116.939925 -269.766716) (xy 116.980063 -269.795882) (xy 117.015144 -269.830967) (xy 117.044305 -269.871109)
			(xy 117.066827 -269.915318) (xy 117.082156 -269.962505) (xy 117.089915 -270.01151) (xy 117.089914 -270.03629)
			(xy 117.398541 -270.03629) (xy 117.402636 -269.985562) (xy 117.414815 -269.936148) (xy 117.434763 -269.889328)
			(xy 117.461964 -269.846314) (xy 117.495712 -269.80822) (xy 117.535134 -269.776033) (xy 117.579208 -269.750587)
			(xy 117.626794 -269.73254) (xy 117.676658 -269.72236) (xy 117.72751 -269.720311) (xy 117.778031 -269.726445)
			(xy 117.826915 -269.740605) (xy 117.872894 -269.762422) (xy 117.914778 -269.791332) (xy 117.951482 -269.826587)
			(xy 117.982055 -269.867273) (xy 118.005706 -269.912336) (xy 118.021822 -269.96061) (xy 118.029986 -270.010844)
			(xy 118.030498 -270.03629) (xy 118.029995 -270.061279) (xy 118.337312 -270.061279) (xy 118.337312 -270.011301)
			(xy 118.345131 -269.961938) (xy 118.360575 -269.914406) (xy 118.383265 -269.869874) (xy 118.412641 -269.829441)
			(xy 118.447981 -269.794101) (xy 118.488414 -269.764725) (xy 118.532946 -269.742035) (xy 118.580478 -269.726591)
			(xy 118.629841 -269.718772) (xy 118.679819 -269.718772) (xy 118.729182 -269.726591) (xy 118.776714 -269.742035)
			(xy 118.821246 -269.764725) (xy 118.861679 -269.794101) (xy 118.897019 -269.829441) (xy 118.926395 -269.869874)
			(xy 118.949085 -269.914406) (xy 118.964529 -269.961938) (xy 118.972348 -270.011301) (xy 118.972838 -270.03629)
			(xy 119.278395 -270.03629) (xy 119.28249 -269.985562) (xy 119.294669 -269.936148) (xy 119.314617 -269.889328)
			(xy 119.341818 -269.846314) (xy 119.375566 -269.80822) (xy 119.414988 -269.776033) (xy 119.459062 -269.750587)
			(xy 119.506648 -269.73254) (xy 119.556512 -269.72236) (xy 119.607364 -269.720311) (xy 119.657885 -269.726445)
			(xy 119.706769 -269.740605) (xy 119.752748 -269.762422) (xy 119.794632 -269.791332) (xy 119.831336 -269.826587)
			(xy 119.861909 -269.867273) (xy 119.88556 -269.912336) (xy 119.901676 -269.96061) (xy 119.90984 -270.010844)
			(xy 119.910352 -270.03629) (xy 120.218449 -270.03629) (xy 120.222544 -269.985562) (xy 120.234723 -269.936148)
			(xy 120.254671 -269.889328) (xy 120.281872 -269.846314) (xy 120.31562 -269.80822) (xy 120.355042 -269.776033)
			(xy 120.399116 -269.750587) (xy 120.446702 -269.73254) (xy 120.496566 -269.72236) (xy 120.547418 -269.720311)
			(xy 120.597939 -269.726445) (xy 120.646823 -269.740605) (xy 120.692802 -269.762422) (xy 120.734686 -269.791332)
			(xy 120.77139 -269.826587) (xy 120.801963 -269.867273) (xy 120.825614 -269.912336) (xy 120.84173 -269.96061)
			(xy 120.849894 -270.010844) (xy 120.850406 -270.03629) (xy 120.849903 -270.061279) (xy 121.15722 -270.061279)
			(xy 121.15722 -270.011301) (xy 121.165039 -269.961938) (xy 121.180483 -269.914406) (xy 121.203173 -269.869874)
			(xy 121.232549 -269.829441) (xy 121.267889 -269.794101) (xy 121.308322 -269.764725) (xy 121.352854 -269.742035)
			(xy 121.400386 -269.726591) (xy 121.449749 -269.718772) (xy 121.499727 -269.718772) (xy 121.54909 -269.726591)
			(xy 121.596622 -269.742035) (xy 121.641154 -269.764725) (xy 121.681587 -269.794101) (xy 121.716927 -269.829441)
			(xy 121.746303 -269.869874) (xy 121.768993 -269.914406) (xy 121.784437 -269.961938) (xy 121.792256 -270.011301)
			(xy 121.792746 -270.03629) (xy 122.098557 -270.03629) (xy 122.102652 -269.985562) (xy 122.114831 -269.936148)
			(xy 122.134779 -269.889328) (xy 122.16198 -269.846314) (xy 122.195728 -269.80822) (xy 122.23515 -269.776033)
			(xy 122.279224 -269.750587) (xy 122.32681 -269.73254) (xy 122.376674 -269.72236) (xy 122.427526 -269.720311)
			(xy 122.478047 -269.726445) (xy 122.526931 -269.740605) (xy 122.57291 -269.762422) (xy 122.614794 -269.791332)
			(xy 122.651498 -269.826587) (xy 122.682071 -269.867273) (xy 122.705722 -269.912336) (xy 122.721838 -269.96061)
			(xy 122.730002 -270.010844) (xy 122.730514 -270.03629) (xy 123.038611 -270.03629) (xy 123.042706 -269.985562)
			(xy 123.054885 -269.936148) (xy 123.074833 -269.889328) (xy 123.102034 -269.846314) (xy 123.135782 -269.80822)
			(xy 123.175204 -269.776033) (xy 123.219278 -269.750587) (xy 123.266864 -269.73254) (xy 123.316728 -269.72236)
			(xy 123.36758 -269.720311) (xy 123.418101 -269.726445) (xy 123.466985 -269.740605) (xy 123.512964 -269.762422)
			(xy 123.554848 -269.791332) (xy 123.591552 -269.826587) (xy 123.622125 -269.867273) (xy 123.645776 -269.912336)
			(xy 123.661892 -269.96061) (xy 123.670056 -270.010844) (xy 123.670568 -270.03629) (xy 123.976638 -270.03629)
			(xy 123.977146 -270.009908) (xy 123.985871 -269.957871) (xy 124.003063 -269.907987) (xy 124.028251 -269.861623)
			(xy 124.060744 -269.820051) (xy 124.099652 -269.784411) (xy 124.143907 -269.75568) (xy 124.192297 -269.734646)
			(xy 124.243494 -269.721884) (xy 124.269754 -269.719298) (xy 124.289566 -269.717774) (xy 124.31649 -269.688564)
			(xy 124.31649 -269.668752) (xy 124.316051 -269.65874) (xy 124.308374 -269.640245) (xy 124.294206 -269.626094)
			(xy 124.275702 -269.618438) (xy 124.26569 -269.617952) (xy 124.234448 -269.617952) (xy 124.224424 -269.61754)
			(xy 124.205899 -269.609877) (xy 124.191723 -269.595701) (xy 124.18406 -269.577176) (xy 124.183648 -269.567152)
			(xy 124.183648 -269.059152) (xy 124.18405 -269.049135) (xy 124.191734 -269.030633) (xy 124.205914 -269.01648)
			(xy 124.22443 -269.008831) (xy 124.234448 -269.008352) (xy 124.448316 -269.008352) (xy 124.448316 -268.999208)
			(xy 124.448842 -268.989217) (xy 124.456544 -268.970773) (xy 124.470679 -268.95664) (xy 124.489125 -268.94894)
			(xy 124.499116 -268.948408) (xy 124.603256 -268.948408) (xy 124.61494 -268.945868) (xy 124.620274 -268.943074)
			(xy 124.642769 -268.932103) (xy 124.69035 -268.916588) (xy 124.739777 -268.90874) (xy 124.7648 -268.908276)
			(xy 124.789788 -268.908782) (xy 124.83915 -268.9166) (xy 124.886681 -268.932043) (xy 124.931211 -268.954732)
			(xy 124.971643 -268.984106) (xy 125.006983 -269.019444) (xy 125.03636 -269.059876) (xy 125.059051 -269.104404)
			(xy 125.074496 -269.151935) (xy 125.082316 -269.201296) (xy 125.082808 -269.226284) (xy 125.08224 -269.253506)
			(xy 125.072946 -269.307151) (xy 125.054659 -269.358433) (xy 125.027914 -269.405855) (xy 124.99349 -269.448036)
			(xy 124.952391 -269.483745) (xy 124.929392 -269.498318) (xy 124.921698 -269.503538) (xy 124.910354 -269.518243)
			(xy 124.907294 -269.52702) (xy 124.901177 -269.54545) (xy 124.883231 -269.579881) (xy 124.859369 -269.61051)
			(xy 124.830373 -269.636333) (xy 124.797194 -269.656501) (xy 124.760921 -269.670353) (xy 124.722745 -269.677434)
			(xy 124.703332 -269.677896) (xy 124.62637 -269.677896) (xy 124.616942 -269.678277) (xy 124.599363 -269.685101)
			(xy 124.585437 -269.697814) (xy 124.580904 -269.70609) (xy 124.534168 -269.80134) (xy 124.537216 -269.830042)
			(xy 124.546106 -269.841472) (xy 124.561756 -269.86252) (xy 124.586636 -269.90869) (xy 124.603587 -269.958322)
			(xy 124.612147 -270.010066) (xy 124.612654 -270.03629) (xy 124.918465 -270.03629) (xy 124.92256 -269.985562)
			(xy 124.934739 -269.936148) (xy 124.954687 -269.889328) (xy 124.981888 -269.846314) (xy 125.015636 -269.80822)
			(xy 125.055058 -269.776033) (xy 125.099132 -269.750587) (xy 125.146718 -269.73254) (xy 125.196582 -269.72236)
			(xy 125.247434 -269.720311) (xy 125.297955 -269.726445) (xy 125.346839 -269.740605) (xy 125.392818 -269.762422)
			(xy 125.434702 -269.791332) (xy 125.471406 -269.826587) (xy 125.501979 -269.867273) (xy 125.52563 -269.912336)
			(xy 125.541746 -269.96061) (xy 125.54991 -270.010844) (xy 125.550422 -270.03629) (xy 125.858519 -270.03629)
			(xy 125.862614 -269.985562) (xy 125.874793 -269.936148) (xy 125.894741 -269.889328) (xy 125.921942 -269.846314)
			(xy 125.95569 -269.80822) (xy 125.995112 -269.776033) (xy 126.039186 -269.750587) (xy 126.086772 -269.73254)
			(xy 126.136636 -269.72236) (xy 126.187488 -269.720311) (xy 126.238009 -269.726445) (xy 126.286893 -269.740605)
			(xy 126.332872 -269.762422) (xy 126.374756 -269.791332) (xy 126.41146 -269.826587) (xy 126.442033 -269.867273)
			(xy 126.465684 -269.912336) (xy 126.4818 -269.96061) (xy 126.489964 -270.010844) (xy 126.490476 -270.03629)
			(xy 126.489964 -270.061736) (xy 126.4818 -270.11197) (xy 126.465684 -270.160244) (xy 126.442033 -270.205307)
			(xy 126.41146 -270.245993) (xy 126.374756 -270.281248) (xy 126.332872 -270.310158) (xy 126.286893 -270.331975)
			(xy 126.238009 -270.346135) (xy 126.187488 -270.352269) (xy 126.136636 -270.35022) (xy 126.086772 -270.34004)
			(xy 126.039186 -270.321993) (xy 125.995112 -270.296547) (xy 125.95569 -270.26436) (xy 125.921942 -270.226266)
			(xy 125.894741 -270.183252) (xy 125.874793 -270.136432) (xy 125.862614 -270.087018) (xy 125.858519 -270.03629)
			(xy 125.550422 -270.03629) (xy 125.54991 -270.061736) (xy 125.541746 -270.11197) (xy 125.52563 -270.160244)
			(xy 125.501979 -270.205307) (xy 125.471406 -270.245993) (xy 125.434702 -270.281248) (xy 125.392818 -270.310158)
			(xy 125.346839 -270.331975) (xy 125.297955 -270.346135) (xy 125.247434 -270.352269) (xy 125.196582 -270.35022)
			(xy 125.146718 -270.34004) (xy 125.099132 -270.321993) (xy 125.055058 -270.296547) (xy 125.015636 -270.26436)
			(xy 124.981888 -270.226266) (xy 124.954687 -270.183252) (xy 124.934739 -270.136432) (xy 124.92256 -270.087018)
			(xy 124.918465 -270.03629) (xy 124.612654 -270.03629) (xy 124.612164 -270.061279) (xy 124.604345 -270.110642)
			(xy 124.588901 -270.158174) (xy 124.566211 -270.202706) (xy 124.536835 -270.243139) (xy 124.501495 -270.278479)
			(xy 124.461062 -270.307855) (xy 124.41653 -270.330545) (xy 124.368998 -270.345989) (xy 124.319635 -270.353808)
			(xy 124.269657 -270.353808) (xy 124.220294 -270.345989) (xy 124.172762 -270.330545) (xy 124.12823 -270.307855)
			(xy 124.087797 -270.278479) (xy 124.052457 -270.243139) (xy 124.023081 -270.202706) (xy 124.000391 -270.158174)
			(xy 123.984947 -270.110642) (xy 123.977128 -270.061279) (xy 123.976638 -270.03629) (xy 123.670568 -270.03629)
			(xy 123.670056 -270.061736) (xy 123.661892 -270.11197) (xy 123.645776 -270.160244) (xy 123.622125 -270.205307)
			(xy 123.591552 -270.245993) (xy 123.554848 -270.281248) (xy 123.512964 -270.310158) (xy 123.466985 -270.331975)
			(xy 123.418101 -270.346135) (xy 123.36758 -270.352269) (xy 123.316728 -270.35022) (xy 123.266864 -270.34004)
			(xy 123.219278 -270.321993) (xy 123.175204 -270.296547) (xy 123.135782 -270.26436) (xy 123.102034 -270.226266)
			(xy 123.074833 -270.183252) (xy 123.054885 -270.136432) (xy 123.042706 -270.087018) (xy 123.038611 -270.03629)
			(xy 122.730514 -270.03629) (xy 122.730002 -270.061736) (xy 122.721838 -270.11197) (xy 122.705722 -270.160244)
			(xy 122.682071 -270.205307) (xy 122.651498 -270.245993) (xy 122.614794 -270.281248) (xy 122.57291 -270.310158)
			(xy 122.526931 -270.331975) (xy 122.478047 -270.346135) (xy 122.427526 -270.352269) (xy 122.376674 -270.35022)
			(xy 122.32681 -270.34004) (xy 122.279224 -270.321993) (xy 122.23515 -270.296547) (xy 122.195728 -270.26436)
			(xy 122.16198 -270.226266) (xy 122.134779 -270.183252) (xy 122.114831 -270.136432) (xy 122.102652 -270.087018)
			(xy 122.098557 -270.03629) (xy 121.792746 -270.03629) (xy 121.792256 -270.061279) (xy 121.784437 -270.110642)
			(xy 121.768993 -270.158174) (xy 121.746303 -270.202706) (xy 121.716927 -270.243139) (xy 121.681587 -270.278479)
			(xy 121.641154 -270.307855) (xy 121.596622 -270.330545) (xy 121.54909 -270.345989) (xy 121.499727 -270.353808)
			(xy 121.449749 -270.353808) (xy 121.400386 -270.345989) (xy 121.352854 -270.330545) (xy 121.308322 -270.307855)
			(xy 121.267889 -270.278479) (xy 121.232549 -270.243139) (xy 121.203173 -270.202706) (xy 121.180483 -270.158174)
			(xy 121.165039 -270.110642) (xy 121.15722 -270.061279) (xy 120.849903 -270.061279) (xy 120.849894 -270.061736)
			(xy 120.84173 -270.11197) (xy 120.825614 -270.160244) (xy 120.801963 -270.205307) (xy 120.77139 -270.245993)
			(xy 120.734686 -270.281248) (xy 120.692802 -270.310158) (xy 120.646823 -270.331975) (xy 120.597939 -270.346135)
			(xy 120.547418 -270.352269) (xy 120.496566 -270.35022) (xy 120.446702 -270.34004) (xy 120.399116 -270.321993)
			(xy 120.355042 -270.296547) (xy 120.31562 -270.26436) (xy 120.281872 -270.226266) (xy 120.254671 -270.183252)
			(xy 120.234723 -270.136432) (xy 120.222544 -270.087018) (xy 120.218449 -270.03629) (xy 119.910352 -270.03629)
			(xy 119.90984 -270.061736) (xy 119.901676 -270.11197) (xy 119.88556 -270.160244) (xy 119.861909 -270.205307)
			(xy 119.831336 -270.245993) (xy 119.794632 -270.281248) (xy 119.752748 -270.310158) (xy 119.706769 -270.331975)
			(xy 119.657885 -270.346135) (xy 119.607364 -270.352269) (xy 119.556512 -270.35022) (xy 119.506648 -270.34004)
			(xy 119.459062 -270.321993) (xy 119.414988 -270.296547) (xy 119.375566 -270.26436) (xy 119.341818 -270.226266)
			(xy 119.314617 -270.183252) (xy 119.294669 -270.136432) (xy 119.28249 -270.087018) (xy 119.278395 -270.03629)
			(xy 118.972838 -270.03629) (xy 118.972348 -270.061279) (xy 118.964529 -270.110642) (xy 118.949085 -270.158174)
			(xy 118.926395 -270.202706) (xy 118.897019 -270.243139) (xy 118.861679 -270.278479) (xy 118.821246 -270.307855)
			(xy 118.776714 -270.330545) (xy 118.729182 -270.345989) (xy 118.679819 -270.353808) (xy 118.629841 -270.353808)
			(xy 118.580478 -270.345989) (xy 118.532946 -270.330545) (xy 118.488414 -270.307855) (xy 118.447981 -270.278479)
			(xy 118.412641 -270.243139) (xy 118.383265 -270.202706) (xy 118.360575 -270.158174) (xy 118.345131 -270.110642)
			(xy 118.337312 -270.061279) (xy 118.029995 -270.061279) (xy 118.029986 -270.061736) (xy 118.021822 -270.11197)
			(xy 118.005706 -270.160244) (xy 117.982055 -270.205307) (xy 117.951482 -270.245993) (xy 117.914778 -270.281248)
			(xy 117.872894 -270.310158) (xy 117.826915 -270.331975) (xy 117.778031 -270.346135) (xy 117.72751 -270.352269)
			(xy 117.676658 -270.35022) (xy 117.626794 -270.34004) (xy 117.579208 -270.321993) (xy 117.535134 -270.296547)
			(xy 117.495712 -270.26436) (xy 117.461964 -270.226266) (xy 117.434763 -270.183252) (xy 117.414815 -270.136432)
			(xy 117.402636 -270.087018) (xy 117.398541 -270.03629) (xy 117.089914 -270.03629) (xy 117.089912 -270.061126)
			(xy 117.082148 -270.11013) (xy 117.066813 -270.157316) (xy 117.044286 -270.201522) (xy 117.015121 -270.24166)
			(xy 116.980036 -270.276742) (xy 116.939895 -270.305903) (xy 116.895686 -270.328425) (xy 116.848498 -270.343755)
			(xy 116.799494 -270.351514) (xy 116.749878 -270.351512) (xy 116.700874 -270.343749) (xy 116.653688 -270.328415)
			(xy 116.609481 -270.305888) (xy 116.569343 -270.276723) (xy 116.534261 -270.241639) (xy 116.505099 -270.201498)
			(xy 116.482576 -270.15729) (xy 116.467246 -270.110102) (xy 116.459486 -270.061098) (xy 116.459 -270.03629)
			(xy 116.459536 -270.009414) (xy 116.468633 -269.956439) (xy 116.48658 -269.905773) (xy 116.512857 -269.858882)
			(xy 116.529358 -269.837662) (xy 116.538756 -269.826232) (xy 116.542058 -269.797276) (xy 116.496338 -269.70101)
			(xy 116.491779 -269.692593) (xy 116.477747 -269.679602) (xy 116.459927 -269.672668) (xy 116.450364 -269.672308)
			(xy 116.350288 -269.672308) (xy 116.330517 -269.671829) (xy 116.291655 -269.664526) (xy 116.254804 -269.650189)
			(xy 116.221223 -269.629309) (xy 116.192064 -269.602601) (xy 116.168322 -269.570979) (xy 116.150812 -269.535526)
			(xy 116.145056 -269.516606) (xy 116.142341 -269.50817) (xy 116.132066 -269.493748) (xy 116.12499 -269.488412)
			(xy 116.104064 -269.473476) (xy 116.066879 -269.437976) (xy 116.035895 -269.396952) (xy 116.011921 -269.351473)
			(xy 115.995584 -269.302729) (xy 115.987308 -269.251989) (xy 115.986814 -269.226284) (xy 115.68049 -269.226284)
			(xy 115.679978 -269.25173) (xy 115.671814 -269.301964) (xy 115.655698 -269.350238) (xy 115.632047 -269.395301)
			(xy 115.601474 -269.435987) (xy 115.56477 -269.471242) (xy 115.522886 -269.500152) (xy 115.476907 -269.521969)
			(xy 115.428023 -269.536129) (xy 115.377502 -269.542263) (xy 115.32665 -269.540214) (xy 115.276786 -269.530034)
			(xy 115.2292 -269.511987) (xy 115.185126 -269.486541) (xy 115.145704 -269.454354) (xy 115.111956 -269.41626)
			(xy 115.084755 -269.373246) (xy 115.064807 -269.326426) (xy 115.052628 -269.277012) (xy 115.048533 -269.226284)
			(xy 114.740436 -269.226284) (xy 114.739924 -269.25173) (xy 114.73176 -269.301964) (xy 114.715644 -269.350238)
			(xy 114.691993 -269.395301) (xy 114.66142 -269.435987) (xy 114.624716 -269.471242) (xy 114.582832 -269.500152)
			(xy 114.536853 -269.521969) (xy 114.487969 -269.536129) (xy 114.437448 -269.542263) (xy 114.386596 -269.540214)
			(xy 114.336732 -269.530034) (xy 114.289146 -269.511987) (xy 114.245072 -269.486541) (xy 114.20565 -269.454354)
			(xy 114.171902 -269.41626) (xy 114.144701 -269.373246) (xy 114.124753 -269.326426) (xy 114.112574 -269.277012)
			(xy 114.108479 -269.226284) (xy 113.802668 -269.226284) (xy 113.802178 -269.251273) (xy 113.794359 -269.300636)
			(xy 113.778915 -269.348168) (xy 113.756225 -269.3927) (xy 113.726849 -269.433133) (xy 113.691509 -269.468473)
			(xy 113.651076 -269.497849) (xy 113.606544 -269.520539) (xy 113.559012 -269.535983) (xy 113.509649 -269.543802)
			(xy 113.459671 -269.543802) (xy 113.410308 -269.535983) (xy 113.362776 -269.520539) (xy 113.318244 -269.497849)
			(xy 113.277811 -269.468473) (xy 113.242471 -269.433133) (xy 113.213095 -269.3927) (xy 113.190405 -269.348168)
			(xy 113.174961 -269.300636) (xy 113.167142 -269.251273) (xy 110.98862 -269.251273) (xy 110.980801 -269.300636)
			(xy 110.965357 -269.348168) (xy 110.942667 -269.3927) (xy 110.913291 -269.433133) (xy 110.877951 -269.468473)
			(xy 110.837518 -269.497849) (xy 110.792986 -269.520539) (xy 110.745454 -269.535983) (xy 110.696091 -269.543802)
			(xy 110.646113 -269.543802) (xy 110.59675 -269.535983) (xy 110.549218 -269.520539) (xy 110.504686 -269.497849)
			(xy 110.464253 -269.468473) (xy 110.428913 -269.433133) (xy 110.399537 -269.3927) (xy 110.376847 -269.348168)
			(xy 110.361403 -269.300636) (xy 110.353584 -269.251273) (xy 110.046267 -269.251273) (xy 110.046258 -269.25173)
			(xy 110.038094 -269.301964) (xy 110.021978 -269.350238) (xy 109.998327 -269.395301) (xy 109.967754 -269.435987)
			(xy 109.93105 -269.471242) (xy 109.889166 -269.500152) (xy 109.843187 -269.521969) (xy 109.794303 -269.536129)
			(xy 109.743782 -269.542263) (xy 109.69293 -269.540214) (xy 109.643066 -269.530034) (xy 109.59548 -269.511987)
			(xy 109.551406 -269.486541) (xy 109.511984 -269.454354) (xy 109.478236 -269.41626) (xy 109.451035 -269.373246)
			(xy 109.431087 -269.326426) (xy 109.418908 -269.277012) (xy 109.414813 -269.226284) (xy 109.106716 -269.226284)
			(xy 109.106204 -269.25173) (xy 109.09804 -269.301964) (xy 109.081924 -269.350238) (xy 109.058273 -269.395301)
			(xy 109.0277 -269.435987) (xy 108.990996 -269.471242) (xy 108.949112 -269.500152) (xy 108.903133 -269.521969)
			(xy 108.854249 -269.536129) (xy 108.803728 -269.542263) (xy 108.752876 -269.540214) (xy 108.703012 -269.530034)
			(xy 108.655426 -269.511987) (xy 108.611352 -269.486541) (xy 108.57193 -269.454354) (xy 108.538182 -269.41626)
			(xy 108.510981 -269.373246) (xy 108.491033 -269.326426) (xy 108.478854 -269.277012) (xy 108.474759 -269.226284)
			(xy 108.168948 -269.226284) (xy 108.168446 -269.251231) (xy 108.160669 -269.300515) (xy 108.145303 -269.347984)
			(xy 108.122724 -269.392476) (xy 108.108496 -269.412974) (xy 108.10367 -269.419578) (xy 108.098844 -269.434564)
			(xy 108.098844 -269.457424) (xy 108.09856 -269.478491) (xy 108.090591 -269.51986) (xy 108.07467 -269.558865)
			(xy 108.051415 -269.593995) (xy 108.021727 -269.623886) (xy 107.986757 -269.647381) (xy 107.947862 -269.663569)
			(xy 107.906549 -269.671821) (xy 107.885484 -269.672308) (xy 107.630468 -269.672308) (xy 107.630468 -269.663164)
			(xy 107.63009 -269.653119) (xy 107.622494 -269.634529) (xy 107.608298 -269.620324) (xy 107.589713 -269.612716)
			(xy 107.579668 -269.612364) (xy 107.4166 -269.612364) (xy 107.406574 -269.61198) (xy 107.38805 -269.604303)
			(xy 107.373877 -269.590119) (xy 107.366213 -269.57159) (xy 107.3658 -269.561564) (xy 105.566972 -269.561564)
			(xy 105.56655 -269.571586) (xy 105.558887 -269.590108) (xy 105.544715 -269.604282) (xy 105.526194 -269.611949)
			(xy 105.516172 -269.612364) (xy 105.353104 -269.612364) (xy 105.343101 -269.612891) (xy 105.324616 -269.620542)
			(xy 105.310464 -269.634683) (xy 105.302798 -269.653161) (xy 105.302304 -269.663164) (xy 105.302304 -269.69847)
			(xy 105.302744 -269.70849) (xy 105.310405 -269.727007) (xy 105.324571 -269.74118) (xy 105.343084 -269.748851)
			(xy 105.353104 -269.74927) (xy 105.363518 -269.74927) (xy 105.373424 -269.744952) (xy 105.39361 -269.736514)
			(xy 105.435718 -269.724637) (xy 105.479056 -269.718644) (xy 105.500932 -269.718282) (xy 105.525918 -269.718817)
			(xy 105.575275 -269.726639) (xy 105.6228 -269.742086) (xy 105.667324 -269.764777) (xy 105.70775 -269.794154)
			(xy 105.743083 -269.829493) (xy 105.772452 -269.869924) (xy 105.795136 -269.914452) (xy 105.810574 -269.96198)
			(xy 105.818388 -270.011338) (xy 105.818386 -270.03629) (xy 106.124751 -270.03629) (xy 106.128846 -269.985562)
			(xy 106.141025 -269.936148) (xy 106.160973 -269.889328) (xy 106.188174 -269.846314) (xy 106.221922 -269.80822)
			(xy 106.261344 -269.776033) (xy 106.305418 -269.750587) (xy 106.353004 -269.73254) (xy 106.402868 -269.72236)
			(xy 106.45372 -269.720311) (xy 106.504241 -269.726445) (xy 106.553125 -269.740605) (xy 106.599104 -269.762422)
			(xy 106.640988 -269.791332) (xy 106.677692 -269.826587) (xy 106.708265 -269.867273) (xy 106.731916 -269.912336)
			(xy 106.748032 -269.96061) (xy 106.756196 -270.010844) (xy 106.756708 -270.03629) (xy 107.064805 -270.03629)
			(xy 107.0689 -269.985562) (xy 107.081079 -269.936148) (xy 107.101027 -269.889328) (xy 107.128228 -269.846314)
			(xy 107.161976 -269.80822) (xy 107.201398 -269.776033) (xy 107.245472 -269.750587) (xy 107.293058 -269.73254)
			(xy 107.342922 -269.72236) (xy 107.393774 -269.720311) (xy 107.444295 -269.726445) (xy 107.493179 -269.740605)
			(xy 107.539158 -269.762422) (xy 107.581042 -269.791332) (xy 107.617746 -269.826587) (xy 107.648319 -269.867273)
			(xy 107.67197 -269.912336) (xy 107.688086 -269.96061) (xy 107.69625 -270.010844) (xy 107.696762 -270.03629)
			(xy 107.696259 -270.061279) (xy 108.003576 -270.061279) (xy 108.003576 -270.011301) (xy 108.011395 -269.961938)
			(xy 108.026839 -269.914406) (xy 108.049529 -269.869874) (xy 108.078905 -269.829441) (xy 108.114245 -269.794101)
			(xy 108.154678 -269.764725) (xy 108.19921 -269.742035) (xy 108.246742 -269.726591) (xy 108.296105 -269.718772)
			(xy 108.346083 -269.718772) (xy 108.395446 -269.726591) (xy 108.442978 -269.742035) (xy 108.48751 -269.764725)
			(xy 108.527943 -269.794101) (xy 108.563283 -269.829441) (xy 108.592659 -269.869874) (xy 108.615349 -269.914406)
			(xy 108.630793 -269.961938) (xy 108.638612 -270.011301) (xy 108.639102 -270.03629) (xy 108.638612 -270.061279)
			(xy 108.94363 -270.061279) (xy 108.94363 -270.011301) (xy 108.951449 -269.961938) (xy 108.966893 -269.914406)
			(xy 108.989583 -269.869874) (xy 109.018959 -269.829441) (xy 109.054299 -269.794101) (xy 109.094732 -269.764725)
			(xy 109.139264 -269.742035) (xy 109.186796 -269.726591) (xy 109.236159 -269.718772) (xy 109.286137 -269.718772)
			(xy 109.3355 -269.726591) (xy 109.383032 -269.742035) (xy 109.427564 -269.764725) (xy 109.467997 -269.794101)
			(xy 109.503337 -269.829441) (xy 109.532713 -269.869874) (xy 109.555403 -269.914406) (xy 109.570847 -269.961938)
			(xy 109.578666 -270.011301) (xy 109.579156 -270.03629) (xy 109.578666 -270.061279) (xy 109.88343 -270.061279)
			(xy 109.88343 -270.011301) (xy 109.891249 -269.961938) (xy 109.906693 -269.914406) (xy 109.929383 -269.869874)
			(xy 109.958759 -269.829441) (xy 109.994099 -269.794101) (xy 110.034532 -269.764725) (xy 110.079064 -269.742035)
			(xy 110.126596 -269.726591) (xy 110.175959 -269.718772) (xy 110.225937 -269.718772) (xy 110.2753 -269.726591)
			(xy 110.322832 -269.742035) (xy 110.367364 -269.764725) (xy 110.407797 -269.794101) (xy 110.443137 -269.829441)
			(xy 110.472513 -269.869874) (xy 110.495203 -269.914406) (xy 110.510647 -269.961938) (xy 110.518466 -270.011301)
			(xy 110.518956 -270.03629) (xy 110.518466 -270.061279) (xy 113.637296 -270.061279) (xy 113.637296 -270.011301)
			(xy 113.645115 -269.961938) (xy 113.660559 -269.914406) (xy 113.683249 -269.869874) (xy 113.712625 -269.829441)
			(xy 113.747965 -269.794101) (xy 113.788398 -269.764725) (xy 113.83293 -269.742035) (xy 113.880462 -269.726591)
			(xy 113.929825 -269.718772) (xy 113.979803 -269.718772) (xy 114.029166 -269.726591) (xy 114.076698 -269.742035)
			(xy 114.12123 -269.764725) (xy 114.161663 -269.794101) (xy 114.197003 -269.829441) (xy 114.226379 -269.869874)
			(xy 114.249069 -269.914406) (xy 114.264513 -269.961938) (xy 114.272332 -270.011301) (xy 114.272822 -270.03629)
			(xy 114.272332 -270.061279) (xy 114.577096 -270.061279) (xy 114.577096 -270.011301) (xy 114.584915 -269.961938)
			(xy 114.600359 -269.914406) (xy 114.623049 -269.869874) (xy 114.652425 -269.829441) (xy 114.687765 -269.794101)
			(xy 114.728198 -269.764725) (xy 114.77273 -269.742035) (xy 114.820262 -269.726591) (xy 114.869625 -269.718772)
			(xy 114.919603 -269.718772) (xy 114.968966 -269.726591) (xy 115.016498 -269.742035) (xy 115.06103 -269.764725)
			(xy 115.101463 -269.794101) (xy 115.136803 -269.829441) (xy 115.166179 -269.869874) (xy 115.188869 -269.914406)
			(xy 115.204313 -269.961938) (xy 115.212132 -270.011301) (xy 115.212622 -270.03629) (xy 115.212132 -270.061279)
			(xy 115.51715 -270.061279) (xy 115.51715 -270.011301) (xy 115.524969 -269.961938) (xy 115.540413 -269.914406)
			(xy 115.563103 -269.869874) (xy 115.592479 -269.829441) (xy 115.627819 -269.794101) (xy 115.668252 -269.764725)
			(xy 115.712784 -269.742035) (xy 115.760316 -269.726591) (xy 115.809679 -269.718772) (xy 115.859657 -269.718772)
			(xy 115.90902 -269.726591) (xy 115.956552 -269.742035) (xy 116.001084 -269.764725) (xy 116.041517 -269.794101)
			(xy 116.076857 -269.829441) (xy 116.106233 -269.869874) (xy 116.128923 -269.914406) (xy 116.144367 -269.961938)
			(xy 116.152186 -270.011301) (xy 116.152676 -270.03629) (xy 116.152186 -270.061279) (xy 116.144367 -270.110642)
			(xy 116.128923 -270.158174) (xy 116.106233 -270.202706) (xy 116.076857 -270.243139) (xy 116.041517 -270.278479)
			(xy 116.001084 -270.307855) (xy 115.956552 -270.330545) (xy 115.90902 -270.345989) (xy 115.859657 -270.353808)
			(xy 115.809679 -270.353808) (xy 115.760316 -270.345989) (xy 115.712784 -270.330545) (xy 115.668252 -270.307855)
			(xy 115.627819 -270.278479) (xy 115.592479 -270.243139) (xy 115.563103 -270.202706) (xy 115.540413 -270.158174)
			(xy 115.524969 -270.110642) (xy 115.51715 -270.061279) (xy 115.212132 -270.061279) (xy 115.204313 -270.110642)
			(xy 115.188869 -270.158174) (xy 115.166179 -270.202706) (xy 115.136803 -270.243139) (xy 115.101463 -270.278479)
			(xy 115.06103 -270.307855) (xy 115.016498 -270.330545) (xy 114.968966 -270.345989) (xy 114.919603 -270.353808)
			(xy 114.869625 -270.353808) (xy 114.820262 -270.345989) (xy 114.77273 -270.330545) (xy 114.728198 -270.307855)
			(xy 114.687765 -270.278479) (xy 114.652425 -270.243139) (xy 114.623049 -270.202706) (xy 114.600359 -270.158174)
			(xy 114.584915 -270.110642) (xy 114.577096 -270.061279) (xy 114.272332 -270.061279) (xy 114.264513 -270.110642)
			(xy 114.249069 -270.158174) (xy 114.226379 -270.202706) (xy 114.197003 -270.243139) (xy 114.161663 -270.278479)
			(xy 114.12123 -270.307855) (xy 114.076698 -270.330545) (xy 114.029166 -270.345989) (xy 113.979803 -270.353808)
			(xy 113.929825 -270.353808) (xy 113.880462 -270.345989) (xy 113.83293 -270.330545) (xy 113.788398 -270.307855)
			(xy 113.747965 -270.278479) (xy 113.712625 -270.243139) (xy 113.683249 -270.202706) (xy 113.660559 -270.158174)
			(xy 113.645115 -270.110642) (xy 113.637296 -270.061279) (xy 110.518466 -270.061279) (xy 110.510647 -270.110642)
			(xy 110.495203 -270.158174) (xy 110.472513 -270.202706) (xy 110.443137 -270.243139) (xy 110.407797 -270.278479)
			(xy 110.367364 -270.307855) (xy 110.322832 -270.330545) (xy 110.2753 -270.345989) (xy 110.225937 -270.353808)
			(xy 110.175959 -270.353808) (xy 110.126596 -270.345989) (xy 110.079064 -270.330545) (xy 110.034532 -270.307855)
			(xy 109.994099 -270.278479) (xy 109.958759 -270.243139) (xy 109.929383 -270.202706) (xy 109.906693 -270.158174)
			(xy 109.891249 -270.110642) (xy 109.88343 -270.061279) (xy 109.578666 -270.061279) (xy 109.570847 -270.110642)
			(xy 109.555403 -270.158174) (xy 109.532713 -270.202706) (xy 109.503337 -270.243139) (xy 109.467997 -270.278479)
			(xy 109.427564 -270.307855) (xy 109.383032 -270.330545) (xy 109.3355 -270.345989) (xy 109.286137 -270.353808)
			(xy 109.236159 -270.353808) (xy 109.186796 -270.345989) (xy 109.139264 -270.330545) (xy 109.094732 -270.307855)
			(xy 109.054299 -270.278479) (xy 109.018959 -270.243139) (xy 108.989583 -270.202706) (xy 108.966893 -270.158174)
			(xy 108.951449 -270.110642) (xy 108.94363 -270.061279) (xy 108.638612 -270.061279) (xy 108.630793 -270.110642)
			(xy 108.615349 -270.158174) (xy 108.592659 -270.202706) (xy 108.563283 -270.243139) (xy 108.527943 -270.278479)
			(xy 108.48751 -270.307855) (xy 108.442978 -270.330545) (xy 108.395446 -270.345989) (xy 108.346083 -270.353808)
			(xy 108.296105 -270.353808) (xy 108.246742 -270.345989) (xy 108.19921 -270.330545) (xy 108.154678 -270.307855)
			(xy 108.114245 -270.278479) (xy 108.078905 -270.243139) (xy 108.049529 -270.202706) (xy 108.026839 -270.158174)
			(xy 108.011395 -270.110642) (xy 108.003576 -270.061279) (xy 107.696259 -270.061279) (xy 107.69625 -270.061736)
			(xy 107.688086 -270.11197) (xy 107.67197 -270.160244) (xy 107.648319 -270.205307) (xy 107.617746 -270.245993)
			(xy 107.581042 -270.281248) (xy 107.539158 -270.310158) (xy 107.493179 -270.331975) (xy 107.444295 -270.346135)
			(xy 107.393774 -270.352269) (xy 107.342922 -270.35022) (xy 107.293058 -270.34004) (xy 107.245472 -270.321993)
			(xy 107.201398 -270.296547) (xy 107.161976 -270.26436) (xy 107.128228 -270.226266) (xy 107.101027 -270.183252)
			(xy 107.081079 -270.136432) (xy 107.0689 -270.087018) (xy 107.064805 -270.03629) (xy 106.756708 -270.03629)
			(xy 106.756196 -270.061736) (xy 106.748032 -270.11197) (xy 106.731916 -270.160244) (xy 106.708265 -270.205307)
			(xy 106.677692 -270.245993) (xy 106.640988 -270.281248) (xy 106.599104 -270.310158) (xy 106.553125 -270.331975)
			(xy 106.504241 -270.346135) (xy 106.45372 -270.352269) (xy 106.402868 -270.35022) (xy 106.353004 -270.34004)
			(xy 106.305418 -270.321993) (xy 106.261344 -270.296547) (xy 106.221922 -270.26436) (xy 106.188174 -270.226266)
			(xy 106.160973 -270.183252) (xy 106.141025 -270.136432) (xy 106.128846 -270.087018) (xy 106.124751 -270.03629)
			(xy 105.818386 -270.03629) (xy 105.818384 -270.061311) (xy 105.810563 -270.110668) (xy 105.795117 -270.158193)
			(xy 105.772427 -270.202718) (xy 105.743051 -270.243144) (xy 105.707712 -270.278478) (xy 105.667282 -270.307849)
			(xy 105.622755 -270.330533) (xy 105.575227 -270.345973) (xy 105.525869 -270.353787) (xy 105.475896 -270.353784)
			(xy 105.426539 -270.345964) (xy 105.379013 -270.33052) (xy 105.334489 -270.30783) (xy 105.294061 -270.278455)
			(xy 105.258727 -270.243118) (xy 105.229355 -270.202688) (xy 105.20667 -270.158161) (xy 105.191229 -270.110634)
			(xy 105.183413 -270.061276) (xy 105.182924 -270.03629) (xy 105.183494 -270.009417) (xy 105.192518 -269.956433)
			(xy 105.210324 -269.905722) (xy 105.236405 -269.858728) (xy 105.252774 -269.837408) (xy 105.261918 -269.825978)
			(xy 105.265474 -269.796768) (xy 105.2195 -269.70101) (xy 105.214967 -269.692577) (xy 105.200924 -269.679588)
			(xy 105.183093 -269.672661) (xy 105.173526 -269.672308) (xy 105.047288 -269.672308) (xy 105.025867 -269.671815)
			(xy 104.983884 -269.66327) (xy 104.944449 -269.646526) (xy 104.909144 -269.622255) (xy 104.879387 -269.591433)
			(xy 104.856373 -269.555296) (xy 104.841026 -269.515296) (xy 104.836976 -269.494254) (xy 104.835154 -269.48581)
			(xy 104.826719 -269.47075) (xy 104.820466 -269.46479) (xy 104.800615 -269.446514) (xy 104.766784 -269.404484)
			(xy 104.740536 -269.357345) (xy 104.722626 -269.30645) (xy 104.713568 -269.253262) (xy 104.713024 -269.226284)
			(xy 102.772972 -269.226284) (xy 102.772972 -269.561564) (xy 102.77255 -269.571586) (xy 102.764887 -269.590108)
			(xy 102.750715 -269.604282) (xy 102.732194 -269.611949) (xy 102.722172 -269.612364) (xy 102.559104 -269.612364)
			(xy 102.549101 -269.612891) (xy 102.530616 -269.620542) (xy 102.516464 -269.634683) (xy 102.508798 -269.653161)
			(xy 102.508304 -269.663164) (xy 102.508304 -269.68831) (xy 102.50878 -269.698319) (xy 102.516444 -269.716811)
			(xy 102.5306 -269.730964) (xy 102.549095 -269.738623) (xy 102.559104 -269.73911) (xy 102.56774 -269.73911)
			(xy 102.575868 -269.736316) (xy 102.601348 -269.727941) (xy 102.654209 -269.71888) (xy 102.681024 -269.718282)
			(xy 102.706011 -269.718808) (xy 102.755369 -269.726629) (xy 102.802896 -269.742076) (xy 102.847422 -269.764767)
			(xy 102.88785 -269.794144) (xy 102.923185 -269.829483) (xy 102.952556 -269.869915) (xy 102.975241 -269.914444)
			(xy 102.990681 -269.961973) (xy 102.998495 -270.011332) (xy 102.998494 -270.03629) (xy 103.304843 -270.03629)
			(xy 103.308938 -269.985562) (xy 103.321117 -269.936148) (xy 103.341065 -269.889328) (xy 103.368266 -269.846314)
			(xy 103.402014 -269.80822) (xy 103.441436 -269.776033) (xy 103.48551 -269.750587) (xy 103.533096 -269.73254)
			(xy 103.58296 -269.72236) (xy 103.633812 -269.720311) (xy 103.684333 -269.726445) (xy 103.733217 -269.740605)
			(xy 103.779196 -269.762422) (xy 103.82108 -269.791332) (xy 103.857784 -269.826587) (xy 103.888357 -269.867273)
			(xy 103.912008 -269.912336) (xy 103.928124 -269.96061) (xy 103.936288 -270.010844) (xy 103.9368 -270.03629)
			(xy 104.244897 -270.03629) (xy 104.248992 -269.985562) (xy 104.261171 -269.936148) (xy 104.281119 -269.889328)
			(xy 104.30832 -269.846314) (xy 104.342068 -269.80822) (xy 104.38149 -269.776033) (xy 104.425564 -269.750587)
			(xy 104.47315 -269.73254) (xy 104.523014 -269.72236) (xy 104.573866 -269.720311) (xy 104.624387 -269.726445)
			(xy 104.673271 -269.740605) (xy 104.71925 -269.762422) (xy 104.761134 -269.791332) (xy 104.797838 -269.826587)
			(xy 104.828411 -269.867273) (xy 104.852062 -269.912336) (xy 104.868178 -269.96061) (xy 104.876342 -270.010844)
			(xy 104.876854 -270.03629) (xy 104.876342 -270.061736) (xy 104.868178 -270.11197) (xy 104.852062 -270.160244)
			(xy 104.828411 -270.205307) (xy 104.797838 -270.245993) (xy 104.761134 -270.281248) (xy 104.71925 -270.310158)
			(xy 104.673271 -270.331975) (xy 104.624387 -270.346135) (xy 104.573866 -270.352269) (xy 104.523014 -270.35022)
			(xy 104.47315 -270.34004) (xy 104.425564 -270.321993) (xy 104.38149 -270.296547) (xy 104.342068 -270.26436)
			(xy 104.30832 -270.226266) (xy 104.281119 -270.183252) (xy 104.261171 -270.136432) (xy 104.248992 -270.087018)
			(xy 104.244897 -270.03629) (xy 103.9368 -270.03629) (xy 103.936288 -270.061736) (xy 103.928124 -270.11197)
			(xy 103.912008 -270.160244) (xy 103.888357 -270.205307) (xy 103.857784 -270.245993) (xy 103.82108 -270.281248)
			(xy 103.779196 -270.310158) (xy 103.733217 -270.331975) (xy 103.684333 -270.346135) (xy 103.633812 -270.352269)
			(xy 103.58296 -270.35022) (xy 103.533096 -270.34004) (xy 103.48551 -270.321993) (xy 103.441436 -270.296547)
			(xy 103.402014 -270.26436) (xy 103.368266 -270.226266) (xy 103.341065 -270.183252) (xy 103.321117 -270.136432)
			(xy 103.308938 -270.087018) (xy 103.304843 -270.03629) (xy 102.998494 -270.03629) (xy 102.998492 -270.061306)
			(xy 102.990672 -270.110665) (xy 102.975226 -270.158192) (xy 102.952536 -270.202718) (xy 102.923159 -270.243146)
			(xy 102.887821 -270.278482) (xy 102.847389 -270.307854) (xy 102.802861 -270.330539) (xy 102.755332 -270.34598)
			(xy 102.705972 -270.353795) (xy 102.655998 -270.353793) (xy 102.60664 -270.345973) (xy 102.559112 -270.330528)
			(xy 102.514586 -270.307838) (xy 102.474157 -270.278462) (xy 102.438821 -270.243124) (xy 102.409449 -270.202693)
			(xy 102.386763 -270.158165) (xy 102.371322 -270.110636) (xy 102.363505 -270.061277) (xy 102.363016 -270.03629)
			(xy 102.363587 -270.009417) (xy 102.372611 -269.956434) (xy 102.390417 -269.905723) (xy 102.416498 -269.858728)
			(xy 102.432866 -269.837408) (xy 102.44201 -269.825978) (xy 102.445566 -269.796768) (xy 102.399592 -269.70101)
			(xy 102.395065 -269.692573) (xy 102.381019 -269.679585) (xy 102.363186 -269.67266) (xy 102.353618 -269.672308)
			(xy 102.253288 -269.672308) (xy 102.233335 -269.671827) (xy 102.194121 -269.664438) (xy 102.156966 -269.649881)
			(xy 102.123168 -269.628666) (xy 102.093907 -269.601533) (xy 102.070205 -269.569429) (xy 102.05289 -269.533477)
			(xy 102.047294 -269.51432) (xy 102.044684 -269.505932) (xy 102.034676 -269.491511) (xy 102.027736 -269.486126)
			(xy 102.007325 -269.471077) (xy 101.971069 -269.435627) (xy 101.940894 -269.394875) (xy 101.917564 -269.349853)
			(xy 101.901671 -269.301701) (xy 101.893615 -269.251638) (xy 101.893116 -269.226284) (xy 99.851972 -269.226284)
			(xy 99.851972 -269.561564) (xy 99.85155 -269.571586) (xy 99.843887 -269.590108) (xy 99.829715 -269.604282)
			(xy 99.811194 -269.611949) (xy 99.801172 -269.612364) (xy 99.587304 -269.612364) (xy 99.587304 -269.621508)
			(xy 99.586818 -269.631516) (xy 99.579157 -269.650007) (xy 99.565003 -269.664159) (xy 99.546512 -269.671819)
			(xy 99.536504 -269.672308) (xy 99.332288 -269.672308) (xy 99.311222 -269.671887) (xy 99.269907 -269.663627)
			(xy 99.231013 -269.64743) (xy 99.196047 -269.623925) (xy 99.166366 -269.594022) (xy 99.143121 -269.558882)
			(xy 99.127214 -269.519868) (xy 99.119262 -269.478493) (xy 99.118928 -269.457424) (xy 99.118928 -269.398242)
			(xy 99.11588 -269.38605) (xy 99.112832 -269.380208) (xy 99.100336 -269.356492) (xy 99.082568 -269.30592)
			(xy 99.073532 -269.253085) (xy 99.072954 -269.226284) (xy 97.841816 -269.226284) (xy 97.841352 -269.251709)
			(xy 97.833576 -269.30196) (xy 97.818204 -269.35043) (xy 97.795599 -269.395978) (xy 97.766292 -269.437532)
			(xy 97.730974 -269.474114) (xy 97.690475 -269.504862) (xy 97.668334 -269.517368) (xy 97.659698 -269.52194)
			(xy 97.640394 -269.5448) (xy 97.638108 -269.549118) (xy 97.631504 -269.560802) (xy 97.62998 -269.565882)
			(xy 97.61322 -269.616106) (xy 97.57147 -269.713413) (xy 97.520672 -269.806318) (xy 97.461285 -269.893981)
			(xy 97.42805 -269.935198) (xy 97.421547 -269.943881) (xy 97.4159 -269.964805) (xy 97.417128 -269.975584)
			(xy 97.419397 -269.990658) (xy 97.42181 -270.021047) (xy 97.421954 -270.03629) (xy 97.664773 -270.03629)
			(xy 97.668868 -269.985562) (xy 97.681047 -269.936148) (xy 97.700995 -269.889328) (xy 97.728196 -269.846314)
			(xy 97.761944 -269.80822) (xy 97.801366 -269.776033) (xy 97.84544 -269.750587) (xy 97.893026 -269.73254)
			(xy 97.94289 -269.72236) (xy 97.993742 -269.720311) (xy 98.044263 -269.726445) (xy 98.093147 -269.740605)
			(xy 98.139126 -269.762422) (xy 98.18101 -269.791332) (xy 98.217714 -269.826587) (xy 98.248287 -269.867273)
			(xy 98.271938 -269.912336) (xy 98.288054 -269.96061) (xy 98.296218 -270.010844) (xy 98.29673 -270.03629)
			(xy 98.604827 -270.03629) (xy 98.608922 -269.985562) (xy 98.621101 -269.936148) (xy 98.641049 -269.889328)
			(xy 98.66825 -269.846314) (xy 98.701998 -269.80822) (xy 98.74142 -269.776033) (xy 98.785494 -269.750587)
			(xy 98.83308 -269.73254) (xy 98.882944 -269.72236) (xy 98.933796 -269.720311) (xy 98.984317 -269.726445)
			(xy 99.033201 -269.740605) (xy 99.07918 -269.762422) (xy 99.121064 -269.791332) (xy 99.157768 -269.826587)
			(xy 99.188341 -269.867273) (xy 99.211992 -269.912336) (xy 99.228108 -269.96061) (xy 99.236272 -270.010844)
			(xy 99.236784 -270.03629) (xy 99.236281 -270.061279) (xy 99.543598 -270.061279) (xy 99.543598 -270.011301)
			(xy 99.551417 -269.961938) (xy 99.566861 -269.914406) (xy 99.589551 -269.869874) (xy 99.618927 -269.829441)
			(xy 99.654267 -269.794101) (xy 99.6947 -269.764725) (xy 99.739232 -269.742035) (xy 99.786764 -269.726591)
			(xy 99.836127 -269.718772) (xy 99.886105 -269.718772) (xy 99.935468 -269.726591) (xy 99.983 -269.742035)
			(xy 100.027532 -269.764725) (xy 100.067965 -269.794101) (xy 100.103305 -269.829441) (xy 100.132681 -269.869874)
			(xy 100.155371 -269.914406) (xy 100.170815 -269.961938) (xy 100.178634 -270.011301) (xy 100.179124 -270.03629)
			(xy 100.484935 -270.03629) (xy 100.48903 -269.985562) (xy 100.501209 -269.936148) (xy 100.521157 -269.889328)
			(xy 100.548358 -269.846314) (xy 100.582106 -269.80822) (xy 100.621528 -269.776033) (xy 100.665602 -269.750587)
			(xy 100.713188 -269.73254) (xy 100.763052 -269.72236) (xy 100.813904 -269.720311) (xy 100.864425 -269.726445)
			(xy 100.913309 -269.740605) (xy 100.959288 -269.762422) (xy 101.001172 -269.791332) (xy 101.037876 -269.826587)
			(xy 101.068449 -269.867273) (xy 101.0921 -269.912336) (xy 101.108216 -269.96061) (xy 101.11638 -270.010844)
			(xy 101.116892 -270.03629) (xy 101.424735 -270.03629) (xy 101.42883 -269.985562) (xy 101.441009 -269.936148)
			(xy 101.460957 -269.889328) (xy 101.488158 -269.846314) (xy 101.521906 -269.80822) (xy 101.561328 -269.776033)
			(xy 101.605402 -269.750587) (xy 101.652988 -269.73254) (xy 101.702852 -269.72236) (xy 101.753704 -269.720311)
			(xy 101.804225 -269.726445) (xy 101.853109 -269.740605) (xy 101.899088 -269.762422) (xy 101.940972 -269.791332)
			(xy 101.977676 -269.826587) (xy 102.008249 -269.867273) (xy 102.0319 -269.912336) (xy 102.048016 -269.96061)
			(xy 102.05618 -270.010844) (xy 102.056692 -270.03629) (xy 102.05618 -270.061736) (xy 102.048016 -270.11197)
			(xy 102.0319 -270.160244) (xy 102.008249 -270.205307) (xy 101.977676 -270.245993) (xy 101.940972 -270.281248)
			(xy 101.899088 -270.310158) (xy 101.853109 -270.331975) (xy 101.804225 -270.346135) (xy 101.753704 -270.352269)
			(xy 101.702852 -270.35022) (xy 101.652988 -270.34004) (xy 101.605402 -270.321993) (xy 101.561328 -270.296547)
			(xy 101.521906 -270.26436) (xy 101.488158 -270.226266) (xy 101.460957 -270.183252) (xy 101.441009 -270.136432)
			(xy 101.42883 -270.087018) (xy 101.424735 -270.03629) (xy 101.116892 -270.03629) (xy 101.11638 -270.061736)
			(xy 101.108216 -270.11197) (xy 101.0921 -270.160244) (xy 101.068449 -270.205307) (xy 101.037876 -270.245993)
			(xy 101.001172 -270.281248) (xy 100.959288 -270.310158) (xy 100.913309 -270.331975) (xy 100.864425 -270.346135)
			(xy 100.813904 -270.352269) (xy 100.763052 -270.35022) (xy 100.713188 -270.34004) (xy 100.665602 -270.321993)
			(xy 100.621528 -270.296547) (xy 100.582106 -270.26436) (xy 100.548358 -270.226266) (xy 100.521157 -270.183252)
			(xy 100.501209 -270.136432) (xy 100.48903 -270.087018) (xy 100.484935 -270.03629) (xy 100.179124 -270.03629)
			(xy 100.178634 -270.061279) (xy 100.170815 -270.110642) (xy 100.155371 -270.158174) (xy 100.132681 -270.202706)
			(xy 100.103305 -270.243139) (xy 100.067965 -270.278479) (xy 100.027532 -270.307855) (xy 99.983 -270.330545)
			(xy 99.935468 -270.345989) (xy 99.886105 -270.353808) (xy 99.836127 -270.353808) (xy 99.786764 -270.345989)
			(xy 99.739232 -270.330545) (xy 99.6947 -270.307855) (xy 99.654267 -270.278479) (xy 99.618927 -270.243139)
			(xy 99.589551 -270.202706) (xy 99.566861 -270.158174) (xy 99.551417 -270.110642) (xy 99.543598 -270.061279)
			(xy 99.236281 -270.061279) (xy 99.236272 -270.061736) (xy 99.228108 -270.11197) (xy 99.211992 -270.160244)
			(xy 99.188341 -270.205307) (xy 99.157768 -270.245993) (xy 99.121064 -270.281248) (xy 99.07918 -270.310158)
			(xy 99.033201 -270.331975) (xy 98.984317 -270.346135) (xy 98.933796 -270.352269) (xy 98.882944 -270.35022)
			(xy 98.83308 -270.34004) (xy 98.785494 -270.321993) (xy 98.74142 -270.296547) (xy 98.701998 -270.26436)
			(xy 98.66825 -270.226266) (xy 98.641049 -270.183252) (xy 98.621101 -270.136432) (xy 98.608922 -270.087018)
			(xy 98.604827 -270.03629) (xy 98.29673 -270.03629) (xy 98.296218 -270.061736) (xy 98.288054 -270.11197)
			(xy 98.271938 -270.160244) (xy 98.248287 -270.205307) (xy 98.217714 -270.245993) (xy 98.18101 -270.281248)
			(xy 98.139126 -270.310158) (xy 98.093147 -270.331975) (xy 98.044263 -270.346135) (xy 97.993742 -270.352269)
			(xy 97.94289 -270.35022) (xy 97.893026 -270.34004) (xy 97.84544 -270.321993) (xy 97.801366 -270.296547)
			(xy 97.761944 -270.26436) (xy 97.728196 -270.226266) (xy 97.700995 -270.183252) (xy 97.681047 -270.136432)
			(xy 97.668868 -270.087018) (xy 97.664773 -270.03629) (xy 97.421954 -270.03629) (xy 97.421954 -270.036544)
			(xy 97.421802 -270.051273) (xy 97.419514 -270.080643) (xy 97.417382 -270.095218) (xy 97.416256 -270.105955)
			(xy 97.422053 -270.126732) (xy 97.428558 -270.13535) (xy 97.459269 -270.173372) (xy 97.514659 -270.253908)
			(xy 97.562778 -270.338988) (xy 97.583498 -270.383254) (xy 97.599216 -270.418592) (xy 97.626289 -270.491049)
			(xy 97.6376 -270.528034) (xy 97.640394 -270.537432) (xy 97.664524 -270.567404) (xy 97.672398 -270.57223)
			(xy 97.692526 -270.584575) (xy 97.729231 -270.614278) (xy 97.761141 -270.649082) (xy 97.787553 -270.688221)
			(xy 97.807888 -270.730836) (xy 97.821699 -270.775989) (xy 97.828681 -270.822687) (xy 97.829116 -270.846296)
			(xy 97.828676 -270.870024) (xy 97.828486 -270.871285) (xy 98.133644 -270.871285) (xy 98.133644 -270.821307)
			(xy 98.141463 -270.771944) (xy 98.156907 -270.724412) (xy 98.179597 -270.67988) (xy 98.208973 -270.639447)
			(xy 98.244313 -270.604107) (xy 98.284746 -270.574731) (xy 98.329278 -270.552041) (xy 98.37681 -270.536597)
			(xy 98.426173 -270.528778) (xy 98.476151 -270.528778) (xy 98.525514 -270.536597) (xy 98.573046 -270.552041)
			(xy 98.617578 -270.574731) (xy 98.658011 -270.604107) (xy 98.693351 -270.639447) (xy 98.722727 -270.67988)
			(xy 98.745417 -270.724412) (xy 98.760861 -270.771944) (xy 98.76868 -270.821307) (xy 98.76917 -270.846296)
			(xy 98.76868 -270.871285) (xy 99.073444 -270.871285) (xy 99.073444 -270.821307) (xy 99.081263 -270.771944)
			(xy 99.096707 -270.724412) (xy 99.119397 -270.67988) (xy 99.148773 -270.639447) (xy 99.184113 -270.604107)
			(xy 99.224546 -270.574731) (xy 99.269078 -270.552041) (xy 99.31661 -270.536597) (xy 99.365973 -270.528778)
			(xy 99.415951 -270.528778) (xy 99.465314 -270.536597) (xy 99.512846 -270.552041) (xy 99.557378 -270.574731)
			(xy 99.597811 -270.604107) (xy 99.633151 -270.639447) (xy 99.662527 -270.67988) (xy 99.685217 -270.724412)
			(xy 99.700661 -270.771944) (xy 99.70848 -270.821307) (xy 99.70897 -270.846296) (xy 99.70848 -270.871285)
			(xy 99.700661 -270.920648) (xy 99.685217 -270.96818) (xy 99.662527 -271.012712) (xy 99.633151 -271.053145)
			(xy 99.597811 -271.088485) (xy 99.557378 -271.117861) (xy 99.512846 -271.140551) (xy 99.465314 -271.155995)
			(xy 99.415951 -271.163814) (xy 99.365973 -271.163814) (xy 99.31661 -271.155995) (xy 99.269078 -271.140551)
			(xy 99.224546 -271.117861) (xy 99.184113 -271.088485) (xy 99.148773 -271.053145) (xy 99.119397 -271.012712)
			(xy 99.096707 -270.96818) (xy 99.081263 -270.920648) (xy 99.073444 -270.871285) (xy 98.76868 -270.871285)
			(xy 98.760861 -270.920648) (xy 98.745417 -270.96818) (xy 98.722727 -271.012712) (xy 98.693351 -271.053145)
			(xy 98.658011 -271.088485) (xy 98.617578 -271.117861) (xy 98.573046 -271.140551) (xy 98.525514 -271.155995)
			(xy 98.476151 -271.163814) (xy 98.426173 -271.163814) (xy 98.37681 -271.155995) (xy 98.329278 -271.140551)
			(xy 98.284746 -271.117861) (xy 98.244313 -271.088485) (xy 98.208973 -271.053145) (xy 98.179597 -271.012712)
			(xy 98.156907 -270.96818) (xy 98.141463 -270.920648) (xy 98.133644 -270.871285) (xy 97.828486 -270.871285)
			(xy 97.82162 -270.916953) (xy 97.807664 -270.962311) (xy 97.787119 -271.005089) (xy 97.760442 -271.044337)
			(xy 97.728225 -271.079182) (xy 97.691185 -271.108849) (xy 97.670874 -271.121124) (xy 97.662492 -271.126204)
			(xy 97.639378 -271.155414) (xy 97.636838 -271.164812) (xy 97.621357 -271.214249) (xy 97.582445 -271.310265)
			(xy 97.534785 -271.402253) (xy 97.47879 -271.489418) (xy 97.414943 -271.571006) (xy 97.37979 -271.609058)
			(xy 97.373186 -271.61617) (xy 97.359216 -271.651476) (xy 97.359086 -271.656302) (xy 97.664773 -271.656302)
			(xy 97.668868 -271.605574) (xy 97.681047 -271.55616) (xy 97.700995 -271.50934) (xy 97.728196 -271.466326)
			(xy 97.761944 -271.428232) (xy 97.801366 -271.396045) (xy 97.84544 -271.370599) (xy 97.893026 -271.352552)
			(xy 97.94289 -271.342372) (xy 97.993742 -271.340323) (xy 98.044263 -271.346457) (xy 98.093147 -271.360617)
			(xy 98.139126 -271.382434) (xy 98.18101 -271.411344) (xy 98.217714 -271.446599) (xy 98.248287 -271.487285)
			(xy 98.271938 -271.532348) (xy 98.288054 -271.580622) (xy 98.296218 -271.630856) (xy 98.29673 -271.656302)
			(xy 98.604827 -271.656302) (xy 98.608922 -271.605574) (xy 98.621101 -271.55616) (xy 98.641049 -271.50934)
			(xy 98.66825 -271.466326) (xy 98.701998 -271.428232) (xy 98.74142 -271.396045) (xy 98.785494 -271.370599)
			(xy 98.83308 -271.352552) (xy 98.882944 -271.342372) (xy 98.933796 -271.340323) (xy 98.984317 -271.346457)
			(xy 99.033201 -271.360617) (xy 99.07918 -271.382434) (xy 99.121064 -271.411344) (xy 99.157768 -271.446599)
			(xy 99.188341 -271.487285) (xy 99.211992 -271.532348) (xy 99.228108 -271.580622) (xy 99.236272 -271.630856)
			(xy 99.236784 -271.656302) (xy 99.428808 -271.656302) (xy 99.429252 -271.628003) (xy 99.436677 -271.571892)
			(xy 99.451361 -271.517231) (xy 99.473052 -271.464953) (xy 99.50138 -271.415952) (xy 99.535859 -271.371068)
			(xy 99.555554 -271.35074) (xy 99.707954 -271.19834) (xy 99.727573 -271.179313) (xy 99.770764 -271.145825)
			(xy 99.81783 -271.118045) (xy 99.868022 -271.096417) (xy 99.920538 -271.081285) (xy 99.947476 -271.076674)
			(xy 99.958652 -271.07515) (xy 99.977194 -271.062704) (xy 100.029518 -270.977614) (xy 100.032058 -270.955516)
			(xy 100.028756 -270.944848) (xy 100.021402 -270.920877) (xy 100.013496 -270.871365) (xy 100.013008 -270.846296)
			(xy 100.013498 -270.821307) (xy 100.021317 -270.771944) (xy 100.036761 -270.724412) (xy 100.059451 -270.67988)
			(xy 100.088827 -270.639447) (xy 100.124167 -270.604107) (xy 100.1646 -270.574731) (xy 100.209132 -270.552041)
			(xy 100.256664 -270.536597) (xy 100.306027 -270.528778) (xy 100.356005 -270.528778) (xy 100.405368 -270.536597)
			(xy 100.4529 -270.552041) (xy 100.497432 -270.574731) (xy 100.537865 -270.604107) (xy 100.573205 -270.639447)
			(xy 100.602581 -270.67988) (xy 100.625271 -270.724412) (xy 100.640715 -270.771944) (xy 100.648534 -270.821307)
			(xy 100.649024 -270.846296) (xy 100.648572 -270.871285) (xy 100.953552 -270.871285) (xy 100.953552 -270.821307)
			(xy 100.961371 -270.771944) (xy 100.976815 -270.724412) (xy 100.999505 -270.67988) (xy 101.028881 -270.639447)
			(xy 101.064221 -270.604107) (xy 101.104654 -270.574731) (xy 101.149186 -270.552041) (xy 101.196718 -270.536597)
			(xy 101.246081 -270.528778) (xy 101.296059 -270.528778) (xy 101.345422 -270.536597) (xy 101.392954 -270.552041)
			(xy 101.437486 -270.574731) (xy 101.477919 -270.604107) (xy 101.513259 -270.639447) (xy 101.542635 -270.67988)
			(xy 101.565325 -270.724412) (xy 101.580769 -270.771944) (xy 101.588588 -270.821307) (xy 101.589078 -270.846296)
			(xy 101.588588 -270.871285) (xy 101.893606 -270.871285) (xy 101.893606 -270.821307) (xy 101.901425 -270.771944)
			(xy 101.916869 -270.724412) (xy 101.939559 -270.67988) (xy 101.968935 -270.639447) (xy 102.004275 -270.604107)
			(xy 102.044708 -270.574731) (xy 102.08924 -270.552041) (xy 102.136772 -270.536597) (xy 102.186135 -270.528778)
			(xy 102.236113 -270.528778) (xy 102.285476 -270.536597) (xy 102.333008 -270.552041) (xy 102.37754 -270.574731)
			(xy 102.417973 -270.604107) (xy 102.453313 -270.639447) (xy 102.482689 -270.67988) (xy 102.505379 -270.724412)
			(xy 102.520823 -270.771944) (xy 102.528642 -270.821307) (xy 102.529132 -270.846296) (xy 102.528642 -270.871285)
			(xy 102.83366 -270.871285) (xy 102.83366 -270.821307) (xy 102.841479 -270.771944) (xy 102.856923 -270.724412)
			(xy 102.879613 -270.67988) (xy 102.908989 -270.639447) (xy 102.944329 -270.604107) (xy 102.984762 -270.574731)
			(xy 103.029294 -270.552041) (xy 103.076826 -270.536597) (xy 103.126189 -270.528778) (xy 103.176167 -270.528778)
			(xy 103.22553 -270.536597) (xy 103.273062 -270.552041) (xy 103.317594 -270.574731) (xy 103.358027 -270.604107)
			(xy 103.393367 -270.639447) (xy 103.422743 -270.67988) (xy 103.445433 -270.724412) (xy 103.460877 -270.771944)
			(xy 103.468696 -270.821307) (xy 103.469186 -270.846296) (xy 103.468696 -270.871285) (xy 103.77346 -270.871285)
			(xy 103.77346 -270.821307) (xy 103.781279 -270.771944) (xy 103.796723 -270.724412) (xy 103.819413 -270.67988)
			(xy 103.848789 -270.639447) (xy 103.884129 -270.604107) (xy 103.924562 -270.574731) (xy 103.969094 -270.552041)
			(xy 104.016626 -270.536597) (xy 104.065989 -270.528778) (xy 104.115967 -270.528778) (xy 104.16533 -270.536597)
			(xy 104.212862 -270.552041) (xy 104.257394 -270.574731) (xy 104.297827 -270.604107) (xy 104.333167 -270.639447)
			(xy 104.362543 -270.67988) (xy 104.385233 -270.724412) (xy 104.400677 -270.771944) (xy 104.408496 -270.821307)
			(xy 104.408986 -270.846296) (xy 104.408496 -270.871285) (xy 104.713514 -270.871285) (xy 104.713514 -270.821307)
			(xy 104.721333 -270.771944) (xy 104.736777 -270.724412) (xy 104.759467 -270.67988) (xy 104.788843 -270.639447)
			(xy 104.824183 -270.604107) (xy 104.864616 -270.574731) (xy 104.909148 -270.552041) (xy 104.95668 -270.536597)
			(xy 105.006043 -270.528778) (xy 105.056021 -270.528778) (xy 105.105384 -270.536597) (xy 105.152916 -270.552041)
			(xy 105.197448 -270.574731) (xy 105.237881 -270.604107) (xy 105.273221 -270.639447) (xy 105.302597 -270.67988)
			(xy 105.325287 -270.724412) (xy 105.340731 -270.771944) (xy 105.34855 -270.821307) (xy 105.34904 -270.846296)
			(xy 105.34855 -270.871285) (xy 105.653568 -270.871285) (xy 105.653568 -270.821307) (xy 105.661387 -270.771944)
			(xy 105.676831 -270.724412) (xy 105.699521 -270.67988) (xy 105.728897 -270.639447) (xy 105.764237 -270.604107)
			(xy 105.80467 -270.574731) (xy 105.849202 -270.552041) (xy 105.896734 -270.536597) (xy 105.946097 -270.528778)
			(xy 105.996075 -270.528778) (xy 106.045438 -270.536597) (xy 106.09297 -270.552041) (xy 106.137502 -270.574731)
			(xy 106.177935 -270.604107) (xy 106.213275 -270.639447) (xy 106.242651 -270.67988) (xy 106.265341 -270.724412)
			(xy 106.280785 -270.771944) (xy 106.288604 -270.821307) (xy 106.289094 -270.846296) (xy 106.288604 -270.871285)
			(xy 106.593622 -270.871285) (xy 106.593622 -270.821307) (xy 106.601441 -270.771944) (xy 106.616885 -270.724412)
			(xy 106.639575 -270.67988) (xy 106.668951 -270.639447) (xy 106.704291 -270.604107) (xy 106.744724 -270.574731)
			(xy 106.789256 -270.552041) (xy 106.836788 -270.536597) (xy 106.886151 -270.528778) (xy 106.936129 -270.528778)
			(xy 106.985492 -270.536597) (xy 107.033024 -270.552041) (xy 107.077556 -270.574731) (xy 107.117989 -270.604107)
			(xy 107.153329 -270.639447) (xy 107.182705 -270.67988) (xy 107.205395 -270.724412) (xy 107.220839 -270.771944)
			(xy 107.228658 -270.821307) (xy 107.229148 -270.846296) (xy 107.228658 -270.871285) (xy 107.533422 -270.871285)
			(xy 107.533422 -270.821307) (xy 107.541241 -270.771944) (xy 107.556685 -270.724412) (xy 107.579375 -270.67988)
			(xy 107.608751 -270.639447) (xy 107.644091 -270.604107) (xy 107.684524 -270.574731) (xy 107.729056 -270.552041)
			(xy 107.776588 -270.536597) (xy 107.825951 -270.528778) (xy 107.875929 -270.528778) (xy 107.925292 -270.536597)
			(xy 107.972824 -270.552041) (xy 108.017356 -270.574731) (xy 108.057789 -270.604107) (xy 108.093129 -270.639447)
			(xy 108.122505 -270.67988) (xy 108.145195 -270.724412) (xy 108.160639 -270.771944) (xy 108.168458 -270.821307)
			(xy 108.168948 -270.846296) (xy 108.168458 -270.871285) (xy 108.160639 -270.920648) (xy 108.145195 -270.96818)
			(xy 108.122505 -271.012712) (xy 108.093129 -271.053145) (xy 108.057789 -271.088485) (xy 108.017356 -271.117861)
			(xy 107.972824 -271.140551) (xy 107.925292 -271.155995) (xy 107.875929 -271.163814) (xy 107.825951 -271.163814)
			(xy 107.776588 -271.155995) (xy 107.729056 -271.140551) (xy 107.684524 -271.117861) (xy 107.644091 -271.088485)
			(xy 107.608751 -271.053145) (xy 107.579375 -271.012712) (xy 107.556685 -270.96818) (xy 107.541241 -270.920648)
			(xy 107.533422 -270.871285) (xy 107.228658 -270.871285) (xy 107.220839 -270.920648) (xy 107.205395 -270.96818)
			(xy 107.182705 -271.012712) (xy 107.153329 -271.053145) (xy 107.117989 -271.088485) (xy 107.077556 -271.117861)
			(xy 107.033024 -271.140551) (xy 106.985492 -271.155995) (xy 106.936129 -271.163814) (xy 106.886151 -271.163814)
			(xy 106.836788 -271.155995) (xy 106.789256 -271.140551) (xy 106.744724 -271.117861) (xy 106.704291 -271.088485)
			(xy 106.668951 -271.053145) (xy 106.639575 -271.012712) (xy 106.616885 -270.96818) (xy 106.601441 -270.920648)
			(xy 106.593622 -270.871285) (xy 106.288604 -270.871285) (xy 106.280785 -270.920648) (xy 106.265341 -270.96818)
			(xy 106.242651 -271.012712) (xy 106.213275 -271.053145) (xy 106.177935 -271.088485) (xy 106.137502 -271.117861)
			(xy 106.09297 -271.140551) (xy 106.045438 -271.155995) (xy 105.996075 -271.163814) (xy 105.946097 -271.163814)
			(xy 105.896734 -271.155995) (xy 105.849202 -271.140551) (xy 105.80467 -271.117861) (xy 105.764237 -271.088485)
			(xy 105.728897 -271.053145) (xy 105.699521 -271.012712) (xy 105.676831 -270.96818) (xy 105.661387 -270.920648)
			(xy 105.653568 -270.871285) (xy 105.34855 -270.871285) (xy 105.340731 -270.920648) (xy 105.325287 -270.96818)
			(xy 105.302597 -271.012712) (xy 105.273221 -271.053145) (xy 105.237881 -271.088485) (xy 105.197448 -271.117861)
			(xy 105.152916 -271.140551) (xy 105.105384 -271.155995) (xy 105.056021 -271.163814) (xy 105.006043 -271.163814)
			(xy 104.95668 -271.155995) (xy 104.909148 -271.140551) (xy 104.864616 -271.117861) (xy 104.824183 -271.088485)
			(xy 104.788843 -271.053145) (xy 104.759467 -271.012712) (xy 104.736777 -270.96818) (xy 104.721333 -270.920648)
			(xy 104.713514 -270.871285) (xy 104.408496 -270.871285) (xy 104.400677 -270.920648) (xy 104.385233 -270.96818)
			(xy 104.362543 -271.012712) (xy 104.333167 -271.053145) (xy 104.297827 -271.088485) (xy 104.257394 -271.117861)
			(xy 104.212862 -271.140551) (xy 104.16533 -271.155995) (xy 104.115967 -271.163814) (xy 104.065989 -271.163814)
			(xy 104.016626 -271.155995) (xy 103.969094 -271.140551) (xy 103.924562 -271.117861) (xy 103.884129 -271.088485)
			(xy 103.848789 -271.053145) (xy 103.819413 -271.012712) (xy 103.796723 -270.96818) (xy 103.781279 -270.920648)
			(xy 103.77346 -270.871285) (xy 103.468696 -270.871285) (xy 103.460877 -270.920648) (xy 103.445433 -270.96818)
			(xy 103.422743 -271.012712) (xy 103.393367 -271.053145) (xy 103.358027 -271.088485) (xy 103.317594 -271.117861)
			(xy 103.273062 -271.140551) (xy 103.22553 -271.155995) (xy 103.176167 -271.163814) (xy 103.126189 -271.163814)
			(xy 103.076826 -271.155995) (xy 103.029294 -271.140551) (xy 102.984762 -271.117861) (xy 102.944329 -271.088485)
			(xy 102.908989 -271.053145) (xy 102.879613 -271.012712) (xy 102.856923 -270.96818) (xy 102.841479 -270.920648)
			(xy 102.83366 -270.871285) (xy 102.528642 -270.871285) (xy 102.520823 -270.920648) (xy 102.505379 -270.96818)
			(xy 102.482689 -271.012712) (xy 102.453313 -271.053145) (xy 102.417973 -271.088485) (xy 102.37754 -271.117861)
			(xy 102.333008 -271.140551) (xy 102.285476 -271.155995) (xy 102.236113 -271.163814) (xy 102.186135 -271.163814)
			(xy 102.136772 -271.155995) (xy 102.08924 -271.140551) (xy 102.044708 -271.117861) (xy 102.004275 -271.088485)
			(xy 101.968935 -271.053145) (xy 101.939559 -271.012712) (xy 101.916869 -270.96818) (xy 101.901425 -270.920648)
			(xy 101.893606 -270.871285) (xy 101.588588 -270.871285) (xy 101.580769 -270.920648) (xy 101.565325 -270.96818)
			(xy 101.542635 -271.012712) (xy 101.513259 -271.053145) (xy 101.477919 -271.088485) (xy 101.437486 -271.117861)
			(xy 101.392954 -271.140551) (xy 101.345422 -271.155995) (xy 101.296059 -271.163814) (xy 101.246081 -271.163814)
			(xy 101.196718 -271.155995) (xy 101.149186 -271.140551) (xy 101.104654 -271.117861) (xy 101.064221 -271.088485)
			(xy 101.028881 -271.053145) (xy 100.999505 -271.012712) (xy 100.976815 -270.96818) (xy 100.961371 -270.920648)
			(xy 100.953552 -270.871285) (xy 100.648572 -270.871285) (xy 100.648568 -270.871501) (xy 100.640609 -270.921279)
			(xy 100.624904 -270.96918) (xy 100.601847 -271.014008) (xy 100.572013 -271.054642) (xy 100.536148 -271.090067)
			(xy 100.515928 -271.105122) (xy 100.507546 -271.110964) (xy 100.496878 -271.128236) (xy 100.482146 -271.21993)
			(xy 100.486972 -271.239488) (xy 100.493068 -271.24787) (xy 100.505321 -271.264955) (xy 100.526823 -271.301087)
			(xy 100.535994 -271.320006) (xy 100.540312 -271.32915) (xy 100.55479 -271.342612) (xy 100.64115 -271.374108)
			(xy 100.660708 -271.373346) (xy 100.670106 -271.369282) (xy 100.690765 -271.360253) (xy 100.73401 -271.347499)
			(xy 100.778628 -271.341018) (xy 100.80117 -271.34058) (xy 100.825983 -271.341035) (xy 100.874999 -271.348794)
			(xy 100.922198 -271.364126) (xy 100.966417 -271.386653) (xy 101.006567 -271.41582) (xy 101.04166 -271.45091)
			(xy 101.070831 -271.491057) (xy 101.093362 -271.535274) (xy 101.108699 -271.582471) (xy 101.116463 -271.631487)
			(xy 101.116463 -271.656302) (xy 101.425248 -271.656302) (xy 101.425735 -271.631492) (xy 101.433497 -271.582484)
			(xy 101.44883 -271.535294) (xy 101.471357 -271.491083) (xy 101.500522 -271.45094) (xy 101.535608 -271.415854)
			(xy 101.575751 -271.386689) (xy 101.619962 -271.364162) (xy 101.667152 -271.348829) (xy 101.71616 -271.341067)
			(xy 101.76578 -271.341067) (xy 101.814788 -271.348829) (xy 101.861978 -271.364162) (xy 101.906189 -271.386689)
			(xy 101.946332 -271.415854) (xy 101.981418 -271.45094) (xy 102.010583 -271.491083) (xy 102.03311 -271.535294)
			(xy 102.048443 -271.582484) (xy 102.056205 -271.631492) (xy 102.056692 -271.656302) (xy 102.056306 -271.677363)
			(xy 102.055772 -271.681291) (xy 102.363506 -271.681291) (xy 102.363506 -271.631313) (xy 102.371325 -271.58195)
			(xy 102.386769 -271.534418) (xy 102.409459 -271.489886) (xy 102.438835 -271.449453) (xy 102.474175 -271.414113)
			(xy 102.514608 -271.384737) (xy 102.55914 -271.362047) (xy 102.606672 -271.346603) (xy 102.656035 -271.338784)
			(xy 102.706013 -271.338784) (xy 102.755376 -271.346603) (xy 102.802908 -271.362047) (xy 102.84744 -271.384737)
			(xy 102.887873 -271.414113) (xy 102.923213 -271.449453) (xy 102.952589 -271.489886) (xy 102.975279 -271.534418)
			(xy 102.990723 -271.58195) (xy 102.998542 -271.631313) (xy 102.999032 -271.656302) (xy 103.304843 -271.656302)
			(xy 103.308938 -271.605574) (xy 103.321117 -271.55616) (xy 103.341065 -271.50934) (xy 103.368266 -271.466326)
			(xy 103.402014 -271.428232) (xy 103.441436 -271.396045) (xy 103.48551 -271.370599) (xy 103.533096 -271.352552)
			(xy 103.58296 -271.342372) (xy 103.633812 -271.340323) (xy 103.684333 -271.346457) (xy 103.733217 -271.360617)
			(xy 103.779196 -271.382434) (xy 103.82108 -271.411344) (xy 103.857784 -271.446599) (xy 103.888357 -271.487285)
			(xy 103.912008 -271.532348) (xy 103.928124 -271.580622) (xy 103.936288 -271.630856) (xy 103.9368 -271.656302)
			(xy 104.244897 -271.656302) (xy 104.248992 -271.605574) (xy 104.261171 -271.55616) (xy 104.281119 -271.50934)
			(xy 104.30832 -271.466326) (xy 104.342068 -271.428232) (xy 104.38149 -271.396045) (xy 104.425564 -271.370599)
			(xy 104.47315 -271.352552) (xy 104.523014 -271.342372) (xy 104.573866 -271.340323) (xy 104.624387 -271.346457)
			(xy 104.673271 -271.360617) (xy 104.71925 -271.382434) (xy 104.761134 -271.411344) (xy 104.797838 -271.446599)
			(xy 104.828411 -271.487285) (xy 104.852062 -271.532348) (xy 104.868178 -271.580622) (xy 104.876342 -271.630856)
			(xy 104.876854 -271.656302) (xy 104.876342 -271.681748) (xy 104.868178 -271.731982) (xy 104.852062 -271.780256)
			(xy 104.828411 -271.825319) (xy 104.797838 -271.866005) (xy 104.761134 -271.90126) (xy 104.71925 -271.93017)
			(xy 104.673271 -271.951987) (xy 104.624387 -271.966147) (xy 104.573866 -271.972281) (xy 104.523014 -271.970232)
			(xy 104.47315 -271.960052) (xy 104.425564 -271.942005) (xy 104.38149 -271.916559) (xy 104.342068 -271.884372)
			(xy 104.30832 -271.846278) (xy 104.281119 -271.803264) (xy 104.261171 -271.756444) (xy 104.248992 -271.70703)
			(xy 104.244897 -271.656302) (xy 103.9368 -271.656302) (xy 103.936288 -271.681748) (xy 103.928124 -271.731982)
			(xy 103.912008 -271.780256) (xy 103.888357 -271.825319) (xy 103.857784 -271.866005) (xy 103.82108 -271.90126)
			(xy 103.779196 -271.93017) (xy 103.733217 -271.951987) (xy 103.684333 -271.966147) (xy 103.633812 -271.972281)
			(xy 103.58296 -271.970232) (xy 103.533096 -271.960052) (xy 103.48551 -271.942005) (xy 103.441436 -271.916559)
			(xy 103.402014 -271.884372) (xy 103.368266 -271.846278) (xy 103.341065 -271.803264) (xy 103.321117 -271.756444)
			(xy 103.308938 -271.70703) (xy 103.304843 -271.656302) (xy 102.999032 -271.656302) (xy 102.998542 -271.681291)
			(xy 102.990723 -271.730654) (xy 102.975279 -271.778186) (xy 102.952589 -271.822718) (xy 102.923213 -271.863151)
			(xy 102.887873 -271.898491) (xy 102.84744 -271.927867) (xy 102.802908 -271.950557) (xy 102.755376 -271.966001)
			(xy 102.706013 -271.97382) (xy 102.656035 -271.97382) (xy 102.606672 -271.966001) (xy 102.55914 -271.950557)
			(xy 102.514608 -271.927867) (xy 102.474175 -271.898491) (xy 102.438835 -271.863151) (xy 102.409459 -271.822718)
			(xy 102.386769 -271.778186) (xy 102.371325 -271.730654) (xy 102.363506 -271.681291) (xy 102.055772 -271.681291)
			(xy 102.05063 -271.719102) (xy 102.039459 -271.759717) (xy 102.031546 -271.779238) (xy 102.02672 -271.790922)
			(xy 102.029006 -271.816322) (xy 102.082854 -271.897602) (xy 102.090361 -271.907767) (xy 102.112647 -271.919619)
			(xy 102.125272 -271.920208) (xy 102.198932 -271.920208) (xy 102.219994 -271.920695) (xy 102.261299 -271.928954)
			(xy 102.300186 -271.945146) (xy 102.335146 -271.968644) (xy 102.364825 -271.998535) (xy 102.388072 -272.033663)
			(xy 102.403986 -272.072664) (xy 102.411951 -272.114028) (xy 102.412292 -272.135092) (xy 102.412292 -272.196814)
			(xy 102.412755 -272.207247) (xy 102.421025 -272.226399) (xy 102.428294 -272.233898) (xy 102.446978 -272.252089)
			(xy 102.478741 -272.293441) (xy 102.503338 -272.339418) (xy 102.520111 -272.38879) (xy 102.52861 -272.440236)
			(xy 102.529132 -272.466308) (xy 104.713024 -272.466308) (xy 104.713483 -272.441541) (xy 104.721142 -272.392604)
			(xy 104.736293 -272.345445) (xy 104.758568 -272.301203) (xy 104.78743 -272.260948) (xy 104.822182 -272.225652)
			(xy 104.841802 -272.21053) (xy 104.850978 -272.202965) (xy 104.861694 -272.181764) (xy 104.862376 -272.16989)
			(xy 104.862376 -272.135346) (xy 104.862376 -272.135092) (xy 104.862655 -272.114024) (xy 104.870623 -272.072654)
			(xy 104.886543 -272.033647) (xy 104.909798 -271.998516) (xy 104.939487 -271.968624) (xy 104.974458 -271.945129)
			(xy 105.013356 -271.928943) (xy 105.054671 -271.920694) (xy 105.075736 -271.920208) (xy 105.11409 -271.920208)
			(xy 105.126629 -271.91951) (xy 105.148738 -271.907663) (xy 105.156254 -271.897602) (xy 105.210356 -271.816322)
			(xy 105.212642 -271.79143) (xy 105.207816 -271.779492) (xy 105.199974 -271.759909) (xy 105.188902 -271.719203)
			(xy 105.183291 -271.677394) (xy 105.182924 -271.656302) (xy 105.183414 -271.631313) (xy 105.191233 -271.58195)
			(xy 105.206677 -271.534418) (xy 105.229367 -271.489886) (xy 105.258743 -271.449453) (xy 105.294083 -271.414113)
			(xy 105.334516 -271.384737) (xy 105.379048 -271.362047) (xy 105.42658 -271.346603) (xy 105.475943 -271.338784)
			(xy 105.525921 -271.338784) (xy 105.575284 -271.346603) (xy 105.622816 -271.362047) (xy 105.667348 -271.384737)
			(xy 105.707781 -271.414113) (xy 105.743121 -271.449453) (xy 105.772497 -271.489886) (xy 105.795187 -271.534418)
			(xy 105.810631 -271.58195) (xy 105.81845 -271.631313) (xy 105.81894 -271.656302) (xy 106.124751 -271.656302)
			(xy 106.128846 -271.605574) (xy 106.141025 -271.55616) (xy 106.160973 -271.50934) (xy 106.188174 -271.466326)
			(xy 106.221922 -271.428232) (xy 106.261344 -271.396045) (xy 106.305418 -271.370599) (xy 106.353004 -271.352552)
			(xy 106.402868 -271.342372) (xy 106.45372 -271.340323) (xy 106.504241 -271.346457) (xy 106.553125 -271.360617)
			(xy 106.599104 -271.382434) (xy 106.640988 -271.411344) (xy 106.677692 -271.446599) (xy 106.708265 -271.487285)
			(xy 106.731916 -271.532348) (xy 106.748032 -271.580622) (xy 106.756196 -271.630856) (xy 106.756708 -271.656302)
			(xy 107.065572 -271.656302) (xy 107.066058 -271.631512) (xy 107.073814 -271.582544) (xy 107.089135 -271.535391)
			(xy 107.111644 -271.491216) (xy 107.140786 -271.451105) (xy 107.175843 -271.416048) (xy 107.215954 -271.386906)
			(xy 107.260129 -271.364397) (xy 107.307282 -271.349076) (xy 107.35625 -271.34132) (xy 107.40583 -271.34132)
			(xy 107.454798 -271.349076) (xy 107.501951 -271.364397) (xy 107.546126 -271.386906) (xy 107.586237 -271.416048)
			(xy 107.621294 -271.451105) (xy 107.650436 -271.491216) (xy 107.672945 -271.535391) (xy 107.688266 -271.582544)
			(xy 107.696022 -271.631512) (xy 107.696508 -271.656302) (xy 107.696202 -271.677358) (xy 107.690621 -271.719097)
			(xy 107.679518 -271.759719) (xy 107.671616 -271.779238) (xy 107.66679 -271.790922) (xy 107.669076 -271.816322)
			(xy 107.722924 -271.897602) (xy 107.730446 -271.907753) (xy 107.752721 -271.919612) (xy 107.765342 -271.920208)
			(xy 107.812586 -271.920208) (xy 107.824615 -271.919552) (xy 107.846079 -271.908683) (xy 107.853734 -271.89938)
			(xy 107.90936 -271.82318) (xy 107.91317 -271.799558) (xy 107.90936 -271.787874) (xy 107.899834 -271.75582)
			(xy 107.889628 -271.689736) (xy 107.88904 -271.656302) (xy 107.889487 -271.628012) (xy 107.896869 -271.571915)
			(xy 107.911507 -271.51726) (xy 107.933151 -271.464983) (xy 107.96143 -271.415976) (xy 107.995861 -271.371077)
			(xy 108.015532 -271.35074) (xy 108.088938 -271.27708) (xy 108.095288 -271.267174) (xy 108.097066 -271.261332)
			(xy 108.107206 -271.232063) (xy 108.134727 -271.176568) (xy 108.169884 -271.125569) (xy 108.211958 -271.080107)
			(xy 108.260089 -271.041114) (xy 108.313291 -271.009388) (xy 108.370476 -270.985577) (xy 108.400342 -270.97736)
			(xy 108.409232 -270.975074) (xy 108.42371 -270.965168) (xy 108.472224 -270.897096) (xy 108.47705 -270.880078)
			(xy 108.476288 -270.870934) (xy 108.475272 -270.846296) (xy 108.475759 -270.821486) (xy 108.483521 -270.772478)
			(xy 108.498854 -270.725288) (xy 108.521381 -270.681077) (xy 108.550546 -270.640934) (xy 108.585632 -270.605848)
			(xy 108.625775 -270.576683) (xy 108.669986 -270.554156) (xy 108.717176 -270.538823) (xy 108.766184 -270.531061)
			(xy 108.815804 -270.531061) (xy 108.864812 -270.538823) (xy 108.912002 -270.554156) (xy 108.956213 -270.576683)
			(xy 108.996356 -270.605848) (xy 109.031442 -270.640934) (xy 109.060607 -270.681077) (xy 109.083134 -270.725288)
			(xy 109.098467 -270.772478) (xy 109.106229 -270.821486) (xy 109.106716 -270.846296) (xy 109.414813 -270.846296)
			(xy 109.418908 -270.795568) (xy 109.431087 -270.746154) (xy 109.451035 -270.699334) (xy 109.478236 -270.65632)
			(xy 109.511984 -270.618226) (xy 109.551406 -270.586039) (xy 109.59548 -270.560593) (xy 109.643066 -270.542546)
			(xy 109.69293 -270.532366) (xy 109.743782 -270.530317) (xy 109.794303 -270.536451) (xy 109.843187 -270.550611)
			(xy 109.889166 -270.572428) (xy 109.93105 -270.601338) (xy 109.967754 -270.636593) (xy 109.998327 -270.677279)
			(xy 110.021978 -270.722342) (xy 110.038094 -270.770616) (xy 110.046258 -270.82085) (xy 110.04677 -270.846296)
			(xy 110.046267 -270.871285) (xy 110.353584 -270.871285) (xy 110.353584 -270.821307) (xy 110.361403 -270.771944)
			(xy 110.376847 -270.724412) (xy 110.399537 -270.67988) (xy 110.428913 -270.639447) (xy 110.464253 -270.604107)
			(xy 110.504686 -270.574731) (xy 110.549218 -270.552041) (xy 110.59675 -270.536597) (xy 110.646113 -270.528778)
			(xy 110.696091 -270.528778) (xy 110.745454 -270.536597) (xy 110.792986 -270.552041) (xy 110.837518 -270.574731)
			(xy 110.877951 -270.604107) (xy 110.913291 -270.639447) (xy 110.942667 -270.67988) (xy 110.965357 -270.724412)
			(xy 110.980801 -270.771944) (xy 110.98862 -270.821307) (xy 110.98911 -270.846296) (xy 110.98862 -270.871285)
			(xy 113.167142 -270.871285) (xy 113.167142 -270.821307) (xy 113.174961 -270.771944) (xy 113.190405 -270.724412)
			(xy 113.213095 -270.67988) (xy 113.242471 -270.639447) (xy 113.277811 -270.604107) (xy 113.318244 -270.574731)
			(xy 113.362776 -270.552041) (xy 113.410308 -270.536597) (xy 113.459671 -270.528778) (xy 113.509649 -270.528778)
			(xy 113.559012 -270.536597) (xy 113.606544 -270.552041) (xy 113.651076 -270.574731) (xy 113.691509 -270.604107)
			(xy 113.726849 -270.639447) (xy 113.756225 -270.67988) (xy 113.778915 -270.724412) (xy 113.794359 -270.771944)
			(xy 113.802178 -270.821307) (xy 113.802668 -270.846296) (xy 114.108479 -270.846296) (xy 114.112574 -270.795568)
			(xy 114.124753 -270.746154) (xy 114.144701 -270.699334) (xy 114.171902 -270.65632) (xy 114.20565 -270.618226)
			(xy 114.245072 -270.586039) (xy 114.289146 -270.560593) (xy 114.336732 -270.542546) (xy 114.386596 -270.532366)
			(xy 114.437448 -270.530317) (xy 114.487969 -270.536451) (xy 114.536853 -270.550611) (xy 114.582832 -270.572428)
			(xy 114.624716 -270.601338) (xy 114.66142 -270.636593) (xy 114.691993 -270.677279) (xy 114.715644 -270.722342)
			(xy 114.73176 -270.770616) (xy 114.739924 -270.82085) (xy 114.740436 -270.846296) (xy 115.0493 -270.846296)
			(xy 115.049786 -270.821506) (xy 115.057542 -270.772538) (xy 115.072863 -270.725385) (xy 115.095372 -270.68121)
			(xy 115.124514 -270.641099) (xy 115.159571 -270.606042) (xy 115.199682 -270.5769) (xy 115.243857 -270.554391)
			(xy 115.29101 -270.53907) (xy 115.339978 -270.531314) (xy 115.389558 -270.531314) (xy 115.438526 -270.53907)
			(xy 115.485679 -270.554391) (xy 115.529854 -270.5769) (xy 115.569965 -270.606042) (xy 115.605022 -270.641099)
			(xy 115.634164 -270.68121) (xy 115.656673 -270.725385) (xy 115.671994 -270.772538) (xy 115.67975 -270.821506)
			(xy 115.680236 -270.846296) (xy 115.680119 -270.858989) (xy 115.678084 -270.884293) (xy 115.676172 -270.896842)
			(xy 115.674394 -270.908018) (xy 115.680744 -270.929608) (xy 115.74653 -271.005554) (xy 115.767104 -271.014698)
			(xy 115.77828 -271.014698) (xy 115.784884 -271.014444) (xy 115.811537 -271.014927) (xy 115.864311 -271.022453)
			(xy 115.89004 -271.02943) (xy 115.896898 -271.031208) (xy 115.914932 -271.031208) (xy 115.924708 -271.031385)
			(xy 115.94417 -271.033289) (xy 115.953794 -271.035018) (xy 115.964638 -271.036381) (xy 115.985809 -271.031081)
			(xy 116.002885 -271.01749) (xy 116.0128 -270.998049) (xy 116.013775 -270.976247) (xy 116.010182 -270.96593)
			(xy 115.999297 -270.937226) (xy 115.987526 -270.876986) (xy 115.986814 -270.846296) (xy 115.987287 -270.821308)
			(xy 115.995105 -270.771946) (xy 116.010549 -270.724415) (xy 116.033238 -270.679886) (xy 116.062614 -270.639454)
			(xy 116.097953 -270.604115) (xy 116.138385 -270.574739) (xy 116.182915 -270.552049) (xy 116.230445 -270.536605)
			(xy 116.279807 -270.528787) (xy 116.329784 -270.528786) (xy 116.379145 -270.536603) (xy 116.426677 -270.552046)
			(xy 116.471207 -270.574734) (xy 116.51164 -270.604109) (xy 116.54698 -270.639447) (xy 116.576357 -270.679878)
			(xy 116.599047 -270.724407) (xy 116.614493 -270.771937) (xy 116.622313 -270.821298) (xy 116.622315 -270.871275)
			(xy 116.622313 -270.871285) (xy 116.927104 -270.871285) (xy 116.927104 -270.821307) (xy 116.934923 -270.771944)
			(xy 116.950367 -270.724412) (xy 116.973057 -270.67988) (xy 117.002433 -270.639447) (xy 117.037773 -270.604107)
			(xy 117.078206 -270.574731) (xy 117.122738 -270.552041) (xy 117.17027 -270.536597) (xy 117.219633 -270.528778)
			(xy 117.269611 -270.528778) (xy 117.318974 -270.536597) (xy 117.366506 -270.552041) (xy 117.411038 -270.574731)
			(xy 117.451471 -270.604107) (xy 117.486811 -270.639447) (xy 117.516187 -270.67988) (xy 117.538877 -270.724412)
			(xy 117.554321 -270.771944) (xy 117.56214 -270.821307) (xy 117.56263 -270.846296) (xy 117.56214 -270.871285)
			(xy 117.867158 -270.871285) (xy 117.867158 -270.821307) (xy 117.874977 -270.771944) (xy 117.890421 -270.724412)
			(xy 117.913111 -270.67988) (xy 117.942487 -270.639447) (xy 117.977827 -270.604107) (xy 118.01826 -270.574731)
			(xy 118.062792 -270.552041) (xy 118.110324 -270.536597) (xy 118.159687 -270.528778) (xy 118.209665 -270.528778)
			(xy 118.259028 -270.536597) (xy 118.30656 -270.552041) (xy 118.351092 -270.574731) (xy 118.391525 -270.604107)
			(xy 118.426865 -270.639447) (xy 118.456241 -270.67988) (xy 118.478931 -270.724412) (xy 118.494375 -270.771944)
			(xy 118.502194 -270.821307) (xy 118.502684 -270.846296) (xy 118.502194 -270.871285) (xy 118.807212 -270.871285)
			(xy 118.807212 -270.821307) (xy 118.815031 -270.771944) (xy 118.830475 -270.724412) (xy 118.853165 -270.67988)
			(xy 118.882541 -270.639447) (xy 118.917881 -270.604107) (xy 118.958314 -270.574731) (xy 119.002846 -270.552041)
			(xy 119.050378 -270.536597) (xy 119.099741 -270.528778) (xy 119.149719 -270.528778) (xy 119.199082 -270.536597)
			(xy 119.246614 -270.552041) (xy 119.291146 -270.574731) (xy 119.331579 -270.604107) (xy 119.366919 -270.639447)
			(xy 119.396295 -270.67988) (xy 119.418985 -270.724412) (xy 119.434429 -270.771944) (xy 119.442248 -270.821307)
			(xy 119.442738 -270.846296) (xy 119.442248 -270.871285) (xy 119.747266 -270.871285) (xy 119.747266 -270.821307)
			(xy 119.755085 -270.771944) (xy 119.770529 -270.724412) (xy 119.793219 -270.67988) (xy 119.822595 -270.639447)
			(xy 119.857935 -270.604107) (xy 119.898368 -270.574731) (xy 119.9429 -270.552041) (xy 119.990432 -270.536597)
			(xy 120.039795 -270.528778) (xy 120.089773 -270.528778) (xy 120.139136 -270.536597) (xy 120.186668 -270.552041)
			(xy 120.2312 -270.574731) (xy 120.271633 -270.604107) (xy 120.306973 -270.639447) (xy 120.336349 -270.67988)
			(xy 120.359039 -270.724412) (xy 120.374483 -270.771944) (xy 120.382302 -270.821307) (xy 120.382792 -270.846296)
			(xy 120.382302 -270.871285) (xy 120.68732 -270.871285) (xy 120.68732 -270.821307) (xy 120.695139 -270.771944)
			(xy 120.710583 -270.724412) (xy 120.733273 -270.67988) (xy 120.762649 -270.639447) (xy 120.797989 -270.604107)
			(xy 120.838422 -270.574731) (xy 120.882954 -270.552041) (xy 120.930486 -270.536597) (xy 120.979849 -270.528778)
			(xy 121.029827 -270.528778) (xy 121.07919 -270.536597) (xy 121.126722 -270.552041) (xy 121.171254 -270.574731)
			(xy 121.211687 -270.604107) (xy 121.247027 -270.639447) (xy 121.276403 -270.67988) (xy 121.299093 -270.724412)
			(xy 121.314537 -270.771944) (xy 121.322356 -270.821307) (xy 121.322846 -270.846296) (xy 121.322356 -270.871285)
			(xy 121.62712 -270.871285) (xy 121.62712 -270.821307) (xy 121.634939 -270.771944) (xy 121.650383 -270.724412)
			(xy 121.673073 -270.67988) (xy 121.702449 -270.639447) (xy 121.737789 -270.604107) (xy 121.778222 -270.574731)
			(xy 121.822754 -270.552041) (xy 121.870286 -270.536597) (xy 121.919649 -270.528778) (xy 121.969627 -270.528778)
			(xy 122.01899 -270.536597) (xy 122.066522 -270.552041) (xy 122.111054 -270.574731) (xy 122.151487 -270.604107)
			(xy 122.186827 -270.639447) (xy 122.216203 -270.67988) (xy 122.238893 -270.724412) (xy 122.254337 -270.771944)
			(xy 122.262156 -270.821307) (xy 122.262646 -270.846296) (xy 122.262156 -270.871285) (xy 122.567174 -270.871285)
			(xy 122.567174 -270.821307) (xy 122.574993 -270.771944) (xy 122.590437 -270.724412) (xy 122.613127 -270.67988)
			(xy 122.642503 -270.639447) (xy 122.677843 -270.604107) (xy 122.718276 -270.574731) (xy 122.762808 -270.552041)
			(xy 122.81034 -270.536597) (xy 122.859703 -270.528778) (xy 122.909681 -270.528778) (xy 122.959044 -270.536597)
			(xy 123.006576 -270.552041) (xy 123.051108 -270.574731) (xy 123.091541 -270.604107) (xy 123.126881 -270.639447)
			(xy 123.156257 -270.67988) (xy 123.178947 -270.724412) (xy 123.194391 -270.771944) (xy 123.20221 -270.821307)
			(xy 123.2027 -270.846296) (xy 123.20221 -270.871285) (xy 123.194391 -270.920648) (xy 123.178947 -270.96818)
			(xy 123.156257 -271.012712) (xy 123.126881 -271.053145) (xy 123.091541 -271.088485) (xy 123.051108 -271.117861)
			(xy 123.006576 -271.140551) (xy 122.959044 -271.155995) (xy 122.909681 -271.163814) (xy 122.859703 -271.163814)
			(xy 122.81034 -271.155995) (xy 122.762808 -271.140551) (xy 122.718276 -271.117861) (xy 122.677843 -271.088485)
			(xy 122.642503 -271.053145) (xy 122.613127 -271.012712) (xy 122.590437 -270.96818) (xy 122.574993 -270.920648)
			(xy 122.567174 -270.871285) (xy 122.262156 -270.871285) (xy 122.254337 -270.920648) (xy 122.238893 -270.96818)
			(xy 122.216203 -271.012712) (xy 122.186827 -271.053145) (xy 122.151487 -271.088485) (xy 122.111054 -271.117861)
			(xy 122.066522 -271.140551) (xy 122.01899 -271.155995) (xy 121.969627 -271.163814) (xy 121.919649 -271.163814)
			(xy 121.870286 -271.155995) (xy 121.822754 -271.140551) (xy 121.778222 -271.117861) (xy 121.737789 -271.088485)
			(xy 121.702449 -271.053145) (xy 121.673073 -271.012712) (xy 121.650383 -270.96818) (xy 121.634939 -270.920648)
			(xy 121.62712 -270.871285) (xy 121.322356 -270.871285) (xy 121.314537 -270.920648) (xy 121.299093 -270.96818)
			(xy 121.276403 -271.012712) (xy 121.247027 -271.053145) (xy 121.211687 -271.088485) (xy 121.171254 -271.117861)
			(xy 121.126722 -271.140551) (xy 121.07919 -271.155995) (xy 121.029827 -271.163814) (xy 120.979849 -271.163814)
			(xy 120.930486 -271.155995) (xy 120.882954 -271.140551) (xy 120.838422 -271.117861) (xy 120.797989 -271.088485)
			(xy 120.762649 -271.053145) (xy 120.733273 -271.012712) (xy 120.710583 -270.96818) (xy 120.695139 -270.920648)
			(xy 120.68732 -270.871285) (xy 120.382302 -270.871285) (xy 120.374483 -270.920648) (xy 120.359039 -270.96818)
			(xy 120.336349 -271.012712) (xy 120.306973 -271.053145) (xy 120.271633 -271.088485) (xy 120.2312 -271.117861)
			(xy 120.186668 -271.140551) (xy 120.139136 -271.155995) (xy 120.089773 -271.163814) (xy 120.039795 -271.163814)
			(xy 119.990432 -271.155995) (xy 119.9429 -271.140551) (xy 119.898368 -271.117861) (xy 119.857935 -271.088485)
			(xy 119.822595 -271.053145) (xy 119.793219 -271.012712) (xy 119.770529 -270.96818) (xy 119.755085 -270.920648)
			(xy 119.747266 -270.871285) (xy 119.442248 -270.871285) (xy 119.434429 -270.920648) (xy 119.418985 -270.96818)
			(xy 119.396295 -271.012712) (xy 119.366919 -271.053145) (xy 119.331579 -271.088485) (xy 119.291146 -271.117861)
			(xy 119.246614 -271.140551) (xy 119.199082 -271.155995) (xy 119.149719 -271.163814) (xy 119.099741 -271.163814)
			(xy 119.050378 -271.155995) (xy 119.002846 -271.140551) (xy 118.958314 -271.117861) (xy 118.917881 -271.088485)
			(xy 118.882541 -271.053145) (xy 118.853165 -271.012712) (xy 118.830475 -270.96818) (xy 118.815031 -270.920648)
			(xy 118.807212 -270.871285) (xy 118.502194 -270.871285) (xy 118.494375 -270.920648) (xy 118.478931 -270.96818)
			(xy 118.456241 -271.012712) (xy 118.426865 -271.053145) (xy 118.391525 -271.088485) (xy 118.351092 -271.117861)
			(xy 118.30656 -271.140551) (xy 118.259028 -271.155995) (xy 118.209665 -271.163814) (xy 118.159687 -271.163814)
			(xy 118.110324 -271.155995) (xy 118.062792 -271.140551) (xy 118.01826 -271.117861) (xy 117.977827 -271.088485)
			(xy 117.942487 -271.053145) (xy 117.913111 -271.012712) (xy 117.890421 -270.96818) (xy 117.874977 -270.920648)
			(xy 117.867158 -270.871285) (xy 117.56214 -270.871285) (xy 117.554321 -270.920648) (xy 117.538877 -270.96818)
			(xy 117.516187 -271.012712) (xy 117.486811 -271.053145) (xy 117.451471 -271.088485) (xy 117.411038 -271.117861)
			(xy 117.366506 -271.140551) (xy 117.318974 -271.155995) (xy 117.269611 -271.163814) (xy 117.219633 -271.163814)
			(xy 117.17027 -271.155995) (xy 117.122738 -271.140551) (xy 117.078206 -271.117861) (xy 117.037773 -271.088485)
			(xy 117.002433 -271.053145) (xy 116.973057 -271.012712) (xy 116.950367 -270.96818) (xy 116.934923 -270.920648)
			(xy 116.927104 -270.871285) (xy 116.622313 -270.871285) (xy 116.614499 -270.920637) (xy 116.599057 -270.968169)
			(xy 116.576371 -271.012699) (xy 116.546997 -271.053133) (xy 116.51166 -271.088474) (xy 116.47123 -271.117852)
			(xy 116.426701 -271.140544) (xy 116.379171 -271.155991) (xy 116.32981 -271.163812) (xy 116.304822 -271.164304)
			(xy 116.275843 -271.163692) (xy 116.218842 -271.153206) (xy 116.191538 -271.143476) (xy 116.181155 -271.140119)
			(xy 116.159401 -271.141515) (xy 116.140178 -271.151793) (xy 116.126936 -271.169108) (xy 116.12205 -271.190351)
			(xy 116.12372 -271.201134) (xy 116.126768 -271.220438) (xy 116.127301 -271.224506) (xy 116.129464 -271.232418)
			(xy 116.131086 -271.236186) (xy 116.14222 -271.261333) (xy 116.157916 -271.31404) (xy 116.165878 -271.368455)
			(xy 116.166392 -271.395952) (xy 116.166392 -271.46123) (xy 116.169186 -271.473168) (xy 116.172234 -271.478502)
			(xy 116.186072 -271.506075) (xy 116.20566 -271.564572) (xy 116.215584 -271.625457) (xy 116.216176 -271.656302)
			(xy 116.215768 -271.68136) (xy 116.209168 -271.73104) (xy 116.196121 -271.779429) (xy 116.176852 -271.825693)
			(xy 116.164614 -271.847564) (xy 116.160155 -271.856097) (xy 116.157297 -271.875122) (xy 116.161643 -271.893862)
			(xy 116.172581 -271.909688) (xy 116.188576 -271.920376) (xy 116.207382 -271.924428) (xy 116.216938 -271.923256)
			(xy 116.225572 -271.921873) (xy 116.242993 -271.92035) (xy 116.251736 -271.920208) (xy 116.39042 -271.920208)
			(xy 116.403032 -271.919607) (xy 116.42528 -271.90772) (xy 116.432838 -271.897602) (xy 116.486686 -271.816322)
			(xy 116.488972 -271.790922) (xy 116.484146 -271.779238) (xy 116.476236 -271.759715) (xy 116.465057 -271.719102)
			(xy 116.459384 -271.677363) (xy 116.459 -271.656302) (xy 116.459487 -271.631492) (xy 116.467249 -271.582484)
			(xy 116.482582 -271.535294) (xy 116.505109 -271.491083) (xy 116.534274 -271.45094) (xy 116.56936 -271.415854)
			(xy 116.609503 -271.386689) (xy 116.653714 -271.364162) (xy 116.700904 -271.348829) (xy 116.749912 -271.341067)
			(xy 116.799532 -271.341067) (xy 116.84854 -271.348829) (xy 116.89573 -271.364162) (xy 116.939941 -271.386689)
			(xy 116.980084 -271.415854) (xy 117.01517 -271.45094) (xy 117.044335 -271.491083) (xy 117.066862 -271.535294)
			(xy 117.082195 -271.582484) (xy 117.089957 -271.631492) (xy 117.090444 -271.656302) (xy 117.398541 -271.656302)
			(xy 117.402636 -271.605574) (xy 117.414815 -271.55616) (xy 117.434763 -271.50934) (xy 117.461964 -271.466326)
			(xy 117.495712 -271.428232) (xy 117.535134 -271.396045) (xy 117.579208 -271.370599) (xy 117.626794 -271.352552)
			(xy 117.676658 -271.342372) (xy 117.72751 -271.340323) (xy 117.778031 -271.346457) (xy 117.826915 -271.360617)
			(xy 117.872894 -271.382434) (xy 117.914778 -271.411344) (xy 117.951482 -271.446599) (xy 117.982055 -271.487285)
			(xy 118.005706 -271.532348) (xy 118.021822 -271.580622) (xy 118.029986 -271.630856) (xy 118.030498 -271.656302)
			(xy 118.336822 -271.656302) (xy 118.337312 -271.631313) (xy 118.345131 -271.58195) (xy 118.360575 -271.534418)
			(xy 118.383265 -271.489886) (xy 118.412641 -271.449453) (xy 118.447981 -271.414113) (xy 118.488414 -271.384737)
			(xy 118.532946 -271.362047) (xy 118.580478 -271.346603) (xy 118.629841 -271.338784) (xy 118.679819 -271.338784)
			(xy 118.729182 -271.346603) (xy 118.776714 -271.362047) (xy 118.821246 -271.384737) (xy 118.861679 -271.414113)
			(xy 118.897019 -271.449453) (xy 118.926395 -271.489886) (xy 118.949085 -271.534418) (xy 118.964529 -271.58195)
			(xy 118.972348 -271.631313) (xy 118.972838 -271.656302) (xy 118.972486 -271.677396) (xy 118.966901 -271.719213)
			(xy 118.955819 -271.759919) (xy 118.947946 -271.779492) (xy 118.94312 -271.79143) (xy 118.945406 -271.816322)
			(xy 118.999508 -271.897602) (xy 119.006991 -271.907701) (xy 119.029119 -271.919561) (xy 119.041672 -271.920208)
			(xy 119.216932 -271.920208) (xy 119.236025 -271.920701) (xy 119.273588 -271.927595) (xy 119.291608 -271.933924)
			(xy 119.300668 -271.936866) (xy 119.319697 -271.936646) (xy 119.337333 -271.929498) (xy 119.351146 -271.916409)
			(xy 119.359231 -271.899182) (xy 119.360473 -271.880192) (xy 119.354701 -271.862059) (xy 119.349012 -271.854422)
			(xy 119.332642 -271.8332) (xy 119.306484 -271.786427) (xy 119.288599 -271.735909) (xy 119.2795 -271.683097)
			(xy 119.278908 -271.656302) (xy 119.279363 -271.631493) (xy 119.287124 -271.582485) (xy 119.302457 -271.535295)
			(xy 119.324982 -271.491084) (xy 119.354146 -271.450941) (xy 119.389231 -271.415855) (xy 119.429373 -271.386689)
			(xy 119.473583 -271.364162) (xy 119.520772 -271.348827) (xy 119.569779 -271.341064) (xy 119.619398 -271.341062)
			(xy 119.668406 -271.348822) (xy 119.715596 -271.364153) (xy 119.759808 -271.386677) (xy 119.799951 -271.41584)
			(xy 119.835039 -271.450924) (xy 119.864206 -271.491065) (xy 119.886735 -271.535274) (xy 119.902071 -271.582463)
			(xy 119.909836 -271.63147) (xy 119.909838 -271.656302) (xy 120.218449 -271.656302) (xy 120.222544 -271.605574)
			(xy 120.234723 -271.55616) (xy 120.254671 -271.50934) (xy 120.281872 -271.466326) (xy 120.31562 -271.428232)
			(xy 120.355042 -271.396045) (xy 120.399116 -271.370599) (xy 120.446702 -271.352552) (xy 120.496566 -271.342372)
			(xy 120.547418 -271.340323) (xy 120.597939 -271.346457) (xy 120.646823 -271.360617) (xy 120.692802 -271.382434)
			(xy 120.734686 -271.411344) (xy 120.77139 -271.446599) (xy 120.801963 -271.487285) (xy 120.825614 -271.532348)
			(xy 120.84173 -271.580622) (xy 120.849894 -271.630856) (xy 120.850406 -271.656302) (xy 120.849903 -271.681291)
			(xy 121.15722 -271.681291) (xy 121.15722 -271.631313) (xy 121.165039 -271.58195) (xy 121.180483 -271.534418)
			(xy 121.203173 -271.489886) (xy 121.232549 -271.449453) (xy 121.267889 -271.414113) (xy 121.308322 -271.384737)
			(xy 121.352854 -271.362047) (xy 121.400386 -271.346603) (xy 121.449749 -271.338784) (xy 121.499727 -271.338784)
			(xy 121.54909 -271.346603) (xy 121.596622 -271.362047) (xy 121.641154 -271.384737) (xy 121.681587 -271.414113)
			(xy 121.716927 -271.449453) (xy 121.746303 -271.489886) (xy 121.768993 -271.534418) (xy 121.784437 -271.58195)
			(xy 121.792256 -271.631313) (xy 121.792746 -271.656302) (xy 121.792256 -271.681291) (xy 121.784437 -271.730654)
			(xy 121.768993 -271.778186) (xy 121.746303 -271.822718) (xy 121.716927 -271.863151) (xy 121.681587 -271.898491)
			(xy 121.641154 -271.927867) (xy 121.596622 -271.950557) (xy 121.54909 -271.966001) (xy 121.499727 -271.97382)
			(xy 121.449749 -271.97382) (xy 121.400386 -271.966001) (xy 121.352854 -271.950557) (xy 121.308322 -271.927867)
			(xy 121.267889 -271.898491) (xy 121.232549 -271.863151) (xy 121.203173 -271.822718) (xy 121.180483 -271.778186)
			(xy 121.165039 -271.730654) (xy 121.15722 -271.681291) (xy 120.849903 -271.681291) (xy 120.849894 -271.681748)
			(xy 120.84173 -271.731982) (xy 120.825614 -271.780256) (xy 120.801963 -271.825319) (xy 120.77139 -271.866005)
			(xy 120.734686 -271.90126) (xy 120.692802 -271.93017) (xy 120.646823 -271.951987) (xy 120.597939 -271.966147)
			(xy 120.547418 -271.972281) (xy 120.496566 -271.970232) (xy 120.446702 -271.960052) (xy 120.399116 -271.942005)
			(xy 120.355042 -271.916559) (xy 120.31562 -271.884372) (xy 120.281872 -271.846278) (xy 120.254671 -271.803264)
			(xy 120.234723 -271.756444) (xy 120.222544 -271.70703) (xy 120.218449 -271.656302) (xy 119.909838 -271.656302)
			(xy 119.909839 -271.681089) (xy 119.90208 -271.730097) (xy 119.886751 -271.777288) (xy 119.864228 -271.8215)
			(xy 119.835066 -271.861644) (xy 119.799983 -271.896733) (xy 119.759843 -271.925901) (xy 119.715635 -271.948431)
			(xy 119.668446 -271.963768) (xy 119.619439 -271.971535) (xy 119.59463 -271.972024) (xy 119.581355 -271.971857)
			(xy 119.554904 -271.96957) (xy 119.541798 -271.967452) (xy 119.529098 -271.96542) (xy 119.505476 -271.973294)
			(xy 119.42953 -272.052288) (xy 119.422672 -272.076418) (xy 119.425466 -272.088864) (xy 119.427764 -272.100282)
			(xy 119.430188 -272.123446) (xy 119.430292 -272.135092) (xy 119.430292 -272.377408) (xy 119.431816 -272.384012)
			(xy 119.436915 -272.404203) (xy 119.442396 -272.445486) (xy 119.442738 -272.466308) (xy 121.62663 -272.466308)
			(xy 121.627156 -272.439082) (xy 121.636422 -272.385425) (xy 121.6547 -272.334133) (xy 121.681455 -272.286709)
			(xy 121.715904 -272.24454) (xy 121.736104 -272.226278) (xy 121.743957 -272.218701) (xy 121.752913 -272.198826)
			(xy 121.753376 -272.187924) (xy 121.753376 -272.135092) (xy 121.753655 -272.114024) (xy 121.761623 -272.072654)
			(xy 121.777543 -272.033647) (xy 121.800798 -271.998516) (xy 121.830487 -271.968624) (xy 121.865458 -271.945129)
			(xy 121.904356 -271.928943) (xy 121.945671 -271.920694) (xy 121.966736 -271.920208) (xy 122.03049 -271.920208)
			(xy 122.0431 -271.919589) (xy 122.065348 -271.907715) (xy 122.072908 -271.897602) (xy 122.126756 -271.816322)
			(xy 122.129042 -271.790922) (xy 122.124216 -271.779238) (xy 122.116349 -271.759708) (xy 122.105271 -271.719086)
			(xy 122.099676 -271.677354) (xy 122.099324 -271.656302) (xy 122.09981 -271.631512) (xy 122.107566 -271.582544)
			(xy 122.122887 -271.535391) (xy 122.145396 -271.491216) (xy 122.174538 -271.451105) (xy 122.209595 -271.416048)
			(xy 122.249706 -271.386906) (xy 122.293881 -271.364397) (xy 122.341034 -271.349076) (xy 122.390002 -271.34132)
			(xy 122.439582 -271.34132) (xy 122.48855 -271.349076) (xy 122.535703 -271.364397) (xy 122.579878 -271.386906)
			(xy 122.619989 -271.416048) (xy 122.655046 -271.451105) (xy 122.684188 -271.491216) (xy 122.706697 -271.535391)
			(xy 122.722018 -271.582544) (xy 122.729774 -271.631512) (xy 122.73026 -271.656302) (xy 122.729867 -271.680564)
			(xy 122.729782 -271.681114) (xy 123.039542 -271.681114) (xy 123.039542 -271.631486) (xy 123.047306 -271.58247)
			(xy 123.062643 -271.535272) (xy 123.085175 -271.491055) (xy 123.114348 -271.450907) (xy 123.149442 -271.415818)
			(xy 123.189594 -271.386651) (xy 123.233815 -271.364125) (xy 123.281015 -271.348795) (xy 123.330032 -271.341038)
			(xy 123.354846 -271.34058) (xy 123.377656 -271.341006) (xy 123.422792 -271.347638) (xy 123.444762 -271.353788)
			(xy 123.453906 -271.356582) (xy 123.472956 -271.355058) (xy 123.55195 -271.316704) (xy 123.56465 -271.302734)
			(xy 123.568206 -271.293844) (xy 123.577787 -271.270586) (xy 123.601594 -271.226275) (xy 123.615704 -271.205452)
			(xy 123.621038 -271.197832) (xy 123.62561 -271.180814) (xy 123.617482 -271.09674) (xy 123.609862 -271.080992)
			(xy 123.603258 -271.074388) (xy 123.585335 -271.056304) (xy 123.554911 -271.015484) (xy 123.531384 -270.970335)
			(xy 123.515357 -270.922012) (xy 123.50724 -270.871752) (xy 123.506738 -270.846296) (xy 123.507228 -270.821307)
			(xy 123.515047 -270.771944) (xy 123.530491 -270.724412) (xy 123.553181 -270.67988) (xy 123.582557 -270.639447)
			(xy 123.617897 -270.604107) (xy 123.65833 -270.574731) (xy 123.702862 -270.552041) (xy 123.750394 -270.536597)
			(xy 123.799757 -270.528778) (xy 123.849735 -270.528778) (xy 123.899098 -270.536597) (xy 123.94663 -270.552041)
			(xy 123.991162 -270.574731) (xy 124.031595 -270.604107) (xy 124.066935 -270.639447) (xy 124.096311 -270.67988)
			(xy 124.119001 -270.724412) (xy 124.134445 -270.771944) (xy 124.142264 -270.821307) (xy 124.142754 -270.846296)
			(xy 124.142506 -270.863973) (xy 124.141684 -270.871285) (xy 124.447282 -270.871285) (xy 124.447282 -270.821307)
			(xy 124.455101 -270.771944) (xy 124.470545 -270.724412) (xy 124.493235 -270.67988) (xy 124.522611 -270.639447)
			(xy 124.557951 -270.604107) (xy 124.598384 -270.574731) (xy 124.642916 -270.552041) (xy 124.690448 -270.536597)
			(xy 124.739811 -270.528778) (xy 124.789789 -270.528778) (xy 124.839152 -270.536597) (xy 124.886684 -270.552041)
			(xy 124.931216 -270.574731) (xy 124.971649 -270.604107) (xy 125.006989 -270.639447) (xy 125.036365 -270.67988)
			(xy 125.059055 -270.724412) (xy 125.074499 -270.771944) (xy 125.082318 -270.821307) (xy 125.082808 -270.846296)
			(xy 125.082318 -270.871285) (xy 125.387336 -270.871285) (xy 125.387336 -270.821307) (xy 125.395155 -270.771944)
			(xy 125.410599 -270.724412) (xy 125.433289 -270.67988) (xy 125.462665 -270.639447) (xy 125.498005 -270.604107)
			(xy 125.538438 -270.574731) (xy 125.58297 -270.552041) (xy 125.630502 -270.536597) (xy 125.679865 -270.528778)
			(xy 125.729843 -270.528778) (xy 125.779206 -270.536597) (xy 125.826738 -270.552041) (xy 125.87127 -270.574731)
			(xy 125.911703 -270.604107) (xy 125.947043 -270.639447) (xy 125.976419 -270.67988) (xy 125.999109 -270.724412)
			(xy 126.014553 -270.771944) (xy 126.022372 -270.821307) (xy 126.022862 -270.846296) (xy 126.022372 -270.871285)
			(xy 126.014553 -270.920648) (xy 125.999109 -270.96818) (xy 125.976419 -271.012712) (xy 125.947043 -271.053145)
			(xy 125.911703 -271.088485) (xy 125.87127 -271.117861) (xy 125.826738 -271.140551) (xy 125.779206 -271.155995)
			(xy 125.729843 -271.163814) (xy 125.679865 -271.163814) (xy 125.630502 -271.155995) (xy 125.58297 -271.140551)
			(xy 125.538438 -271.117861) (xy 125.498005 -271.088485) (xy 125.462665 -271.053145) (xy 125.433289 -271.012712)
			(xy 125.410599 -270.96818) (xy 125.395155 -270.920648) (xy 125.387336 -270.871285) (xy 125.082318 -270.871285)
			(xy 125.074499 -270.920648) (xy 125.059055 -270.96818) (xy 125.036365 -271.012712) (xy 125.006989 -271.053145)
			(xy 124.971649 -271.088485) (xy 124.931216 -271.117861) (xy 124.886684 -271.140551) (xy 124.839152 -271.155995)
			(xy 124.789789 -271.163814) (xy 124.739811 -271.163814) (xy 124.690448 -271.155995) (xy 124.642916 -271.140551)
			(xy 124.598384 -271.117861) (xy 124.557951 -271.088485) (xy 124.522611 -271.053145) (xy 124.493235 -271.012712)
			(xy 124.470545 -270.96818) (xy 124.455101 -270.920648) (xy 124.447282 -270.871285) (xy 124.141684 -270.871285)
			(xy 124.138557 -270.899107) (xy 124.13488 -270.9164) (xy 124.132848 -270.926052) (xy 124.135896 -270.945102)
			(xy 124.18187 -271.022318) (xy 124.197364 -271.034002) (xy 124.207016 -271.036542) (xy 124.233706 -271.044409)
			(xy 124.284958 -271.066077) (xy 124.333004 -271.094147) (xy 124.377046 -271.128155) (xy 124.397008 -271.14754)
			(xy 124.600208 -271.35074) (xy 124.619875 -271.37108) (xy 124.654304 -271.415979) (xy 124.68258 -271.464986)
			(xy 124.704221 -271.517263) (xy 124.718857 -271.571916) (xy 124.726238 -271.628012) (xy 124.7267 -271.656302)
			(xy 124.918465 -271.656302) (xy 124.92256 -271.605574) (xy 124.934739 -271.55616) (xy 124.954687 -271.50934)
			(xy 124.981888 -271.466326) (xy 125.015636 -271.428232) (xy 125.055058 -271.396045) (xy 125.099132 -271.370599)
			(xy 125.146718 -271.352552) (xy 125.196582 -271.342372) (xy 125.247434 -271.340323) (xy 125.297955 -271.346457)
			(xy 125.346839 -271.360617) (xy 125.392818 -271.382434) (xy 125.434702 -271.411344) (xy 125.471406 -271.446599)
			(xy 125.501979 -271.487285) (xy 125.52563 -271.532348) (xy 125.541746 -271.580622) (xy 125.54991 -271.630856)
			(xy 125.550422 -271.656302) (xy 125.858519 -271.656302) (xy 125.862614 -271.605574) (xy 125.874793 -271.55616)
			(xy 125.894741 -271.50934) (xy 125.921942 -271.466326) (xy 125.95569 -271.428232) (xy 125.995112 -271.396045)
			(xy 126.039186 -271.370599) (xy 126.086772 -271.352552) (xy 126.136636 -271.342372) (xy 126.187488 -271.340323)
			(xy 126.238009 -271.346457) (xy 126.286893 -271.360617) (xy 126.332872 -271.382434) (xy 126.374756 -271.411344)
			(xy 126.41146 -271.446599) (xy 126.442033 -271.487285) (xy 126.465684 -271.532348) (xy 126.4818 -271.580622)
			(xy 126.489964 -271.630856) (xy 126.490476 -271.656302) (xy 126.489964 -271.681748) (xy 126.4818 -271.731982)
			(xy 126.465684 -271.780256) (xy 126.442033 -271.825319) (xy 126.41146 -271.866005) (xy 126.374756 -271.90126)
			(xy 126.332872 -271.93017) (xy 126.286893 -271.951987) (xy 126.238009 -271.966147) (xy 126.187488 -271.972281)
			(xy 126.136636 -271.970232) (xy 126.086772 -271.960052) (xy 126.039186 -271.942005) (xy 125.995112 -271.916559)
			(xy 125.95569 -271.884372) (xy 125.921942 -271.846278) (xy 125.894741 -271.803264) (xy 125.874793 -271.756444)
			(xy 125.862614 -271.70703) (xy 125.858519 -271.656302) (xy 125.550422 -271.656302) (xy 125.54991 -271.681748)
			(xy 125.541746 -271.731982) (xy 125.52563 -271.780256) (xy 125.501979 -271.825319) (xy 125.471406 -271.866005)
			(xy 125.434702 -271.90126) (xy 125.392818 -271.93017) (xy 125.346839 -271.951987) (xy 125.297955 -271.966147)
			(xy 125.247434 -271.972281) (xy 125.196582 -271.970232) (xy 125.146718 -271.960052) (xy 125.099132 -271.942005)
			(xy 125.055058 -271.916559) (xy 125.015636 -271.884372) (xy 124.981888 -271.846278) (xy 124.954687 -271.803264)
			(xy 124.934739 -271.756444) (xy 124.92256 -271.70703) (xy 124.918465 -271.656302) (xy 124.7267 -271.656302)
			(xy 124.726193 -271.684588) (xy 124.71881 -271.740676) (xy 124.704168 -271.795321) (xy 124.68252 -271.847588)
			(xy 124.654236 -271.896582) (xy 124.619799 -271.941465) (xy 124.579798 -271.98147) (xy 124.534918 -272.015911)
			(xy 124.485927 -272.044201) (xy 124.433663 -272.065854) (xy 124.37902 -272.080501) (xy 124.322932 -272.087891)
			(xy 124.294646 -272.088356) (xy 124.266357 -272.087881) (xy 124.210261 -272.080505) (xy 124.155607 -272.065872)
			(xy 124.103329 -272.044234) (xy 124.054322 -272.01596) (xy 124.009422 -271.981533) (xy 123.989084 -271.961864)
			(xy 123.9139 -271.88668) (xy 123.900438 -271.879822) (xy 123.892564 -271.878298) (xy 123.866917 -271.87322)
			(xy 123.816994 -271.857685) (xy 123.792996 -271.84731) (xy 123.78309 -271.842992) (xy 123.633992 -271.842992)
			(xy 123.622973 -271.843528) (xy 123.602957 -271.852749) (xy 123.595384 -271.860772) (xy 123.577238 -271.881268)
			(xy 123.535129 -271.91624) (xy 123.48762 -271.943428) (xy 123.436135 -271.962015) (xy 123.382215 -271.971445)
			(xy 123.354846 -271.972024) (xy 123.330032 -271.971562) (xy 123.281015 -271.963805) (xy 123.233815 -271.948475)
			(xy 123.189594 -271.925949) (xy 123.149442 -271.896782) (xy 123.114348 -271.861693) (xy 123.085175 -271.821545)
			(xy 123.062643 -271.777328) (xy 123.047306 -271.73013) (xy 123.039542 -271.681114) (xy 122.729782 -271.681114)
			(xy 122.722442 -271.728516) (xy 122.707768 -271.774767) (xy 122.68619 -271.818229) (xy 122.658216 -271.857877)
			(xy 122.624505 -271.892778) (xy 122.585851 -271.92211) (xy 122.543164 -271.945183) (xy 122.520456 -271.953736)
			(xy 122.504962 -271.95907) (xy 122.48642 -271.985232) (xy 122.48642 -272.491297) (xy 124.447282 -272.491297)
			(xy 124.447282 -272.441319) (xy 124.455101 -272.391956) (xy 124.470545 -272.344424) (xy 124.493235 -272.299892)
			(xy 124.522611 -272.259459) (xy 124.557951 -272.224119) (xy 124.598384 -272.194743) (xy 124.642916 -272.172053)
			(xy 124.690448 -272.156609) (xy 124.739811 -272.14879) (xy 124.789789 -272.14879) (xy 124.839152 -272.156609)
			(xy 124.886684 -272.172053) (xy 124.931216 -272.194743) (xy 124.971649 -272.224119) (xy 125.006989 -272.259459)
			(xy 125.036365 -272.299892) (xy 125.059055 -272.344424) (xy 125.074499 -272.391956) (xy 125.082318 -272.441319)
			(xy 125.082808 -272.466308) (xy 125.082318 -272.491297) (xy 125.074499 -272.54066) (xy 125.059055 -272.588192)
			(xy 125.036365 -272.632724) (xy 125.006989 -272.673157) (xy 124.971649 -272.708497) (xy 124.931216 -272.737873)
			(xy 124.886684 -272.760563) (xy 124.839152 -272.776007) (xy 124.789789 -272.783826) (xy 124.739811 -272.783826)
			(xy 124.690448 -272.776007) (xy 124.642916 -272.760563) (xy 124.598384 -272.737873) (xy 124.557951 -272.708497)
			(xy 124.522611 -272.673157) (xy 124.493235 -272.632724) (xy 124.470545 -272.588192) (xy 124.455101 -272.54066)
			(xy 124.447282 -272.491297) (xy 122.48642 -272.491297) (xy 122.48642 -272.538952) (xy 122.485942 -272.548968)
			(xy 122.478291 -272.56748) (xy 122.464137 -272.581653) (xy 122.445635 -272.589328) (xy 122.43562 -272.589752)
			(xy 122.237754 -272.589752) (xy 122.22734 -272.612104) (xy 122.224733 -272.617591) (xy 122.2219 -272.629399)
			(xy 122.221752 -272.635472) (xy 122.221752 -272.649696) (xy 122.20448 -272.649696) (xy 122.18944 -272.670114)
			(xy 122.15399 -272.706373) (xy 122.113237 -272.736549) (xy 122.068213 -272.759879) (xy 122.020058 -272.77577)
			(xy 121.969992 -272.78382) (xy 121.944638 -272.784316) (xy 121.919648 -272.783808) (xy 121.870283 -272.775995)
			(xy 121.822749 -272.760555) (xy 121.778214 -272.737869) (xy 121.737778 -272.708495) (xy 121.702435 -272.673157)
			(xy 121.673055 -272.632725) (xy 121.650362 -272.588194) (xy 121.634916 -272.540661) (xy 121.627096 -272.491298)
			(xy 121.62663 -272.466308) (xy 119.442738 -272.466308) (xy 119.442225 -272.491296) (xy 119.434407 -272.540656)
			(xy 119.418963 -272.588186) (xy 119.396275 -272.632715) (xy 119.366901 -272.673147) (xy 119.331564 -272.708487)
			(xy 119.291134 -272.737864) (xy 119.246607 -272.760555) (xy 119.199078 -272.776001) (xy 119.149718 -272.783823)
			(xy 119.12473 -272.784316) (xy 119.100195 -272.783918) (xy 119.051704 -272.776396) (xy 119.004945 -272.761512)
			(xy 118.961029 -272.739619) (xy 118.920999 -272.711237) (xy 118.885807 -272.677041) (xy 118.856288 -272.637842)
			(xy 118.844314 -272.616422) (xy 118.83771 -272.603976) (xy 118.813834 -272.589752) (xy 118.748048 -272.589752)
			(xy 118.738024 -272.58934) (xy 118.719499 -272.581677) (xy 118.705323 -272.567501) (xy 118.69766 -272.548976)
			(xy 118.697248 -272.538952) (xy 118.697248 -272.045684) (xy 118.696813 -272.035803) (xy 118.689355 -272.017504)
			(xy 118.68277 -272.010124) (xy 118.661434 -271.98828) (xy 118.654755 -271.982073) (xy 118.638228 -271.974396)
			(xy 118.629176 -271.973294) (xy 118.602957 -271.970691) (xy 118.551861 -271.957834) (xy 118.503583 -271.936733)
			(xy 118.459441 -271.907966) (xy 118.420644 -271.872318) (xy 118.38825 -271.830764) (xy 118.363147 -271.784441)
			(xy 118.34602 -271.734614) (xy 118.337338 -271.682646) (xy 118.336822 -271.656302) (xy 118.030498 -271.656302)
			(xy 118.029986 -271.681748) (xy 118.021822 -271.731982) (xy 118.005706 -271.780256) (xy 117.982055 -271.825319)
			(xy 117.951482 -271.866005) (xy 117.914778 -271.90126) (xy 117.872894 -271.93017) (xy 117.826915 -271.951987)
			(xy 117.778031 -271.966147) (xy 117.72751 -271.972281) (xy 117.676658 -271.970232) (xy 117.626794 -271.960052)
			(xy 117.579208 -271.942005) (xy 117.535134 -271.916559) (xy 117.495712 -271.884372) (xy 117.461964 -271.846278)
			(xy 117.434763 -271.803264) (xy 117.414815 -271.756444) (xy 117.402636 -271.70703) (xy 117.398541 -271.656302)
			(xy 117.090444 -271.656302) (xy 117.089959 -271.681589) (xy 117.081918 -271.73152) (xy 117.066012 -271.779527)
			(xy 117.042648 -271.82438) (xy 117.012424 -271.864929) (xy 116.976116 -271.900135) (xy 116.934655 -271.929094)
			(xy 116.889103 -271.951065) (xy 116.840629 -271.965484) (xy 116.815616 -271.96923) (xy 116.79682 -271.97177)
			(xy 116.77142 -272.000472) (xy 116.77142 -272.538952) (xy 116.770942 -272.548968) (xy 116.763291 -272.56748)
			(xy 116.749137 -272.581653) (xy 116.730635 -272.589328) (xy 116.72062 -272.589752) (xy 116.615718 -272.589752)
			(xy 116.591842 -272.603976) (xy 116.585238 -272.616422) (xy 116.573275 -272.637843) (xy 116.543734 -272.677016)
			(xy 116.508529 -272.71119) (xy 116.468497 -272.739556) (xy 116.424585 -272.761441) (xy 116.377835 -272.776327)
			(xy 116.329354 -272.783861) (xy 116.304822 -272.784316) (xy 116.279832 -272.783823) (xy 116.230466 -272.776007)
			(xy 116.182931 -272.760565) (xy 116.138397 -272.737877) (xy 116.097961 -272.708502) (xy 116.062618 -272.673162)
			(xy 116.033238 -272.632728) (xy 116.010546 -272.588196) (xy 115.9951 -272.540663) (xy 115.98728 -272.491298)
			(xy 115.986814 -272.466308) (xy 115.987416 -272.437904) (xy 115.997498 -272.381996) (xy 116.017326 -272.328759)
			(xy 116.031264 -272.304002) (xy 116.034549 -272.298034) (xy 116.038157 -272.284903) (xy 116.038376 -272.278094)
			(xy 116.038376 -272.135092) (xy 116.03863 -272.130012) (xy 116.03863 -272.118328) (xy 116.029232 -272.0975)
			(xy 115.949222 -272.031968) (xy 115.927124 -272.026634) (xy 115.91544 -272.02892) (xy 115.895492 -272.032959)
			(xy 115.855019 -272.037284) (xy 115.834668 -272.037556) (xy 115.804696 -272.037017) (xy 115.745481 -272.027702)
			(xy 115.688456 -272.009227) (xy 115.635028 -271.98205) (xy 115.586515 -271.946841) (xy 115.56492 -271.92605)
			(xy 115.515136 -271.876266) (xy 115.495538 -271.855938) (xy 115.461953 -271.810548) (xy 115.435412 -271.76071)
			(xy 115.425474 -271.73428) (xy 115.419632 -271.718024) (xy 115.395248 -271.700752) (xy 115.395248 -271.232376)
			(xy 115.394838 -271.222673) (xy 115.387658 -271.204646) (xy 115.381278 -271.197324) (xy 115.36045 -271.17548)
			(xy 115.354041 -271.169252) (xy 115.338045 -271.161313) (xy 115.329208 -271.159986) (xy 115.303858 -271.156574)
			(xy 115.25464 -271.14266) (xy 115.208309 -271.120993) (xy 115.166076 -271.092141) (xy 115.129048 -271.056858)
			(xy 115.098191 -271.016068) (xy 115.074313 -270.970837) (xy 115.058039 -270.922348) (xy 115.049794 -270.871869)
			(xy 115.0493 -270.846296) (xy 114.740436 -270.846296) (xy 114.739924 -270.871742) (xy 114.73176 -270.921976)
			(xy 114.715644 -270.97025) (xy 114.691993 -271.015313) (xy 114.66142 -271.055999) (xy 114.624716 -271.091254)
			(xy 114.582832 -271.120164) (xy 114.536853 -271.141981) (xy 114.487969 -271.156141) (xy 114.437448 -271.162275)
			(xy 114.386596 -271.160226) (xy 114.336732 -271.150046) (xy 114.289146 -271.131999) (xy 114.245072 -271.106553)
			(xy 114.20565 -271.074366) (xy 114.171902 -271.036272) (xy 114.144701 -270.993258) (xy 114.124753 -270.946438)
			(xy 114.112574 -270.897024) (xy 114.108479 -270.846296) (xy 113.802668 -270.846296) (xy 113.802178 -270.871285)
			(xy 113.794359 -270.920648) (xy 113.778915 -270.96818) (xy 113.756225 -271.012712) (xy 113.726849 -271.053145)
			(xy 113.691509 -271.088485) (xy 113.651076 -271.117861) (xy 113.606544 -271.140551) (xy 113.559012 -271.155995)
			(xy 113.509649 -271.163814) (xy 113.459671 -271.163814) (xy 113.410308 -271.155995) (xy 113.362776 -271.140551)
			(xy 113.318244 -271.117861) (xy 113.277811 -271.088485) (xy 113.242471 -271.053145) (xy 113.213095 -271.012712)
			(xy 113.190405 -270.96818) (xy 113.174961 -270.920648) (xy 113.167142 -270.871285) (xy 110.98862 -270.871285)
			(xy 110.980801 -270.920648) (xy 110.965357 -270.96818) (xy 110.942667 -271.012712) (xy 110.913291 -271.053145)
			(xy 110.877951 -271.088485) (xy 110.837518 -271.117861) (xy 110.792986 -271.140551) (xy 110.745454 -271.155995)
			(xy 110.696091 -271.163814) (xy 110.646113 -271.163814) (xy 110.59675 -271.155995) (xy 110.549218 -271.140551)
			(xy 110.504686 -271.117861) (xy 110.464253 -271.088485) (xy 110.428913 -271.053145) (xy 110.399537 -271.012712)
			(xy 110.376847 -270.96818) (xy 110.361403 -270.920648) (xy 110.353584 -270.871285) (xy 110.046267 -270.871285)
			(xy 110.046258 -270.871742) (xy 110.038094 -270.921976) (xy 110.021978 -270.97025) (xy 109.998327 -271.015313)
			(xy 109.967754 -271.055999) (xy 109.93105 -271.091254) (xy 109.889166 -271.120164) (xy 109.843187 -271.141981)
			(xy 109.794303 -271.156141) (xy 109.743782 -271.162275) (xy 109.69293 -271.160226) (xy 109.643066 -271.150046)
			(xy 109.59548 -271.131999) (xy 109.551406 -271.106553) (xy 109.511984 -271.074366) (xy 109.478236 -271.036272)
			(xy 109.451035 -270.993258) (xy 109.431087 -270.946438) (xy 109.418908 -270.897024) (xy 109.414813 -270.846296)
			(xy 109.106716 -270.846296) (xy 109.106191 -270.871714) (xy 109.098053 -270.921894) (xy 109.081973 -270.970118)
			(xy 109.058365 -271.01514) (xy 109.027842 -271.055791) (xy 108.991194 -271.091021) (xy 108.949369 -271.119916)
			(xy 108.92663 -271.131284) (xy 108.913168 -271.137634) (xy 108.89742 -271.162272) (xy 108.89742 -271.209008)
			(xy 108.901992 -271.218914) (xy 108.914017 -271.246862) (xy 108.930949 -271.3053) (xy 108.939539 -271.365532)
			(xy 108.940092 -271.395952) (xy 108.940092 -271.469612) (xy 108.939543 -271.500033) (xy 108.930967 -271.560268)
			(xy 108.914014 -271.6187) (xy 108.901992 -271.64665) (xy 108.89742 -271.656556) (xy 108.89742 -271.700752)
			(xy 108.873036 -271.700752) (xy 108.85996 -271.720768) (xy 108.830046 -271.758065) (xy 108.813346 -271.775174)
			(xy 108.626656 -271.961864) (xy 108.606327 -271.981543) (xy 108.561425 -272.015968) (xy 108.512415 -272.044242)
			(xy 108.460136 -272.065881) (xy 108.405481 -272.080515) (xy 108.349384 -272.087895) (xy 108.321094 -272.088356)
			(xy 108.294532 -272.087942) (xy 108.241805 -272.081453) (xy 108.215938 -272.075402) (xy 108.204502 -272.073145)
			(xy 108.181739 -272.078032) (xy 108.17225 -272.0848) (xy 108.126784 -272.120614) (xy 108.127292 -272.135092)
			(xy 108.127292 -272.302224) (xy 108.130086 -272.313654) (xy 108.13288 -272.319242) (xy 108.144237 -272.342075)
			(xy 108.160306 -272.390471) (xy 108.168443 -272.440811) (xy 108.168948 -272.466308) (xy 108.474759 -272.466308)
			(xy 108.478854 -272.41558) (xy 108.491033 -272.366166) (xy 108.510981 -272.319346) (xy 108.538182 -272.276332)
			(xy 108.57193 -272.238238) (xy 108.611352 -272.206051) (xy 108.655426 -272.180605) (xy 108.703012 -272.162558)
			(xy 108.752876 -272.152378) (xy 108.803728 -272.150329) (xy 108.854249 -272.156463) (xy 108.903133 -272.170623)
			(xy 108.949112 -272.19244) (xy 108.990996 -272.22135) (xy 109.0277 -272.256605) (xy 109.058273 -272.297291)
			(xy 109.081924 -272.342354) (xy 109.09804 -272.390628) (xy 109.106204 -272.440862) (xy 109.106716 -272.466308)
			(xy 109.414813 -272.466308) (xy 109.418908 -272.41558) (xy 109.431087 -272.366166) (xy 109.451035 -272.319346)
			(xy 109.478236 -272.276332) (xy 109.511984 -272.238238) (xy 109.551406 -272.206051) (xy 109.59548 -272.180605)
			(xy 109.643066 -272.162558) (xy 109.69293 -272.152378) (xy 109.743782 -272.150329) (xy 109.794303 -272.156463)
			(xy 109.843187 -272.170623) (xy 109.889166 -272.19244) (xy 109.93105 -272.22135) (xy 109.967754 -272.256605)
			(xy 109.998327 -272.297291) (xy 110.021978 -272.342354) (xy 110.038094 -272.390628) (xy 110.046258 -272.440862)
			(xy 110.04677 -272.466308) (xy 110.046267 -272.491297) (xy 110.353584 -272.491297) (xy 110.353584 -272.441319)
			(xy 110.361403 -272.391956) (xy 110.376847 -272.344424) (xy 110.399537 -272.299892) (xy 110.428913 -272.259459)
			(xy 110.464253 -272.224119) (xy 110.504686 -272.194743) (xy 110.549218 -272.172053) (xy 110.59675 -272.156609)
			(xy 110.646113 -272.14879) (xy 110.696091 -272.14879) (xy 110.745454 -272.156609) (xy 110.792986 -272.172053)
			(xy 110.837518 -272.194743) (xy 110.877951 -272.224119) (xy 110.913291 -272.259459) (xy 110.942667 -272.299892)
			(xy 110.965357 -272.344424) (xy 110.980801 -272.391956) (xy 110.98862 -272.441319) (xy 110.98911 -272.466308)
			(xy 110.98862 -272.491297) (xy 113.167142 -272.491297) (xy 113.167142 -272.441319) (xy 113.174961 -272.391956)
			(xy 113.190405 -272.344424) (xy 113.213095 -272.299892) (xy 113.242471 -272.259459) (xy 113.277811 -272.224119)
			(xy 113.318244 -272.194743) (xy 113.362776 -272.172053) (xy 113.410308 -272.156609) (xy 113.459671 -272.14879)
			(xy 113.509649 -272.14879) (xy 113.559012 -272.156609) (xy 113.606544 -272.172053) (xy 113.651076 -272.194743)
			(xy 113.691509 -272.224119) (xy 113.726849 -272.259459) (xy 113.756225 -272.299892) (xy 113.778915 -272.344424)
			(xy 113.794359 -272.391956) (xy 113.802178 -272.441319) (xy 113.802668 -272.466308) (xy 114.108479 -272.466308)
			(xy 114.112574 -272.41558) (xy 114.124753 -272.366166) (xy 114.144701 -272.319346) (xy 114.171902 -272.276332)
			(xy 114.20565 -272.238238) (xy 114.245072 -272.206051) (xy 114.289146 -272.180605) (xy 114.336732 -272.162558)
			(xy 114.386596 -272.152378) (xy 114.437448 -272.150329) (xy 114.487969 -272.156463) (xy 114.536853 -272.170623)
			(xy 114.582832 -272.19244) (xy 114.624716 -272.22135) (xy 114.66142 -272.256605) (xy 114.691993 -272.297291)
			(xy 114.715644 -272.342354) (xy 114.73176 -272.390628) (xy 114.739924 -272.440862) (xy 114.740436 -272.466308)
			(xy 115.048533 -272.466308) (xy 115.052628 -272.41558) (xy 115.064807 -272.366166) (xy 115.084755 -272.319346)
			(xy 115.111956 -272.276332) (xy 115.145704 -272.238238) (xy 115.185126 -272.206051) (xy 115.2292 -272.180605)
			(xy 115.276786 -272.162558) (xy 115.32665 -272.152378) (xy 115.377502 -272.150329) (xy 115.428023 -272.156463)
			(xy 115.476907 -272.170623) (xy 115.522886 -272.19244) (xy 115.56477 -272.22135) (xy 115.601474 -272.256605)
			(xy 115.632047 -272.297291) (xy 115.655698 -272.342354) (xy 115.671814 -272.390628) (xy 115.679978 -272.440862)
			(xy 115.68049 -272.466308) (xy 115.679978 -272.491754) (xy 115.671814 -272.541988) (xy 115.655698 -272.590262)
			(xy 115.632047 -272.635325) (xy 115.601474 -272.676011) (xy 115.56477 -272.711266) (xy 115.522886 -272.740176)
			(xy 115.476907 -272.761993) (xy 115.428023 -272.776153) (xy 115.377502 -272.782287) (xy 115.32665 -272.780238)
			(xy 115.276786 -272.770058) (xy 115.2292 -272.752011) (xy 115.185126 -272.726565) (xy 115.145704 -272.694378)
			(xy 115.111956 -272.656284) (xy 115.084755 -272.61327) (xy 115.064807 -272.56645) (xy 115.052628 -272.517036)
			(xy 115.048533 -272.466308) (xy 114.740436 -272.466308) (xy 114.739924 -272.491754) (xy 114.73176 -272.541988)
			(xy 114.715644 -272.590262) (xy 114.691993 -272.635325) (xy 114.66142 -272.676011) (xy 114.624716 -272.711266)
			(xy 114.582832 -272.740176) (xy 114.536853 -272.761993) (xy 114.487969 -272.776153) (xy 114.437448 -272.782287)
			(xy 114.386596 -272.780238) (xy 114.336732 -272.770058) (xy 114.289146 -272.752011) (xy 114.245072 -272.726565)
			(xy 114.20565 -272.694378) (xy 114.171902 -272.656284) (xy 114.144701 -272.61327) (xy 114.124753 -272.56645)
			(xy 114.112574 -272.517036) (xy 114.108479 -272.466308) (xy 113.802668 -272.466308) (xy 113.802178 -272.491297)
			(xy 113.794359 -272.54066) (xy 113.778915 -272.588192) (xy 113.756225 -272.632724) (xy 113.726849 -272.673157)
			(xy 113.691509 -272.708497) (xy 113.651076 -272.737873) (xy 113.606544 -272.760563) (xy 113.559012 -272.776007)
			(xy 113.509649 -272.783826) (xy 113.459671 -272.783826) (xy 113.410308 -272.776007) (xy 113.362776 -272.760563)
			(xy 113.318244 -272.737873) (xy 113.277811 -272.708497) (xy 113.242471 -272.673157) (xy 113.213095 -272.632724)
			(xy 113.190405 -272.588192) (xy 113.174961 -272.54066) (xy 113.167142 -272.491297) (xy 110.98862 -272.491297)
			(xy 110.980801 -272.54066) (xy 110.965357 -272.588192) (xy 110.942667 -272.632724) (xy 110.913291 -272.673157)
			(xy 110.877951 -272.708497) (xy 110.837518 -272.737873) (xy 110.792986 -272.760563) (xy 110.745454 -272.776007)
			(xy 110.696091 -272.783826) (xy 110.646113 -272.783826) (xy 110.59675 -272.776007) (xy 110.549218 -272.760563)
			(xy 110.504686 -272.737873) (xy 110.464253 -272.708497) (xy 110.428913 -272.673157) (xy 110.399537 -272.632724)
			(xy 110.376847 -272.588192) (xy 110.361403 -272.54066) (xy 110.353584 -272.491297) (xy 110.046267 -272.491297)
			(xy 110.046258 -272.491754) (xy 110.038094 -272.541988) (xy 110.021978 -272.590262) (xy 109.998327 -272.635325)
			(xy 109.967754 -272.676011) (xy 109.93105 -272.711266) (xy 109.889166 -272.740176) (xy 109.843187 -272.761993)
			(xy 109.794303 -272.776153) (xy 109.743782 -272.782287) (xy 109.69293 -272.780238) (xy 109.643066 -272.770058)
			(xy 109.59548 -272.752011) (xy 109.551406 -272.726565) (xy 109.511984 -272.694378) (xy 109.478236 -272.656284)
			(xy 109.451035 -272.61327) (xy 109.431087 -272.56645) (xy 109.418908 -272.517036) (xy 109.414813 -272.466308)
			(xy 109.106716 -272.466308) (xy 109.106204 -272.491754) (xy 109.09804 -272.541988) (xy 109.081924 -272.590262)
			(xy 109.058273 -272.635325) (xy 109.0277 -272.676011) (xy 108.990996 -272.711266) (xy 108.949112 -272.740176)
			(xy 108.903133 -272.761993) (xy 108.854249 -272.776153) (xy 108.803728 -272.782287) (xy 108.752876 -272.780238)
			(xy 108.703012 -272.770058) (xy 108.655426 -272.752011) (xy 108.611352 -272.726565) (xy 108.57193 -272.694378)
			(xy 108.538182 -272.656284) (xy 108.510981 -272.61327) (xy 108.491033 -272.56645) (xy 108.478854 -272.517036)
			(xy 108.474759 -272.466308) (xy 108.168948 -272.466308) (xy 108.168425 -272.491295) (xy 108.160607 -272.540655)
			(xy 108.145164 -272.588184) (xy 108.122477 -272.632712) (xy 108.093104 -272.673144) (xy 108.057768 -272.708483)
			(xy 108.01734 -272.73786) (xy 107.972813 -272.760552) (xy 107.925286 -272.775999) (xy 107.875927 -272.783823)
			(xy 107.85094 -272.784316) (xy 107.826405 -272.78391) (xy 107.777915 -272.77639) (xy 107.731156 -272.761507)
			(xy 107.68724 -272.739615) (xy 107.64721 -272.711235) (xy 107.612017 -272.677039) (xy 107.582498 -272.637842)
			(xy 107.570524 -272.616422) (xy 107.56392 -272.603976) (xy 107.540044 -272.589752) (xy 107.445048 -272.589752)
			(xy 107.435024 -272.58934) (xy 107.416499 -272.581677) (xy 107.402323 -272.567501) (xy 107.39466 -272.548976)
			(xy 107.394248 -272.538952) (xy 107.394248 -272.00098) (xy 107.368086 -271.972278) (xy 107.348528 -271.970246)
			(xy 107.322964 -271.967159) (xy 107.273294 -271.953585) (xy 107.226486 -271.932129) (xy 107.183781 -271.903359)
			(xy 107.146313 -271.868038) (xy 107.115074 -271.827105) (xy 107.090895 -271.781643) (xy 107.074415 -271.73286)
			(xy 107.066073 -271.682048) (xy 107.065572 -271.656302) (xy 106.756708 -271.656302) (xy 106.756196 -271.681748)
			(xy 106.748032 -271.731982) (xy 106.731916 -271.780256) (xy 106.708265 -271.825319) (xy 106.677692 -271.866005)
			(xy 106.640988 -271.90126) (xy 106.599104 -271.93017) (xy 106.553125 -271.951987) (xy 106.504241 -271.966147)
			(xy 106.45372 -271.972281) (xy 106.402868 -271.970232) (xy 106.353004 -271.960052) (xy 106.305418 -271.942005)
			(xy 106.261344 -271.916559) (xy 106.221922 -271.884372) (xy 106.188174 -271.846278) (xy 106.160973 -271.803264)
			(xy 106.141025 -271.756444) (xy 106.128846 -271.70703) (xy 106.124751 -271.656302) (xy 105.81894 -271.656302)
			(xy 105.818349 -271.682791) (xy 105.809577 -271.735038) (xy 105.792274 -271.785112) (xy 105.76692 -271.831629)
			(xy 105.734213 -271.873306) (xy 105.695056 -271.908992) (xy 105.650532 -271.937702) (xy 105.626408 -271.948656)
			(xy 105.612184 -271.954752) (xy 105.59542 -271.979898) (xy 105.59542 -272.538952) (xy 105.594942 -272.548968)
			(xy 105.587291 -272.56748) (xy 105.573137 -272.581653) (xy 105.554635 -272.589328) (xy 105.54462 -272.589752)
			(xy 105.381552 -272.589752) (xy 105.371547 -272.590248) (xy 105.353064 -272.597914) (xy 105.338914 -272.612064)
			(xy 105.331248 -272.630547) (xy 105.330752 -272.640552) (xy 105.330752 -272.649696) (xy 105.31602 -272.649696)
			(xy 105.304799 -272.650359) (xy 105.284508 -272.659962) (xy 105.276904 -272.668238) (xy 105.261698 -272.686061)
			(xy 105.226971 -272.717505) (xy 105.188004 -272.74351) (xy 105.145642 -272.763512) (xy 105.100802 -272.77708)
			(xy 105.054456 -272.783918) (xy 105.031032 -272.784316) (xy 105.006042 -272.783814) (xy 104.956677 -272.776)
			(xy 104.909142 -272.760559) (xy 104.864608 -272.737872) (xy 104.824171 -272.708498) (xy 104.788828 -272.673159)
			(xy 104.759449 -272.632726) (xy 104.736756 -272.588195) (xy 104.72131 -272.540662) (xy 104.71349 -272.491298)
			(xy 104.713024 -272.466308) (xy 102.529132 -272.466308) (xy 102.528625 -272.491296) (xy 102.520806 -272.540657)
			(xy 102.505363 -272.588188) (xy 102.482674 -272.632717) (xy 102.453299 -272.673149) (xy 102.417961 -272.708489)
			(xy 102.377531 -272.737866) (xy 102.333002 -272.760556) (xy 102.285473 -272.776003) (xy 102.236112 -272.783824)
			(xy 102.211124 -272.784316) (xy 102.187702 -272.783894) (xy 102.141361 -272.777044) (xy 102.096526 -272.763474)
			(xy 102.054164 -272.743478) (xy 102.015192 -272.717487) (xy 101.980452 -272.686063) (xy 101.965252 -272.668238)
			(xy 101.950012 -272.649696) (xy 101.943916 -272.649696) (xy 101.943916 -272.639536) (xy 101.937058 -272.627598)
			(xy 101.930708 -272.616422) (xy 101.924104 -272.603976) (xy 101.900228 -272.589752) (xy 101.730048 -272.589752)
			(xy 101.720024 -272.58934) (xy 101.701499 -272.581677) (xy 101.687323 -272.567501) (xy 101.67966 -272.548976)
			(xy 101.679248 -272.538952) (xy 101.679248 -271.98828) (xy 101.65969 -271.96161) (xy 101.643942 -271.95653)
			(xy 101.620461 -271.948425) (xy 101.576151 -271.92598) (xy 101.535907 -271.896865) (xy 101.500726 -271.861802)
			(xy 101.471476 -271.821657) (xy 101.448881 -271.777423) (xy 101.4335 -271.730194) (xy 101.425713 -271.681137)
			(xy 101.425248 -271.656302) (xy 101.116463 -271.656302) (xy 101.116463 -271.681113) (xy 101.108699 -271.730129)
			(xy 101.093362 -271.777326) (xy 101.070831 -271.821543) (xy 101.04166 -271.86169) (xy 101.006567 -271.89678)
			(xy 100.966417 -271.925947) (xy 100.922198 -271.948474) (xy 100.874999 -271.963806) (xy 100.825983 -271.971565)
			(xy 100.80117 -271.972024) (xy 100.775819 -271.971488) (xy 100.725775 -271.963348) (xy 100.677674 -271.947315)
			(xy 100.632755 -271.923801) (xy 100.59217 -271.893409) (xy 100.556965 -271.856923) (xy 100.54209 -271.836388)
			(xy 100.534724 -271.825974) (xy 100.51288 -271.814544) (xy 100.477828 -271.814544) (xy 100.44938 -271.842992)
			(xy 100.448974 -271.853015) (xy 100.441302 -271.871536) (xy 100.427126 -271.885709) (xy 100.408603 -271.893376)
			(xy 100.39858 -271.893792) (xy 100.331778 -271.893792) (xy 100.321872 -271.89811) (xy 100.295373 -271.909524)
			(xy 100.240068 -271.925965) (xy 100.211636 -271.930876) (xy 100.203508 -271.932146) (xy 100.189284 -271.939512)
			(xy 100.166678 -271.961864) (xy 100.14634 -271.981533) (xy 100.101439 -272.015959) (xy 100.052431 -272.044234)
			(xy 100.000154 -272.065874) (xy 99.945501 -272.080511) (xy 99.889406 -272.087893) (xy 99.861116 -272.088356)
			(xy 99.832824 -272.087831) (xy 99.776724 -272.080451) (xy 99.722067 -272.065814) (xy 99.669786 -272.044171)
			(xy 99.620776 -272.015892) (xy 99.575875 -271.98146) (xy 99.53585 -271.941465) (xy 99.501385 -271.896588)
			(xy 99.47307 -271.847599) (xy 99.451388 -271.795335) (xy 99.436711 -271.740688) (xy 99.42929 -271.684593)
			(xy 99.428808 -271.656302) (xy 99.236784 -271.656302) (xy 99.236272 -271.681748) (xy 99.228108 -271.731982)
			(xy 99.211992 -271.780256) (xy 99.188341 -271.825319) (xy 99.157768 -271.866005) (xy 99.121064 -271.90126)
			(xy 99.07918 -271.93017) (xy 99.033201 -271.951987) (xy 98.984317 -271.966147) (xy 98.933796 -271.972281)
			(xy 98.882944 -271.970232) (xy 98.83308 -271.960052) (xy 98.785494 -271.942005) (xy 98.74142 -271.916559)
			(xy 98.701998 -271.884372) (xy 98.66825 -271.846278) (xy 98.641049 -271.803264) (xy 98.621101 -271.756444)
			(xy 98.608922 -271.70703) (xy 98.604827 -271.656302) (xy 98.29673 -271.656302) (xy 98.296218 -271.681748)
			(xy 98.288054 -271.731982) (xy 98.271938 -271.780256) (xy 98.248287 -271.825319) (xy 98.217714 -271.866005)
			(xy 98.18101 -271.90126) (xy 98.139126 -271.93017) (xy 98.093147 -271.951987) (xy 98.044263 -271.966147)
			(xy 97.993742 -271.972281) (xy 97.94289 -271.970232) (xy 97.893026 -271.960052) (xy 97.84544 -271.942005)
			(xy 97.801366 -271.916559) (xy 97.761944 -271.884372) (xy 97.728196 -271.846278) (xy 97.700995 -271.803264)
			(xy 97.681047 -271.756444) (xy 97.668868 -271.70703) (xy 97.664773 -271.656302) (xy 97.359086 -271.656302)
			(xy 97.358962 -271.660874) (xy 97.358692 -271.672485) (xy 97.356655 -271.695622) (xy 97.354898 -271.707102)
			(xy 97.350414 -271.731713) (xy 97.334788 -271.779233) (xy 97.311921 -271.823723) (xy 97.282376 -271.864089)
			(xy 97.24688 -271.899335) (xy 97.226882 -271.914366) (xy 97.222056 -271.917668) (xy 97.21469 -271.926304)
			(xy 97.195386 -271.962372) (xy 97.195386 -272.491297) (xy 99.073444 -272.491297) (xy 99.073444 -272.441319)
			(xy 99.081263 -272.391956) (xy 99.096707 -272.344424) (xy 99.119397 -272.299892) (xy 99.148773 -272.259459)
			(xy 99.184113 -272.224119) (xy 99.224546 -272.194743) (xy 99.269078 -272.172053) (xy 99.31661 -272.156609)
			(xy 99.365973 -272.14879) (xy 99.415951 -272.14879) (xy 99.465314 -272.156609) (xy 99.512846 -272.172053)
			(xy 99.557378 -272.194743) (xy 99.597811 -272.224119) (xy 99.633151 -272.259459) (xy 99.662527 -272.299892)
			(xy 99.685217 -272.344424) (xy 99.700661 -272.391956) (xy 99.70848 -272.441319) (xy 99.70897 -272.466308)
			(xy 99.70848 -272.491297) (xy 99.700661 -272.54066) (xy 99.685217 -272.588192) (xy 99.662527 -272.632724)
			(xy 99.633151 -272.673157) (xy 99.597811 -272.708497) (xy 99.557378 -272.737873) (xy 99.512846 -272.760563)
			(xy 99.465314 -272.776007) (xy 99.415951 -272.783826) (xy 99.365973 -272.783826) (xy 99.31661 -272.776007)
			(xy 99.269078 -272.760563) (xy 99.224546 -272.737873) (xy 99.184113 -272.708497) (xy 99.148773 -272.673157)
			(xy 99.119397 -272.632724) (xy 99.096707 -272.588192) (xy 99.081263 -272.54066) (xy 99.073444 -272.491297)
			(xy 97.195386 -272.491297) (xy 97.195386 -272.957544) (xy 97.195553 -272.963698) (xy 97.198505 -272.975645)
			(xy 97.201228 -272.981166) (xy 97.211134 -272.999708) (xy 97.214004 -273.004881) (xy 97.221706 -273.013854)
			(xy 97.226374 -273.017488) (xy 97.246538 -273.032549) (xy 97.282293 -273.067967) (xy 97.312024 -273.108573)
			(xy 97.334991 -273.153354) (xy 97.350619 -273.201193) (xy 97.358519 -273.250896) (xy 97.358962 -273.27606)
			(xy 97.358962 -273.276314) (xy 97.664773 -273.276314) (xy 97.668868 -273.225586) (xy 97.681047 -273.176172)
			(xy 97.700995 -273.129352) (xy 97.728196 -273.086338) (xy 97.761944 -273.048244) (xy 97.801366 -273.016057)
			(xy 97.84544 -272.990611) (xy 97.893026 -272.972564) (xy 97.94289 -272.962384) (xy 97.993742 -272.960335)
			(xy 98.044263 -272.966469) (xy 98.093147 -272.980629) (xy 98.139126 -273.002446) (xy 98.18101 -273.031356)
			(xy 98.217714 -273.066611) (xy 98.248287 -273.107297) (xy 98.271938 -273.15236) (xy 98.288054 -273.200634)
			(xy 98.296218 -273.250868) (xy 98.29673 -273.276314) (xy 98.604827 -273.276314) (xy 98.608922 -273.225586)
			(xy 98.621101 -273.176172) (xy 98.641049 -273.129352) (xy 98.66825 -273.086338) (xy 98.701998 -273.048244)
			(xy 98.74142 -273.016057) (xy 98.785494 -272.990611) (xy 98.83308 -272.972564) (xy 98.882944 -272.962384)
			(xy 98.933796 -272.960335) (xy 98.984317 -272.966469) (xy 99.033201 -272.980629) (xy 99.07918 -273.002446)
			(xy 99.121064 -273.031356) (xy 99.157768 -273.066611) (xy 99.188341 -273.107297) (xy 99.211992 -273.15236)
			(xy 99.228108 -273.200634) (xy 99.236272 -273.250868) (xy 99.236784 -273.276314) (xy 99.236281 -273.301303)
			(xy 99.543598 -273.301303) (xy 99.543598 -273.251325) (xy 99.551417 -273.201962) (xy 99.566861 -273.15443)
			(xy 99.589551 -273.109898) (xy 99.618927 -273.069465) (xy 99.654267 -273.034125) (xy 99.6947 -273.004749)
			(xy 99.739232 -272.982059) (xy 99.786764 -272.966615) (xy 99.836127 -272.958796) (xy 99.886105 -272.958796)
			(xy 99.935468 -272.966615) (xy 99.983 -272.982059) (xy 100.027532 -273.004749) (xy 100.067965 -273.034125)
			(xy 100.103305 -273.069465) (xy 100.132681 -273.109898) (xy 100.155371 -273.15443) (xy 100.170815 -273.201962)
			(xy 100.178634 -273.251325) (xy 100.179124 -273.276314) (xy 100.484935 -273.276314) (xy 100.48903 -273.225586)
			(xy 100.501209 -273.176172) (xy 100.521157 -273.129352) (xy 100.548358 -273.086338) (xy 100.582106 -273.048244)
			(xy 100.621528 -273.016057) (xy 100.665602 -272.990611) (xy 100.713188 -272.972564) (xy 100.763052 -272.962384)
			(xy 100.813904 -272.960335) (xy 100.864425 -272.966469) (xy 100.913309 -272.980629) (xy 100.959288 -273.002446)
			(xy 101.001172 -273.031356) (xy 101.037876 -273.066611) (xy 101.068449 -273.107297) (xy 101.0921 -273.15236)
			(xy 101.108216 -273.200634) (xy 101.11638 -273.250868) (xy 101.116892 -273.276314) (xy 101.424735 -273.276314)
			(xy 101.42883 -273.225586) (xy 101.441009 -273.176172) (xy 101.460957 -273.129352) (xy 101.488158 -273.086338)
			(xy 101.521906 -273.048244) (xy 101.561328 -273.016057) (xy 101.605402 -272.990611) (xy 101.652988 -272.972564)
			(xy 101.702852 -272.962384) (xy 101.753704 -272.960335) (xy 101.804225 -272.966469) (xy 101.853109 -272.980629)
			(xy 101.899088 -273.002446) (xy 101.940972 -273.031356) (xy 101.977676 -273.066611) (xy 102.008249 -273.107297)
			(xy 102.0319 -273.15236) (xy 102.048016 -273.200634) (xy 102.05618 -273.250868) (xy 102.056692 -273.276314)
			(xy 102.056189 -273.301303) (xy 102.363506 -273.301303) (xy 102.363506 -273.251325) (xy 102.371325 -273.201962)
			(xy 102.386769 -273.15443) (xy 102.409459 -273.109898) (xy 102.438835 -273.069465) (xy 102.474175 -273.034125)
			(xy 102.514608 -273.004749) (xy 102.55914 -272.982059) (xy 102.606672 -272.966615) (xy 102.656035 -272.958796)
			(xy 102.706013 -272.958796) (xy 102.755376 -272.966615) (xy 102.802908 -272.982059) (xy 102.84744 -273.004749)
			(xy 102.887873 -273.034125) (xy 102.923213 -273.069465) (xy 102.952589 -273.109898) (xy 102.975279 -273.15443)
			(xy 102.990723 -273.201962) (xy 102.998542 -273.251325) (xy 102.999032 -273.276314) (xy 103.304843 -273.276314)
			(xy 103.308938 -273.225586) (xy 103.321117 -273.176172) (xy 103.341065 -273.129352) (xy 103.368266 -273.086338)
			(xy 103.402014 -273.048244) (xy 103.441436 -273.016057) (xy 103.48551 -272.990611) (xy 103.533096 -272.972564)
			(xy 103.58296 -272.962384) (xy 103.633812 -272.960335) (xy 103.684333 -272.966469) (xy 103.733217 -272.980629)
			(xy 103.779196 -273.002446) (xy 103.82108 -273.031356) (xy 103.857784 -273.066611) (xy 103.888357 -273.107297)
			(xy 103.912008 -273.15236) (xy 103.928124 -273.200634) (xy 103.936288 -273.250868) (xy 103.9368 -273.276314)
			(xy 104.244897 -273.276314) (xy 104.248992 -273.225586) (xy 104.261171 -273.176172) (xy 104.281119 -273.129352)
			(xy 104.30832 -273.086338) (xy 104.342068 -273.048244) (xy 104.38149 -273.016057) (xy 104.425564 -272.990611)
			(xy 104.47315 -272.972564) (xy 104.523014 -272.962384) (xy 104.573866 -272.960335) (xy 104.624387 -272.966469)
			(xy 104.673271 -272.980629) (xy 104.71925 -273.002446) (xy 104.761134 -273.031356) (xy 104.797838 -273.066611)
			(xy 104.828411 -273.107297) (xy 104.852062 -273.15236) (xy 104.868178 -273.200634) (xy 104.876342 -273.250868)
			(xy 104.876854 -273.276314) (xy 104.876351 -273.301303) (xy 105.183414 -273.301303) (xy 105.183414 -273.251325)
			(xy 105.191233 -273.201962) (xy 105.206677 -273.15443) (xy 105.229367 -273.109898) (xy 105.258743 -273.069465)
			(xy 105.294083 -273.034125) (xy 105.334516 -273.004749) (xy 105.379048 -272.982059) (xy 105.42658 -272.966615)
			(xy 105.475943 -272.958796) (xy 105.525921 -272.958796) (xy 105.575284 -272.966615) (xy 105.622816 -272.982059)
			(xy 105.667348 -273.004749) (xy 105.707781 -273.034125) (xy 105.743121 -273.069465) (xy 105.772497 -273.109898)
			(xy 105.795187 -273.15443) (xy 105.810631 -273.201962) (xy 105.81845 -273.251325) (xy 105.81894 -273.276314)
			(xy 106.124751 -273.276314) (xy 106.128846 -273.225586) (xy 106.141025 -273.176172) (xy 106.160973 -273.129352)
			(xy 106.188174 -273.086338) (xy 106.221922 -273.048244) (xy 106.261344 -273.016057) (xy 106.305418 -272.990611)
			(xy 106.353004 -272.972564) (xy 106.402868 -272.962384) (xy 106.45372 -272.960335) (xy 106.504241 -272.966469)
			(xy 106.553125 -272.980629) (xy 106.599104 -273.002446) (xy 106.640988 -273.031356) (xy 106.677692 -273.066611)
			(xy 106.708265 -273.107297) (xy 106.731916 -273.15236) (xy 106.748032 -273.200634) (xy 106.756196 -273.250868)
			(xy 106.756708 -273.276314) (xy 107.064805 -273.276314) (xy 107.0689 -273.225586) (xy 107.081079 -273.176172)
			(xy 107.101027 -273.129352) (xy 107.128228 -273.086338) (xy 107.161976 -273.048244) (xy 107.201398 -273.016057)
			(xy 107.245472 -272.990611) (xy 107.293058 -272.972564) (xy 107.342922 -272.962384) (xy 107.393774 -272.960335)
			(xy 107.444295 -272.966469) (xy 107.493179 -272.980629) (xy 107.539158 -273.002446) (xy 107.581042 -273.031356)
			(xy 107.617746 -273.066611) (xy 107.648319 -273.107297) (xy 107.67197 -273.15236) (xy 107.688086 -273.200634)
			(xy 107.69625 -273.250868) (xy 107.696762 -273.276314) (xy 107.696259 -273.301303) (xy 108.003576 -273.301303)
			(xy 108.003576 -273.251325) (xy 108.011395 -273.201962) (xy 108.026839 -273.15443) (xy 108.049529 -273.109898)
			(xy 108.078905 -273.069465) (xy 108.114245 -273.034125) (xy 108.154678 -273.004749) (xy 108.19921 -272.982059)
			(xy 108.246742 -272.966615) (xy 108.296105 -272.958796) (xy 108.346083 -272.958796) (xy 108.395446 -272.966615)
			(xy 108.442978 -272.982059) (xy 108.48751 -273.004749) (xy 108.527943 -273.034125) (xy 108.563283 -273.069465)
			(xy 108.592659 -273.109898) (xy 108.615349 -273.15443) (xy 108.630793 -273.201962) (xy 108.638612 -273.251325)
			(xy 108.639102 -273.276314) (xy 108.638612 -273.301303) (xy 108.94363 -273.301303) (xy 108.94363 -273.251325)
			(xy 108.951449 -273.201962) (xy 108.966893 -273.15443) (xy 108.989583 -273.109898) (xy 109.018959 -273.069465)
			(xy 109.054299 -273.034125) (xy 109.094732 -273.004749) (xy 109.139264 -272.982059) (xy 109.186796 -272.966615)
			(xy 109.236159 -272.958796) (xy 109.286137 -272.958796) (xy 109.3355 -272.966615) (xy 109.383032 -272.982059)
			(xy 109.427564 -273.004749) (xy 109.467997 -273.034125) (xy 109.503337 -273.069465) (xy 109.532713 -273.109898)
			(xy 109.555403 -273.15443) (xy 109.570847 -273.201962) (xy 109.578666 -273.251325) (xy 109.579156 -273.276314)
			(xy 109.578666 -273.301303) (xy 109.88343 -273.301303) (xy 109.88343 -273.251325) (xy 109.891249 -273.201962)
			(xy 109.906693 -273.15443) (xy 109.929383 -273.109898) (xy 109.958759 -273.069465) (xy 109.994099 -273.034125)
			(xy 110.034532 -273.004749) (xy 110.079064 -272.982059) (xy 110.126596 -272.966615) (xy 110.175959 -272.958796)
			(xy 110.225937 -272.958796) (xy 110.2753 -272.966615) (xy 110.322832 -272.982059) (xy 110.367364 -273.004749)
			(xy 110.407797 -273.034125) (xy 110.443137 -273.069465) (xy 110.472513 -273.109898) (xy 110.495203 -273.15443)
			(xy 110.510647 -273.201962) (xy 110.518466 -273.251325) (xy 110.518956 -273.276314) (xy 110.518466 -273.301303)
			(xy 113.637296 -273.301303) (xy 113.637296 -273.251325) (xy 113.645115 -273.201962) (xy 113.660559 -273.15443)
			(xy 113.683249 -273.109898) (xy 113.712625 -273.069465) (xy 113.747965 -273.034125) (xy 113.788398 -273.004749)
			(xy 113.83293 -272.982059) (xy 113.880462 -272.966615) (xy 113.929825 -272.958796) (xy 113.979803 -272.958796)
			(xy 114.029166 -272.966615) (xy 114.076698 -272.982059) (xy 114.12123 -273.004749) (xy 114.161663 -273.034125)
			(xy 114.197003 -273.069465) (xy 114.226379 -273.109898) (xy 114.249069 -273.15443) (xy 114.264513 -273.201962)
			(xy 114.272332 -273.251325) (xy 114.272822 -273.276314) (xy 114.272332 -273.301303) (xy 114.577096 -273.301303)
			(xy 114.577096 -273.251325) (xy 114.584915 -273.201962) (xy 114.600359 -273.15443) (xy 114.623049 -273.109898)
			(xy 114.652425 -273.069465) (xy 114.687765 -273.034125) (xy 114.728198 -273.004749) (xy 114.77273 -272.982059)
			(xy 114.820262 -272.966615) (xy 114.869625 -272.958796) (xy 114.919603 -272.958796) (xy 114.968966 -272.966615)
			(xy 115.016498 -272.982059) (xy 115.06103 -273.004749) (xy 115.101463 -273.034125) (xy 115.136803 -273.069465)
			(xy 115.166179 -273.109898) (xy 115.188869 -273.15443) (xy 115.204313 -273.201962) (xy 115.212132 -273.251325)
			(xy 115.212622 -273.276314) (xy 115.212132 -273.301303) (xy 115.51715 -273.301303) (xy 115.51715 -273.251325)
			(xy 115.524969 -273.201962) (xy 115.540413 -273.15443) (xy 115.563103 -273.109898) (xy 115.592479 -273.069465)
			(xy 115.627819 -273.034125) (xy 115.668252 -273.004749) (xy 115.712784 -272.982059) (xy 115.760316 -272.966615)
			(xy 115.809679 -272.958796) (xy 115.859657 -272.958796) (xy 115.90902 -272.966615) (xy 115.956552 -272.982059)
			(xy 116.001084 -273.004749) (xy 116.041517 -273.034125) (xy 116.076857 -273.069465) (xy 116.106233 -273.109898)
			(xy 116.128923 -273.15443) (xy 116.144367 -273.201962) (xy 116.152186 -273.251325) (xy 116.152676 -273.276314)
			(xy 116.458487 -273.276314) (xy 116.462582 -273.225586) (xy 116.474761 -273.176172) (xy 116.494709 -273.129352)
			(xy 116.52191 -273.086338) (xy 116.555658 -273.048244) (xy 116.59508 -273.016057) (xy 116.639154 -272.990611)
			(xy 116.68674 -272.972564) (xy 116.736604 -272.962384) (xy 116.787456 -272.960335) (xy 116.837977 -272.966469)
			(xy 116.886861 -272.980629) (xy 116.93284 -273.002446) (xy 116.974724 -273.031356) (xy 117.011428 -273.066611)
			(xy 117.042001 -273.107297) (xy 117.065652 -273.15236) (xy 117.081768 -273.200634) (xy 117.089932 -273.250868)
			(xy 117.090444 -273.276314) (xy 117.398541 -273.276314) (xy 117.402636 -273.225586) (xy 117.414815 -273.176172)
			(xy 117.434763 -273.129352) (xy 117.461964 -273.086338) (xy 117.495712 -273.048244) (xy 117.535134 -273.016057)
			(xy 117.579208 -272.990611) (xy 117.626794 -272.972564) (xy 117.676658 -272.962384) (xy 117.72751 -272.960335)
			(xy 117.778031 -272.966469) (xy 117.826915 -272.980629) (xy 117.872894 -273.002446) (xy 117.914778 -273.031356)
			(xy 117.951482 -273.066611) (xy 117.982055 -273.107297) (xy 118.005706 -273.15236) (xy 118.021822 -273.200634)
			(xy 118.029986 -273.250868) (xy 118.030498 -273.276314) (xy 118.029995 -273.301303) (xy 118.337312 -273.301303)
			(xy 118.337312 -273.251325) (xy 118.345131 -273.201962) (xy 118.360575 -273.15443) (xy 118.383265 -273.109898)
			(xy 118.412641 -273.069465) (xy 118.447981 -273.034125) (xy 118.488414 -273.004749) (xy 118.532946 -272.982059)
			(xy 118.580478 -272.966615) (xy 118.629841 -272.958796) (xy 118.679819 -272.958796) (xy 118.729182 -272.966615)
			(xy 118.776714 -272.982059) (xy 118.821246 -273.004749) (xy 118.861679 -273.034125) (xy 118.897019 -273.069465)
			(xy 118.926395 -273.109898) (xy 118.949085 -273.15443) (xy 118.964529 -273.201962) (xy 118.972348 -273.251325)
			(xy 118.972838 -273.276314) (xy 119.278395 -273.276314) (xy 119.28249 -273.225586) (xy 119.294669 -273.176172)
			(xy 119.314617 -273.129352) (xy 119.341818 -273.086338) (xy 119.375566 -273.048244) (xy 119.414988 -273.016057)
			(xy 119.459062 -272.990611) (xy 119.506648 -272.972564) (xy 119.556512 -272.962384) (xy 119.607364 -272.960335)
			(xy 119.657885 -272.966469) (xy 119.706769 -272.980629) (xy 119.752748 -273.002446) (xy 119.794632 -273.031356)
			(xy 119.831336 -273.066611) (xy 119.861909 -273.107297) (xy 119.88556 -273.15236) (xy 119.901676 -273.200634)
			(xy 119.90984 -273.250868) (xy 119.910352 -273.276314) (xy 120.218449 -273.276314) (xy 120.222544 -273.225586)
			(xy 120.234723 -273.176172) (xy 120.254671 -273.129352) (xy 120.281872 -273.086338) (xy 120.31562 -273.048244)
			(xy 120.355042 -273.016057) (xy 120.399116 -272.990611) (xy 120.446702 -272.972564) (xy 120.496566 -272.962384)
			(xy 120.547418 -272.960335) (xy 120.597939 -272.966469) (xy 120.646823 -272.980629) (xy 120.692802 -273.002446)
			(xy 120.734686 -273.031356) (xy 120.77139 -273.066611) (xy 120.801963 -273.107297) (xy 120.825614 -273.15236)
			(xy 120.84173 -273.200634) (xy 120.849894 -273.250868) (xy 120.850406 -273.276314) (xy 120.849903 -273.301303)
			(xy 121.15722 -273.301303) (xy 121.15722 -273.251325) (xy 121.165039 -273.201962) (xy 121.180483 -273.15443)
			(xy 121.203173 -273.109898) (xy 121.232549 -273.069465) (xy 121.267889 -273.034125) (xy 121.308322 -273.004749)
			(xy 121.352854 -272.982059) (xy 121.400386 -272.966615) (xy 121.449749 -272.958796) (xy 121.499727 -272.958796)
			(xy 121.54909 -272.966615) (xy 121.596622 -272.982059) (xy 121.641154 -273.004749) (xy 121.681587 -273.034125)
			(xy 121.716927 -273.069465) (xy 121.746303 -273.109898) (xy 121.768993 -273.15443) (xy 121.784437 -273.201962)
			(xy 121.792256 -273.251325) (xy 121.792746 -273.276314) (xy 122.098557 -273.276314) (xy 122.102652 -273.225586)
			(xy 122.114831 -273.176172) (xy 122.134779 -273.129352) (xy 122.16198 -273.086338) (xy 122.195728 -273.048244)
			(xy 122.23515 -273.016057) (xy 122.279224 -272.990611) (xy 122.32681 -272.972564) (xy 122.376674 -272.962384)
			(xy 122.427526 -272.960335) (xy 122.478047 -272.966469) (xy 122.526931 -272.980629) (xy 122.57291 -273.002446)
			(xy 122.614794 -273.031356) (xy 122.651498 -273.066611) (xy 122.682071 -273.107297) (xy 122.705722 -273.15236)
			(xy 122.721838 -273.200634) (xy 122.730002 -273.250868) (xy 122.730514 -273.276314) (xy 123.038611 -273.276314)
			(xy 123.042706 -273.225586) (xy 123.054885 -273.176172) (xy 123.074833 -273.129352) (xy 123.102034 -273.086338)
			(xy 123.135782 -273.048244) (xy 123.175204 -273.016057) (xy 123.219278 -272.990611) (xy 123.266864 -272.972564)
			(xy 123.316728 -272.962384) (xy 123.36758 -272.960335) (xy 123.418101 -272.966469) (xy 123.466985 -272.980629)
			(xy 123.512964 -273.002446) (xy 123.554848 -273.031356) (xy 123.591552 -273.066611) (xy 123.622125 -273.107297)
			(xy 123.645776 -273.15236) (xy 123.661892 -273.200634) (xy 123.670056 -273.250868) (xy 123.670568 -273.276314)
			(xy 123.670065 -273.301303) (xy 123.977128 -273.301303) (xy 123.977128 -273.251325) (xy 123.984947 -273.201962)
			(xy 124.000391 -273.15443) (xy 124.023081 -273.109898) (xy 124.052457 -273.069465) (xy 124.087797 -273.034125)
			(xy 124.12823 -273.004749) (xy 124.172762 -272.982059) (xy 124.220294 -272.966615) (xy 124.269657 -272.958796)
			(xy 124.319635 -272.958796) (xy 124.368998 -272.966615) (xy 124.41653 -272.982059) (xy 124.461062 -273.004749)
			(xy 124.501495 -273.034125) (xy 124.536835 -273.069465) (xy 124.566211 -273.109898) (xy 124.588901 -273.15443)
			(xy 124.604345 -273.201962) (xy 124.612164 -273.251325) (xy 124.612654 -273.276314) (xy 124.918465 -273.276314)
			(xy 124.92256 -273.225586) (xy 124.934739 -273.176172) (xy 124.954687 -273.129352) (xy 124.981888 -273.086338)
			(xy 125.015636 -273.048244) (xy 125.055058 -273.016057) (xy 125.099132 -272.990611) (xy 125.146718 -272.972564)
			(xy 125.196582 -272.962384) (xy 125.247434 -272.960335) (xy 125.297955 -272.966469) (xy 125.346839 -272.980629)
			(xy 125.392818 -273.002446) (xy 125.434702 -273.031356) (xy 125.471406 -273.066611) (xy 125.501979 -273.107297)
			(xy 125.52563 -273.15236) (xy 125.541746 -273.200634) (xy 125.54991 -273.250868) (xy 125.550422 -273.276314)
			(xy 125.858519 -273.276314) (xy 125.862614 -273.225586) (xy 125.874793 -273.176172) (xy 125.894741 -273.129352)
			(xy 125.921942 -273.086338) (xy 125.95569 -273.048244) (xy 125.995112 -273.016057) (xy 126.039186 -272.990611)
			(xy 126.086772 -272.972564) (xy 126.136636 -272.962384) (xy 126.187488 -272.960335) (xy 126.238009 -272.966469)
			(xy 126.286893 -272.980629) (xy 126.332872 -273.002446) (xy 126.374756 -273.031356) (xy 126.41146 -273.066611)
			(xy 126.442033 -273.107297) (xy 126.465684 -273.15236) (xy 126.4818 -273.200634) (xy 126.489964 -273.250868)
			(xy 126.490476 -273.276314) (xy 126.489964 -273.30176) (xy 126.4818 -273.351994) (xy 126.465684 -273.400268)
			(xy 126.442033 -273.445331) (xy 126.41146 -273.486017) (xy 126.374756 -273.521272) (xy 126.332872 -273.550182)
			(xy 126.286893 -273.571999) (xy 126.238009 -273.586159) (xy 126.187488 -273.592293) (xy 126.136636 -273.590244)
			(xy 126.086772 -273.580064) (xy 126.039186 -273.562017) (xy 125.995112 -273.536571) (xy 125.95569 -273.504384)
			(xy 125.921942 -273.46629) (xy 125.894741 -273.423276) (xy 125.874793 -273.376456) (xy 125.862614 -273.327042)
			(xy 125.858519 -273.276314) (xy 125.550422 -273.276314) (xy 125.54991 -273.30176) (xy 125.541746 -273.351994)
			(xy 125.52563 -273.400268) (xy 125.501979 -273.445331) (xy 125.471406 -273.486017) (xy 125.434702 -273.521272)
			(xy 125.392818 -273.550182) (xy 125.346839 -273.571999) (xy 125.297955 -273.586159) (xy 125.247434 -273.592293)
			(xy 125.196582 -273.590244) (xy 125.146718 -273.580064) (xy 125.099132 -273.562017) (xy 125.055058 -273.536571)
			(xy 125.015636 -273.504384) (xy 124.981888 -273.46629) (xy 124.954687 -273.423276) (xy 124.934739 -273.376456)
			(xy 124.92256 -273.327042) (xy 124.918465 -273.276314) (xy 124.612654 -273.276314) (xy 124.612164 -273.301303)
			(xy 124.604345 -273.350666) (xy 124.588901 -273.398198) (xy 124.566211 -273.44273) (xy 124.536835 -273.483163)
			(xy 124.501495 -273.518503) (xy 124.461062 -273.547879) (xy 124.41653 -273.570569) (xy 124.368998 -273.586013)
			(xy 124.319635 -273.593832) (xy 124.269657 -273.593832) (xy 124.220294 -273.586013) (xy 124.172762 -273.570569)
			(xy 124.12823 -273.547879) (xy 124.087797 -273.518503) (xy 124.052457 -273.483163) (xy 124.023081 -273.44273)
			(xy 124.000391 -273.398198) (xy 123.984947 -273.350666) (xy 123.977128 -273.301303) (xy 123.670065 -273.301303)
			(xy 123.670056 -273.30176) (xy 123.661892 -273.351994) (xy 123.645776 -273.400268) (xy 123.622125 -273.445331)
			(xy 123.591552 -273.486017) (xy 123.554848 -273.521272) (xy 123.512964 -273.550182) (xy 123.466985 -273.571999)
			(xy 123.418101 -273.586159) (xy 123.36758 -273.592293) (xy 123.316728 -273.590244) (xy 123.266864 -273.580064)
			(xy 123.219278 -273.562017) (xy 123.175204 -273.536571) (xy 123.135782 -273.504384) (xy 123.102034 -273.46629)
			(xy 123.074833 -273.423276) (xy 123.054885 -273.376456) (xy 123.042706 -273.327042) (xy 123.038611 -273.276314)
			(xy 122.730514 -273.276314) (xy 122.730002 -273.30176) (xy 122.721838 -273.351994) (xy 122.705722 -273.400268)
			(xy 122.682071 -273.445331) (xy 122.651498 -273.486017) (xy 122.614794 -273.521272) (xy 122.57291 -273.550182)
			(xy 122.526931 -273.571999) (xy 122.478047 -273.586159) (xy 122.427526 -273.592293) (xy 122.376674 -273.590244)
			(xy 122.32681 -273.580064) (xy 122.279224 -273.562017) (xy 122.23515 -273.536571) (xy 122.195728 -273.504384)
			(xy 122.16198 -273.46629) (xy 122.134779 -273.423276) (xy 122.114831 -273.376456) (xy 122.102652 -273.327042)
			(xy 122.098557 -273.276314) (xy 121.792746 -273.276314) (xy 121.792256 -273.301303) (xy 121.784437 -273.350666)
			(xy 121.768993 -273.398198) (xy 121.746303 -273.44273) (xy 121.716927 -273.483163) (xy 121.681587 -273.518503)
			(xy 121.641154 -273.547879) (xy 121.596622 -273.570569) (xy 121.54909 -273.586013) (xy 121.499727 -273.593832)
			(xy 121.449749 -273.593832) (xy 121.400386 -273.586013) (xy 121.352854 -273.570569) (xy 121.308322 -273.547879)
			(xy 121.267889 -273.518503) (xy 121.232549 -273.483163) (xy 121.203173 -273.44273) (xy 121.180483 -273.398198)
			(xy 121.165039 -273.350666) (xy 121.15722 -273.301303) (xy 120.849903 -273.301303) (xy 120.849894 -273.30176)
			(xy 120.84173 -273.351994) (xy 120.825614 -273.400268) (xy 120.801963 -273.445331) (xy 120.77139 -273.486017)
			(xy 120.734686 -273.521272) (xy 120.692802 -273.550182) (xy 120.646823 -273.571999) (xy 120.597939 -273.586159)
			(xy 120.547418 -273.592293) (xy 120.496566 -273.590244) (xy 120.446702 -273.580064) (xy 120.399116 -273.562017)
			(xy 120.355042 -273.536571) (xy 120.31562 -273.504384) (xy 120.281872 -273.46629) (xy 120.254671 -273.423276)
			(xy 120.234723 -273.376456) (xy 120.222544 -273.327042) (xy 120.218449 -273.276314) (xy 119.910352 -273.276314)
			(xy 119.90984 -273.30176) (xy 119.901676 -273.351994) (xy 119.88556 -273.400268) (xy 119.861909 -273.445331)
			(xy 119.831336 -273.486017) (xy 119.794632 -273.521272) (xy 119.752748 -273.550182) (xy 119.706769 -273.571999)
			(xy 119.657885 -273.586159) (xy 119.607364 -273.592293) (xy 119.556512 -273.590244) (xy 119.506648 -273.580064)
			(xy 119.459062 -273.562017) (xy 119.414988 -273.536571) (xy 119.375566 -273.504384) (xy 119.341818 -273.46629)
			(xy 119.314617 -273.423276) (xy 119.294669 -273.376456) (xy 119.28249 -273.327042) (xy 119.278395 -273.276314)
			(xy 118.972838 -273.276314) (xy 118.972348 -273.301303) (xy 118.964529 -273.350666) (xy 118.949085 -273.398198)
			(xy 118.926395 -273.44273) (xy 118.897019 -273.483163) (xy 118.861679 -273.518503) (xy 118.821246 -273.547879)
			(xy 118.776714 -273.570569) (xy 118.729182 -273.586013) (xy 118.679819 -273.593832) (xy 118.629841 -273.593832)
			(xy 118.580478 -273.586013) (xy 118.532946 -273.570569) (xy 118.488414 -273.547879) (xy 118.447981 -273.518503)
			(xy 118.412641 -273.483163) (xy 118.383265 -273.44273) (xy 118.360575 -273.398198) (xy 118.345131 -273.350666)
			(xy 118.337312 -273.301303) (xy 118.029995 -273.301303) (xy 118.029986 -273.30176) (xy 118.021822 -273.351994)
			(xy 118.005706 -273.400268) (xy 117.982055 -273.445331) (xy 117.951482 -273.486017) (xy 117.914778 -273.521272)
			(xy 117.872894 -273.550182) (xy 117.826915 -273.571999) (xy 117.778031 -273.586159) (xy 117.72751 -273.592293)
			(xy 117.676658 -273.590244) (xy 117.626794 -273.580064) (xy 117.579208 -273.562017) (xy 117.535134 -273.536571)
			(xy 117.495712 -273.504384) (xy 117.461964 -273.46629) (xy 117.434763 -273.423276) (xy 117.414815 -273.376456)
			(xy 117.402636 -273.327042) (xy 117.398541 -273.276314) (xy 117.090444 -273.276314) (xy 117.089932 -273.30176)
			(xy 117.081768 -273.351994) (xy 117.065652 -273.400268) (xy 117.042001 -273.445331) (xy 117.011428 -273.486017)
			(xy 116.974724 -273.521272) (xy 116.93284 -273.550182) (xy 116.886861 -273.571999) (xy 116.837977 -273.586159)
			(xy 116.787456 -273.592293) (xy 116.736604 -273.590244) (xy 116.68674 -273.580064) (xy 116.639154 -273.562017)
			(xy 116.59508 -273.536571) (xy 116.555658 -273.504384) (xy 116.52191 -273.46629) (xy 116.494709 -273.423276)
			(xy 116.474761 -273.376456) (xy 116.462582 -273.327042) (xy 116.458487 -273.276314) (xy 116.152676 -273.276314)
			(xy 116.152186 -273.301303) (xy 116.144367 -273.350666) (xy 116.128923 -273.398198) (xy 116.106233 -273.44273)
			(xy 116.076857 -273.483163) (xy 116.041517 -273.518503) (xy 116.001084 -273.547879) (xy 115.956552 -273.570569)
			(xy 115.90902 -273.586013) (xy 115.859657 -273.593832) (xy 115.809679 -273.593832) (xy 115.760316 -273.586013)
			(xy 115.712784 -273.570569) (xy 115.668252 -273.547879) (xy 115.627819 -273.518503) (xy 115.592479 -273.483163)
			(xy 115.563103 -273.44273) (xy 115.540413 -273.398198) (xy 115.524969 -273.350666) (xy 115.51715 -273.301303)
			(xy 115.212132 -273.301303) (xy 115.204313 -273.350666) (xy 115.188869 -273.398198) (xy 115.166179 -273.44273)
			(xy 115.136803 -273.483163) (xy 115.101463 -273.518503) (xy 115.06103 -273.547879) (xy 115.016498 -273.570569)
			(xy 114.968966 -273.586013) (xy 114.919603 -273.593832) (xy 114.869625 -273.593832) (xy 114.820262 -273.586013)
			(xy 114.77273 -273.570569) (xy 114.728198 -273.547879) (xy 114.687765 -273.518503) (xy 114.652425 -273.483163)
			(xy 114.623049 -273.44273) (xy 114.600359 -273.398198) (xy 114.584915 -273.350666) (xy 114.577096 -273.301303)
			(xy 114.272332 -273.301303) (xy 114.264513 -273.350666) (xy 114.249069 -273.398198) (xy 114.226379 -273.44273)
			(xy 114.197003 -273.483163) (xy 114.161663 -273.518503) (xy 114.12123 -273.547879) (xy 114.076698 -273.570569)
			(xy 114.029166 -273.586013) (xy 113.979803 -273.593832) (xy 113.929825 -273.593832) (xy 113.880462 -273.586013)
			(xy 113.83293 -273.570569) (xy 113.788398 -273.547879) (xy 113.747965 -273.518503) (xy 113.712625 -273.483163)
			(xy 113.683249 -273.44273) (xy 113.660559 -273.398198) (xy 113.645115 -273.350666) (xy 113.637296 -273.301303)
			(xy 110.518466 -273.301303) (xy 110.510647 -273.350666) (xy 110.495203 -273.398198) (xy 110.472513 -273.44273)
			(xy 110.443137 -273.483163) (xy 110.407797 -273.518503) (xy 110.367364 -273.547879) (xy 110.322832 -273.570569)
			(xy 110.2753 -273.586013) (xy 110.225937 -273.593832) (xy 110.175959 -273.593832) (xy 110.126596 -273.586013)
			(xy 110.079064 -273.570569) (xy 110.034532 -273.547879) (xy 109.994099 -273.518503) (xy 109.958759 -273.483163)
			(xy 109.929383 -273.44273) (xy 109.906693 -273.398198) (xy 109.891249 -273.350666) (xy 109.88343 -273.301303)
			(xy 109.578666 -273.301303) (xy 109.570847 -273.350666) (xy 109.555403 -273.398198) (xy 109.532713 -273.44273)
			(xy 109.503337 -273.483163) (xy 109.467997 -273.518503) (xy 109.427564 -273.547879) (xy 109.383032 -273.570569)
			(xy 109.3355 -273.586013) (xy 109.286137 -273.593832) (xy 109.236159 -273.593832) (xy 109.186796 -273.586013)
			(xy 109.139264 -273.570569) (xy 109.094732 -273.547879) (xy 109.054299 -273.518503) (xy 109.018959 -273.483163)
			(xy 108.989583 -273.44273) (xy 108.966893 -273.398198) (xy 108.951449 -273.350666) (xy 108.94363 -273.301303)
			(xy 108.638612 -273.301303) (xy 108.630793 -273.350666) (xy 108.615349 -273.398198) (xy 108.592659 -273.44273)
			(xy 108.563283 -273.483163) (xy 108.527943 -273.518503) (xy 108.48751 -273.547879) (xy 108.442978 -273.570569)
			(xy 108.395446 -273.586013) (xy 108.346083 -273.593832) (xy 108.296105 -273.593832) (xy 108.246742 -273.586013)
			(xy 108.19921 -273.570569) (xy 108.154678 -273.547879) (xy 108.114245 -273.518503) (xy 108.078905 -273.483163)
			(xy 108.049529 -273.44273) (xy 108.026839 -273.398198) (xy 108.011395 -273.350666) (xy 108.003576 -273.301303)
			(xy 107.696259 -273.301303) (xy 107.69625 -273.30176) (xy 107.688086 -273.351994) (xy 107.67197 -273.400268)
			(xy 107.648319 -273.445331) (xy 107.617746 -273.486017) (xy 107.581042 -273.521272) (xy 107.539158 -273.550182)
			(xy 107.493179 -273.571999) (xy 107.444295 -273.586159) (xy 107.393774 -273.592293) (xy 107.342922 -273.590244)
			(xy 107.293058 -273.580064) (xy 107.245472 -273.562017) (xy 107.201398 -273.536571) (xy 107.161976 -273.504384)
			(xy 107.128228 -273.46629) (xy 107.101027 -273.423276) (xy 107.081079 -273.376456) (xy 107.0689 -273.327042)
			(xy 107.064805 -273.276314) (xy 106.756708 -273.276314) (xy 106.756196 -273.30176) (xy 106.748032 -273.351994)
			(xy 106.731916 -273.400268) (xy 106.708265 -273.445331) (xy 106.677692 -273.486017) (xy 106.640988 -273.521272)
			(xy 106.599104 -273.550182) (xy 106.553125 -273.571999) (xy 106.504241 -273.586159) (xy 106.45372 -273.592293)
			(xy 106.402868 -273.590244) (xy 106.353004 -273.580064) (xy 106.305418 -273.562017) (xy 106.261344 -273.536571)
			(xy 106.221922 -273.504384) (xy 106.188174 -273.46629) (xy 106.160973 -273.423276) (xy 106.141025 -273.376456)
			(xy 106.128846 -273.327042) (xy 106.124751 -273.276314) (xy 105.81894 -273.276314) (xy 105.81845 -273.301303)
			(xy 105.810631 -273.350666) (xy 105.795187 -273.398198) (xy 105.772497 -273.44273) (xy 105.743121 -273.483163)
			(xy 105.707781 -273.518503) (xy 105.667348 -273.547879) (xy 105.622816 -273.570569) (xy 105.575284 -273.586013)
			(xy 105.525921 -273.593832) (xy 105.475943 -273.593832) (xy 105.42658 -273.586013) (xy 105.379048 -273.570569)
			(xy 105.334516 -273.547879) (xy 105.294083 -273.518503) (xy 105.258743 -273.483163) (xy 105.229367 -273.44273)
			(xy 105.206677 -273.398198) (xy 105.191233 -273.350666) (xy 105.183414 -273.301303) (xy 104.876351 -273.301303)
			(xy 104.876342 -273.30176) (xy 104.868178 -273.351994) (xy 104.852062 -273.400268) (xy 104.828411 -273.445331)
			(xy 104.797838 -273.486017) (xy 104.761134 -273.521272) (xy 104.71925 -273.550182) (xy 104.673271 -273.571999)
			(xy 104.624387 -273.586159) (xy 104.573866 -273.592293) (xy 104.523014 -273.590244) (xy 104.47315 -273.580064)
			(xy 104.425564 -273.562017) (xy 104.38149 -273.536571) (xy 104.342068 -273.504384) (xy 104.30832 -273.46629)
			(xy 104.281119 -273.423276) (xy 104.261171 -273.376456) (xy 104.248992 -273.327042) (xy 104.244897 -273.276314)
			(xy 103.9368 -273.276314) (xy 103.936288 -273.30176) (xy 103.928124 -273.351994) (xy 103.912008 -273.400268)
			(xy 103.888357 -273.445331) (xy 103.857784 -273.486017) (xy 103.82108 -273.521272) (xy 103.779196 -273.550182)
			(xy 103.733217 -273.571999) (xy 103.684333 -273.586159) (xy 103.633812 -273.592293) (xy 103.58296 -273.590244)
			(xy 103.533096 -273.580064) (xy 103.48551 -273.562017) (xy 103.441436 -273.536571) (xy 103.402014 -273.504384)
			(xy 103.368266 -273.46629) (xy 103.341065 -273.423276) (xy 103.321117 -273.376456) (xy 103.308938 -273.327042)
			(xy 103.304843 -273.276314) (xy 102.999032 -273.276314) (xy 102.998542 -273.301303) (xy 102.990723 -273.350666)
			(xy 102.975279 -273.398198) (xy 102.952589 -273.44273) (xy 102.923213 -273.483163) (xy 102.887873 -273.518503)
			(xy 102.84744 -273.547879) (xy 102.802908 -273.570569) (xy 102.755376 -273.586013) (xy 102.706013 -273.593832)
			(xy 102.656035 -273.593832) (xy 102.606672 -273.586013) (xy 102.55914 -273.570569) (xy 102.514608 -273.547879)
			(xy 102.474175 -273.518503) (xy 102.438835 -273.483163) (xy 102.409459 -273.44273) (xy 102.386769 -273.398198)
			(xy 102.371325 -273.350666) (xy 102.363506 -273.301303) (xy 102.056189 -273.301303) (xy 102.05618 -273.30176)
			(xy 102.048016 -273.351994) (xy 102.0319 -273.400268) (xy 102.008249 -273.445331) (xy 101.977676 -273.486017)
			(xy 101.940972 -273.521272) (xy 101.899088 -273.550182) (xy 101.853109 -273.571999) (xy 101.804225 -273.586159)
			(xy 101.753704 -273.592293) (xy 101.702852 -273.590244) (xy 101.652988 -273.580064) (xy 101.605402 -273.562017)
			(xy 101.561328 -273.536571) (xy 101.521906 -273.504384) (xy 101.488158 -273.46629) (xy 101.460957 -273.423276)
			(xy 101.441009 -273.376456) (xy 101.42883 -273.327042) (xy 101.424735 -273.276314) (xy 101.116892 -273.276314)
			(xy 101.11638 -273.30176) (xy 101.108216 -273.351994) (xy 101.0921 -273.400268) (xy 101.068449 -273.445331)
			(xy 101.037876 -273.486017) (xy 101.001172 -273.521272) (xy 100.959288 -273.550182) (xy 100.913309 -273.571999)
			(xy 100.864425 -273.586159) (xy 100.813904 -273.592293) (xy 100.763052 -273.590244) (xy 100.713188 -273.580064)
			(xy 100.665602 -273.562017) (xy 100.621528 -273.536571) (xy 100.582106 -273.504384) (xy 100.548358 -273.46629)
			(xy 100.521157 -273.423276) (xy 100.501209 -273.376456) (xy 100.48903 -273.327042) (xy 100.484935 -273.276314)
			(xy 100.179124 -273.276314) (xy 100.178634 -273.301303) (xy 100.170815 -273.350666) (xy 100.155371 -273.398198)
			(xy 100.132681 -273.44273) (xy 100.103305 -273.483163) (xy 100.067965 -273.518503) (xy 100.027532 -273.547879)
			(xy 99.983 -273.570569) (xy 99.935468 -273.586013) (xy 99.886105 -273.593832) (xy 99.836127 -273.593832)
			(xy 99.786764 -273.586013) (xy 99.739232 -273.570569) (xy 99.6947 -273.547879) (xy 99.654267 -273.518503)
			(xy 99.618927 -273.483163) (xy 99.589551 -273.44273) (xy 99.566861 -273.398198) (xy 99.551417 -273.350666)
			(xy 99.543598 -273.301303) (xy 99.236281 -273.301303) (xy 99.236272 -273.30176) (xy 99.228108 -273.351994)
			(xy 99.211992 -273.400268) (xy 99.188341 -273.445331) (xy 99.157768 -273.486017) (xy 99.121064 -273.521272)
			(xy 99.07918 -273.550182) (xy 99.033201 -273.571999) (xy 98.984317 -273.586159) (xy 98.933796 -273.592293)
			(xy 98.882944 -273.590244) (xy 98.83308 -273.580064) (xy 98.785494 -273.562017) (xy 98.74142 -273.536571)
			(xy 98.701998 -273.504384) (xy 98.66825 -273.46629) (xy 98.641049 -273.423276) (xy 98.621101 -273.376456)
			(xy 98.608922 -273.327042) (xy 98.604827 -273.276314) (xy 98.29673 -273.276314) (xy 98.296218 -273.30176)
			(xy 98.288054 -273.351994) (xy 98.271938 -273.400268) (xy 98.248287 -273.445331) (xy 98.217714 -273.486017)
			(xy 98.18101 -273.521272) (xy 98.139126 -273.550182) (xy 98.093147 -273.571999) (xy 98.044263 -273.586159)
			(xy 97.993742 -273.592293) (xy 97.94289 -273.590244) (xy 97.893026 -273.580064) (xy 97.84544 -273.562017)
			(xy 97.801366 -273.536571) (xy 97.761944 -273.504384) (xy 97.728196 -273.46629) (xy 97.700995 -273.423276)
			(xy 97.681047 -273.376456) (xy 97.668868 -273.327042) (xy 97.664773 -273.276314) (xy 97.358962 -273.276314)
			(xy 97.358516 -273.300409) (xy 97.351242 -273.348047) (xy 97.336863 -273.394041) (xy 97.315707 -273.437339)
			(xy 97.28826 -273.476949) (xy 97.255151 -273.511963) (xy 97.217136 -273.54158) (xy 97.175088 -273.565122)
			(xy 97.129969 -273.582049) (xy 97.106486 -273.587464) (xy 97.09912 -273.588988) (xy 97.086166 -273.5961)
			(xy 96.826578 -273.855688) (xy 96.823276 -273.891756) (xy 96.83369 -273.906996) (xy 96.846741 -273.926897)
			(xy 96.867419 -273.969757) (xy 96.881479 -274.015221) (xy 96.888606 -274.062272) (xy 96.889062 -274.086066)
			(xy 96.889062 -274.093178) (xy 96.888333 -274.111309) (xy 97.19359 -274.111309) (xy 97.19359 -274.061331)
			(xy 97.201409 -274.011968) (xy 97.216853 -273.964436) (xy 97.239543 -273.919904) (xy 97.268919 -273.879471)
			(xy 97.304259 -273.844131) (xy 97.344692 -273.814755) (xy 97.389224 -273.792065) (xy 97.436756 -273.776621)
			(xy 97.486119 -273.768802) (xy 97.536097 -273.768802) (xy 97.58546 -273.776621) (xy 97.632992 -273.792065)
			(xy 97.677524 -273.814755) (xy 97.717957 -273.844131) (xy 97.753297 -273.879471) (xy 97.782673 -273.919904)
			(xy 97.805363 -273.964436) (xy 97.820807 -274.011968) (xy 97.828626 -274.061331) (xy 97.829116 -274.08632)
			(xy 97.828626 -274.111309) (xy 98.133644 -274.111309) (xy 98.133644 -274.061331) (xy 98.141463 -274.011968)
			(xy 98.156907 -273.964436) (xy 98.179597 -273.919904) (xy 98.208973 -273.879471) (xy 98.244313 -273.844131)
			(xy 98.284746 -273.814755) (xy 98.329278 -273.792065) (xy 98.37681 -273.776621) (xy 98.426173 -273.768802)
			(xy 98.476151 -273.768802) (xy 98.525514 -273.776621) (xy 98.573046 -273.792065) (xy 98.617578 -273.814755)
			(xy 98.658011 -273.844131) (xy 98.693351 -273.879471) (xy 98.722727 -273.919904) (xy 98.745417 -273.964436)
			(xy 98.760861 -274.011968) (xy 98.76868 -274.061331) (xy 98.76917 -274.08632) (xy 98.76868 -274.111309)
			(xy 99.073444 -274.111309) (xy 99.073444 -274.061331) (xy 99.081263 -274.011968) (xy 99.096707 -273.964436)
			(xy 99.119397 -273.919904) (xy 99.148773 -273.879471) (xy 99.184113 -273.844131) (xy 99.224546 -273.814755)
			(xy 99.269078 -273.792065) (xy 99.31661 -273.776621) (xy 99.365973 -273.768802) (xy 99.415951 -273.768802)
			(xy 99.465314 -273.776621) (xy 99.512846 -273.792065) (xy 99.557378 -273.814755) (xy 99.597811 -273.844131)
			(xy 99.633151 -273.879471) (xy 99.662527 -273.919904) (xy 99.685217 -273.964436) (xy 99.700661 -274.011968)
			(xy 99.70848 -274.061331) (xy 99.70897 -274.08632) (xy 99.70848 -274.111309) (xy 100.013498 -274.111309)
			(xy 100.013498 -274.061331) (xy 100.021317 -274.011968) (xy 100.036761 -273.964436) (xy 100.059451 -273.919904)
			(xy 100.088827 -273.879471) (xy 100.124167 -273.844131) (xy 100.1646 -273.814755) (xy 100.209132 -273.792065)
			(xy 100.256664 -273.776621) (xy 100.306027 -273.768802) (xy 100.356005 -273.768802) (xy 100.405368 -273.776621)
			(xy 100.4529 -273.792065) (xy 100.497432 -273.814755) (xy 100.537865 -273.844131) (xy 100.573205 -273.879471)
			(xy 100.602581 -273.919904) (xy 100.625271 -273.964436) (xy 100.640715 -274.011968) (xy 100.648534 -274.061331)
			(xy 100.649024 -274.08632) (xy 100.648534 -274.111309) (xy 100.953552 -274.111309) (xy 100.953552 -274.061331)
			(xy 100.961371 -274.011968) (xy 100.976815 -273.964436) (xy 100.999505 -273.919904) (xy 101.028881 -273.879471)
			(xy 101.064221 -273.844131) (xy 101.104654 -273.814755) (xy 101.149186 -273.792065) (xy 101.196718 -273.776621)
			(xy 101.246081 -273.768802) (xy 101.296059 -273.768802) (xy 101.345422 -273.776621) (xy 101.392954 -273.792065)
			(xy 101.437486 -273.814755) (xy 101.477919 -273.844131) (xy 101.513259 -273.879471) (xy 101.542635 -273.919904)
			(xy 101.565325 -273.964436) (xy 101.580769 -274.011968) (xy 101.588588 -274.061331) (xy 101.589078 -274.08632)
			(xy 101.588588 -274.111309) (xy 101.893606 -274.111309) (xy 101.893606 -274.061331) (xy 101.901425 -274.011968)
			(xy 101.916869 -273.964436) (xy 101.939559 -273.919904) (xy 101.968935 -273.879471) (xy 102.004275 -273.844131)
			(xy 102.044708 -273.814755) (xy 102.08924 -273.792065) (xy 102.136772 -273.776621) (xy 102.186135 -273.768802)
			(xy 102.236113 -273.768802) (xy 102.285476 -273.776621) (xy 102.333008 -273.792065) (xy 102.37754 -273.814755)
			(xy 102.417973 -273.844131) (xy 102.453313 -273.879471) (xy 102.482689 -273.919904) (xy 102.505379 -273.964436)
			(xy 102.520823 -274.011968) (xy 102.528642 -274.061331) (xy 102.529132 -274.08632) (xy 102.528642 -274.111309)
			(xy 102.83366 -274.111309) (xy 102.83366 -274.061331) (xy 102.841479 -274.011968) (xy 102.856923 -273.964436)
			(xy 102.879613 -273.919904) (xy 102.908989 -273.879471) (xy 102.944329 -273.844131) (xy 102.984762 -273.814755)
			(xy 103.029294 -273.792065) (xy 103.076826 -273.776621) (xy 103.126189 -273.768802) (xy 103.176167 -273.768802)
			(xy 103.22553 -273.776621) (xy 103.273062 -273.792065) (xy 103.317594 -273.814755) (xy 103.358027 -273.844131)
			(xy 103.393367 -273.879471) (xy 103.422743 -273.919904) (xy 103.445433 -273.964436) (xy 103.460877 -274.011968)
			(xy 103.468696 -274.061331) (xy 103.469186 -274.08632) (xy 103.468696 -274.111309) (xy 103.77346 -274.111309)
			(xy 103.77346 -274.061331) (xy 103.781279 -274.011968) (xy 103.796723 -273.964436) (xy 103.819413 -273.919904)
			(xy 103.848789 -273.879471) (xy 103.884129 -273.844131) (xy 103.924562 -273.814755) (xy 103.969094 -273.792065)
			(xy 104.016626 -273.776621) (xy 104.065989 -273.768802) (xy 104.115967 -273.768802) (xy 104.16533 -273.776621)
			(xy 104.212862 -273.792065) (xy 104.257394 -273.814755) (xy 104.297827 -273.844131) (xy 104.333167 -273.879471)
			(xy 104.362543 -273.919904) (xy 104.385233 -273.964436) (xy 104.400677 -274.011968) (xy 104.408496 -274.061331)
			(xy 104.408986 -274.08632) (xy 104.408496 -274.111309) (xy 104.713514 -274.111309) (xy 104.713514 -274.061331)
			(xy 104.721333 -274.011968) (xy 104.736777 -273.964436) (xy 104.759467 -273.919904) (xy 104.788843 -273.879471)
			(xy 104.824183 -273.844131) (xy 104.864616 -273.814755) (xy 104.909148 -273.792065) (xy 104.95668 -273.776621)
			(xy 105.006043 -273.768802) (xy 105.056021 -273.768802) (xy 105.105384 -273.776621) (xy 105.152916 -273.792065)
			(xy 105.197448 -273.814755) (xy 105.237881 -273.844131) (xy 105.273221 -273.879471) (xy 105.302597 -273.919904)
			(xy 105.325287 -273.964436) (xy 105.340731 -274.011968) (xy 105.34855 -274.061331) (xy 105.34904 -274.08632)
			(xy 105.34855 -274.111309) (xy 105.653568 -274.111309) (xy 105.653568 -274.061331) (xy 105.661387 -274.011968)
			(xy 105.676831 -273.964436) (xy 105.699521 -273.919904) (xy 105.728897 -273.879471) (xy 105.764237 -273.844131)
			(xy 105.80467 -273.814755) (xy 105.849202 -273.792065) (xy 105.896734 -273.776621) (xy 105.946097 -273.768802)
			(xy 105.996075 -273.768802) (xy 106.045438 -273.776621) (xy 106.09297 -273.792065) (xy 106.137502 -273.814755)
			(xy 106.177935 -273.844131) (xy 106.213275 -273.879471) (xy 106.242651 -273.919904) (xy 106.265341 -273.964436)
			(xy 106.280785 -274.011968) (xy 106.288604 -274.061331) (xy 106.289094 -274.08632) (xy 106.288604 -274.111309)
			(xy 106.593622 -274.111309) (xy 106.593622 -274.061331) (xy 106.601441 -274.011968) (xy 106.616885 -273.964436)
			(xy 106.639575 -273.919904) (xy 106.668951 -273.879471) (xy 106.704291 -273.844131) (xy 106.744724 -273.814755)
			(xy 106.789256 -273.792065) (xy 106.836788 -273.776621) (xy 106.886151 -273.768802) (xy 106.936129 -273.768802)
			(xy 106.985492 -273.776621) (xy 107.033024 -273.792065) (xy 107.077556 -273.814755) (xy 107.117989 -273.844131)
			(xy 107.153329 -273.879471) (xy 107.182705 -273.919904) (xy 107.205395 -273.964436) (xy 107.220839 -274.011968)
			(xy 107.228658 -274.061331) (xy 107.229148 -274.08632) (xy 107.228658 -274.111309) (xy 107.533422 -274.111309)
			(xy 107.533422 -274.061331) (xy 107.541241 -274.011968) (xy 107.556685 -273.964436) (xy 107.579375 -273.919904)
			(xy 107.608751 -273.879471) (xy 107.644091 -273.844131) (xy 107.684524 -273.814755) (xy 107.729056 -273.792065)
			(xy 107.776588 -273.776621) (xy 107.825951 -273.768802) (xy 107.875929 -273.768802) (xy 107.925292 -273.776621)
			(xy 107.972824 -273.792065) (xy 108.017356 -273.814755) (xy 108.057789 -273.844131) (xy 108.093129 -273.879471)
			(xy 108.122505 -273.919904) (xy 108.145195 -273.964436) (xy 108.160639 -274.011968) (xy 108.168458 -274.061331)
			(xy 108.168948 -274.08632) (xy 108.474759 -274.08632) (xy 108.478854 -274.035592) (xy 108.491033 -273.986178)
			(xy 108.510981 -273.939358) (xy 108.538182 -273.896344) (xy 108.57193 -273.85825) (xy 108.611352 -273.826063)
			(xy 108.655426 -273.800617) (xy 108.703012 -273.78257) (xy 108.752876 -273.77239) (xy 108.803728 -273.770341)
			(xy 108.854249 -273.776475) (xy 108.903133 -273.790635) (xy 108.949112 -273.812452) (xy 108.990996 -273.841362)
			(xy 109.0277 -273.876617) (xy 109.058273 -273.917303) (xy 109.081924 -273.962366) (xy 109.09804 -274.01064)
			(xy 109.106204 -274.060874) (xy 109.106716 -274.08632) (xy 109.414813 -274.08632) (xy 109.418908 -274.035592)
			(xy 109.431087 -273.986178) (xy 109.451035 -273.939358) (xy 109.478236 -273.896344) (xy 109.511984 -273.85825)
			(xy 109.551406 -273.826063) (xy 109.59548 -273.800617) (xy 109.643066 -273.78257) (xy 109.69293 -273.77239)
			(xy 109.743782 -273.770341) (xy 109.794303 -273.776475) (xy 109.843187 -273.790635) (xy 109.889166 -273.812452)
			(xy 109.93105 -273.841362) (xy 109.967754 -273.876617) (xy 109.998327 -273.917303) (xy 110.021978 -273.962366)
			(xy 110.038094 -274.01064) (xy 110.046258 -274.060874) (xy 110.04677 -274.08632) (xy 110.046267 -274.111309)
			(xy 110.353584 -274.111309) (xy 110.353584 -274.061331) (xy 110.361403 -274.011968) (xy 110.376847 -273.964436)
			(xy 110.399537 -273.919904) (xy 110.428913 -273.879471) (xy 110.464253 -273.844131) (xy 110.504686 -273.814755)
			(xy 110.549218 -273.792065) (xy 110.59675 -273.776621) (xy 110.646113 -273.768802) (xy 110.696091 -273.768802)
			(xy 110.745454 -273.776621) (xy 110.792986 -273.792065) (xy 110.837518 -273.814755) (xy 110.877951 -273.844131)
			(xy 110.913291 -273.879471) (xy 110.942667 -273.919904) (xy 110.965357 -273.964436) (xy 110.980801 -274.011968)
			(xy 110.98862 -274.061331) (xy 110.98911 -274.08632) (xy 110.98862 -274.111309) (xy 113.167142 -274.111309)
			(xy 113.167142 -274.061331) (xy 113.174961 -274.011968) (xy 113.190405 -273.964436) (xy 113.213095 -273.919904)
			(xy 113.242471 -273.879471) (xy 113.277811 -273.844131) (xy 113.318244 -273.814755) (xy 113.362776 -273.792065)
			(xy 113.410308 -273.776621) (xy 113.459671 -273.768802) (xy 113.509649 -273.768802) (xy 113.559012 -273.776621)
			(xy 113.606544 -273.792065) (xy 113.651076 -273.814755) (xy 113.691509 -273.844131) (xy 113.726849 -273.879471)
			(xy 113.756225 -273.919904) (xy 113.778915 -273.964436) (xy 113.794359 -274.011968) (xy 113.802178 -274.061331)
			(xy 113.802668 -274.08632) (xy 114.108479 -274.08632) (xy 114.112574 -274.035592) (xy 114.124753 -273.986178)
			(xy 114.144701 -273.939358) (xy 114.171902 -273.896344) (xy 114.20565 -273.85825) (xy 114.245072 -273.826063)
			(xy 114.289146 -273.800617) (xy 114.336732 -273.78257) (xy 114.386596 -273.77239) (xy 114.437448 -273.770341)
			(xy 114.487969 -273.776475) (xy 114.536853 -273.790635) (xy 114.582832 -273.812452) (xy 114.624716 -273.841362)
			(xy 114.66142 -273.876617) (xy 114.691993 -273.917303) (xy 114.715644 -273.962366) (xy 114.73176 -274.01064)
			(xy 114.739924 -274.060874) (xy 114.740436 -274.08632) (xy 115.048533 -274.08632) (xy 115.052628 -274.035592)
			(xy 115.064807 -273.986178) (xy 115.084755 -273.939358) (xy 115.111956 -273.896344) (xy 115.145704 -273.85825)
			(xy 115.185126 -273.826063) (xy 115.2292 -273.800617) (xy 115.276786 -273.78257) (xy 115.32665 -273.77239)
			(xy 115.377502 -273.770341) (xy 115.428023 -273.776475) (xy 115.476907 -273.790635) (xy 115.522886 -273.812452)
			(xy 115.56477 -273.841362) (xy 115.601474 -273.876617) (xy 115.632047 -273.917303) (xy 115.655698 -273.962366)
			(xy 115.671814 -274.01064) (xy 115.679978 -274.060874) (xy 115.68049 -274.08632) (xy 115.679987 -274.111309)
			(xy 115.987304 -274.111309) (xy 115.987304 -274.061331) (xy 115.995123 -274.011968) (xy 116.010567 -273.964436)
			(xy 116.033257 -273.919904) (xy 116.062633 -273.879471) (xy 116.097973 -273.844131) (xy 116.138406 -273.814755)
			(xy 116.182938 -273.792065) (xy 116.23047 -273.776621) (xy 116.279833 -273.768802) (xy 116.329811 -273.768802)
			(xy 116.379174 -273.776621) (xy 116.426706 -273.792065) (xy 116.471238 -273.814755) (xy 116.511671 -273.844131)
			(xy 116.547011 -273.879471) (xy 116.576387 -273.919904) (xy 116.599077 -273.964436) (xy 116.614521 -274.011968)
			(xy 116.62234 -274.061331) (xy 116.62283 -274.08632) (xy 116.62234 -274.111309) (xy 116.927104 -274.111309)
			(xy 116.927104 -274.061331) (xy 116.934923 -274.011968) (xy 116.950367 -273.964436) (xy 116.973057 -273.919904)
			(xy 117.002433 -273.879471) (xy 117.037773 -273.844131) (xy 117.078206 -273.814755) (xy 117.122738 -273.792065)
			(xy 117.17027 -273.776621) (xy 117.219633 -273.768802) (xy 117.269611 -273.768802) (xy 117.318974 -273.776621)
			(xy 117.366506 -273.792065) (xy 117.411038 -273.814755) (xy 117.451471 -273.844131) (xy 117.486811 -273.879471)
			(xy 117.516187 -273.919904) (xy 117.538877 -273.964436) (xy 117.554321 -274.011968) (xy 117.56214 -274.061331)
			(xy 117.56263 -274.08632) (xy 117.56214 -274.111309) (xy 117.867158 -274.111309) (xy 117.867158 -274.061331)
			(xy 117.874977 -274.011968) (xy 117.890421 -273.964436) (xy 117.913111 -273.919904) (xy 117.942487 -273.879471)
			(xy 117.977827 -273.844131) (xy 118.01826 -273.814755) (xy 118.062792 -273.792065) (xy 118.110324 -273.776621)
			(xy 118.159687 -273.768802) (xy 118.209665 -273.768802) (xy 118.259028 -273.776621) (xy 118.30656 -273.792065)
			(xy 118.351092 -273.814755) (xy 118.391525 -273.844131) (xy 118.426865 -273.879471) (xy 118.456241 -273.919904)
			(xy 118.478931 -273.964436) (xy 118.494375 -274.011968) (xy 118.502194 -274.061331) (xy 118.502684 -274.08632)
			(xy 118.502194 -274.111309) (xy 118.807212 -274.111309) (xy 118.807212 -274.061331) (xy 118.815031 -274.011968)
			(xy 118.830475 -273.964436) (xy 118.853165 -273.919904) (xy 118.882541 -273.879471) (xy 118.917881 -273.844131)
			(xy 118.958314 -273.814755) (xy 119.002846 -273.792065) (xy 119.050378 -273.776621) (xy 119.099741 -273.768802)
			(xy 119.149719 -273.768802) (xy 119.199082 -273.776621) (xy 119.246614 -273.792065) (xy 119.291146 -273.814755)
			(xy 119.331579 -273.844131) (xy 119.366919 -273.879471) (xy 119.396295 -273.919904) (xy 119.418985 -273.964436)
			(xy 119.434429 -274.011968) (xy 119.442248 -274.061331) (xy 119.442738 -274.08632) (xy 119.442248 -274.111309)
			(xy 119.747266 -274.111309) (xy 119.747266 -274.061331) (xy 119.755085 -274.011968) (xy 119.770529 -273.964436)
			(xy 119.793219 -273.919904) (xy 119.822595 -273.879471) (xy 119.857935 -273.844131) (xy 119.898368 -273.814755)
			(xy 119.9429 -273.792065) (xy 119.990432 -273.776621) (xy 120.039795 -273.768802) (xy 120.089773 -273.768802)
			(xy 120.139136 -273.776621) (xy 120.186668 -273.792065) (xy 120.2312 -273.814755) (xy 120.271633 -273.844131)
			(xy 120.306973 -273.879471) (xy 120.336349 -273.919904) (xy 120.359039 -273.964436) (xy 120.374483 -274.011968)
			(xy 120.382302 -274.061331) (xy 120.382792 -274.08632) (xy 120.382302 -274.111309) (xy 120.68732 -274.111309)
			(xy 120.68732 -274.061331) (xy 120.695139 -274.011968) (xy 120.710583 -273.964436) (xy 120.733273 -273.919904)
			(xy 120.762649 -273.879471) (xy 120.797989 -273.844131) (xy 120.838422 -273.814755) (xy 120.882954 -273.792065)
			(xy 120.930486 -273.776621) (xy 120.979849 -273.768802) (xy 121.029827 -273.768802) (xy 121.07919 -273.776621)
			(xy 121.126722 -273.792065) (xy 121.171254 -273.814755) (xy 121.211687 -273.844131) (xy 121.247027 -273.879471)
			(xy 121.276403 -273.919904) (xy 121.299093 -273.964436) (xy 121.314537 -274.011968) (xy 121.322356 -274.061331)
			(xy 121.322846 -274.08632) (xy 121.322356 -274.111309) (xy 121.62712 -274.111309) (xy 121.62712 -274.061331)
			(xy 121.634939 -274.011968) (xy 121.650383 -273.964436) (xy 121.673073 -273.919904) (xy 121.702449 -273.879471)
			(xy 121.737789 -273.844131) (xy 121.778222 -273.814755) (xy 121.822754 -273.792065) (xy 121.870286 -273.776621)
			(xy 121.919649 -273.768802) (xy 121.969627 -273.768802) (xy 122.01899 -273.776621) (xy 122.066522 -273.792065)
			(xy 122.111054 -273.814755) (xy 122.151487 -273.844131) (xy 122.186827 -273.879471) (xy 122.216203 -273.919904)
			(xy 122.238893 -273.964436) (xy 122.254337 -274.011968) (xy 122.262156 -274.061331) (xy 122.262646 -274.08632)
			(xy 122.262156 -274.111309) (xy 122.567174 -274.111309) (xy 122.567174 -274.061331) (xy 122.574993 -274.011968)
			(xy 122.590437 -273.964436) (xy 122.613127 -273.919904) (xy 122.642503 -273.879471) (xy 122.677843 -273.844131)
			(xy 122.718276 -273.814755) (xy 122.762808 -273.792065) (xy 122.81034 -273.776621) (xy 122.859703 -273.768802)
			(xy 122.909681 -273.768802) (xy 122.959044 -273.776621) (xy 123.006576 -273.792065) (xy 123.051108 -273.814755)
			(xy 123.091541 -273.844131) (xy 123.126881 -273.879471) (xy 123.156257 -273.919904) (xy 123.178947 -273.964436)
			(xy 123.194391 -274.011968) (xy 123.20221 -274.061331) (xy 123.2027 -274.08632) (xy 123.20221 -274.111309)
			(xy 123.507228 -274.111309) (xy 123.507228 -274.061331) (xy 123.515047 -274.011968) (xy 123.530491 -273.964436)
			(xy 123.553181 -273.919904) (xy 123.582557 -273.879471) (xy 123.617897 -273.844131) (xy 123.65833 -273.814755)
			(xy 123.702862 -273.792065) (xy 123.750394 -273.776621) (xy 123.799757 -273.768802) (xy 123.849735 -273.768802)
			(xy 123.899098 -273.776621) (xy 123.94663 -273.792065) (xy 123.991162 -273.814755) (xy 124.031595 -273.844131)
			(xy 124.066935 -273.879471) (xy 124.096311 -273.919904) (xy 124.119001 -273.964436) (xy 124.134445 -274.011968)
			(xy 124.142264 -274.061331) (xy 124.142754 -274.08632) (xy 124.142264 -274.111309) (xy 124.447282 -274.111309)
			(xy 124.447282 -274.061331) (xy 124.455101 -274.011968) (xy 124.470545 -273.964436) (xy 124.493235 -273.919904)
			(xy 124.522611 -273.879471) (xy 124.557951 -273.844131) (xy 124.598384 -273.814755) (xy 124.642916 -273.792065)
			(xy 124.690448 -273.776621) (xy 124.739811 -273.768802) (xy 124.789789 -273.768802) (xy 124.839152 -273.776621)
			(xy 124.886684 -273.792065) (xy 124.931216 -273.814755) (xy 124.971649 -273.844131) (xy 125.006989 -273.879471)
			(xy 125.036365 -273.919904) (xy 125.059055 -273.964436) (xy 125.074499 -274.011968) (xy 125.082318 -274.061331)
			(xy 125.082808 -274.08632) (xy 125.082318 -274.111309) (xy 125.387336 -274.111309) (xy 125.387336 -274.061331)
			(xy 125.395155 -274.011968) (xy 125.410599 -273.964436) (xy 125.433289 -273.919904) (xy 125.462665 -273.879471)
			(xy 125.498005 -273.844131) (xy 125.538438 -273.814755) (xy 125.58297 -273.792065) (xy 125.630502 -273.776621)
			(xy 125.679865 -273.768802) (xy 125.729843 -273.768802) (xy 125.779206 -273.776621) (xy 125.826738 -273.792065)
			(xy 125.87127 -273.814755) (xy 125.911703 -273.844131) (xy 125.947043 -273.879471) (xy 125.976419 -273.919904)
			(xy 125.999109 -273.964436) (xy 126.014553 -274.011968) (xy 126.022372 -274.061331) (xy 126.022862 -274.08632)
			(xy 126.022372 -274.111309) (xy 126.014553 -274.160672) (xy 125.999109 -274.208204) (xy 125.976419 -274.252736)
			(xy 125.947043 -274.293169) (xy 125.911703 -274.328509) (xy 125.87127 -274.357885) (xy 125.826738 -274.380575)
			(xy 125.779206 -274.396019) (xy 125.729843 -274.403838) (xy 125.679865 -274.403838) (xy 125.630502 -274.396019)
			(xy 125.58297 -274.380575) (xy 125.538438 -274.357885) (xy 125.498005 -274.328509) (xy 125.462665 -274.293169)
			(xy 125.433289 -274.252736) (xy 125.410599 -274.208204) (xy 125.395155 -274.160672) (xy 125.387336 -274.111309)
			(xy 125.082318 -274.111309) (xy 125.074499 -274.160672) (xy 125.059055 -274.208204) (xy 125.036365 -274.252736)
			(xy 125.006989 -274.293169) (xy 124.971649 -274.328509) (xy 124.931216 -274.357885) (xy 124.886684 -274.380575)
			(xy 124.839152 -274.396019) (xy 124.789789 -274.403838) (xy 124.739811 -274.403838) (xy 124.690448 -274.396019)
			(xy 124.642916 -274.380575) (xy 124.598384 -274.357885) (xy 124.557951 -274.328509) (xy 124.522611 -274.293169)
			(xy 124.493235 -274.252736) (xy 124.470545 -274.208204) (xy 124.455101 -274.160672) (xy 124.447282 -274.111309)
			(xy 124.142264 -274.111309) (xy 124.134445 -274.160672) (xy 124.119001 -274.208204) (xy 124.096311 -274.252736)
			(xy 124.066935 -274.293169) (xy 124.031595 -274.328509) (xy 123.991162 -274.357885) (xy 123.94663 -274.380575)
			(xy 123.899098 -274.396019) (xy 123.849735 -274.403838) (xy 123.799757 -274.403838) (xy 123.750394 -274.396019)
			(xy 123.702862 -274.380575) (xy 123.65833 -274.357885) (xy 123.617897 -274.328509) (xy 123.582557 -274.293169)
			(xy 123.553181 -274.252736) (xy 123.530491 -274.208204) (xy 123.515047 -274.160672) (xy 123.507228 -274.111309)
			(xy 123.20221 -274.111309) (xy 123.194391 -274.160672) (xy 123.178947 -274.208204) (xy 123.156257 -274.252736)
			(xy 123.126881 -274.293169) (xy 123.091541 -274.328509) (xy 123.051108 -274.357885) (xy 123.006576 -274.380575)
			(xy 122.959044 -274.396019) (xy 122.909681 -274.403838) (xy 122.859703 -274.403838) (xy 122.81034 -274.396019)
			(xy 122.762808 -274.380575) (xy 122.718276 -274.357885) (xy 122.677843 -274.328509) (xy 122.642503 -274.293169)
			(xy 122.613127 -274.252736) (xy 122.590437 -274.208204) (xy 122.574993 -274.160672) (xy 122.567174 -274.111309)
			(xy 122.262156 -274.111309) (xy 122.254337 -274.160672) (xy 122.238893 -274.208204) (xy 122.216203 -274.252736)
			(xy 122.186827 -274.293169) (xy 122.151487 -274.328509) (xy 122.111054 -274.357885) (xy 122.066522 -274.380575)
			(xy 122.01899 -274.396019) (xy 121.969627 -274.403838) (xy 121.919649 -274.403838) (xy 121.870286 -274.396019)
			(xy 121.822754 -274.380575) (xy 121.778222 -274.357885) (xy 121.737789 -274.328509) (xy 121.702449 -274.293169)
			(xy 121.673073 -274.252736) (xy 121.650383 -274.208204) (xy 121.634939 -274.160672) (xy 121.62712 -274.111309)
			(xy 121.322356 -274.111309) (xy 121.314537 -274.160672) (xy 121.299093 -274.208204) (xy 121.276403 -274.252736)
			(xy 121.247027 -274.293169) (xy 121.211687 -274.328509) (xy 121.171254 -274.357885) (xy 121.126722 -274.380575)
			(xy 121.07919 -274.396019) (xy 121.029827 -274.403838) (xy 120.979849 -274.403838) (xy 120.930486 -274.396019)
			(xy 120.882954 -274.380575) (xy 120.838422 -274.357885) (xy 120.797989 -274.328509) (xy 120.762649 -274.293169)
			(xy 120.733273 -274.252736) (xy 120.710583 -274.208204) (xy 120.695139 -274.160672) (xy 120.68732 -274.111309)
			(xy 120.382302 -274.111309) (xy 120.374483 -274.160672) (xy 120.359039 -274.208204) (xy 120.336349 -274.252736)
			(xy 120.306973 -274.293169) (xy 120.271633 -274.328509) (xy 120.2312 -274.357885) (xy 120.186668 -274.380575)
			(xy 120.139136 -274.396019) (xy 120.089773 -274.403838) (xy 120.039795 -274.403838) (xy 119.990432 -274.396019)
			(xy 119.9429 -274.380575) (xy 119.898368 -274.357885) (xy 119.857935 -274.328509) (xy 119.822595 -274.293169)
			(xy 119.793219 -274.252736) (xy 119.770529 -274.208204) (xy 119.755085 -274.160672) (xy 119.747266 -274.111309)
			(xy 119.442248 -274.111309) (xy 119.434429 -274.160672) (xy 119.418985 -274.208204) (xy 119.396295 -274.252736)
			(xy 119.366919 -274.293169) (xy 119.331579 -274.328509) (xy 119.291146 -274.357885) (xy 119.246614 -274.380575)
			(xy 119.199082 -274.396019) (xy 119.149719 -274.403838) (xy 119.099741 -274.403838) (xy 119.050378 -274.396019)
			(xy 119.002846 -274.380575) (xy 118.958314 -274.357885) (xy 118.917881 -274.328509) (xy 118.882541 -274.293169)
			(xy 118.853165 -274.252736) (xy 118.830475 -274.208204) (xy 118.815031 -274.160672) (xy 118.807212 -274.111309)
			(xy 118.502194 -274.111309) (xy 118.494375 -274.160672) (xy 118.478931 -274.208204) (xy 118.456241 -274.252736)
			(xy 118.426865 -274.293169) (xy 118.391525 -274.328509) (xy 118.351092 -274.357885) (xy 118.30656 -274.380575)
			(xy 118.259028 -274.396019) (xy 118.209665 -274.403838) (xy 118.159687 -274.403838) (xy 118.110324 -274.396019)
			(xy 118.062792 -274.380575) (xy 118.01826 -274.357885) (xy 117.977827 -274.328509) (xy 117.942487 -274.293169)
			(xy 117.913111 -274.252736) (xy 117.890421 -274.208204) (xy 117.874977 -274.160672) (xy 117.867158 -274.111309)
			(xy 117.56214 -274.111309) (xy 117.554321 -274.160672) (xy 117.538877 -274.208204) (xy 117.516187 -274.252736)
			(xy 117.486811 -274.293169) (xy 117.451471 -274.328509) (xy 117.411038 -274.357885) (xy 117.366506 -274.380575)
			(xy 117.318974 -274.396019) (xy 117.269611 -274.403838) (xy 117.219633 -274.403838) (xy 117.17027 -274.396019)
			(xy 117.122738 -274.380575) (xy 117.078206 -274.357885) (xy 117.037773 -274.328509) (xy 117.002433 -274.293169)
			(xy 116.973057 -274.252736) (xy 116.950367 -274.208204) (xy 116.934923 -274.160672) (xy 116.927104 -274.111309)
			(xy 116.62234 -274.111309) (xy 116.614521 -274.160672) (xy 116.599077 -274.208204) (xy 116.576387 -274.252736)
			(xy 116.547011 -274.293169) (xy 116.511671 -274.328509) (xy 116.471238 -274.357885) (xy 116.426706 -274.380575)
			(xy 116.379174 -274.396019) (xy 116.329811 -274.403838) (xy 116.279833 -274.403838) (xy 116.23047 -274.396019)
			(xy 116.182938 -274.380575) (xy 116.138406 -274.357885) (xy 116.097973 -274.328509) (xy 116.062633 -274.293169)
			(xy 116.033257 -274.252736) (xy 116.010567 -274.208204) (xy 115.995123 -274.160672) (xy 115.987304 -274.111309)
			(xy 115.679987 -274.111309) (xy 115.679978 -274.111766) (xy 115.671814 -274.162) (xy 115.655698 -274.210274)
			(xy 115.632047 -274.255337) (xy 115.601474 -274.296023) (xy 115.56477 -274.331278) (xy 115.522886 -274.360188)
			(xy 115.476907 -274.382005) (xy 115.428023 -274.396165) (xy 115.377502 -274.402299) (xy 115.32665 -274.40025)
			(xy 115.276786 -274.39007) (xy 115.2292 -274.372023) (xy 115.185126 -274.346577) (xy 115.145704 -274.31439)
			(xy 115.111956 -274.276296) (xy 115.084755 -274.233282) (xy 115.064807 -274.186462) (xy 115.052628 -274.137048)
			(xy 115.048533 -274.08632) (xy 114.740436 -274.08632) (xy 114.739924 -274.111766) (xy 114.73176 -274.162)
			(xy 114.715644 -274.210274) (xy 114.691993 -274.255337) (xy 114.66142 -274.296023) (xy 114.624716 -274.331278)
			(xy 114.582832 -274.360188) (xy 114.536853 -274.382005) (xy 114.487969 -274.396165) (xy 114.437448 -274.402299)
			(xy 114.386596 -274.40025) (xy 114.336732 -274.39007) (xy 114.289146 -274.372023) (xy 114.245072 -274.346577)
			(xy 114.20565 -274.31439) (xy 114.171902 -274.276296) (xy 114.144701 -274.233282) (xy 114.124753 -274.186462)
			(xy 114.112574 -274.137048) (xy 114.108479 -274.08632) (xy 113.802668 -274.08632) (xy 113.802178 -274.111309)
			(xy 113.794359 -274.160672) (xy 113.778915 -274.208204) (xy 113.756225 -274.252736) (xy 113.726849 -274.293169)
			(xy 113.691509 -274.328509) (xy 113.651076 -274.357885) (xy 113.606544 -274.380575) (xy 113.559012 -274.396019)
			(xy 113.509649 -274.403838) (xy 113.459671 -274.403838) (xy 113.410308 -274.396019) (xy 113.362776 -274.380575)
			(xy 113.318244 -274.357885) (xy 113.277811 -274.328509) (xy 113.242471 -274.293169) (xy 113.213095 -274.252736)
			(xy 113.190405 -274.208204) (xy 113.174961 -274.160672) (xy 113.167142 -274.111309) (xy 110.98862 -274.111309)
			(xy 110.980801 -274.160672) (xy 110.965357 -274.208204) (xy 110.942667 -274.252736) (xy 110.913291 -274.293169)
			(xy 110.877951 -274.328509) (xy 110.837518 -274.357885) (xy 110.792986 -274.380575) (xy 110.745454 -274.396019)
			(xy 110.696091 -274.403838) (xy 110.646113 -274.403838) (xy 110.59675 -274.396019) (xy 110.549218 -274.380575)
			(xy 110.504686 -274.357885) (xy 110.464253 -274.328509) (xy 110.428913 -274.293169) (xy 110.399537 -274.252736)
			(xy 110.376847 -274.208204) (xy 110.361403 -274.160672) (xy 110.353584 -274.111309) (xy 110.046267 -274.111309)
			(xy 110.046258 -274.111766) (xy 110.038094 -274.162) (xy 110.021978 -274.210274) (xy 109.998327 -274.255337)
			(xy 109.967754 -274.296023) (xy 109.93105 -274.331278) (xy 109.889166 -274.360188) (xy 109.843187 -274.382005)
			(xy 109.794303 -274.396165) (xy 109.743782 -274.402299) (xy 109.69293 -274.40025) (xy 109.643066 -274.39007)
			(xy 109.59548 -274.372023) (xy 109.551406 -274.346577) (xy 109.511984 -274.31439) (xy 109.478236 -274.276296)
			(xy 109.451035 -274.233282) (xy 109.431087 -274.186462) (xy 109.418908 -274.137048) (xy 109.414813 -274.08632)
			(xy 109.106716 -274.08632) (xy 109.106204 -274.111766) (xy 109.09804 -274.162) (xy 109.081924 -274.210274)
			(xy 109.058273 -274.255337) (xy 109.0277 -274.296023) (xy 108.990996 -274.331278) (xy 108.949112 -274.360188)
			(xy 108.903133 -274.382005) (xy 108.854249 -274.396165) (xy 108.803728 -274.402299) (xy 108.752876 -274.40025)
			(xy 108.703012 -274.39007) (xy 108.655426 -274.372023) (xy 108.611352 -274.346577) (xy 108.57193 -274.31439)
			(xy 108.538182 -274.276296) (xy 108.510981 -274.233282) (xy 108.491033 -274.186462) (xy 108.478854 -274.137048)
			(xy 108.474759 -274.08632) (xy 108.168948 -274.08632) (xy 108.168458 -274.111309) (xy 108.160639 -274.160672)
			(xy 108.145195 -274.208204) (xy 108.122505 -274.252736) (xy 108.093129 -274.293169) (xy 108.057789 -274.328509)
			(xy 108.017356 -274.357885) (xy 107.972824 -274.380575) (xy 107.925292 -274.396019) (xy 107.875929 -274.403838)
			(xy 107.825951 -274.403838) (xy 107.776588 -274.396019) (xy 107.729056 -274.380575) (xy 107.684524 -274.357885)
			(xy 107.644091 -274.328509) (xy 107.608751 -274.293169) (xy 107.579375 -274.252736) (xy 107.556685 -274.208204)
			(xy 107.541241 -274.160672) (xy 107.533422 -274.111309) (xy 107.228658 -274.111309) (xy 107.220839 -274.160672)
			(xy 107.205395 -274.208204) (xy 107.182705 -274.252736) (xy 107.153329 -274.293169) (xy 107.117989 -274.328509)
			(xy 107.077556 -274.357885) (xy 107.033024 -274.380575) (xy 106.985492 -274.396019) (xy 106.936129 -274.403838)
			(xy 106.886151 -274.403838) (xy 106.836788 -274.396019) (xy 106.789256 -274.380575) (xy 106.744724 -274.357885)
			(xy 106.704291 -274.328509) (xy 106.668951 -274.293169) (xy 106.639575 -274.252736) (xy 106.616885 -274.208204)
			(xy 106.601441 -274.160672) (xy 106.593622 -274.111309) (xy 106.288604 -274.111309) (xy 106.280785 -274.160672)
			(xy 106.265341 -274.208204) (xy 106.242651 -274.252736) (xy 106.213275 -274.293169) (xy 106.177935 -274.328509)
			(xy 106.137502 -274.357885) (xy 106.09297 -274.380575) (xy 106.045438 -274.396019) (xy 105.996075 -274.403838)
			(xy 105.946097 -274.403838) (xy 105.896734 -274.396019) (xy 105.849202 -274.380575) (xy 105.80467 -274.357885)
			(xy 105.764237 -274.328509) (xy 105.728897 -274.293169) (xy 105.699521 -274.252736) (xy 105.676831 -274.208204)
			(xy 105.661387 -274.160672) (xy 105.653568 -274.111309) (xy 105.34855 -274.111309) (xy 105.340731 -274.160672)
			(xy 105.325287 -274.208204) (xy 105.302597 -274.252736) (xy 105.273221 -274.293169) (xy 105.237881 -274.328509)
			(xy 105.197448 -274.357885) (xy 105.152916 -274.380575) (xy 105.105384 -274.396019) (xy 105.056021 -274.403838)
			(xy 105.006043 -274.403838) (xy 104.95668 -274.396019) (xy 104.909148 -274.380575) (xy 104.864616 -274.357885)
			(xy 104.824183 -274.328509) (xy 104.788843 -274.293169) (xy 104.759467 -274.252736) (xy 104.736777 -274.208204)
			(xy 104.721333 -274.160672) (xy 104.713514 -274.111309) (xy 104.408496 -274.111309) (xy 104.400677 -274.160672)
			(xy 104.385233 -274.208204) (xy 104.362543 -274.252736) (xy 104.333167 -274.293169) (xy 104.297827 -274.328509)
			(xy 104.257394 -274.357885) (xy 104.212862 -274.380575) (xy 104.16533 -274.396019) (xy 104.115967 -274.403838)
			(xy 104.065989 -274.403838) (xy 104.016626 -274.396019) (xy 103.969094 -274.380575) (xy 103.924562 -274.357885)
			(xy 103.884129 -274.328509) (xy 103.848789 -274.293169) (xy 103.819413 -274.252736) (xy 103.796723 -274.208204)
			(xy 103.781279 -274.160672) (xy 103.77346 -274.111309) (xy 103.468696 -274.111309) (xy 103.460877 -274.160672)
			(xy 103.445433 -274.208204) (xy 103.422743 -274.252736) (xy 103.393367 -274.293169) (xy 103.358027 -274.328509)
			(xy 103.317594 -274.357885) (xy 103.273062 -274.380575) (xy 103.22553 -274.396019) (xy 103.176167 -274.403838)
			(xy 103.126189 -274.403838) (xy 103.076826 -274.396019) (xy 103.029294 -274.380575) (xy 102.984762 -274.357885)
			(xy 102.944329 -274.328509) (xy 102.908989 -274.293169) (xy 102.879613 -274.252736) (xy 102.856923 -274.208204)
			(xy 102.841479 -274.160672) (xy 102.83366 -274.111309) (xy 102.528642 -274.111309) (xy 102.520823 -274.160672)
			(xy 102.505379 -274.208204) (xy 102.482689 -274.252736) (xy 102.453313 -274.293169) (xy 102.417973 -274.328509)
			(xy 102.37754 -274.357885) (xy 102.333008 -274.380575) (xy 102.285476 -274.396019) (xy 102.236113 -274.403838)
			(xy 102.186135 -274.403838) (xy 102.136772 -274.396019) (xy 102.08924 -274.380575) (xy 102.044708 -274.357885)
			(xy 102.004275 -274.328509) (xy 101.968935 -274.293169) (xy 101.939559 -274.252736) (xy 101.916869 -274.208204)
			(xy 101.901425 -274.160672) (xy 101.893606 -274.111309) (xy 101.588588 -274.111309) (xy 101.580769 -274.160672)
			(xy 101.565325 -274.208204) (xy 101.542635 -274.252736) (xy 101.513259 -274.293169) (xy 101.477919 -274.328509)
			(xy 101.437486 -274.357885) (xy 101.392954 -274.380575) (xy 101.345422 -274.396019) (xy 101.296059 -274.403838)
			(xy 101.246081 -274.403838) (xy 101.196718 -274.396019) (xy 101.149186 -274.380575) (xy 101.104654 -274.357885)
			(xy 101.064221 -274.328509) (xy 101.028881 -274.293169) (xy 100.999505 -274.252736) (xy 100.976815 -274.208204)
			(xy 100.961371 -274.160672) (xy 100.953552 -274.111309) (xy 100.648534 -274.111309) (xy 100.640715 -274.160672)
			(xy 100.625271 -274.208204) (xy 100.602581 -274.252736) (xy 100.573205 -274.293169) (xy 100.537865 -274.328509)
			(xy 100.497432 -274.357885) (xy 100.4529 -274.380575) (xy 100.405368 -274.396019) (xy 100.356005 -274.403838)
			(xy 100.306027 -274.403838) (xy 100.256664 -274.396019) (xy 100.209132 -274.380575) (xy 100.1646 -274.357885)
			(xy 100.124167 -274.328509) (xy 100.088827 -274.293169) (xy 100.059451 -274.252736) (xy 100.036761 -274.208204)
			(xy 100.021317 -274.160672) (xy 100.013498 -274.111309) (xy 99.70848 -274.111309) (xy 99.700661 -274.160672)
			(xy 99.685217 -274.208204) (xy 99.662527 -274.252736) (xy 99.633151 -274.293169) (xy 99.597811 -274.328509)
			(xy 99.557378 -274.357885) (xy 99.512846 -274.380575) (xy 99.465314 -274.396019) (xy 99.415951 -274.403838)
			(xy 99.365973 -274.403838) (xy 99.31661 -274.396019) (xy 99.269078 -274.380575) (xy 99.224546 -274.357885)
			(xy 99.184113 -274.328509) (xy 99.148773 -274.293169) (xy 99.119397 -274.252736) (xy 99.096707 -274.208204)
			(xy 99.081263 -274.160672) (xy 99.073444 -274.111309) (xy 98.76868 -274.111309) (xy 98.760861 -274.160672)
			(xy 98.745417 -274.208204) (xy 98.722727 -274.252736) (xy 98.693351 -274.293169) (xy 98.658011 -274.328509)
			(xy 98.617578 -274.357885) (xy 98.573046 -274.380575) (xy 98.525514 -274.396019) (xy 98.476151 -274.403838)
			(xy 98.426173 -274.403838) (xy 98.37681 -274.396019) (xy 98.329278 -274.380575) (xy 98.284746 -274.357885)
			(xy 98.244313 -274.328509) (xy 98.208973 -274.293169) (xy 98.179597 -274.252736) (xy 98.156907 -274.208204)
			(xy 98.141463 -274.160672) (xy 98.133644 -274.111309) (xy 97.828626 -274.111309) (xy 97.820807 -274.160672)
			(xy 97.805363 -274.208204) (xy 97.782673 -274.252736) (xy 97.753297 -274.293169) (xy 97.717957 -274.328509)
			(xy 97.677524 -274.357885) (xy 97.632992 -274.380575) (xy 97.58546 -274.396019) (xy 97.536097 -274.403838)
			(xy 97.486119 -274.403838) (xy 97.436756 -274.396019) (xy 97.389224 -274.380575) (xy 97.344692 -274.357885)
			(xy 97.304259 -274.328509) (xy 97.268919 -274.293169) (xy 97.239543 -274.252736) (xy 97.216853 -274.208204)
			(xy 97.201409 -274.160672) (xy 97.19359 -274.111309) (xy 96.888333 -274.111309) (xy 96.888072 -274.117815)
			(xy 96.879424 -274.166355) (xy 96.863386 -274.212978) (xy 96.840344 -274.256567) (xy 96.810848 -274.296076)
			(xy 96.775607 -274.330557) (xy 96.735465 -274.359186) (xy 96.691385 -274.381274) (xy 96.644423 -274.396292)
			(xy 96.595706 -274.403881) (xy 96.571054 -274.404328) (xy 96.547457 -274.403902) (xy 96.50078 -274.396933)
			(xy 96.455645 -274.383141) (xy 96.413046 -274.362828) (xy 96.393254 -274.349972) (xy 96.39173 -274.348956)
			(xy 96.388174 -274.346924) (xy 96.378285 -274.341921) (xy 96.356227 -274.340048) (xy 96.335421 -274.347608)
			(xy 96.327214 -274.355052) (xy 96.226376 -274.45589) (xy 96.218459 -274.464735) (xy 96.211038 -274.487252)
			(xy 96.212152 -274.49907) (xy 96.214184 -274.512786) (xy 96.225868 -274.590002) (xy 96.239838 -274.609814)
			(xy 96.250506 -274.615402) (xy 96.272002 -274.62737) (xy 96.311348 -274.656903) (xy 96.345681 -274.69214)
			(xy 96.374182 -274.73224) (xy 96.396174 -274.776248) (xy 96.411131 -274.823116) (xy 96.418697 -274.871727)
			(xy 96.419162 -274.896326) (xy 96.418695 -274.921315) (xy 96.723436 -274.921315) (xy 96.723436 -274.871337)
			(xy 96.731255 -274.821974) (xy 96.746699 -274.774442) (xy 96.769389 -274.72991) (xy 96.798765 -274.689477)
			(xy 96.834105 -274.654137) (xy 96.874538 -274.624761) (xy 96.91907 -274.602071) (xy 96.966602 -274.586627)
			(xy 97.015965 -274.578808) (xy 97.065943 -274.578808) (xy 97.115306 -274.586627) (xy 97.162838 -274.602071)
			(xy 97.20737 -274.624761) (xy 97.247803 -274.654137) (xy 97.283143 -274.689477) (xy 97.312519 -274.72991)
			(xy 97.335209 -274.774442) (xy 97.350653 -274.821974) (xy 97.358472 -274.871337) (xy 97.358962 -274.896326)
			(xy 97.664773 -274.896326) (xy 97.668868 -274.845598) (xy 97.681047 -274.796184) (xy 97.700995 -274.749364)
			(xy 97.728196 -274.70635) (xy 97.761944 -274.668256) (xy 97.801366 -274.636069) (xy 97.84544 -274.610623)
			(xy 97.893026 -274.592576) (xy 97.94289 -274.582396) (xy 97.993742 -274.580347) (xy 98.044263 -274.586481)
			(xy 98.093147 -274.600641) (xy 98.139126 -274.622458) (xy 98.18101 -274.651368) (xy 98.217714 -274.686623)
			(xy 98.248287 -274.727309) (xy 98.271938 -274.772372) (xy 98.288054 -274.820646) (xy 98.296218 -274.87088)
			(xy 98.29673 -274.896326) (xy 98.604827 -274.896326) (xy 98.608922 -274.845598) (xy 98.621101 -274.796184)
			(xy 98.641049 -274.749364) (xy 98.66825 -274.70635) (xy 98.701998 -274.668256) (xy 98.74142 -274.636069)
			(xy 98.785494 -274.610623) (xy 98.83308 -274.592576) (xy 98.882944 -274.582396) (xy 98.933796 -274.580347)
			(xy 98.984317 -274.586481) (xy 99.033201 -274.600641) (xy 99.07918 -274.622458) (xy 99.121064 -274.651368)
			(xy 99.157768 -274.686623) (xy 99.188341 -274.727309) (xy 99.211992 -274.772372) (xy 99.228108 -274.820646)
			(xy 99.236272 -274.87088) (xy 99.236784 -274.896326) (xy 99.236281 -274.921315) (xy 99.543598 -274.921315)
			(xy 99.543598 -274.871337) (xy 99.551417 -274.821974) (xy 99.566861 -274.774442) (xy 99.589551 -274.72991)
			(xy 99.618927 -274.689477) (xy 99.654267 -274.654137) (xy 99.6947 -274.624761) (xy 99.739232 -274.602071)
			(xy 99.786764 -274.586627) (xy 99.836127 -274.578808) (xy 99.886105 -274.578808) (xy 99.935468 -274.586627)
			(xy 99.983 -274.602071) (xy 100.027532 -274.624761) (xy 100.067965 -274.654137) (xy 100.103305 -274.689477)
			(xy 100.132681 -274.72991) (xy 100.155371 -274.774442) (xy 100.170815 -274.821974) (xy 100.178634 -274.871337)
			(xy 100.179124 -274.896326) (xy 100.484935 -274.896326) (xy 100.48903 -274.845598) (xy 100.501209 -274.796184)
			(xy 100.521157 -274.749364) (xy 100.548358 -274.70635) (xy 100.582106 -274.668256) (xy 100.621528 -274.636069)
			(xy 100.665602 -274.610623) (xy 100.713188 -274.592576) (xy 100.763052 -274.582396) (xy 100.813904 -274.580347)
			(xy 100.864425 -274.586481) (xy 100.913309 -274.600641) (xy 100.959288 -274.622458) (xy 101.001172 -274.651368)
			(xy 101.037876 -274.686623) (xy 101.068449 -274.727309) (xy 101.0921 -274.772372) (xy 101.108216 -274.820646)
			(xy 101.11638 -274.87088) (xy 101.116892 -274.896326) (xy 101.424735 -274.896326) (xy 101.42883 -274.845598)
			(xy 101.441009 -274.796184) (xy 101.460957 -274.749364) (xy 101.488158 -274.70635) (xy 101.521906 -274.668256)
			(xy 101.561328 -274.636069) (xy 101.605402 -274.610623) (xy 101.652988 -274.592576) (xy 101.702852 -274.582396)
			(xy 101.753704 -274.580347) (xy 101.804225 -274.586481) (xy 101.853109 -274.600641) (xy 101.899088 -274.622458)
			(xy 101.940972 -274.651368) (xy 101.977676 -274.686623) (xy 102.008249 -274.727309) (xy 102.0319 -274.772372)
			(xy 102.048016 -274.820646) (xy 102.05618 -274.87088) (xy 102.056692 -274.896326) (xy 102.056189 -274.921315)
			(xy 102.363506 -274.921315) (xy 102.363506 -274.871337) (xy 102.371325 -274.821974) (xy 102.386769 -274.774442)
			(xy 102.409459 -274.72991) (xy 102.438835 -274.689477) (xy 102.474175 -274.654137) (xy 102.514608 -274.624761)
			(xy 102.55914 -274.602071) (xy 102.606672 -274.586627) (xy 102.656035 -274.578808) (xy 102.706013 -274.578808)
			(xy 102.755376 -274.586627) (xy 102.802908 -274.602071) (xy 102.84744 -274.624761) (xy 102.887873 -274.654137)
			(xy 102.923213 -274.689477) (xy 102.952589 -274.72991) (xy 102.975279 -274.774442) (xy 102.990723 -274.821974)
			(xy 102.998542 -274.871337) (xy 102.999032 -274.896326) (xy 103.304843 -274.896326) (xy 103.308938 -274.845598)
			(xy 103.321117 -274.796184) (xy 103.341065 -274.749364) (xy 103.368266 -274.70635) (xy 103.402014 -274.668256)
			(xy 103.441436 -274.636069) (xy 103.48551 -274.610623) (xy 103.533096 -274.592576) (xy 103.58296 -274.582396)
			(xy 103.633812 -274.580347) (xy 103.684333 -274.586481) (xy 103.733217 -274.600641) (xy 103.779196 -274.622458)
			(xy 103.82108 -274.651368) (xy 103.857784 -274.686623) (xy 103.888357 -274.727309) (xy 103.912008 -274.772372)
			(xy 103.928124 -274.820646) (xy 103.936288 -274.87088) (xy 103.9368 -274.896326) (xy 104.244897 -274.896326)
			(xy 104.248992 -274.845598) (xy 104.261171 -274.796184) (xy 104.281119 -274.749364) (xy 104.30832 -274.70635)
			(xy 104.342068 -274.668256) (xy 104.38149 -274.636069) (xy 104.425564 -274.610623) (xy 104.47315 -274.592576)
			(xy 104.523014 -274.582396) (xy 104.573866 -274.580347) (xy 104.624387 -274.586481) (xy 104.673271 -274.600641)
			(xy 104.71925 -274.622458) (xy 104.761134 -274.651368) (xy 104.797838 -274.686623) (xy 104.828411 -274.727309)
			(xy 104.852062 -274.772372) (xy 104.868178 -274.820646) (xy 104.876342 -274.87088) (xy 104.876854 -274.896326)
			(xy 104.876351 -274.921315) (xy 105.183414 -274.921315) (xy 105.183414 -274.871337) (xy 105.191233 -274.821974)
			(xy 105.206677 -274.774442) (xy 105.229367 -274.72991) (xy 105.258743 -274.689477) (xy 105.294083 -274.654137)
			(xy 105.334516 -274.624761) (xy 105.379048 -274.602071) (xy 105.42658 -274.586627) (xy 105.475943 -274.578808)
			(xy 105.525921 -274.578808) (xy 105.575284 -274.586627) (xy 105.622816 -274.602071) (xy 105.667348 -274.624761)
			(xy 105.707781 -274.654137) (xy 105.743121 -274.689477) (xy 105.772497 -274.72991) (xy 105.795187 -274.774442)
			(xy 105.810631 -274.821974) (xy 105.81845 -274.871337) (xy 105.81894 -274.896326) (xy 106.124751 -274.896326)
			(xy 106.128846 -274.845598) (xy 106.141025 -274.796184) (xy 106.160973 -274.749364) (xy 106.188174 -274.70635)
			(xy 106.221922 -274.668256) (xy 106.261344 -274.636069) (xy 106.305418 -274.610623) (xy 106.353004 -274.592576)
			(xy 106.402868 -274.582396) (xy 106.45372 -274.580347) (xy 106.504241 -274.586481) (xy 106.553125 -274.600641)
			(xy 106.599104 -274.622458) (xy 106.640988 -274.651368) (xy 106.677692 -274.686623) (xy 106.708265 -274.727309)
			(xy 106.731916 -274.772372) (xy 106.748032 -274.820646) (xy 106.756196 -274.87088) (xy 106.756708 -274.896326)
			(xy 107.064805 -274.896326) (xy 107.0689 -274.845598) (xy 107.081079 -274.796184) (xy 107.101027 -274.749364)
			(xy 107.128228 -274.70635) (xy 107.161976 -274.668256) (xy 107.201398 -274.636069) (xy 107.245472 -274.610623)
			(xy 107.293058 -274.592576) (xy 107.342922 -274.582396) (xy 107.393774 -274.580347) (xy 107.444295 -274.586481)
			(xy 107.493179 -274.600641) (xy 107.539158 -274.622458) (xy 107.581042 -274.651368) (xy 107.617746 -274.686623)
			(xy 107.648319 -274.727309) (xy 107.67197 -274.772372) (xy 107.688086 -274.820646) (xy 107.69625 -274.87088)
			(xy 107.696762 -274.896326) (xy 107.696259 -274.921315) (xy 108.003576 -274.921315) (xy 108.003576 -274.871337)
			(xy 108.011395 -274.821974) (xy 108.026839 -274.774442) (xy 108.049529 -274.72991) (xy 108.078905 -274.689477)
			(xy 108.114245 -274.654137) (xy 108.154678 -274.624761) (xy 108.19921 -274.602071) (xy 108.246742 -274.586627)
			(xy 108.296105 -274.578808) (xy 108.346083 -274.578808) (xy 108.395446 -274.586627) (xy 108.442978 -274.602071)
			(xy 108.48751 -274.624761) (xy 108.527943 -274.654137) (xy 108.563283 -274.689477) (xy 108.592659 -274.72991)
			(xy 108.615349 -274.774442) (xy 108.630793 -274.821974) (xy 108.638612 -274.871337) (xy 108.639102 -274.896326)
			(xy 108.638612 -274.921315) (xy 115.51715 -274.921315) (xy 115.51715 -274.871337) (xy 115.524969 -274.821974)
			(xy 115.540413 -274.774442) (xy 115.563103 -274.72991) (xy 115.592479 -274.689477) (xy 115.627819 -274.654137)
			(xy 115.668252 -274.624761) (xy 115.712784 -274.602071) (xy 115.760316 -274.586627) (xy 115.809679 -274.578808)
			(xy 115.859657 -274.578808) (xy 115.90902 -274.586627) (xy 115.956552 -274.602071) (xy 116.001084 -274.624761)
			(xy 116.041517 -274.654137) (xy 116.076857 -274.689477) (xy 116.106233 -274.72991) (xy 116.128923 -274.774442)
			(xy 116.144367 -274.821974) (xy 116.152186 -274.871337) (xy 116.152676 -274.896326) (xy 116.458487 -274.896326)
			(xy 116.462582 -274.845598) (xy 116.474761 -274.796184) (xy 116.494709 -274.749364) (xy 116.52191 -274.70635)
			(xy 116.555658 -274.668256) (xy 116.59508 -274.636069) (xy 116.639154 -274.610623) (xy 116.68674 -274.592576)
			(xy 116.736604 -274.582396) (xy 116.787456 -274.580347) (xy 116.837977 -274.586481) (xy 116.886861 -274.600641)
			(xy 116.93284 -274.622458) (xy 116.974724 -274.651368) (xy 117.011428 -274.686623) (xy 117.042001 -274.727309)
			(xy 117.065652 -274.772372) (xy 117.081768 -274.820646) (xy 117.089932 -274.87088) (xy 117.090444 -274.896326)
			(xy 117.398541 -274.896326) (xy 117.402636 -274.845598) (xy 117.414815 -274.796184) (xy 117.434763 -274.749364)
			(xy 117.461964 -274.70635) (xy 117.495712 -274.668256) (xy 117.535134 -274.636069) (xy 117.579208 -274.610623)
			(xy 117.626794 -274.592576) (xy 117.676658 -274.582396) (xy 117.72751 -274.580347) (xy 117.778031 -274.586481)
			(xy 117.826915 -274.600641) (xy 117.872894 -274.622458) (xy 117.914778 -274.651368) (xy 117.951482 -274.686623)
			(xy 117.982055 -274.727309) (xy 118.005706 -274.772372) (xy 118.021822 -274.820646) (xy 118.029986 -274.87088)
			(xy 118.030498 -274.896326) (xy 118.029995 -274.921315) (xy 118.337312 -274.921315) (xy 118.337312 -274.871337)
			(xy 118.345131 -274.821974) (xy 118.360575 -274.774442) (xy 118.383265 -274.72991) (xy 118.412641 -274.689477)
			(xy 118.447981 -274.654137) (xy 118.488414 -274.624761) (xy 118.532946 -274.602071) (xy 118.580478 -274.586627)
			(xy 118.629841 -274.578808) (xy 118.679819 -274.578808) (xy 118.729182 -274.586627) (xy 118.776714 -274.602071)
			(xy 118.821246 -274.624761) (xy 118.861679 -274.654137) (xy 118.897019 -274.689477) (xy 118.926395 -274.72991)
			(xy 118.949085 -274.774442) (xy 118.964529 -274.821974) (xy 118.972348 -274.871337) (xy 118.972838 -274.896326)
			(xy 119.278395 -274.896326) (xy 119.28249 -274.845598) (xy 119.294669 -274.796184) (xy 119.314617 -274.749364)
			(xy 119.341818 -274.70635) (xy 119.375566 -274.668256) (xy 119.414988 -274.636069) (xy 119.459062 -274.610623)
			(xy 119.506648 -274.592576) (xy 119.556512 -274.582396) (xy 119.607364 -274.580347) (xy 119.657885 -274.586481)
			(xy 119.706769 -274.600641) (xy 119.752748 -274.622458) (xy 119.794632 -274.651368) (xy 119.831336 -274.686623)
			(xy 119.861909 -274.727309) (xy 119.88556 -274.772372) (xy 119.901676 -274.820646) (xy 119.90984 -274.87088)
			(xy 119.910352 -274.896326) (xy 120.218449 -274.896326) (xy 120.222544 -274.845598) (xy 120.234723 -274.796184)
			(xy 120.254671 -274.749364) (xy 120.281872 -274.70635) (xy 120.31562 -274.668256) (xy 120.355042 -274.636069)
			(xy 120.399116 -274.610623) (xy 120.446702 -274.592576) (xy 120.496566 -274.582396) (xy 120.547418 -274.580347)
			(xy 120.597939 -274.586481) (xy 120.646823 -274.600641) (xy 120.692802 -274.622458) (xy 120.734686 -274.651368)
			(xy 120.77139 -274.686623) (xy 120.801963 -274.727309) (xy 120.825614 -274.772372) (xy 120.84173 -274.820646)
			(xy 120.849894 -274.87088) (xy 120.850406 -274.896326) (xy 120.849903 -274.921315) (xy 121.15722 -274.921315)
			(xy 121.15722 -274.871337) (xy 121.165039 -274.821974) (xy 121.180483 -274.774442) (xy 121.203173 -274.72991)
			(xy 121.232549 -274.689477) (xy 121.267889 -274.654137) (xy 121.308322 -274.624761) (xy 121.352854 -274.602071)
			(xy 121.400386 -274.586627) (xy 121.449749 -274.578808) (xy 121.499727 -274.578808) (xy 121.54909 -274.586627)
			(xy 121.596622 -274.602071) (xy 121.641154 -274.624761) (xy 121.681587 -274.654137) (xy 121.716927 -274.689477)
			(xy 121.746303 -274.72991) (xy 121.768993 -274.774442) (xy 121.784437 -274.821974) (xy 121.792256 -274.871337)
			(xy 121.792746 -274.896326) (xy 122.098557 -274.896326) (xy 122.102652 -274.845598) (xy 122.114831 -274.796184)
			(xy 122.134779 -274.749364) (xy 122.16198 -274.70635) (xy 122.195728 -274.668256) (xy 122.23515 -274.636069)
			(xy 122.279224 -274.610623) (xy 122.32681 -274.592576) (xy 122.376674 -274.582396) (xy 122.427526 -274.580347)
			(xy 122.478047 -274.586481) (xy 122.526931 -274.600641) (xy 122.57291 -274.622458) (xy 122.614794 -274.651368)
			(xy 122.651498 -274.686623) (xy 122.682071 -274.727309) (xy 122.705722 -274.772372) (xy 122.721838 -274.820646)
			(xy 122.730002 -274.87088) (xy 122.730514 -274.896326) (xy 123.038611 -274.896326) (xy 123.042706 -274.845598)
			(xy 123.054885 -274.796184) (xy 123.074833 -274.749364) (xy 123.102034 -274.70635) (xy 123.135782 -274.668256)
			(xy 123.175204 -274.636069) (xy 123.219278 -274.610623) (xy 123.266864 -274.592576) (xy 123.316728 -274.582396)
			(xy 123.36758 -274.580347) (xy 123.418101 -274.586481) (xy 123.466985 -274.600641) (xy 123.512964 -274.622458)
			(xy 123.554848 -274.651368) (xy 123.591552 -274.686623) (xy 123.622125 -274.727309) (xy 123.645776 -274.772372)
			(xy 123.661892 -274.820646) (xy 123.670056 -274.87088) (xy 123.670568 -274.896326) (xy 123.670065 -274.921315)
			(xy 123.977128 -274.921315) (xy 123.977128 -274.871337) (xy 123.984947 -274.821974) (xy 124.000391 -274.774442)
			(xy 124.023081 -274.72991) (xy 124.052457 -274.689477) (xy 124.087797 -274.654137) (xy 124.12823 -274.624761)
			(xy 124.172762 -274.602071) (xy 124.220294 -274.586627) (xy 124.269657 -274.578808) (xy 124.319635 -274.578808)
			(xy 124.368998 -274.586627) (xy 124.41653 -274.602071) (xy 124.461062 -274.624761) (xy 124.501495 -274.654137)
			(xy 124.536835 -274.689477) (xy 124.566211 -274.72991) (xy 124.588901 -274.774442) (xy 124.604345 -274.821974)
			(xy 124.612164 -274.871337) (xy 124.612654 -274.896326) (xy 124.918465 -274.896326) (xy 124.92256 -274.845598)
			(xy 124.934739 -274.796184) (xy 124.954687 -274.749364) (xy 124.981888 -274.70635) (xy 125.015636 -274.668256)
			(xy 125.055058 -274.636069) (xy 125.099132 -274.610623) (xy 125.146718 -274.592576) (xy 125.196582 -274.582396)
			(xy 125.247434 -274.580347) (xy 125.297955 -274.586481) (xy 125.346839 -274.600641) (xy 125.392818 -274.622458)
			(xy 125.434702 -274.651368) (xy 125.471406 -274.686623) (xy 125.501979 -274.727309) (xy 125.52563 -274.772372)
			(xy 125.541746 -274.820646) (xy 125.54991 -274.87088) (xy 125.550422 -274.896326) (xy 125.858519 -274.896326)
			(xy 125.862614 -274.845598) (xy 125.874793 -274.796184) (xy 125.894741 -274.749364) (xy 125.921942 -274.70635)
			(xy 125.95569 -274.668256) (xy 125.995112 -274.636069) (xy 126.039186 -274.610623) (xy 126.086772 -274.592576)
			(xy 126.136636 -274.582396) (xy 126.187488 -274.580347) (xy 126.238009 -274.586481) (xy 126.286893 -274.600641)
			(xy 126.332872 -274.622458) (xy 126.374756 -274.651368) (xy 126.41146 -274.686623) (xy 126.442033 -274.727309)
			(xy 126.465684 -274.772372) (xy 126.4818 -274.820646) (xy 126.489964 -274.87088) (xy 126.490476 -274.896326)
			(xy 126.489964 -274.921772) (xy 126.4818 -274.972006) (xy 126.465684 -275.02028) (xy 126.442033 -275.065343)
			(xy 126.41146 -275.106029) (xy 126.374756 -275.141284) (xy 126.332872 -275.170194) (xy 126.286893 -275.192011)
			(xy 126.238009 -275.206171) (xy 126.187488 -275.212305) (xy 126.136636 -275.210256) (xy 126.086772 -275.200076)
			(xy 126.039186 -275.182029) (xy 125.995112 -275.156583) (xy 125.95569 -275.124396) (xy 125.921942 -275.086302)
			(xy 125.894741 -275.043288) (xy 125.874793 -274.996468) (xy 125.862614 -274.947054) (xy 125.858519 -274.896326)
			(xy 125.550422 -274.896326) (xy 125.54991 -274.921772) (xy 125.541746 -274.972006) (xy 125.52563 -275.02028)
			(xy 125.501979 -275.065343) (xy 125.471406 -275.106029) (xy 125.434702 -275.141284) (xy 125.392818 -275.170194)
			(xy 125.346839 -275.192011) (xy 125.297955 -275.206171) (xy 125.247434 -275.212305) (xy 125.196582 -275.210256)
			(xy 125.146718 -275.200076) (xy 125.099132 -275.182029) (xy 125.055058 -275.156583) (xy 125.015636 -275.124396)
			(xy 124.981888 -275.086302) (xy 124.954687 -275.043288) (xy 124.934739 -274.996468) (xy 124.92256 -274.947054)
			(xy 124.918465 -274.896326) (xy 124.612654 -274.896326) (xy 124.612164 -274.921315) (xy 124.604345 -274.970678)
			(xy 124.588901 -275.01821) (xy 124.566211 -275.062742) (xy 124.536835 -275.103175) (xy 124.501495 -275.138515)
			(xy 124.461062 -275.167891) (xy 124.41653 -275.190581) (xy 124.368998 -275.206025) (xy 124.319635 -275.213844)
			(xy 124.269657 -275.213844) (xy 124.220294 -275.206025) (xy 124.172762 -275.190581) (xy 124.12823 -275.167891)
			(xy 124.087797 -275.138515) (xy 124.052457 -275.103175) (xy 124.023081 -275.062742) (xy 124.000391 -275.01821)
			(xy 123.984947 -274.970678) (xy 123.977128 -274.921315) (xy 123.670065 -274.921315) (xy 123.670056 -274.921772)
			(xy 123.661892 -274.972006) (xy 123.645776 -275.02028) (xy 123.622125 -275.065343) (xy 123.591552 -275.106029)
			(xy 123.554848 -275.141284) (xy 123.512964 -275.170194) (xy 123.466985 -275.192011) (xy 123.418101 -275.206171)
			(xy 123.36758 -275.212305) (xy 123.316728 -275.210256) (xy 123.266864 -275.200076) (xy 123.219278 -275.182029)
			(xy 123.175204 -275.156583) (xy 123.135782 -275.124396) (xy 123.102034 -275.086302) (xy 123.074833 -275.043288)
			(xy 123.054885 -274.996468) (xy 123.042706 -274.947054) (xy 123.038611 -274.896326) (xy 122.730514 -274.896326)
			(xy 122.730002 -274.921772) (xy 122.721838 -274.972006) (xy 122.705722 -275.02028) (xy 122.682071 -275.065343)
			(xy 122.651498 -275.106029) (xy 122.614794 -275.141284) (xy 122.57291 -275.170194) (xy 122.526931 -275.192011)
			(xy 122.478047 -275.206171) (xy 122.427526 -275.212305) (xy 122.376674 -275.210256) (xy 122.32681 -275.200076)
			(xy 122.279224 -275.182029) (xy 122.23515 -275.156583) (xy 122.195728 -275.124396) (xy 122.16198 -275.086302)
			(xy 122.134779 -275.043288) (xy 122.114831 -274.996468) (xy 122.102652 -274.947054) (xy 122.098557 -274.896326)
			(xy 121.792746 -274.896326) (xy 121.792256 -274.921315) (xy 121.784437 -274.970678) (xy 121.768993 -275.01821)
			(xy 121.746303 -275.062742) (xy 121.716927 -275.103175) (xy 121.681587 -275.138515) (xy 121.641154 -275.167891)
			(xy 121.596622 -275.190581) (xy 121.54909 -275.206025) (xy 121.499727 -275.213844) (xy 121.449749 -275.213844)
			(xy 121.400386 -275.206025) (xy 121.352854 -275.190581) (xy 121.308322 -275.167891) (xy 121.267889 -275.138515)
			(xy 121.232549 -275.103175) (xy 121.203173 -275.062742) (xy 121.180483 -275.01821) (xy 121.165039 -274.970678)
			(xy 121.15722 -274.921315) (xy 120.849903 -274.921315) (xy 120.849894 -274.921772) (xy 120.84173 -274.972006)
			(xy 120.825614 -275.02028) (xy 120.801963 -275.065343) (xy 120.77139 -275.106029) (xy 120.734686 -275.141284)
			(xy 120.692802 -275.170194) (xy 120.646823 -275.192011) (xy 120.597939 -275.206171) (xy 120.547418 -275.212305)
			(xy 120.496566 -275.210256) (xy 120.446702 -275.200076) (xy 120.399116 -275.182029) (xy 120.355042 -275.156583)
			(xy 120.31562 -275.124396) (xy 120.281872 -275.086302) (xy 120.254671 -275.043288) (xy 120.234723 -274.996468)
			(xy 120.222544 -274.947054) (xy 120.218449 -274.896326) (xy 119.910352 -274.896326) (xy 119.90984 -274.921772)
			(xy 119.901676 -274.972006) (xy 119.88556 -275.02028) (xy 119.861909 -275.065343) (xy 119.831336 -275.106029)
			(xy 119.794632 -275.141284) (xy 119.752748 -275.170194) (xy 119.706769 -275.192011) (xy 119.657885 -275.206171)
			(xy 119.607364 -275.212305) (xy 119.556512 -275.210256) (xy 119.506648 -275.200076) (xy 119.459062 -275.182029)
			(xy 119.414988 -275.156583) (xy 119.375566 -275.124396) (xy 119.341818 -275.086302) (xy 119.314617 -275.043288)
			(xy 119.294669 -274.996468) (xy 119.28249 -274.947054) (xy 119.278395 -274.896326) (xy 118.972838 -274.896326)
			(xy 118.972348 -274.921315) (xy 118.964529 -274.970678) (xy 118.949085 -275.01821) (xy 118.926395 -275.062742)
			(xy 118.897019 -275.103175) (xy 118.861679 -275.138515) (xy 118.821246 -275.167891) (xy 118.776714 -275.190581)
			(xy 118.729182 -275.206025) (xy 118.679819 -275.213844) (xy 118.629841 -275.213844) (xy 118.580478 -275.206025)
			(xy 118.532946 -275.190581) (xy 118.488414 -275.167891) (xy 118.447981 -275.138515) (xy 118.412641 -275.103175)
			(xy 118.383265 -275.062742) (xy 118.360575 -275.01821) (xy 118.345131 -274.970678) (xy 118.337312 -274.921315)
			(xy 118.029995 -274.921315) (xy 118.029986 -274.921772) (xy 118.021822 -274.972006) (xy 118.005706 -275.02028)
			(xy 117.982055 -275.065343) (xy 117.951482 -275.106029) (xy 117.914778 -275.141284) (xy 117.872894 -275.170194)
			(xy 117.826915 -275.192011) (xy 117.778031 -275.206171) (xy 117.72751 -275.212305) (xy 117.676658 -275.210256)
			(xy 117.626794 -275.200076) (xy 117.579208 -275.182029) (xy 117.535134 -275.156583) (xy 117.495712 -275.124396)
			(xy 117.461964 -275.086302) (xy 117.434763 -275.043288) (xy 117.414815 -274.996468) (xy 117.402636 -274.947054)
			(xy 117.398541 -274.896326) (xy 117.090444 -274.896326) (xy 117.089932 -274.921772) (xy 117.081768 -274.972006)
			(xy 117.065652 -275.02028) (xy 117.042001 -275.065343) (xy 117.011428 -275.106029) (xy 116.974724 -275.141284)
			(xy 116.93284 -275.170194) (xy 116.886861 -275.192011) (xy 116.837977 -275.206171) (xy 116.787456 -275.212305)
			(xy 116.736604 -275.210256) (xy 116.68674 -275.200076) (xy 116.639154 -275.182029) (xy 116.59508 -275.156583)
			(xy 116.555658 -275.124396) (xy 116.52191 -275.086302) (xy 116.494709 -275.043288) (xy 116.474761 -274.996468)
			(xy 116.462582 -274.947054) (xy 116.458487 -274.896326) (xy 116.152676 -274.896326) (xy 116.152186 -274.921315)
			(xy 116.144367 -274.970678) (xy 116.128923 -275.01821) (xy 116.106233 -275.062742) (xy 116.076857 -275.103175)
			(xy 116.041517 -275.138515) (xy 116.001084 -275.167891) (xy 115.956552 -275.190581) (xy 115.90902 -275.206025)
			(xy 115.859657 -275.213844) (xy 115.809679 -275.213844) (xy 115.760316 -275.206025) (xy 115.712784 -275.190581)
			(xy 115.668252 -275.167891) (xy 115.627819 -275.138515) (xy 115.592479 -275.103175) (xy 115.563103 -275.062742)
			(xy 115.540413 -275.01821) (xy 115.524969 -274.970678) (xy 115.51715 -274.921315) (xy 108.638612 -274.921315)
			(xy 108.630793 -274.970678) (xy 108.615349 -275.01821) (xy 108.592659 -275.062742) (xy 108.563283 -275.103175)
			(xy 108.527943 -275.138515) (xy 108.48751 -275.167891) (xy 108.442978 -275.190581) (xy 108.395446 -275.206025)
			(xy 108.346083 -275.213844) (xy 108.296105 -275.213844) (xy 108.246742 -275.206025) (xy 108.19921 -275.190581)
			(xy 108.154678 -275.167891) (xy 108.114245 -275.138515) (xy 108.078905 -275.103175) (xy 108.049529 -275.062742)
			(xy 108.026839 -275.01821) (xy 108.011395 -274.970678) (xy 108.003576 -274.921315) (xy 107.696259 -274.921315)
			(xy 107.69625 -274.921772) (xy 107.688086 -274.972006) (xy 107.67197 -275.02028) (xy 107.648319 -275.065343)
			(xy 107.617746 -275.106029) (xy 107.581042 -275.141284) (xy 107.539158 -275.170194) (xy 107.493179 -275.192011)
			(xy 107.444295 -275.206171) (xy 107.393774 -275.212305) (xy 107.342922 -275.210256) (xy 107.293058 -275.200076)
			(xy 107.245472 -275.182029) (xy 107.201398 -275.156583) (xy 107.161976 -275.124396) (xy 107.128228 -275.086302)
			(xy 107.101027 -275.043288) (xy 107.081079 -274.996468) (xy 107.0689 -274.947054) (xy 107.064805 -274.896326)
			(xy 106.756708 -274.896326) (xy 106.756196 -274.921772) (xy 106.748032 -274.972006) (xy 106.731916 -275.02028)
			(xy 106.708265 -275.065343) (xy 106.677692 -275.106029) (xy 106.640988 -275.141284) (xy 106.599104 -275.170194)
			(xy 106.553125 -275.192011) (xy 106.504241 -275.206171) (xy 106.45372 -275.212305) (xy 106.402868 -275.210256)
			(xy 106.353004 -275.200076) (xy 106.305418 -275.182029) (xy 106.261344 -275.156583) (xy 106.221922 -275.124396)
			(xy 106.188174 -275.086302) (xy 106.160973 -275.043288) (xy 106.141025 -274.996468) (xy 106.128846 -274.947054)
			(xy 106.124751 -274.896326) (xy 105.81894 -274.896326) (xy 105.81845 -274.921315) (xy 105.810631 -274.970678)
			(xy 105.795187 -275.01821) (xy 105.772497 -275.062742) (xy 105.743121 -275.103175) (xy 105.707781 -275.138515)
			(xy 105.667348 -275.167891) (xy 105.622816 -275.190581) (xy 105.575284 -275.206025) (xy 105.525921 -275.213844)
			(xy 105.475943 -275.213844) (xy 105.42658 -275.206025) (xy 105.379048 -275.190581) (xy 105.334516 -275.167891)
			(xy 105.294083 -275.138515) (xy 105.258743 -275.103175) (xy 105.229367 -275.062742) (xy 105.206677 -275.01821)
			(xy 105.191233 -274.970678) (xy 105.183414 -274.921315) (xy 104.876351 -274.921315) (xy 104.876342 -274.921772)
			(xy 104.868178 -274.972006) (xy 104.852062 -275.02028) (xy 104.828411 -275.065343) (xy 104.797838 -275.106029)
			(xy 104.761134 -275.141284) (xy 104.71925 -275.170194) (xy 104.673271 -275.192011) (xy 104.624387 -275.206171)
			(xy 104.573866 -275.212305) (xy 104.523014 -275.210256) (xy 104.47315 -275.200076) (xy 104.425564 -275.182029)
			(xy 104.38149 -275.156583) (xy 104.342068 -275.124396) (xy 104.30832 -275.086302) (xy 104.281119 -275.043288)
			(xy 104.261171 -274.996468) (xy 104.248992 -274.947054) (xy 104.244897 -274.896326) (xy 103.9368 -274.896326)
			(xy 103.936288 -274.921772) (xy 103.928124 -274.972006) (xy 103.912008 -275.02028) (xy 103.888357 -275.065343)
			(xy 103.857784 -275.106029) (xy 103.82108 -275.141284) (xy 103.779196 -275.170194) (xy 103.733217 -275.192011)
			(xy 103.684333 -275.206171) (xy 103.633812 -275.212305) (xy 103.58296 -275.210256) (xy 103.533096 -275.200076)
			(xy 103.48551 -275.182029) (xy 103.441436 -275.156583) (xy 103.402014 -275.124396) (xy 103.368266 -275.086302)
			(xy 103.341065 -275.043288) (xy 103.321117 -274.996468) (xy 103.308938 -274.947054) (xy 103.304843 -274.896326)
			(xy 102.999032 -274.896326) (xy 102.998542 -274.921315) (xy 102.990723 -274.970678) (xy 102.975279 -275.01821)
			(xy 102.952589 -275.062742) (xy 102.923213 -275.103175) (xy 102.887873 -275.138515) (xy 102.84744 -275.167891)
			(xy 102.802908 -275.190581) (xy 102.755376 -275.206025) (xy 102.706013 -275.213844) (xy 102.656035 -275.213844)
			(xy 102.606672 -275.206025) (xy 102.55914 -275.190581) (xy 102.514608 -275.167891) (xy 102.474175 -275.138515)
			(xy 102.438835 -275.103175) (xy 102.409459 -275.062742) (xy 102.386769 -275.01821) (xy 102.371325 -274.970678)
			(xy 102.363506 -274.921315) (xy 102.056189 -274.921315) (xy 102.05618 -274.921772) (xy 102.048016 -274.972006)
			(xy 102.0319 -275.02028) (xy 102.008249 -275.065343) (xy 101.977676 -275.106029) (xy 101.940972 -275.141284)
			(xy 101.899088 -275.170194) (xy 101.853109 -275.192011) (xy 101.804225 -275.206171) (xy 101.753704 -275.212305)
			(xy 101.702852 -275.210256) (xy 101.652988 -275.200076) (xy 101.605402 -275.182029) (xy 101.561328 -275.156583)
			(xy 101.521906 -275.124396) (xy 101.488158 -275.086302) (xy 101.460957 -275.043288) (xy 101.441009 -274.996468)
			(xy 101.42883 -274.947054) (xy 101.424735 -274.896326) (xy 101.116892 -274.896326) (xy 101.11638 -274.921772)
			(xy 101.108216 -274.972006) (xy 101.0921 -275.02028) (xy 101.068449 -275.065343) (xy 101.037876 -275.106029)
			(xy 101.001172 -275.141284) (xy 100.959288 -275.170194) (xy 100.913309 -275.192011) (xy 100.864425 -275.206171)
			(xy 100.813904 -275.212305) (xy 100.763052 -275.210256) (xy 100.713188 -275.200076) (xy 100.665602 -275.182029)
			(xy 100.621528 -275.156583) (xy 100.582106 -275.124396) (xy 100.548358 -275.086302) (xy 100.521157 -275.043288)
			(xy 100.501209 -274.996468) (xy 100.48903 -274.947054) (xy 100.484935 -274.896326) (xy 100.179124 -274.896326)
			(xy 100.178634 -274.921315) (xy 100.170815 -274.970678) (xy 100.155371 -275.01821) (xy 100.132681 -275.062742)
			(xy 100.103305 -275.103175) (xy 100.067965 -275.138515) (xy 100.027532 -275.167891) (xy 99.983 -275.190581)
			(xy 99.935468 -275.206025) (xy 99.886105 -275.213844) (xy 99.836127 -275.213844) (xy 99.786764 -275.206025)
			(xy 99.739232 -275.190581) (xy 99.6947 -275.167891) (xy 99.654267 -275.138515) (xy 99.618927 -275.103175)
			(xy 99.589551 -275.062742) (xy 99.566861 -275.01821) (xy 99.551417 -274.970678) (xy 99.543598 -274.921315)
			(xy 99.236281 -274.921315) (xy 99.236272 -274.921772) (xy 99.228108 -274.972006) (xy 99.211992 -275.02028)
			(xy 99.188341 -275.065343) (xy 99.157768 -275.106029) (xy 99.121064 -275.141284) (xy 99.07918 -275.170194)
			(xy 99.033201 -275.192011) (xy 98.984317 -275.206171) (xy 98.933796 -275.212305) (xy 98.882944 -275.210256)
			(xy 98.83308 -275.200076) (xy 98.785494 -275.182029) (xy 98.74142 -275.156583) (xy 98.701998 -275.124396)
			(xy 98.66825 -275.086302) (xy 98.641049 -275.043288) (xy 98.621101 -274.996468) (xy 98.608922 -274.947054)
			(xy 98.604827 -274.896326) (xy 98.29673 -274.896326) (xy 98.296218 -274.921772) (xy 98.288054 -274.972006)
			(xy 98.271938 -275.02028) (xy 98.248287 -275.065343) (xy 98.217714 -275.106029) (xy 98.18101 -275.141284)
			(xy 98.139126 -275.170194) (xy 98.093147 -275.192011) (xy 98.044263 -275.206171) (xy 97.993742 -275.212305)
			(xy 97.94289 -275.210256) (xy 97.893026 -275.200076) (xy 97.84544 -275.182029) (xy 97.801366 -275.156583)
			(xy 97.761944 -275.124396) (xy 97.728196 -275.086302) (xy 97.700995 -275.043288) (xy 97.681047 -274.996468)
			(xy 97.668868 -274.947054) (xy 97.664773 -274.896326) (xy 97.358962 -274.896326) (xy 97.358472 -274.921315)
			(xy 97.350653 -274.970678) (xy 97.335209 -275.01821) (xy 97.312519 -275.062742) (xy 97.283143 -275.103175)
			(xy 97.247803 -275.138515) (xy 97.20737 -275.167891) (xy 97.162838 -275.190581) (xy 97.115306 -275.206025)
			(xy 97.065943 -275.213844) (xy 97.015965 -275.213844) (xy 96.966602 -275.206025) (xy 96.91907 -275.190581)
			(xy 96.874538 -275.167891) (xy 96.834105 -275.138515) (xy 96.798765 -275.103175) (xy 96.769389 -275.062742)
			(xy 96.746699 -275.01821) (xy 96.731255 -274.970678) (xy 96.723436 -274.921315) (xy 96.418695 -274.921315)
			(xy 96.410873 -274.970676) (xy 96.395424 -275.018205) (xy 96.372731 -275.062733) (xy 96.343351 -275.103162)
			(xy 96.308007 -275.138497) (xy 96.267572 -275.167868) (xy 96.223039 -275.190552) (xy 96.175506 -275.205989)
			(xy 96.126143 -275.213801) (xy 96.101154 -275.214334) (xy 96.076557 -275.213872) (xy 96.027949 -275.206297)
			(xy 95.981085 -275.191334) (xy 95.93708 -275.16934) (xy 95.896983 -275.140838) (xy 95.861749 -275.106507)
			(xy 95.832215 -275.067163) (xy 95.82023 -275.045678) (xy 95.817436 -275.04009) (xy 95.809562 -275.0312)
			(xy 95.794576 -275.02104) (xy 95.782892 -275.019262) (xy 95.717614 -275.009356) (xy 95.703898 -275.007324)
			(xy 95.692078 -275.006212) (xy 95.669554 -275.013621) (xy 95.660718 -275.021548) (xy 95.080074 -275.602192)
			(xy 95.07855 -275.604224) (xy 95.066765 -275.618421) (xy 95.042377 -275.646113) (xy 95.029782 -275.659596)
			(xy 95.023178 -275.666454) (xy 95.008954 -275.70049) (xy 95.008954 -275.706332) (xy 95.314765 -275.706332)
			(xy 95.31886 -275.655604) (xy 95.331039 -275.60619) (xy 95.350987 -275.55937) (xy 95.378188 -275.516356)
			(xy 95.411936 -275.478262) (xy 95.451358 -275.446075) (xy 95.495432 -275.420629) (xy 95.543018 -275.402582)
			(xy 95.592882 -275.392402) (xy 95.643734 -275.390353) (xy 95.694255 -275.396487) (xy 95.743139 -275.410647)
			(xy 95.789118 -275.432464) (xy 95.831002 -275.461374) (xy 95.867706 -275.496629) (xy 95.898279 -275.537315)
			(xy 95.92193 -275.582378) (xy 95.938046 -275.630652) (xy 95.94621 -275.680886) (xy 95.946722 -275.706332)
			(xy 95.946219 -275.731321) (xy 96.253536 -275.731321) (xy 96.253536 -275.681343) (xy 96.261355 -275.63198)
			(xy 96.276799 -275.584448) (xy 96.299489 -275.539916) (xy 96.328865 -275.499483) (xy 96.364205 -275.464143)
			(xy 96.404638 -275.434767) (xy 96.44917 -275.412077) (xy 96.496702 -275.396633) (xy 96.546065 -275.388814)
			(xy 96.596043 -275.388814) (xy 96.645406 -275.396633) (xy 96.692938 -275.412077) (xy 96.73747 -275.434767)
			(xy 96.777903 -275.464143) (xy 96.813243 -275.499483) (xy 96.842619 -275.539916) (xy 96.865309 -275.584448)
			(xy 96.880753 -275.63198) (xy 96.888572 -275.681343) (xy 96.889062 -275.706332) (xy 96.888572 -275.731321)
			(xy 99.073444 -275.731321) (xy 99.073444 -275.681343) (xy 99.081263 -275.63198) (xy 99.096707 -275.584448)
			(xy 99.119397 -275.539916) (xy 99.148773 -275.499483) (xy 99.184113 -275.464143) (xy 99.224546 -275.434767)
			(xy 99.269078 -275.412077) (xy 99.31661 -275.396633) (xy 99.365973 -275.388814) (xy 99.415951 -275.388814)
			(xy 99.465314 -275.396633) (xy 99.512846 -275.412077) (xy 99.557378 -275.434767) (xy 99.597811 -275.464143)
			(xy 99.633151 -275.499483) (xy 99.662527 -275.539916) (xy 99.685217 -275.584448) (xy 99.700661 -275.63198)
			(xy 99.70848 -275.681343) (xy 99.70897 -275.706332) (xy 99.70848 -275.731321) (xy 101.893606 -275.731321)
			(xy 101.893606 -275.681343) (xy 101.901425 -275.63198) (xy 101.916869 -275.584448) (xy 101.939559 -275.539916)
			(xy 101.968935 -275.499483) (xy 102.004275 -275.464143) (xy 102.044708 -275.434767) (xy 102.08924 -275.412077)
			(xy 102.136772 -275.396633) (xy 102.186135 -275.388814) (xy 102.236113 -275.388814) (xy 102.285476 -275.396633)
			(xy 102.333008 -275.412077) (xy 102.37754 -275.434767) (xy 102.417973 -275.464143) (xy 102.453313 -275.499483)
			(xy 102.482689 -275.539916) (xy 102.505379 -275.584448) (xy 102.520823 -275.63198) (xy 102.528642 -275.681343)
			(xy 102.529132 -275.706332) (xy 102.528642 -275.731321) (xy 104.713514 -275.731321) (xy 104.713514 -275.681343)
			(xy 104.721333 -275.63198) (xy 104.736777 -275.584448) (xy 104.759467 -275.539916) (xy 104.788843 -275.499483)
			(xy 104.824183 -275.464143) (xy 104.864616 -275.434767) (xy 104.909148 -275.412077) (xy 104.95668 -275.396633)
			(xy 105.006043 -275.388814) (xy 105.056021 -275.388814) (xy 105.105384 -275.396633) (xy 105.152916 -275.412077)
			(xy 105.197448 -275.434767) (xy 105.237881 -275.464143) (xy 105.273221 -275.499483) (xy 105.302597 -275.539916)
			(xy 105.325287 -275.584448) (xy 105.340731 -275.63198) (xy 105.34855 -275.681343) (xy 105.34904 -275.706332)
			(xy 105.34855 -275.731321) (xy 107.533422 -275.731321) (xy 107.533422 -275.681343) (xy 107.541241 -275.63198)
			(xy 107.556685 -275.584448) (xy 107.579375 -275.539916) (xy 107.608751 -275.499483) (xy 107.644091 -275.464143)
			(xy 107.684524 -275.434767) (xy 107.729056 -275.412077) (xy 107.776588 -275.396633) (xy 107.825951 -275.388814)
			(xy 107.875929 -275.388814) (xy 107.925292 -275.396633) (xy 107.972824 -275.412077) (xy 108.017356 -275.434767)
			(xy 108.057789 -275.464143) (xy 108.093129 -275.499483) (xy 108.122505 -275.539916) (xy 108.145195 -275.584448)
			(xy 108.160639 -275.63198) (xy 108.168458 -275.681343) (xy 108.168948 -275.706332) (xy 108.474759 -275.706332)
			(xy 108.478854 -275.655604) (xy 108.491033 -275.60619) (xy 108.510981 -275.55937) (xy 108.538182 -275.516356)
			(xy 108.57193 -275.478262) (xy 108.611352 -275.446075) (xy 108.655426 -275.420629) (xy 108.703012 -275.402582)
			(xy 108.752876 -275.392402) (xy 108.803728 -275.390353) (xy 108.854249 -275.396487) (xy 108.903133 -275.410647)
			(xy 108.949112 -275.432464) (xy 108.990996 -275.461374) (xy 109.0277 -275.496629) (xy 109.058273 -275.537315)
			(xy 109.081924 -275.582378) (xy 109.09804 -275.630652) (xy 109.106204 -275.680886) (xy 109.106716 -275.706332)
			(xy 109.414813 -275.706332) (xy 109.418908 -275.655604) (xy 109.431087 -275.60619) (xy 109.451035 -275.55937)
			(xy 109.478236 -275.516356) (xy 109.511984 -275.478262) (xy 109.551406 -275.446075) (xy 109.59548 -275.420629)
			(xy 109.643066 -275.402582) (xy 109.69293 -275.392402) (xy 109.743782 -275.390353) (xy 109.794303 -275.396487)
			(xy 109.843187 -275.410647) (xy 109.889166 -275.432464) (xy 109.93105 -275.461374) (xy 109.967754 -275.496629)
			(xy 109.998327 -275.537315) (xy 110.021978 -275.582378) (xy 110.038094 -275.630652) (xy 110.046258 -275.680886)
			(xy 110.04677 -275.706332) (xy 110.046267 -275.731321) (xy 110.353584 -275.731321) (xy 110.353584 -275.681343)
			(xy 110.361403 -275.63198) (xy 110.376847 -275.584448) (xy 110.399537 -275.539916) (xy 110.428913 -275.499483)
			(xy 110.464253 -275.464143) (xy 110.504686 -275.434767) (xy 110.549218 -275.412077) (xy 110.59675 -275.396633)
			(xy 110.646113 -275.388814) (xy 110.696091 -275.388814) (xy 110.745454 -275.396633) (xy 110.792986 -275.412077)
			(xy 110.837518 -275.434767) (xy 110.877951 -275.464143) (xy 110.913291 -275.499483) (xy 110.942667 -275.539916)
			(xy 110.965357 -275.584448) (xy 110.980801 -275.63198) (xy 110.98862 -275.681343) (xy 110.98911 -275.706332)
			(xy 110.98862 -275.731321) (xy 113.167142 -275.731321) (xy 113.167142 -275.681343) (xy 113.174961 -275.63198)
			(xy 113.190405 -275.584448) (xy 113.213095 -275.539916) (xy 113.242471 -275.499483) (xy 113.277811 -275.464143)
			(xy 113.318244 -275.434767) (xy 113.362776 -275.412077) (xy 113.410308 -275.396633) (xy 113.459671 -275.388814)
			(xy 113.509649 -275.388814) (xy 113.559012 -275.396633) (xy 113.606544 -275.412077) (xy 113.651076 -275.434767)
			(xy 113.691509 -275.464143) (xy 113.726849 -275.499483) (xy 113.756225 -275.539916) (xy 113.778915 -275.584448)
			(xy 113.794359 -275.63198) (xy 113.802178 -275.681343) (xy 113.802668 -275.706332) (xy 114.108479 -275.706332)
			(xy 114.112574 -275.655604) (xy 114.124753 -275.60619) (xy 114.144701 -275.55937) (xy 114.171902 -275.516356)
			(xy 114.20565 -275.478262) (xy 114.245072 -275.446075) (xy 114.289146 -275.420629) (xy 114.336732 -275.402582)
			(xy 114.386596 -275.392402) (xy 114.437448 -275.390353) (xy 114.487969 -275.396487) (xy 114.536853 -275.410647)
			(xy 114.582832 -275.432464) (xy 114.624716 -275.461374) (xy 114.66142 -275.496629) (xy 114.691993 -275.537315)
			(xy 114.715644 -275.582378) (xy 114.73176 -275.630652) (xy 114.739924 -275.680886) (xy 114.740436 -275.706332)
			(xy 115.048533 -275.706332) (xy 115.052628 -275.655604) (xy 115.064807 -275.60619) (xy 115.084755 -275.55937)
			(xy 115.111956 -275.516356) (xy 115.145704 -275.478262) (xy 115.185126 -275.446075) (xy 115.2292 -275.420629)
			(xy 115.276786 -275.402582) (xy 115.32665 -275.392402) (xy 115.377502 -275.390353) (xy 115.428023 -275.396487)
			(xy 115.476907 -275.410647) (xy 115.522886 -275.432464) (xy 115.56477 -275.461374) (xy 115.601474 -275.496629)
			(xy 115.632047 -275.537315) (xy 115.655698 -275.582378) (xy 115.671814 -275.630652) (xy 115.679978 -275.680886)
			(xy 115.68049 -275.706332) (xy 115.679987 -275.731321) (xy 115.987304 -275.731321) (xy 115.987304 -275.681343)
			(xy 115.995123 -275.63198) (xy 116.010567 -275.584448) (xy 116.033257 -275.539916) (xy 116.062633 -275.499483)
			(xy 116.097973 -275.464143) (xy 116.138406 -275.434767) (xy 116.182938 -275.412077) (xy 116.23047 -275.396633)
			(xy 116.279833 -275.388814) (xy 116.329811 -275.388814) (xy 116.379174 -275.396633) (xy 116.426706 -275.412077)
			(xy 116.471238 -275.434767) (xy 116.511671 -275.464143) (xy 116.547011 -275.499483) (xy 116.576387 -275.539916)
			(xy 116.599077 -275.584448) (xy 116.614521 -275.63198) (xy 116.62234 -275.681343) (xy 116.62283 -275.706332)
			(xy 116.62234 -275.731321) (xy 118.807212 -275.731321) (xy 118.807212 -275.681343) (xy 118.815031 -275.63198)
			(xy 118.830475 -275.584448) (xy 118.853165 -275.539916) (xy 118.882541 -275.499483) (xy 118.917881 -275.464143)
			(xy 118.958314 -275.434767) (xy 119.002846 -275.412077) (xy 119.050378 -275.396633) (xy 119.099741 -275.388814)
			(xy 119.149719 -275.388814) (xy 119.199082 -275.396633) (xy 119.246614 -275.412077) (xy 119.291146 -275.434767)
			(xy 119.331579 -275.464143) (xy 119.366919 -275.499483) (xy 119.396295 -275.539916) (xy 119.418985 -275.584448)
			(xy 119.434429 -275.63198) (xy 119.442248 -275.681343) (xy 119.442738 -275.706332) (xy 119.442248 -275.731321)
			(xy 121.62712 -275.731321) (xy 121.62712 -275.681343) (xy 121.634939 -275.63198) (xy 121.650383 -275.584448)
			(xy 121.673073 -275.539916) (xy 121.702449 -275.499483) (xy 121.737789 -275.464143) (xy 121.778222 -275.434767)
			(xy 121.822754 -275.412077) (xy 121.870286 -275.396633) (xy 121.919649 -275.388814) (xy 121.969627 -275.388814)
			(xy 122.01899 -275.396633) (xy 122.066522 -275.412077) (xy 122.111054 -275.434767) (xy 122.151487 -275.464143)
			(xy 122.186827 -275.499483) (xy 122.216203 -275.539916) (xy 122.238893 -275.584448) (xy 122.254337 -275.63198)
			(xy 122.262156 -275.681343) (xy 122.262646 -275.706332) (xy 122.262156 -275.731321) (xy 124.447282 -275.731321)
			(xy 124.447282 -275.681343) (xy 124.455101 -275.63198) (xy 124.470545 -275.584448) (xy 124.493235 -275.539916)
			(xy 124.522611 -275.499483) (xy 124.557951 -275.464143) (xy 124.598384 -275.434767) (xy 124.642916 -275.412077)
			(xy 124.690448 -275.396633) (xy 124.739811 -275.388814) (xy 124.789789 -275.388814) (xy 124.839152 -275.396633)
			(xy 124.886684 -275.412077) (xy 124.931216 -275.434767) (xy 124.971649 -275.464143) (xy 125.006989 -275.499483)
			(xy 125.036365 -275.539916) (xy 125.059055 -275.584448) (xy 125.074499 -275.63198) (xy 125.082318 -275.681343)
			(xy 125.082808 -275.706332) (xy 125.082318 -275.731321) (xy 125.074499 -275.780684) (xy 125.059055 -275.828216)
			(xy 125.036365 -275.872748) (xy 125.006989 -275.913181) (xy 124.971649 -275.948521) (xy 124.931216 -275.977897)
			(xy 124.886684 -276.000587) (xy 124.839152 -276.016031) (xy 124.789789 -276.02385) (xy 124.739811 -276.02385)
			(xy 124.690448 -276.016031) (xy 124.642916 -276.000587) (xy 124.598384 -275.977897) (xy 124.557951 -275.948521)
			(xy 124.522611 -275.913181) (xy 124.493235 -275.872748) (xy 124.470545 -275.828216) (xy 124.455101 -275.780684)
			(xy 124.447282 -275.731321) (xy 122.262156 -275.731321) (xy 122.254337 -275.780684) (xy 122.238893 -275.828216)
			(xy 122.216203 -275.872748) (xy 122.186827 -275.913181) (xy 122.151487 -275.948521) (xy 122.111054 -275.977897)
			(xy 122.066522 -276.000587) (xy 122.01899 -276.016031) (xy 121.969627 -276.02385) (xy 121.919649 -276.02385)
			(xy 121.870286 -276.016031) (xy 121.822754 -276.000587) (xy 121.778222 -275.977897) (xy 121.737789 -275.948521)
			(xy 121.702449 -275.913181) (xy 121.673073 -275.872748) (xy 121.650383 -275.828216) (xy 121.634939 -275.780684)
			(xy 121.62712 -275.731321) (xy 119.442248 -275.731321) (xy 119.434429 -275.780684) (xy 119.418985 -275.828216)
			(xy 119.396295 -275.872748) (xy 119.366919 -275.913181) (xy 119.331579 -275.948521) (xy 119.291146 -275.977897)
			(xy 119.246614 -276.000587) (xy 119.199082 -276.016031) (xy 119.149719 -276.02385) (xy 119.099741 -276.02385)
			(xy 119.050378 -276.016031) (xy 119.002846 -276.000587) (xy 118.958314 -275.977897) (xy 118.917881 -275.948521)
			(xy 118.882541 -275.913181) (xy 118.853165 -275.872748) (xy 118.830475 -275.828216) (xy 118.815031 -275.780684)
			(xy 118.807212 -275.731321) (xy 116.62234 -275.731321) (xy 116.614521 -275.780684) (xy 116.599077 -275.828216)
			(xy 116.576387 -275.872748) (xy 116.547011 -275.913181) (xy 116.511671 -275.948521) (xy 116.471238 -275.977897)
			(xy 116.426706 -276.000587) (xy 116.379174 -276.016031) (xy 116.329811 -276.02385) (xy 116.279833 -276.02385)
			(xy 116.23047 -276.016031) (xy 116.182938 -276.000587) (xy 116.138406 -275.977897) (xy 116.097973 -275.948521)
			(xy 116.062633 -275.913181) (xy 116.033257 -275.872748) (xy 116.010567 -275.828216) (xy 115.995123 -275.780684)
			(xy 115.987304 -275.731321) (xy 115.679987 -275.731321) (xy 115.679978 -275.731778) (xy 115.671814 -275.782012)
			(xy 115.655698 -275.830286) (xy 115.632047 -275.875349) (xy 115.601474 -275.916035) (xy 115.56477 -275.95129)
			(xy 115.522886 -275.9802) (xy 115.476907 -276.002017) (xy 115.428023 -276.016177) (xy 115.377502 -276.022311)
			(xy 115.32665 -276.020262) (xy 115.276786 -276.010082) (xy 115.2292 -275.992035) (xy 115.185126 -275.966589)
			(xy 115.145704 -275.934402) (xy 115.111956 -275.896308) (xy 115.084755 -275.853294) (xy 115.064807 -275.806474)
			(xy 115.052628 -275.75706) (xy 115.048533 -275.706332) (xy 114.740436 -275.706332) (xy 114.739924 -275.731778)
			(xy 114.73176 -275.782012) (xy 114.715644 -275.830286) (xy 114.691993 -275.875349) (xy 114.66142 -275.916035)
			(xy 114.624716 -275.95129) (xy 114.582832 -275.9802) (xy 114.536853 -276.002017) (xy 114.487969 -276.016177)
			(xy 114.437448 -276.022311) (xy 114.386596 -276.020262) (xy 114.336732 -276.010082) (xy 114.289146 -275.992035)
			(xy 114.245072 -275.966589) (xy 114.20565 -275.934402) (xy 114.171902 -275.896308) (xy 114.144701 -275.853294)
			(xy 114.124753 -275.806474) (xy 114.112574 -275.75706) (xy 114.108479 -275.706332) (xy 113.802668 -275.706332)
			(xy 113.802178 -275.731321) (xy 113.794359 -275.780684) (xy 113.778915 -275.828216) (xy 113.756225 -275.872748)
			(xy 113.726849 -275.913181) (xy 113.691509 -275.948521) (xy 113.651076 -275.977897) (xy 113.606544 -276.000587)
			(xy 113.559012 -276.016031) (xy 113.509649 -276.02385) (xy 113.459671 -276.02385) (xy 113.410308 -276.016031)
			(xy 113.362776 -276.000587) (xy 113.318244 -275.977897) (xy 113.277811 -275.948521) (xy 113.242471 -275.913181)
			(xy 113.213095 -275.872748) (xy 113.190405 -275.828216) (xy 113.174961 -275.780684) (xy 113.167142 -275.731321)
			(xy 110.98862 -275.731321) (xy 110.980801 -275.780684) (xy 110.965357 -275.828216) (xy 110.942667 -275.872748)
			(xy 110.913291 -275.913181) (xy 110.877951 -275.948521) (xy 110.837518 -275.977897) (xy 110.792986 -276.000587)
			(xy 110.745454 -276.016031) (xy 110.696091 -276.02385) (xy 110.646113 -276.02385) (xy 110.59675 -276.016031)
			(xy 110.549218 -276.000587) (xy 110.504686 -275.977897) (xy 110.464253 -275.948521) (xy 110.428913 -275.913181)
			(xy 110.399537 -275.872748) (xy 110.376847 -275.828216) (xy 110.361403 -275.780684) (xy 110.353584 -275.731321)
			(xy 110.046267 -275.731321) (xy 110.046258 -275.731778) (xy 110.038094 -275.782012) (xy 110.021978 -275.830286)
			(xy 109.998327 -275.875349) (xy 109.967754 -275.916035) (xy 109.93105 -275.95129) (xy 109.889166 -275.9802)
			(xy 109.843187 -276.002017) (xy 109.794303 -276.016177) (xy 109.743782 -276.022311) (xy 109.69293 -276.020262)
			(xy 109.643066 -276.010082) (xy 109.59548 -275.992035) (xy 109.551406 -275.966589) (xy 109.511984 -275.934402)
			(xy 109.478236 -275.896308) (xy 109.451035 -275.853294) (xy 109.431087 -275.806474) (xy 109.418908 -275.75706)
			(xy 109.414813 -275.706332) (xy 109.106716 -275.706332) (xy 109.106204 -275.731778) (xy 109.09804 -275.782012)
			(xy 109.081924 -275.830286) (xy 109.058273 -275.875349) (xy 109.0277 -275.916035) (xy 108.990996 -275.95129)
			(xy 108.949112 -275.9802) (xy 108.903133 -276.002017) (xy 108.854249 -276.016177) (xy 108.803728 -276.022311)
			(xy 108.752876 -276.020262) (xy 108.703012 -276.010082) (xy 108.655426 -275.992035) (xy 108.611352 -275.966589)
			(xy 108.57193 -275.934402) (xy 108.538182 -275.896308) (xy 108.510981 -275.853294) (xy 108.491033 -275.806474)
			(xy 108.478854 -275.75706) (xy 108.474759 -275.706332) (xy 108.168948 -275.706332) (xy 108.168458 -275.731321)
			(xy 108.160639 -275.780684) (xy 108.145195 -275.828216) (xy 108.122505 -275.872748) (xy 108.093129 -275.913181)
			(xy 108.057789 -275.948521) (xy 108.017356 -275.977897) (xy 107.972824 -276.000587) (xy 107.925292 -276.016031)
			(xy 107.875929 -276.02385) (xy 107.825951 -276.02385) (xy 107.776588 -276.016031) (xy 107.729056 -276.000587)
			(xy 107.684524 -275.977897) (xy 107.644091 -275.948521) (xy 107.608751 -275.913181) (xy 107.579375 -275.872748)
			(xy 107.556685 -275.828216) (xy 107.541241 -275.780684) (xy 107.533422 -275.731321) (xy 105.34855 -275.731321)
			(xy 105.340731 -275.780684) (xy 105.325287 -275.828216) (xy 105.302597 -275.872748) (xy 105.273221 -275.913181)
			(xy 105.237881 -275.948521) (xy 105.197448 -275.977897) (xy 105.152916 -276.000587) (xy 105.105384 -276.016031)
			(xy 105.056021 -276.02385) (xy 105.006043 -276.02385) (xy 104.95668 -276.016031) (xy 104.909148 -276.000587)
			(xy 104.864616 -275.977897) (xy 104.824183 -275.948521) (xy 104.788843 -275.913181) (xy 104.759467 -275.872748)
			(xy 104.736777 -275.828216) (xy 104.721333 -275.780684) (xy 104.713514 -275.731321) (xy 102.528642 -275.731321)
			(xy 102.520823 -275.780684) (xy 102.505379 -275.828216) (xy 102.482689 -275.872748) (xy 102.453313 -275.913181)
			(xy 102.417973 -275.948521) (xy 102.37754 -275.977897) (xy 102.333008 -276.000587) (xy 102.285476 -276.016031)
			(xy 102.236113 -276.02385) (xy 102.186135 -276.02385) (xy 102.136772 -276.016031) (xy 102.08924 -276.000587)
			(xy 102.044708 -275.977897) (xy 102.004275 -275.948521) (xy 101.968935 -275.913181) (xy 101.939559 -275.872748)
			(xy 101.916869 -275.828216) (xy 101.901425 -275.780684) (xy 101.893606 -275.731321) (xy 99.70848 -275.731321)
			(xy 99.700661 -275.780684) (xy 99.685217 -275.828216) (xy 99.662527 -275.872748) (xy 99.633151 -275.913181)
			(xy 99.597811 -275.948521) (xy 99.557378 -275.977897) (xy 99.512846 -276.000587) (xy 99.465314 -276.016031)
			(xy 99.415951 -276.02385) (xy 99.365973 -276.02385) (xy 99.31661 -276.016031) (xy 99.269078 -276.000587)
			(xy 99.224546 -275.977897) (xy 99.184113 -275.948521) (xy 99.148773 -275.913181) (xy 99.119397 -275.872748)
			(xy 99.096707 -275.828216) (xy 99.081263 -275.780684) (xy 99.073444 -275.731321) (xy 96.888572 -275.731321)
			(xy 96.880753 -275.780684) (xy 96.865309 -275.828216) (xy 96.842619 -275.872748) (xy 96.813243 -275.913181)
			(xy 96.777903 -275.948521) (xy 96.73747 -275.977897) (xy 96.692938 -276.000587) (xy 96.645406 -276.016031)
			(xy 96.596043 -276.02385) (xy 96.546065 -276.02385) (xy 96.496702 -276.016031) (xy 96.44917 -276.000587)
			(xy 96.404638 -275.977897) (xy 96.364205 -275.948521) (xy 96.328865 -275.913181) (xy 96.299489 -275.872748)
			(xy 96.276799 -275.828216) (xy 96.261355 -275.780684) (xy 96.253536 -275.731321) (xy 95.946219 -275.731321)
			(xy 95.94621 -275.731778) (xy 95.938046 -275.782012) (xy 95.92193 -275.830286) (xy 95.898279 -275.875349)
			(xy 95.867706 -275.916035) (xy 95.831002 -275.95129) (xy 95.789118 -275.9802) (xy 95.743139 -276.002017)
			(xy 95.694255 -276.016177) (xy 95.643734 -276.022311) (xy 95.592882 -276.020262) (xy 95.543018 -276.010082)
			(xy 95.495432 -275.992035) (xy 95.451358 -275.966589) (xy 95.411936 -275.934402) (xy 95.378188 -275.896308)
			(xy 95.350987 -275.853294) (xy 95.331039 -275.806474) (xy 95.31886 -275.75706) (xy 95.314765 -275.706332)
			(xy 95.008954 -275.706332) (xy 95.008954 -275.710142) (xy 95.008246 -275.733577) (xy 95.000792 -275.779865)
			(xy 94.986626 -275.824558) (xy 94.966055 -275.866688) (xy 94.939524 -275.905343) (xy 94.907608 -275.939687)
			(xy 94.870997 -275.968975) (xy 94.850966 -275.98116) (xy 94.842584 -275.985986) (xy 94.818962 -276.015958)
			(xy 94.816168 -276.02561) (xy 94.815914 -276.02561) (xy 94.80051 -276.075008) (xy 94.761752 -276.170956)
			(xy 94.714243 -276.262886) (xy 94.658395 -276.350002) (xy 94.594692 -276.43155) (xy 94.559628 -276.469602)
			(xy 94.553024 -276.476206) (xy 94.539054 -276.509988) (xy 94.539054 -276.519894) (xy 94.538428 -276.541327)
			(xy 94.843582 -276.541327) (xy 94.843582 -276.491349) (xy 94.851401 -276.441986) (xy 94.866845 -276.394454)
			(xy 94.889535 -276.349922) (xy 94.918911 -276.309489) (xy 94.954251 -276.274149) (xy 94.994684 -276.244773)
			(xy 95.039216 -276.222083) (xy 95.086748 -276.206639) (xy 95.136111 -276.19882) (xy 95.186089 -276.19882)
			(xy 95.235452 -276.206639) (xy 95.282984 -276.222083) (xy 95.327516 -276.244773) (xy 95.367949 -276.274149)
			(xy 95.403289 -276.309489) (xy 95.432665 -276.349922) (xy 95.455355 -276.394454) (xy 95.470799 -276.441986)
			(xy 95.478618 -276.491349) (xy 95.479108 -276.516338) (xy 95.784919 -276.516338) (xy 95.789014 -276.46561)
			(xy 95.801193 -276.416196) (xy 95.821141 -276.369376) (xy 95.848342 -276.326362) (xy 95.88209 -276.288268)
			(xy 95.921512 -276.256081) (xy 95.965586 -276.230635) (xy 96.013172 -276.212588) (xy 96.063036 -276.202408)
			(xy 96.113888 -276.200359) (xy 96.164409 -276.206493) (xy 96.213293 -276.220653) (xy 96.259272 -276.24247)
			(xy 96.301156 -276.27138) (xy 96.33786 -276.306635) (xy 96.368433 -276.347321) (xy 96.392084 -276.392384)
			(xy 96.4082 -276.440658) (xy 96.416364 -276.490892) (xy 96.416876 -276.516338) (xy 96.416373 -276.541327)
			(xy 96.723436 -276.541327) (xy 96.723436 -276.491349) (xy 96.731255 -276.441986) (xy 96.746699 -276.394454)
			(xy 96.769389 -276.349922) (xy 96.798765 -276.309489) (xy 96.834105 -276.274149) (xy 96.874538 -276.244773)
			(xy 96.91907 -276.222083) (xy 96.966602 -276.206639) (xy 97.015965 -276.19882) (xy 97.065943 -276.19882)
			(xy 97.115306 -276.206639) (xy 97.162838 -276.222083) (xy 97.20737 -276.244773) (xy 97.247803 -276.274149)
			(xy 97.283143 -276.309489) (xy 97.312519 -276.349922) (xy 97.335209 -276.394454) (xy 97.350653 -276.441986)
			(xy 97.358472 -276.491349) (xy 97.358962 -276.516338) (xy 97.664773 -276.516338) (xy 97.668868 -276.46561)
			(xy 97.681047 -276.416196) (xy 97.700995 -276.369376) (xy 97.728196 -276.326362) (xy 97.761944 -276.288268)
			(xy 97.801366 -276.256081) (xy 97.84544 -276.230635) (xy 97.893026 -276.212588) (xy 97.94289 -276.202408)
			(xy 97.993742 -276.200359) (xy 98.044263 -276.206493) (xy 98.093147 -276.220653) (xy 98.139126 -276.24247)
			(xy 98.18101 -276.27138) (xy 98.217714 -276.306635) (xy 98.248287 -276.347321) (xy 98.271938 -276.392384)
			(xy 98.288054 -276.440658) (xy 98.296218 -276.490892) (xy 98.29673 -276.516338) (xy 98.604827 -276.516338)
			(xy 98.608922 -276.46561) (xy 98.621101 -276.416196) (xy 98.641049 -276.369376) (xy 98.66825 -276.326362)
			(xy 98.701998 -276.288268) (xy 98.74142 -276.256081) (xy 98.785494 -276.230635) (xy 98.83308 -276.212588)
			(xy 98.882944 -276.202408) (xy 98.933796 -276.200359) (xy 98.984317 -276.206493) (xy 99.033201 -276.220653)
			(xy 99.07918 -276.24247) (xy 99.121064 -276.27138) (xy 99.157768 -276.306635) (xy 99.188341 -276.347321)
			(xy 99.211992 -276.392384) (xy 99.228108 -276.440658) (xy 99.236272 -276.490892) (xy 99.236784 -276.516338)
			(xy 99.236281 -276.541327) (xy 99.543598 -276.541327) (xy 99.543598 -276.491349) (xy 99.551417 -276.441986)
			(xy 99.566861 -276.394454) (xy 99.589551 -276.349922) (xy 99.618927 -276.309489) (xy 99.654267 -276.274149)
			(xy 99.6947 -276.244773) (xy 99.739232 -276.222083) (xy 99.786764 -276.206639) (xy 99.836127 -276.19882)
			(xy 99.886105 -276.19882) (xy 99.935468 -276.206639) (xy 99.983 -276.222083) (xy 100.027532 -276.244773)
			(xy 100.067965 -276.274149) (xy 100.103305 -276.309489) (xy 100.132681 -276.349922) (xy 100.155371 -276.394454)
			(xy 100.170815 -276.441986) (xy 100.178634 -276.491349) (xy 100.179124 -276.516338) (xy 100.484935 -276.516338)
			(xy 100.48903 -276.46561) (xy 100.501209 -276.416196) (xy 100.521157 -276.369376) (xy 100.548358 -276.326362)
			(xy 100.582106 -276.288268) (xy 100.621528 -276.256081) (xy 100.665602 -276.230635) (xy 100.713188 -276.212588)
			(xy 100.763052 -276.202408) (xy 100.813904 -276.200359) (xy 100.864425 -276.206493) (xy 100.913309 -276.220653)
			(xy 100.959288 -276.24247) (xy 101.001172 -276.27138) (xy 101.037876 -276.306635) (xy 101.068449 -276.347321)
			(xy 101.0921 -276.392384) (xy 101.108216 -276.440658) (xy 101.11638 -276.490892) (xy 101.116892 -276.516338)
			(xy 101.424735 -276.516338) (xy 101.42883 -276.46561) (xy 101.441009 -276.416196) (xy 101.460957 -276.369376)
			(xy 101.488158 -276.326362) (xy 101.521906 -276.288268) (xy 101.561328 -276.256081) (xy 101.605402 -276.230635)
			(xy 101.652988 -276.212588) (xy 101.702852 -276.202408) (xy 101.753704 -276.200359) (xy 101.804225 -276.206493)
			(xy 101.853109 -276.220653) (xy 101.899088 -276.24247) (xy 101.940972 -276.27138) (xy 101.977676 -276.306635)
			(xy 102.008249 -276.347321) (xy 102.0319 -276.392384) (xy 102.048016 -276.440658) (xy 102.05618 -276.490892)
			(xy 102.056692 -276.516338) (xy 102.056189 -276.541327) (xy 102.363506 -276.541327) (xy 102.363506 -276.491349)
			(xy 102.371325 -276.441986) (xy 102.386769 -276.394454) (xy 102.409459 -276.349922) (xy 102.438835 -276.309489)
			(xy 102.474175 -276.274149) (xy 102.514608 -276.244773) (xy 102.55914 -276.222083) (xy 102.606672 -276.206639)
			(xy 102.656035 -276.19882) (xy 102.706013 -276.19882) (xy 102.755376 -276.206639) (xy 102.802908 -276.222083)
			(xy 102.84744 -276.244773) (xy 102.887873 -276.274149) (xy 102.923213 -276.309489) (xy 102.952589 -276.349922)
			(xy 102.975279 -276.394454) (xy 102.990723 -276.441986) (xy 102.998542 -276.491349) (xy 102.999032 -276.516338)
			(xy 103.304843 -276.516338) (xy 103.308938 -276.46561) (xy 103.321117 -276.416196) (xy 103.341065 -276.369376)
			(xy 103.368266 -276.326362) (xy 103.402014 -276.288268) (xy 103.441436 -276.256081) (xy 103.48551 -276.230635)
			(xy 103.533096 -276.212588) (xy 103.58296 -276.202408) (xy 103.633812 -276.200359) (xy 103.684333 -276.206493)
			(xy 103.733217 -276.220653) (xy 103.779196 -276.24247) (xy 103.82108 -276.27138) (xy 103.857784 -276.306635)
			(xy 103.888357 -276.347321) (xy 103.912008 -276.392384) (xy 103.928124 -276.440658) (xy 103.936288 -276.490892)
			(xy 103.9368 -276.516338) (xy 104.244897 -276.516338) (xy 104.248992 -276.46561) (xy 104.261171 -276.416196)
			(xy 104.281119 -276.369376) (xy 104.30832 -276.326362) (xy 104.342068 -276.288268) (xy 104.38149 -276.256081)
			(xy 104.425564 -276.230635) (xy 104.47315 -276.212588) (xy 104.523014 -276.202408) (xy 104.573866 -276.200359)
			(xy 104.624387 -276.206493) (xy 104.673271 -276.220653) (xy 104.71925 -276.24247) (xy 104.761134 -276.27138)
			(xy 104.797838 -276.306635) (xy 104.828411 -276.347321) (xy 104.852062 -276.392384) (xy 104.868178 -276.440658)
			(xy 104.876342 -276.490892) (xy 104.876854 -276.516338) (xy 104.876351 -276.541327) (xy 105.183414 -276.541327)
			(xy 105.183414 -276.491349) (xy 105.191233 -276.441986) (xy 105.206677 -276.394454) (xy 105.229367 -276.349922)
			(xy 105.258743 -276.309489) (xy 105.294083 -276.274149) (xy 105.334516 -276.244773) (xy 105.379048 -276.222083)
			(xy 105.42658 -276.206639) (xy 105.475943 -276.19882) (xy 105.525921 -276.19882) (xy 105.575284 -276.206639)
			(xy 105.622816 -276.222083) (xy 105.667348 -276.244773) (xy 105.707781 -276.274149) (xy 105.743121 -276.309489)
			(xy 105.772497 -276.349922) (xy 105.795187 -276.394454) (xy 105.810631 -276.441986) (xy 105.81845 -276.491349)
			(xy 105.81894 -276.516338) (xy 106.124751 -276.516338) (xy 106.128846 -276.46561) (xy 106.141025 -276.416196)
			(xy 106.160973 -276.369376) (xy 106.188174 -276.326362) (xy 106.221922 -276.288268) (xy 106.261344 -276.256081)
			(xy 106.305418 -276.230635) (xy 106.353004 -276.212588) (xy 106.402868 -276.202408) (xy 106.45372 -276.200359)
			(xy 106.504241 -276.206493) (xy 106.553125 -276.220653) (xy 106.599104 -276.24247) (xy 106.640988 -276.27138)
			(xy 106.677692 -276.306635) (xy 106.708265 -276.347321) (xy 106.731916 -276.392384) (xy 106.748032 -276.440658)
			(xy 106.756196 -276.490892) (xy 106.756708 -276.516338) (xy 107.064805 -276.516338) (xy 107.0689 -276.46561)
			(xy 107.081079 -276.416196) (xy 107.101027 -276.369376) (xy 107.128228 -276.326362) (xy 107.161976 -276.288268)
			(xy 107.201398 -276.256081) (xy 107.245472 -276.230635) (xy 107.293058 -276.212588) (xy 107.342922 -276.202408)
			(xy 107.393774 -276.200359) (xy 107.444295 -276.206493) (xy 107.493179 -276.220653) (xy 107.539158 -276.24247)
			(xy 107.581042 -276.27138) (xy 107.617746 -276.306635) (xy 107.648319 -276.347321) (xy 107.67197 -276.392384)
			(xy 107.688086 -276.440658) (xy 107.69625 -276.490892) (xy 107.696762 -276.516338) (xy 107.696259 -276.541327)
			(xy 108.003576 -276.541327) (xy 108.003576 -276.491349) (xy 108.011395 -276.441986) (xy 108.026839 -276.394454)
			(xy 108.049529 -276.349922) (xy 108.078905 -276.309489) (xy 108.114245 -276.274149) (xy 108.154678 -276.244773)
			(xy 108.19921 -276.222083) (xy 108.246742 -276.206639) (xy 108.296105 -276.19882) (xy 108.346083 -276.19882)
			(xy 108.395446 -276.206639) (xy 108.442978 -276.222083) (xy 108.48751 -276.244773) (xy 108.527943 -276.274149)
			(xy 108.563283 -276.309489) (xy 108.592659 -276.349922) (xy 108.615349 -276.394454) (xy 108.630793 -276.441986)
			(xy 108.638612 -276.491349) (xy 108.639102 -276.516338) (xy 108.638612 -276.541327) (xy 108.94363 -276.541327)
			(xy 108.94363 -276.491349) (xy 108.951449 -276.441986) (xy 108.966893 -276.394454) (xy 108.989583 -276.349922)
			(xy 109.018959 -276.309489) (xy 109.054299 -276.274149) (xy 109.094732 -276.244773) (xy 109.139264 -276.222083)
			(xy 109.186796 -276.206639) (xy 109.236159 -276.19882) (xy 109.286137 -276.19882) (xy 109.3355 -276.206639)
			(xy 109.383032 -276.222083) (xy 109.427564 -276.244773) (xy 109.467997 -276.274149) (xy 109.503337 -276.309489)
			(xy 109.532713 -276.349922) (xy 109.555403 -276.394454) (xy 109.570847 -276.441986) (xy 109.578666 -276.491349)
			(xy 109.579156 -276.516338) (xy 109.578666 -276.541327) (xy 109.88343 -276.541327) (xy 109.88343 -276.491349)
			(xy 109.891249 -276.441986) (xy 109.906693 -276.394454) (xy 109.929383 -276.349922) (xy 109.958759 -276.309489)
			(xy 109.994099 -276.274149) (xy 110.034532 -276.244773) (xy 110.079064 -276.222083) (xy 110.126596 -276.206639)
			(xy 110.175959 -276.19882) (xy 110.225937 -276.19882) (xy 110.2753 -276.206639) (xy 110.322832 -276.222083)
			(xy 110.367364 -276.244773) (xy 110.407797 -276.274149) (xy 110.443137 -276.309489) (xy 110.472513 -276.349922)
			(xy 110.495203 -276.394454) (xy 110.510647 -276.441986) (xy 110.518466 -276.491349) (xy 110.518956 -276.516338)
			(xy 110.518466 -276.541327) (xy 113.637296 -276.541327) (xy 113.637296 -276.491349) (xy 113.645115 -276.441986)
			(xy 113.660559 -276.394454) (xy 113.683249 -276.349922) (xy 113.712625 -276.309489) (xy 113.747965 -276.274149)
			(xy 113.788398 -276.244773) (xy 113.83293 -276.222083) (xy 113.880462 -276.206639) (xy 113.929825 -276.19882)
			(xy 113.979803 -276.19882) (xy 114.029166 -276.206639) (xy 114.076698 -276.222083) (xy 114.12123 -276.244773)
			(xy 114.161663 -276.274149) (xy 114.197003 -276.309489) (xy 114.226379 -276.349922) (xy 114.249069 -276.394454)
			(xy 114.264513 -276.441986) (xy 114.272332 -276.491349) (xy 114.272822 -276.516338) (xy 114.272332 -276.541327)
			(xy 114.577096 -276.541327) (xy 114.577096 -276.491349) (xy 114.584915 -276.441986) (xy 114.600359 -276.394454)
			(xy 114.623049 -276.349922) (xy 114.652425 -276.309489) (xy 114.687765 -276.274149) (xy 114.728198 -276.244773)
			(xy 114.77273 -276.222083) (xy 114.820262 -276.206639) (xy 114.869625 -276.19882) (xy 114.919603 -276.19882)
			(xy 114.968966 -276.206639) (xy 115.016498 -276.222083) (xy 115.06103 -276.244773) (xy 115.101463 -276.274149)
			(xy 115.136803 -276.309489) (xy 115.166179 -276.349922) (xy 115.188869 -276.394454) (xy 115.204313 -276.441986)
			(xy 115.212132 -276.491349) (xy 115.212622 -276.516338) (xy 115.212132 -276.541327) (xy 115.51715 -276.541327)
			(xy 115.51715 -276.491349) (xy 115.524969 -276.441986) (xy 115.540413 -276.394454) (xy 115.563103 -276.349922)
			(xy 115.592479 -276.309489) (xy 115.627819 -276.274149) (xy 115.668252 -276.244773) (xy 115.712784 -276.222083)
			(xy 115.760316 -276.206639) (xy 115.809679 -276.19882) (xy 115.859657 -276.19882) (xy 115.90902 -276.206639)
			(xy 115.956552 -276.222083) (xy 116.001084 -276.244773) (xy 116.041517 -276.274149) (xy 116.076857 -276.309489)
			(xy 116.106233 -276.349922) (xy 116.128923 -276.394454) (xy 116.144367 -276.441986) (xy 116.152186 -276.491349)
			(xy 116.152676 -276.516338) (xy 116.458487 -276.516338) (xy 116.462582 -276.46561) (xy 116.474761 -276.416196)
			(xy 116.494709 -276.369376) (xy 116.52191 -276.326362) (xy 116.555658 -276.288268) (xy 116.59508 -276.256081)
			(xy 116.639154 -276.230635) (xy 116.68674 -276.212588) (xy 116.736604 -276.202408) (xy 116.787456 -276.200359)
			(xy 116.837977 -276.206493) (xy 116.886861 -276.220653) (xy 116.93284 -276.24247) (xy 116.974724 -276.27138)
			(xy 117.011428 -276.306635) (xy 117.042001 -276.347321) (xy 117.065652 -276.392384) (xy 117.081768 -276.440658)
			(xy 117.089932 -276.490892) (xy 117.090444 -276.516338) (xy 117.398541 -276.516338) (xy 117.402636 -276.46561)
			(xy 117.414815 -276.416196) (xy 117.434763 -276.369376) (xy 117.461964 -276.326362) (xy 117.495712 -276.288268)
			(xy 117.535134 -276.256081) (xy 117.579208 -276.230635) (xy 117.626794 -276.212588) (xy 117.676658 -276.202408)
			(xy 117.72751 -276.200359) (xy 117.778031 -276.206493) (xy 117.826915 -276.220653) (xy 117.872894 -276.24247)
			(xy 117.914778 -276.27138) (xy 117.951482 -276.306635) (xy 117.982055 -276.347321) (xy 118.005706 -276.392384)
			(xy 118.021822 -276.440658) (xy 118.029986 -276.490892) (xy 118.030498 -276.516338) (xy 118.029995 -276.541327)
			(xy 118.337312 -276.541327) (xy 118.337312 -276.491349) (xy 118.345131 -276.441986) (xy 118.360575 -276.394454)
			(xy 118.383265 -276.349922) (xy 118.412641 -276.309489) (xy 118.447981 -276.274149) (xy 118.488414 -276.244773)
			(xy 118.532946 -276.222083) (xy 118.580478 -276.206639) (xy 118.629841 -276.19882) (xy 118.679819 -276.19882)
			(xy 118.729182 -276.206639) (xy 118.776714 -276.222083) (xy 118.821246 -276.244773) (xy 118.861679 -276.274149)
			(xy 118.897019 -276.309489) (xy 118.926395 -276.349922) (xy 118.949085 -276.394454) (xy 118.964529 -276.441986)
			(xy 118.972348 -276.491349) (xy 118.972838 -276.516338) (xy 119.278395 -276.516338) (xy 119.28249 -276.46561)
			(xy 119.294669 -276.416196) (xy 119.314617 -276.369376) (xy 119.341818 -276.326362) (xy 119.375566 -276.288268)
			(xy 119.414988 -276.256081) (xy 119.459062 -276.230635) (xy 119.506648 -276.212588) (xy 119.556512 -276.202408)
			(xy 119.607364 -276.200359) (xy 119.657885 -276.206493) (xy 119.706769 -276.220653) (xy 119.752748 -276.24247)
			(xy 119.794632 -276.27138) (xy 119.831336 -276.306635) (xy 119.861909 -276.347321) (xy 119.88556 -276.392384)
			(xy 119.901676 -276.440658) (xy 119.90984 -276.490892) (xy 119.910352 -276.516338) (xy 120.218449 -276.516338)
			(xy 120.222544 -276.46561) (xy 120.234723 -276.416196) (xy 120.254671 -276.369376) (xy 120.281872 -276.326362)
			(xy 120.31562 -276.288268) (xy 120.355042 -276.256081) (xy 120.399116 -276.230635) (xy 120.446702 -276.212588)
			(xy 120.496566 -276.202408) (xy 120.547418 -276.200359) (xy 120.597939 -276.206493) (xy 120.646823 -276.220653)
			(xy 120.692802 -276.24247) (xy 120.734686 -276.27138) (xy 120.77139 -276.306635) (xy 120.801963 -276.347321)
			(xy 120.825614 -276.392384) (xy 120.84173 -276.440658) (xy 120.849894 -276.490892) (xy 120.850406 -276.516338)
			(xy 120.849903 -276.541327) (xy 121.15722 -276.541327) (xy 121.15722 -276.491349) (xy 121.165039 -276.441986)
			(xy 121.180483 -276.394454) (xy 121.203173 -276.349922) (xy 121.232549 -276.309489) (xy 121.267889 -276.274149)
			(xy 121.308322 -276.244773) (xy 121.352854 -276.222083) (xy 121.400386 -276.206639) (xy 121.449749 -276.19882)
			(xy 121.499727 -276.19882) (xy 121.54909 -276.206639) (xy 121.596622 -276.222083) (xy 121.641154 -276.244773)
			(xy 121.681587 -276.274149) (xy 121.716927 -276.309489) (xy 121.746303 -276.349922) (xy 121.768993 -276.394454)
			(xy 121.784437 -276.441986) (xy 121.792256 -276.491349) (xy 121.792746 -276.516338) (xy 122.098557 -276.516338)
			(xy 122.102652 -276.46561) (xy 122.114831 -276.416196) (xy 122.134779 -276.369376) (xy 122.16198 -276.326362)
			(xy 122.195728 -276.288268) (xy 122.23515 -276.256081) (xy 122.279224 -276.230635) (xy 122.32681 -276.212588)
			(xy 122.376674 -276.202408) (xy 122.427526 -276.200359) (xy 122.478047 -276.206493) (xy 122.526931 -276.220653)
			(xy 122.57291 -276.24247) (xy 122.614794 -276.27138) (xy 122.651498 -276.306635) (xy 122.682071 -276.347321)
			(xy 122.705722 -276.392384) (xy 122.721838 -276.440658) (xy 122.730002 -276.490892) (xy 122.730514 -276.516338)
			(xy 123.038611 -276.516338) (xy 123.042706 -276.46561) (xy 123.054885 -276.416196) (xy 123.074833 -276.369376)
			(xy 123.102034 -276.326362) (xy 123.135782 -276.288268) (xy 123.175204 -276.256081) (xy 123.219278 -276.230635)
			(xy 123.266864 -276.212588) (xy 123.316728 -276.202408) (xy 123.36758 -276.200359) (xy 123.418101 -276.206493)
			(xy 123.466985 -276.220653) (xy 123.512964 -276.24247) (xy 123.554848 -276.27138) (xy 123.591552 -276.306635)
			(xy 123.622125 -276.347321) (xy 123.645776 -276.392384) (xy 123.661892 -276.440658) (xy 123.670056 -276.490892)
			(xy 123.670568 -276.516338) (xy 123.670065 -276.541327) (xy 123.977128 -276.541327) (xy 123.977128 -276.491349)
			(xy 123.984947 -276.441986) (xy 124.000391 -276.394454) (xy 124.023081 -276.349922) (xy 124.052457 -276.309489)
			(xy 124.087797 -276.274149) (xy 124.12823 -276.244773) (xy 124.172762 -276.222083) (xy 124.220294 -276.206639)
			(xy 124.269657 -276.19882) (xy 124.319635 -276.19882) (xy 124.368998 -276.206639) (xy 124.41653 -276.222083)
			(xy 124.461062 -276.244773) (xy 124.501495 -276.274149) (xy 124.536835 -276.309489) (xy 124.566211 -276.349922)
			(xy 124.588901 -276.394454) (xy 124.604345 -276.441986) (xy 124.612164 -276.491349) (xy 124.612654 -276.516338)
			(xy 124.918465 -276.516338) (xy 124.92256 -276.46561) (xy 124.934739 -276.416196) (xy 124.954687 -276.369376)
			(xy 124.981888 -276.326362) (xy 125.015636 -276.288268) (xy 125.055058 -276.256081) (xy 125.099132 -276.230635)
			(xy 125.146718 -276.212588) (xy 125.196582 -276.202408) (xy 125.247434 -276.200359) (xy 125.297955 -276.206493)
			(xy 125.346839 -276.220653) (xy 125.392818 -276.24247) (xy 125.434702 -276.27138) (xy 125.471406 -276.306635)
			(xy 125.501979 -276.347321) (xy 125.52563 -276.392384) (xy 125.541746 -276.440658) (xy 125.54991 -276.490892)
			(xy 125.550422 -276.516338) (xy 125.858519 -276.516338) (xy 125.862614 -276.46561) (xy 125.874793 -276.416196)
			(xy 125.894741 -276.369376) (xy 125.921942 -276.326362) (xy 125.95569 -276.288268) (xy 125.995112 -276.256081)
			(xy 126.039186 -276.230635) (xy 126.086772 -276.212588) (xy 126.136636 -276.202408) (xy 126.187488 -276.200359)
			(xy 126.238009 -276.206493) (xy 126.286893 -276.220653) (xy 126.332872 -276.24247) (xy 126.374756 -276.27138)
			(xy 126.41146 -276.306635) (xy 126.442033 -276.347321) (xy 126.465684 -276.392384) (xy 126.4818 -276.440658)
			(xy 126.489964 -276.490892) (xy 126.490476 -276.516338) (xy 126.489964 -276.541784) (xy 126.4818 -276.592018)
			(xy 126.465684 -276.640292) (xy 126.442033 -276.685355) (xy 126.41146 -276.726041) (xy 126.374756 -276.761296)
			(xy 126.332872 -276.790206) (xy 126.286893 -276.812023) (xy 126.238009 -276.826183) (xy 126.187488 -276.832317)
			(xy 126.136636 -276.830268) (xy 126.086772 -276.820088) (xy 126.039186 -276.802041) (xy 125.995112 -276.776595)
			(xy 125.95569 -276.744408) (xy 125.921942 -276.706314) (xy 125.894741 -276.6633) (xy 125.874793 -276.61648)
			(xy 125.862614 -276.567066) (xy 125.858519 -276.516338) (xy 125.550422 -276.516338) (xy 125.54991 -276.541784)
			(xy 125.541746 -276.592018) (xy 125.52563 -276.640292) (xy 125.501979 -276.685355) (xy 125.471406 -276.726041)
			(xy 125.434702 -276.761296) (xy 125.392818 -276.790206) (xy 125.346839 -276.812023) (xy 125.297955 -276.826183)
			(xy 125.247434 -276.832317) (xy 125.196582 -276.830268) (xy 125.146718 -276.820088) (xy 125.099132 -276.802041)
			(xy 125.055058 -276.776595) (xy 125.015636 -276.744408) (xy 124.981888 -276.706314) (xy 124.954687 -276.6633)
			(xy 124.934739 -276.61648) (xy 124.92256 -276.567066) (xy 124.918465 -276.516338) (xy 124.612654 -276.516338)
			(xy 124.612164 -276.541327) (xy 124.604345 -276.59069) (xy 124.588901 -276.638222) (xy 124.566211 -276.682754)
			(xy 124.536835 -276.723187) (xy 124.501495 -276.758527) (xy 124.461062 -276.787903) (xy 124.41653 -276.810593)
			(xy 124.368998 -276.826037) (xy 124.319635 -276.833856) (xy 124.269657 -276.833856) (xy 124.220294 -276.826037)
			(xy 124.172762 -276.810593) (xy 124.12823 -276.787903) (xy 124.087797 -276.758527) (xy 124.052457 -276.723187)
			(xy 124.023081 -276.682754) (xy 124.000391 -276.638222) (xy 123.984947 -276.59069) (xy 123.977128 -276.541327)
			(xy 123.670065 -276.541327) (xy 123.670056 -276.541784) (xy 123.661892 -276.592018) (xy 123.645776 -276.640292)
			(xy 123.622125 -276.685355) (xy 123.591552 -276.726041) (xy 123.554848 -276.761296) (xy 123.512964 -276.790206)
			(xy 123.466985 -276.812023) (xy 123.418101 -276.826183) (xy 123.36758 -276.832317) (xy 123.316728 -276.830268)
			(xy 123.266864 -276.820088) (xy 123.219278 -276.802041) (xy 123.175204 -276.776595) (xy 123.135782 -276.744408)
			(xy 123.102034 -276.706314) (xy 123.074833 -276.6633) (xy 123.054885 -276.61648) (xy 123.042706 -276.567066)
			(xy 123.038611 -276.516338) (xy 122.730514 -276.516338) (xy 122.730002 -276.541784) (xy 122.721838 -276.592018)
			(xy 122.705722 -276.640292) (xy 122.682071 -276.685355) (xy 122.651498 -276.726041) (xy 122.614794 -276.761296)
			(xy 122.57291 -276.790206) (xy 122.526931 -276.812023) (xy 122.478047 -276.826183) (xy 122.427526 -276.832317)
			(xy 122.376674 -276.830268) (xy 122.32681 -276.820088) (xy 122.279224 -276.802041) (xy 122.23515 -276.776595)
			(xy 122.195728 -276.744408) (xy 122.16198 -276.706314) (xy 122.134779 -276.6633) (xy 122.114831 -276.61648)
			(xy 122.102652 -276.567066) (xy 122.098557 -276.516338) (xy 121.792746 -276.516338) (xy 121.792256 -276.541327)
			(xy 121.784437 -276.59069) (xy 121.768993 -276.638222) (xy 121.746303 -276.682754) (xy 121.716927 -276.723187)
			(xy 121.681587 -276.758527) (xy 121.641154 -276.787903) (xy 121.596622 -276.810593) (xy 121.54909 -276.826037)
			(xy 121.499727 -276.833856) (xy 121.449749 -276.833856) (xy 121.400386 -276.826037) (xy 121.352854 -276.810593)
			(xy 121.308322 -276.787903) (xy 121.267889 -276.758527) (xy 121.232549 -276.723187) (xy 121.203173 -276.682754)
			(xy 121.180483 -276.638222) (xy 121.165039 -276.59069) (xy 121.15722 -276.541327) (xy 120.849903 -276.541327)
			(xy 120.849894 -276.541784) (xy 120.84173 -276.592018) (xy 120.825614 -276.640292) (xy 120.801963 -276.685355)
			(xy 120.77139 -276.726041) (xy 120.734686 -276.761296) (xy 120.692802 -276.790206) (xy 120.646823 -276.812023)
			(xy 120.597939 -276.826183) (xy 120.547418 -276.832317) (xy 120.496566 -276.830268) (xy 120.446702 -276.820088)
			(xy 120.399116 -276.802041) (xy 120.355042 -276.776595) (xy 120.31562 -276.744408) (xy 120.281872 -276.706314)
			(xy 120.254671 -276.6633) (xy 120.234723 -276.61648) (xy 120.222544 -276.567066) (xy 120.218449 -276.516338)
			(xy 119.910352 -276.516338) (xy 119.90984 -276.541784) (xy 119.901676 -276.592018) (xy 119.88556 -276.640292)
			(xy 119.861909 -276.685355) (xy 119.831336 -276.726041) (xy 119.794632 -276.761296) (xy 119.752748 -276.790206)
			(xy 119.706769 -276.812023) (xy 119.657885 -276.826183) (xy 119.607364 -276.832317) (xy 119.556512 -276.830268)
			(xy 119.506648 -276.820088) (xy 119.459062 -276.802041) (xy 119.414988 -276.776595) (xy 119.375566 -276.744408)
			(xy 119.341818 -276.706314) (xy 119.314617 -276.6633) (xy 119.294669 -276.61648) (xy 119.28249 -276.567066)
			(xy 119.278395 -276.516338) (xy 118.972838 -276.516338) (xy 118.972348 -276.541327) (xy 118.964529 -276.59069)
			(xy 118.949085 -276.638222) (xy 118.926395 -276.682754) (xy 118.897019 -276.723187) (xy 118.861679 -276.758527)
			(xy 118.821246 -276.787903) (xy 118.776714 -276.810593) (xy 118.729182 -276.826037) (xy 118.679819 -276.833856)
			(xy 118.629841 -276.833856) (xy 118.580478 -276.826037) (xy 118.532946 -276.810593) (xy 118.488414 -276.787903)
			(xy 118.447981 -276.758527) (xy 118.412641 -276.723187) (xy 118.383265 -276.682754) (xy 118.360575 -276.638222)
			(xy 118.345131 -276.59069) (xy 118.337312 -276.541327) (xy 118.029995 -276.541327) (xy 118.029986 -276.541784)
			(xy 118.021822 -276.592018) (xy 118.005706 -276.640292) (xy 117.982055 -276.685355) (xy 117.951482 -276.726041)
			(xy 117.914778 -276.761296) (xy 117.872894 -276.790206) (xy 117.826915 -276.812023) (xy 117.778031 -276.826183)
			(xy 117.72751 -276.832317) (xy 117.676658 -276.830268) (xy 117.626794 -276.820088) (xy 117.579208 -276.802041)
			(xy 117.535134 -276.776595) (xy 117.495712 -276.744408) (xy 117.461964 -276.706314) (xy 117.434763 -276.6633)
			(xy 117.414815 -276.61648) (xy 117.402636 -276.567066) (xy 117.398541 -276.516338) (xy 117.090444 -276.516338)
			(xy 117.089932 -276.541784) (xy 117.081768 -276.592018) (xy 117.065652 -276.640292) (xy 117.042001 -276.685355)
			(xy 117.011428 -276.726041) (xy 116.974724 -276.761296) (xy 116.93284 -276.790206) (xy 116.886861 -276.812023)
			(xy 116.837977 -276.826183) (xy 116.787456 -276.832317) (xy 116.736604 -276.830268) (xy 116.68674 -276.820088)
			(xy 116.639154 -276.802041) (xy 116.59508 -276.776595) (xy 116.555658 -276.744408) (xy 116.52191 -276.706314)
			(xy 116.494709 -276.6633) (xy 116.474761 -276.61648) (xy 116.462582 -276.567066) (xy 116.458487 -276.516338)
			(xy 116.152676 -276.516338) (xy 116.152186 -276.541327) (xy 116.144367 -276.59069) (xy 116.128923 -276.638222)
			(xy 116.106233 -276.682754) (xy 116.076857 -276.723187) (xy 116.041517 -276.758527) (xy 116.001084 -276.787903)
			(xy 115.956552 -276.810593) (xy 115.90902 -276.826037) (xy 115.859657 -276.833856) (xy 115.809679 -276.833856)
			(xy 115.760316 -276.826037) (xy 115.712784 -276.810593) (xy 115.668252 -276.787903) (xy 115.627819 -276.758527)
			(xy 115.592479 -276.723187) (xy 115.563103 -276.682754) (xy 115.540413 -276.638222) (xy 115.524969 -276.59069)
			(xy 115.51715 -276.541327) (xy 115.212132 -276.541327) (xy 115.204313 -276.59069) (xy 115.188869 -276.638222)
			(xy 115.166179 -276.682754) (xy 115.136803 -276.723187) (xy 115.101463 -276.758527) (xy 115.06103 -276.787903)
			(xy 115.016498 -276.810593) (xy 114.968966 -276.826037) (xy 114.919603 -276.833856) (xy 114.869625 -276.833856)
			(xy 114.820262 -276.826037) (xy 114.77273 -276.810593) (xy 114.728198 -276.787903) (xy 114.687765 -276.758527)
			(xy 114.652425 -276.723187) (xy 114.623049 -276.682754) (xy 114.600359 -276.638222) (xy 114.584915 -276.59069)
			(xy 114.577096 -276.541327) (xy 114.272332 -276.541327) (xy 114.264513 -276.59069) (xy 114.249069 -276.638222)
			(xy 114.226379 -276.682754) (xy 114.197003 -276.723187) (xy 114.161663 -276.758527) (xy 114.12123 -276.787903)
			(xy 114.076698 -276.810593) (xy 114.029166 -276.826037) (xy 113.979803 -276.833856) (xy 113.929825 -276.833856)
			(xy 113.880462 -276.826037) (xy 113.83293 -276.810593) (xy 113.788398 -276.787903) (xy 113.747965 -276.758527)
			(xy 113.712625 -276.723187) (xy 113.683249 -276.682754) (xy 113.660559 -276.638222) (xy 113.645115 -276.59069)
			(xy 113.637296 -276.541327) (xy 110.518466 -276.541327) (xy 110.510647 -276.59069) (xy 110.495203 -276.638222)
			(xy 110.472513 -276.682754) (xy 110.443137 -276.723187) (xy 110.407797 -276.758527) (xy 110.367364 -276.787903)
			(xy 110.322832 -276.810593) (xy 110.2753 -276.826037) (xy 110.225937 -276.833856) (xy 110.175959 -276.833856)
			(xy 110.126596 -276.826037) (xy 110.079064 -276.810593) (xy 110.034532 -276.787903) (xy 109.994099 -276.758527)
			(xy 109.958759 -276.723187) (xy 109.929383 -276.682754) (xy 109.906693 -276.638222) (xy 109.891249 -276.59069)
			(xy 109.88343 -276.541327) (xy 109.578666 -276.541327) (xy 109.570847 -276.59069) (xy 109.555403 -276.638222)
			(xy 109.532713 -276.682754) (xy 109.503337 -276.723187) (xy 109.467997 -276.758527) (xy 109.427564 -276.787903)
			(xy 109.383032 -276.810593) (xy 109.3355 -276.826037) (xy 109.286137 -276.833856) (xy 109.236159 -276.833856)
			(xy 109.186796 -276.826037) (xy 109.139264 -276.810593) (xy 109.094732 -276.787903) (xy 109.054299 -276.758527)
			(xy 109.018959 -276.723187) (xy 108.989583 -276.682754) (xy 108.966893 -276.638222) (xy 108.951449 -276.59069)
			(xy 108.94363 -276.541327) (xy 108.638612 -276.541327) (xy 108.630793 -276.59069) (xy 108.615349 -276.638222)
			(xy 108.592659 -276.682754) (xy 108.563283 -276.723187) (xy 108.527943 -276.758527) (xy 108.48751 -276.787903)
			(xy 108.442978 -276.810593) (xy 108.395446 -276.826037) (xy 108.346083 -276.833856) (xy 108.296105 -276.833856)
			(xy 108.246742 -276.826037) (xy 108.19921 -276.810593) (xy 108.154678 -276.787903) (xy 108.114245 -276.758527)
			(xy 108.078905 -276.723187) (xy 108.049529 -276.682754) (xy 108.026839 -276.638222) (xy 108.011395 -276.59069)
			(xy 108.003576 -276.541327) (xy 107.696259 -276.541327) (xy 107.69625 -276.541784) (xy 107.688086 -276.592018)
			(xy 107.67197 -276.640292) (xy 107.648319 -276.685355) (xy 107.617746 -276.726041) (xy 107.581042 -276.761296)
			(xy 107.539158 -276.790206) (xy 107.493179 -276.812023) (xy 107.444295 -276.826183) (xy 107.393774 -276.832317)
			(xy 107.342922 -276.830268) (xy 107.293058 -276.820088) (xy 107.245472 -276.802041) (xy 107.201398 -276.776595)
			(xy 107.161976 -276.744408) (xy 107.128228 -276.706314) (xy 107.101027 -276.6633) (xy 107.081079 -276.61648)
			(xy 107.0689 -276.567066) (xy 107.064805 -276.516338) (xy 106.756708 -276.516338) (xy 106.756196 -276.541784)
			(xy 106.748032 -276.592018) (xy 106.731916 -276.640292) (xy 106.708265 -276.685355) (xy 106.677692 -276.726041)
			(xy 106.640988 -276.761296) (xy 106.599104 -276.790206) (xy 106.553125 -276.812023) (xy 106.504241 -276.826183)
			(xy 106.45372 -276.832317) (xy 106.402868 -276.830268) (xy 106.353004 -276.820088) (xy 106.305418 -276.802041)
			(xy 106.261344 -276.776595) (xy 106.221922 -276.744408) (xy 106.188174 -276.706314) (xy 106.160973 -276.6633)
			(xy 106.141025 -276.61648) (xy 106.128846 -276.567066) (xy 106.124751 -276.516338) (xy 105.81894 -276.516338)
			(xy 105.81845 -276.541327) (xy 105.810631 -276.59069) (xy 105.795187 -276.638222) (xy 105.772497 -276.682754)
			(xy 105.743121 -276.723187) (xy 105.707781 -276.758527) (xy 105.667348 -276.787903) (xy 105.622816 -276.810593)
			(xy 105.575284 -276.826037) (xy 105.525921 -276.833856) (xy 105.475943 -276.833856) (xy 105.42658 -276.826037)
			(xy 105.379048 -276.810593) (xy 105.334516 -276.787903) (xy 105.294083 -276.758527) (xy 105.258743 -276.723187)
			(xy 105.229367 -276.682754) (xy 105.206677 -276.638222) (xy 105.191233 -276.59069) (xy 105.183414 -276.541327)
			(xy 104.876351 -276.541327) (xy 104.876342 -276.541784) (xy 104.868178 -276.592018) (xy 104.852062 -276.640292)
			(xy 104.828411 -276.685355) (xy 104.797838 -276.726041) (xy 104.761134 -276.761296) (xy 104.71925 -276.790206)
			(xy 104.673271 -276.812023) (xy 104.624387 -276.826183) (xy 104.573866 -276.832317) (xy 104.523014 -276.830268)
			(xy 104.47315 -276.820088) (xy 104.425564 -276.802041) (xy 104.38149 -276.776595) (xy 104.342068 -276.744408)
			(xy 104.30832 -276.706314) (xy 104.281119 -276.6633) (xy 104.261171 -276.61648) (xy 104.248992 -276.567066)
			(xy 104.244897 -276.516338) (xy 103.9368 -276.516338) (xy 103.936288 -276.541784) (xy 103.928124 -276.592018)
			(xy 103.912008 -276.640292) (xy 103.888357 -276.685355) (xy 103.857784 -276.726041) (xy 103.82108 -276.761296)
			(xy 103.779196 -276.790206) (xy 103.733217 -276.812023) (xy 103.684333 -276.826183) (xy 103.633812 -276.832317)
			(xy 103.58296 -276.830268) (xy 103.533096 -276.820088) (xy 103.48551 -276.802041) (xy 103.441436 -276.776595)
			(xy 103.402014 -276.744408) (xy 103.368266 -276.706314) (xy 103.341065 -276.6633) (xy 103.321117 -276.61648)
			(xy 103.308938 -276.567066) (xy 103.304843 -276.516338) (xy 102.999032 -276.516338) (xy 102.998542 -276.541327)
			(xy 102.990723 -276.59069) (xy 102.975279 -276.638222) (xy 102.952589 -276.682754) (xy 102.923213 -276.723187)
			(xy 102.887873 -276.758527) (xy 102.84744 -276.787903) (xy 102.802908 -276.810593) (xy 102.755376 -276.826037)
			(xy 102.706013 -276.833856) (xy 102.656035 -276.833856) (xy 102.606672 -276.826037) (xy 102.55914 -276.810593)
			(xy 102.514608 -276.787903) (xy 102.474175 -276.758527) (xy 102.438835 -276.723187) (xy 102.409459 -276.682754)
			(xy 102.386769 -276.638222) (xy 102.371325 -276.59069) (xy 102.363506 -276.541327) (xy 102.056189 -276.541327)
			(xy 102.05618 -276.541784) (xy 102.048016 -276.592018) (xy 102.0319 -276.640292) (xy 102.008249 -276.685355)
			(xy 101.977676 -276.726041) (xy 101.940972 -276.761296) (xy 101.899088 -276.790206) (xy 101.853109 -276.812023)
			(xy 101.804225 -276.826183) (xy 101.753704 -276.832317) (xy 101.702852 -276.830268) (xy 101.652988 -276.820088)
			(xy 101.605402 -276.802041) (xy 101.561328 -276.776595) (xy 101.521906 -276.744408) (xy 101.488158 -276.706314)
			(xy 101.460957 -276.6633) (xy 101.441009 -276.61648) (xy 101.42883 -276.567066) (xy 101.424735 -276.516338)
			(xy 101.116892 -276.516338) (xy 101.11638 -276.541784) (xy 101.108216 -276.592018) (xy 101.0921 -276.640292)
			(xy 101.068449 -276.685355) (xy 101.037876 -276.726041) (xy 101.001172 -276.761296) (xy 100.959288 -276.790206)
			(xy 100.913309 -276.812023) (xy 100.864425 -276.826183) (xy 100.813904 -276.832317) (xy 100.763052 -276.830268)
			(xy 100.713188 -276.820088) (xy 100.665602 -276.802041) (xy 100.621528 -276.776595) (xy 100.582106 -276.744408)
			(xy 100.548358 -276.706314) (xy 100.521157 -276.6633) (xy 100.501209 -276.61648) (xy 100.48903 -276.567066)
			(xy 100.484935 -276.516338) (xy 100.179124 -276.516338) (xy 100.178634 -276.541327) (xy 100.170815 -276.59069)
			(xy 100.155371 -276.638222) (xy 100.132681 -276.682754) (xy 100.103305 -276.723187) (xy 100.067965 -276.758527)
			(xy 100.027532 -276.787903) (xy 99.983 -276.810593) (xy 99.935468 -276.826037) (xy 99.886105 -276.833856)
			(xy 99.836127 -276.833856) (xy 99.786764 -276.826037) (xy 99.739232 -276.810593) (xy 99.6947 -276.787903)
			(xy 99.654267 -276.758527) (xy 99.618927 -276.723187) (xy 99.589551 -276.682754) (xy 99.566861 -276.638222)
			(xy 99.551417 -276.59069) (xy 99.543598 -276.541327) (xy 99.236281 -276.541327) (xy 99.236272 -276.541784)
			(xy 99.228108 -276.592018) (xy 99.211992 -276.640292) (xy 99.188341 -276.685355) (xy 99.157768 -276.726041)
			(xy 99.121064 -276.761296) (xy 99.07918 -276.790206) (xy 99.033201 -276.812023) (xy 98.984317 -276.826183)
			(xy 98.933796 -276.832317) (xy 98.882944 -276.830268) (xy 98.83308 -276.820088) (xy 98.785494 -276.802041)
			(xy 98.74142 -276.776595) (xy 98.701998 -276.744408) (xy 98.66825 -276.706314) (xy 98.641049 -276.6633)
			(xy 98.621101 -276.61648) (xy 98.608922 -276.567066) (xy 98.604827 -276.516338) (xy 98.29673 -276.516338)
			(xy 98.296218 -276.541784) (xy 98.288054 -276.592018) (xy 98.271938 -276.640292) (xy 98.248287 -276.685355)
			(xy 98.217714 -276.726041) (xy 98.18101 -276.761296) (xy 98.139126 -276.790206) (xy 98.093147 -276.812023)
			(xy 98.044263 -276.826183) (xy 97.993742 -276.832317) (xy 97.94289 -276.830268) (xy 97.893026 -276.820088)
			(xy 97.84544 -276.802041) (xy 97.801366 -276.776595) (xy 97.761944 -276.744408) (xy 97.728196 -276.706314)
			(xy 97.700995 -276.6633) (xy 97.681047 -276.61648) (xy 97.668868 -276.567066) (xy 97.664773 -276.516338)
			(xy 97.358962 -276.516338) (xy 97.358472 -276.541327) (xy 97.350653 -276.59069) (xy 97.335209 -276.638222)
			(xy 97.312519 -276.682754) (xy 97.283143 -276.723187) (xy 97.247803 -276.758527) (xy 97.20737 -276.787903)
			(xy 97.162838 -276.810593) (xy 97.115306 -276.826037) (xy 97.065943 -276.833856) (xy 97.015965 -276.833856)
			(xy 96.966602 -276.826037) (xy 96.91907 -276.810593) (xy 96.874538 -276.787903) (xy 96.834105 -276.758527)
			(xy 96.798765 -276.723187) (xy 96.769389 -276.682754) (xy 96.746699 -276.638222) (xy 96.731255 -276.59069)
			(xy 96.723436 -276.541327) (xy 96.416373 -276.541327) (xy 96.416364 -276.541784) (xy 96.4082 -276.592018)
			(xy 96.392084 -276.640292) (xy 96.368433 -276.685355) (xy 96.33786 -276.726041) (xy 96.301156 -276.761296)
			(xy 96.259272 -276.790206) (xy 96.213293 -276.812023) (xy 96.164409 -276.826183) (xy 96.113888 -276.832317)
			(xy 96.063036 -276.830268) (xy 96.013172 -276.820088) (xy 95.965586 -276.802041) (xy 95.921512 -276.776595)
			(xy 95.88209 -276.744408) (xy 95.848342 -276.706314) (xy 95.821141 -276.6633) (xy 95.801193 -276.61648)
			(xy 95.789014 -276.567066) (xy 95.784919 -276.516338) (xy 95.479108 -276.516338) (xy 95.478618 -276.541327)
			(xy 95.470799 -276.59069) (xy 95.455355 -276.638222) (xy 95.432665 -276.682754) (xy 95.403289 -276.723187)
			(xy 95.367949 -276.758527) (xy 95.327516 -276.787903) (xy 95.282984 -276.810593) (xy 95.235452 -276.826037)
			(xy 95.186089 -276.833856) (xy 95.136111 -276.833856) (xy 95.086748 -276.826037) (xy 95.039216 -276.810593)
			(xy 94.994684 -276.787903) (xy 94.954251 -276.758527) (xy 94.918911 -276.723187) (xy 94.889535 -276.682754)
			(xy 94.866845 -276.638222) (xy 94.851401 -276.59069) (xy 94.843582 -276.541327) (xy 94.538428 -276.541327)
			(xy 94.538369 -276.543348) (xy 94.53095 -276.589679) (xy 94.516802 -276.634417) (xy 94.496234 -276.67659)
			(xy 94.469691 -276.715282) (xy 94.437751 -276.749654) (xy 94.401106 -276.778958) (xy 94.381066 -276.791166)
			(xy 94.372684 -276.795992) (xy 94.349062 -276.825964) (xy 94.346268 -276.835362) (xy 94.332983 -276.878005)
			(xy 94.30048 -276.961207) (xy 94.261398 -277.041529) (xy 94.23908 -277.080218) (xy 94.216407 -277.117996)
			(xy 94.165932 -277.190219) (xy 94.138242 -277.22449) (xy 94.131628 -277.233201) (xy 94.12582 -277.254265)
			(xy 94.127066 -277.26513) (xy 94.129413 -277.280325) (xy 94.131955 -277.31097) (xy 94.132146 -277.326344)
			(xy 94.374711 -277.326344) (xy 94.378806 -277.275616) (xy 94.390985 -277.226202) (xy 94.410933 -277.179382)
			(xy 94.438134 -277.136368) (xy 94.471882 -277.098274) (xy 94.511304 -277.066087) (xy 94.555378 -277.040641)
			(xy 94.602964 -277.022594) (xy 94.652828 -277.012414) (xy 94.70368 -277.010365) (xy 94.754201 -277.016499)
			(xy 94.803085 -277.030659) (xy 94.849064 -277.052476) (xy 94.890948 -277.081386) (xy 94.927652 -277.116641)
			(xy 94.958225 -277.157327) (xy 94.981876 -277.20239) (xy 94.997992 -277.250664) (xy 95.006156 -277.300898)
			(xy 95.006668 -277.326344) (xy 95.314765 -277.326344) (xy 95.31886 -277.275616) (xy 95.331039 -277.226202)
			(xy 95.350987 -277.179382) (xy 95.378188 -277.136368) (xy 95.411936 -277.098274) (xy 95.451358 -277.066087)
			(xy 95.495432 -277.040641) (xy 95.543018 -277.022594) (xy 95.592882 -277.012414) (xy 95.643734 -277.010365)
			(xy 95.694255 -277.016499) (xy 95.743139 -277.030659) (xy 95.789118 -277.052476) (xy 95.831002 -277.081386)
			(xy 95.867706 -277.116641) (xy 95.898279 -277.157327) (xy 95.92193 -277.20239) (xy 95.938046 -277.250664)
			(xy 95.94621 -277.300898) (xy 95.946722 -277.326344) (xy 95.946219 -277.351333) (xy 96.253536 -277.351333)
			(xy 96.253536 -277.301355) (xy 96.261355 -277.251992) (xy 96.276799 -277.20446) (xy 96.299489 -277.159928)
			(xy 96.328865 -277.119495) (xy 96.364205 -277.084155) (xy 96.404638 -277.054779) (xy 96.44917 -277.032089)
			(xy 96.496702 -277.016645) (xy 96.546065 -277.008826) (xy 96.596043 -277.008826) (xy 96.645406 -277.016645)
			(xy 96.692938 -277.032089) (xy 96.73747 -277.054779) (xy 96.777903 -277.084155) (xy 96.813243 -277.119495)
			(xy 96.842619 -277.159928) (xy 96.865309 -277.20446) (xy 96.880753 -277.251992) (xy 96.888572 -277.301355)
			(xy 96.889062 -277.326344) (xy 96.888572 -277.351333) (xy 97.19359 -277.351333) (xy 97.19359 -277.301355)
			(xy 97.201409 -277.251992) (xy 97.216853 -277.20446) (xy 97.239543 -277.159928) (xy 97.268919 -277.119495)
			(xy 97.304259 -277.084155) (xy 97.344692 -277.054779) (xy 97.389224 -277.032089) (xy 97.436756 -277.016645)
			(xy 97.486119 -277.008826) (xy 97.536097 -277.008826) (xy 97.58546 -277.016645) (xy 97.632992 -277.032089)
			(xy 97.677524 -277.054779) (xy 97.717957 -277.084155) (xy 97.753297 -277.119495) (xy 97.782673 -277.159928)
			(xy 97.805363 -277.20446) (xy 97.820807 -277.251992) (xy 97.828626 -277.301355) (xy 97.829116 -277.326344)
			(xy 97.828626 -277.351333) (xy 98.133644 -277.351333) (xy 98.133644 -277.301355) (xy 98.141463 -277.251992)
			(xy 98.156907 -277.20446) (xy 98.179597 -277.159928) (xy 98.208973 -277.119495) (xy 98.244313 -277.084155)
			(xy 98.284746 -277.054779) (xy 98.329278 -277.032089) (xy 98.37681 -277.016645) (xy 98.426173 -277.008826)
			(xy 98.476151 -277.008826) (xy 98.525514 -277.016645) (xy 98.573046 -277.032089) (xy 98.617578 -277.054779)
			(xy 98.658011 -277.084155) (xy 98.693351 -277.119495) (xy 98.722727 -277.159928) (xy 98.745417 -277.20446)
			(xy 98.760861 -277.251992) (xy 98.76868 -277.301355) (xy 98.76917 -277.326344) (xy 98.76868 -277.351333)
			(xy 99.073444 -277.351333) (xy 99.073444 -277.301355) (xy 99.081263 -277.251992) (xy 99.096707 -277.20446)
			(xy 99.119397 -277.159928) (xy 99.148773 -277.119495) (xy 99.184113 -277.084155) (xy 99.224546 -277.054779)
			(xy 99.269078 -277.032089) (xy 99.31661 -277.016645) (xy 99.365973 -277.008826) (xy 99.415951 -277.008826)
			(xy 99.465314 -277.016645) (xy 99.512846 -277.032089) (xy 99.557378 -277.054779) (xy 99.597811 -277.084155)
			(xy 99.633151 -277.119495) (xy 99.662527 -277.159928) (xy 99.685217 -277.20446) (xy 99.700661 -277.251992)
			(xy 99.70848 -277.301355) (xy 99.70897 -277.326344) (xy 99.70848 -277.351333) (xy 100.013498 -277.351333)
			(xy 100.013498 -277.301355) (xy 100.021317 -277.251992) (xy 100.036761 -277.20446) (xy 100.059451 -277.159928)
			(xy 100.088827 -277.119495) (xy 100.124167 -277.084155) (xy 100.1646 -277.054779) (xy 100.209132 -277.032089)
			(xy 100.256664 -277.016645) (xy 100.306027 -277.008826) (xy 100.356005 -277.008826) (xy 100.405368 -277.016645)
			(xy 100.4529 -277.032089) (xy 100.497432 -277.054779) (xy 100.537865 -277.084155) (xy 100.573205 -277.119495)
			(xy 100.602581 -277.159928) (xy 100.625271 -277.20446) (xy 100.640715 -277.251992) (xy 100.648534 -277.301355)
			(xy 100.649024 -277.326344) (xy 100.648534 -277.351333) (xy 100.953552 -277.351333) (xy 100.953552 -277.301355)
			(xy 100.961371 -277.251992) (xy 100.976815 -277.20446) (xy 100.999505 -277.159928) (xy 101.028881 -277.119495)
			(xy 101.064221 -277.084155) (xy 101.104654 -277.054779) (xy 101.149186 -277.032089) (xy 101.196718 -277.016645)
			(xy 101.246081 -277.008826) (xy 101.296059 -277.008826) (xy 101.345422 -277.016645) (xy 101.392954 -277.032089)
			(xy 101.437486 -277.054779) (xy 101.477919 -277.084155) (xy 101.513259 -277.119495) (xy 101.542635 -277.159928)
			(xy 101.565325 -277.20446) (xy 101.580769 -277.251992) (xy 101.588588 -277.301355) (xy 101.589078 -277.326344)
			(xy 101.588588 -277.351333) (xy 101.893606 -277.351333) (xy 101.893606 -277.301355) (xy 101.901425 -277.251992)
			(xy 101.916869 -277.20446) (xy 101.939559 -277.159928) (xy 101.968935 -277.119495) (xy 102.004275 -277.084155)
			(xy 102.044708 -277.054779) (xy 102.08924 -277.032089) (xy 102.136772 -277.016645) (xy 102.186135 -277.008826)
			(xy 102.236113 -277.008826) (xy 102.285476 -277.016645) (xy 102.333008 -277.032089) (xy 102.37754 -277.054779)
			(xy 102.417973 -277.084155) (xy 102.453313 -277.119495) (xy 102.482689 -277.159928) (xy 102.505379 -277.20446)
			(xy 102.520823 -277.251992) (xy 102.528642 -277.301355) (xy 102.529132 -277.326344) (xy 102.528642 -277.351333)
			(xy 102.83366 -277.351333) (xy 102.83366 -277.301355) (xy 102.841479 -277.251992) (xy 102.856923 -277.20446)
			(xy 102.879613 -277.159928) (xy 102.908989 -277.119495) (xy 102.944329 -277.084155) (xy 102.984762 -277.054779)
			(xy 103.029294 -277.032089) (xy 103.076826 -277.016645) (xy 103.126189 -277.008826) (xy 103.176167 -277.008826)
			(xy 103.22553 -277.016645) (xy 103.273062 -277.032089) (xy 103.317594 -277.054779) (xy 103.358027 -277.084155)
			(xy 103.393367 -277.119495) (xy 103.422743 -277.159928) (xy 103.445433 -277.20446) (xy 103.460877 -277.251992)
			(xy 103.468696 -277.301355) (xy 103.469186 -277.326344) (xy 103.468696 -277.351333) (xy 103.77346 -277.351333)
			(xy 103.77346 -277.301355) (xy 103.781279 -277.251992) (xy 103.796723 -277.20446) (xy 103.819413 -277.159928)
			(xy 103.848789 -277.119495) (xy 103.884129 -277.084155) (xy 103.924562 -277.054779) (xy 103.969094 -277.032089)
			(xy 104.016626 -277.016645) (xy 104.065989 -277.008826) (xy 104.115967 -277.008826) (xy 104.16533 -277.016645)
			(xy 104.212862 -277.032089) (xy 104.257394 -277.054779) (xy 104.297827 -277.084155) (xy 104.333167 -277.119495)
			(xy 104.362543 -277.159928) (xy 104.385233 -277.20446) (xy 104.400677 -277.251992) (xy 104.408496 -277.301355)
			(xy 104.408986 -277.326344) (xy 104.408496 -277.351333) (xy 104.713514 -277.351333) (xy 104.713514 -277.301355)
			(xy 104.721333 -277.251992) (xy 104.736777 -277.20446) (xy 104.759467 -277.159928) (xy 104.788843 -277.119495)
			(xy 104.824183 -277.084155) (xy 104.864616 -277.054779) (xy 104.909148 -277.032089) (xy 104.95668 -277.016645)
			(xy 105.006043 -277.008826) (xy 105.056021 -277.008826) (xy 105.105384 -277.016645) (xy 105.152916 -277.032089)
			(xy 105.197448 -277.054779) (xy 105.237881 -277.084155) (xy 105.273221 -277.119495) (xy 105.302597 -277.159928)
			(xy 105.325287 -277.20446) (xy 105.340731 -277.251992) (xy 105.34855 -277.301355) (xy 105.34904 -277.326344)
			(xy 105.34855 -277.351333) (xy 105.653568 -277.351333) (xy 105.653568 -277.301355) (xy 105.661387 -277.251992)
			(xy 105.676831 -277.20446) (xy 105.699521 -277.159928) (xy 105.728897 -277.119495) (xy 105.764237 -277.084155)
			(xy 105.80467 -277.054779) (xy 105.849202 -277.032089) (xy 105.896734 -277.016645) (xy 105.946097 -277.008826)
			(xy 105.996075 -277.008826) (xy 106.045438 -277.016645) (xy 106.09297 -277.032089) (xy 106.137502 -277.054779)
			(xy 106.177935 -277.084155) (xy 106.213275 -277.119495) (xy 106.242651 -277.159928) (xy 106.265341 -277.20446)
			(xy 106.280785 -277.251992) (xy 106.288604 -277.301355) (xy 106.289094 -277.326344) (xy 106.288604 -277.351333)
			(xy 106.593622 -277.351333) (xy 106.593622 -277.301355) (xy 106.601441 -277.251992) (xy 106.616885 -277.20446)
			(xy 106.639575 -277.159928) (xy 106.668951 -277.119495) (xy 106.704291 -277.084155) (xy 106.744724 -277.054779)
			(xy 106.789256 -277.032089) (xy 106.836788 -277.016645) (xy 106.886151 -277.008826) (xy 106.936129 -277.008826)
			(xy 106.985492 -277.016645) (xy 107.033024 -277.032089) (xy 107.077556 -277.054779) (xy 107.117989 -277.084155)
			(xy 107.153329 -277.119495) (xy 107.182705 -277.159928) (xy 107.205395 -277.20446) (xy 107.220839 -277.251992)
			(xy 107.228658 -277.301355) (xy 107.229148 -277.326344) (xy 107.228658 -277.351333) (xy 107.533422 -277.351333)
			(xy 107.533422 -277.301355) (xy 107.541241 -277.251992) (xy 107.556685 -277.20446) (xy 107.579375 -277.159928)
			(xy 107.608751 -277.119495) (xy 107.644091 -277.084155) (xy 107.684524 -277.054779) (xy 107.729056 -277.032089)
			(xy 107.776588 -277.016645) (xy 107.825951 -277.008826) (xy 107.875929 -277.008826) (xy 107.925292 -277.016645)
			(xy 107.972824 -277.032089) (xy 108.017356 -277.054779) (xy 108.057789 -277.084155) (xy 108.093129 -277.119495)
			(xy 108.122505 -277.159928) (xy 108.145195 -277.20446) (xy 108.160639 -277.251992) (xy 108.168458 -277.301355)
			(xy 108.168948 -277.326344) (xy 108.474759 -277.326344) (xy 108.478854 -277.275616) (xy 108.491033 -277.226202)
			(xy 108.510981 -277.179382) (xy 108.538182 -277.136368) (xy 108.57193 -277.098274) (xy 108.611352 -277.066087)
			(xy 108.655426 -277.040641) (xy 108.703012 -277.022594) (xy 108.752876 -277.012414) (xy 108.803728 -277.010365)
			(xy 108.854249 -277.016499) (xy 108.903133 -277.030659) (xy 108.949112 -277.052476) (xy 108.990996 -277.081386)
			(xy 109.0277 -277.116641) (xy 109.058273 -277.157327) (xy 109.081924 -277.20239) (xy 109.09804 -277.250664)
			(xy 109.106204 -277.300898) (xy 109.106716 -277.326344) (xy 109.414813 -277.326344) (xy 109.418908 -277.275616)
			(xy 109.431087 -277.226202) (xy 109.451035 -277.179382) (xy 109.478236 -277.136368) (xy 109.511984 -277.098274)
			(xy 109.551406 -277.066087) (xy 109.59548 -277.040641) (xy 109.643066 -277.022594) (xy 109.69293 -277.012414)
			(xy 109.743782 -277.010365) (xy 109.794303 -277.016499) (xy 109.843187 -277.030659) (xy 109.889166 -277.052476)
			(xy 109.93105 -277.081386) (xy 109.967754 -277.116641) (xy 109.998327 -277.157327) (xy 110.021978 -277.20239)
			(xy 110.038094 -277.250664) (xy 110.046258 -277.300898) (xy 110.04677 -277.326344) (xy 110.046267 -277.351333)
			(xy 110.353584 -277.351333) (xy 110.353584 -277.301355) (xy 110.361403 -277.251992) (xy 110.376847 -277.20446)
			(xy 110.399537 -277.159928) (xy 110.428913 -277.119495) (xy 110.464253 -277.084155) (xy 110.504686 -277.054779)
			(xy 110.549218 -277.032089) (xy 110.59675 -277.016645) (xy 110.646113 -277.008826) (xy 110.696091 -277.008826)
			(xy 110.745454 -277.016645) (xy 110.792986 -277.032089) (xy 110.837518 -277.054779) (xy 110.877951 -277.084155)
			(xy 110.913291 -277.119495) (xy 110.942667 -277.159928) (xy 110.965357 -277.20446) (xy 110.980801 -277.251992)
			(xy 110.98862 -277.301355) (xy 110.98911 -277.326344) (xy 110.98862 -277.351333) (xy 113.167142 -277.351333)
			(xy 113.167142 -277.301355) (xy 113.174961 -277.251992) (xy 113.190405 -277.20446) (xy 113.213095 -277.159928)
			(xy 113.242471 -277.119495) (xy 113.277811 -277.084155) (xy 113.318244 -277.054779) (xy 113.362776 -277.032089)
			(xy 113.410308 -277.016645) (xy 113.459671 -277.008826) (xy 113.509649 -277.008826) (xy 113.559012 -277.016645)
			(xy 113.606544 -277.032089) (xy 113.651076 -277.054779) (xy 113.691509 -277.084155) (xy 113.726849 -277.119495)
			(xy 113.756225 -277.159928) (xy 113.778915 -277.20446) (xy 113.794359 -277.251992) (xy 113.802178 -277.301355)
			(xy 113.802668 -277.326344) (xy 114.108479 -277.326344) (xy 114.112574 -277.275616) (xy 114.124753 -277.226202)
			(xy 114.144701 -277.179382) (xy 114.171902 -277.136368) (xy 114.20565 -277.098274) (xy 114.245072 -277.066087)
			(xy 114.289146 -277.040641) (xy 114.336732 -277.022594) (xy 114.386596 -277.012414) (xy 114.437448 -277.010365)
			(xy 114.487969 -277.016499) (xy 114.536853 -277.030659) (xy 114.582832 -277.052476) (xy 114.624716 -277.081386)
			(xy 114.66142 -277.116641) (xy 114.691993 -277.157327) (xy 114.715644 -277.20239) (xy 114.73176 -277.250664)
			(xy 114.739924 -277.300898) (xy 114.740436 -277.326344) (xy 115.048533 -277.326344) (xy 115.052628 -277.275616)
			(xy 115.064807 -277.226202) (xy 115.084755 -277.179382) (xy 115.111956 -277.136368) (xy 115.145704 -277.098274)
			(xy 115.185126 -277.066087) (xy 115.2292 -277.040641) (xy 115.276786 -277.022594) (xy 115.32665 -277.012414)
			(xy 115.377502 -277.010365) (xy 115.428023 -277.016499) (xy 115.476907 -277.030659) (xy 115.522886 -277.052476)
			(xy 115.56477 -277.081386) (xy 115.601474 -277.116641) (xy 115.632047 -277.157327) (xy 115.655698 -277.20239)
			(xy 115.671814 -277.250664) (xy 115.679978 -277.300898) (xy 115.68049 -277.326344) (xy 115.679987 -277.351333)
			(xy 115.987304 -277.351333) (xy 115.987304 -277.301355) (xy 115.995123 -277.251992) (xy 116.010567 -277.20446)
			(xy 116.033257 -277.159928) (xy 116.062633 -277.119495) (xy 116.097973 -277.084155) (xy 116.138406 -277.054779)
			(xy 116.182938 -277.032089) (xy 116.23047 -277.016645) (xy 116.279833 -277.008826) (xy 116.329811 -277.008826)
			(xy 116.379174 -277.016645) (xy 116.426706 -277.032089) (xy 116.471238 -277.054779) (xy 116.511671 -277.084155)
			(xy 116.547011 -277.119495) (xy 116.576387 -277.159928) (xy 116.599077 -277.20446) (xy 116.614521 -277.251992)
			(xy 116.62234 -277.301355) (xy 116.62283 -277.326344) (xy 116.62234 -277.351333) (xy 116.927104 -277.351333)
			(xy 116.927104 -277.301355) (xy 116.934923 -277.251992) (xy 116.950367 -277.20446) (xy 116.973057 -277.159928)
			(xy 117.002433 -277.119495) (xy 117.037773 -277.084155) (xy 117.078206 -277.054779) (xy 117.122738 -277.032089)
			(xy 117.17027 -277.016645) (xy 117.219633 -277.008826) (xy 117.269611 -277.008826) (xy 117.318974 -277.016645)
			(xy 117.366506 -277.032089) (xy 117.411038 -277.054779) (xy 117.451471 -277.084155) (xy 117.486811 -277.119495)
			(xy 117.516187 -277.159928) (xy 117.538877 -277.20446) (xy 117.554321 -277.251992) (xy 117.56214 -277.301355)
			(xy 117.56263 -277.326344) (xy 117.56214 -277.351333) (xy 117.867158 -277.351333) (xy 117.867158 -277.301355)
			(xy 117.874977 -277.251992) (xy 117.890421 -277.20446) (xy 117.913111 -277.159928) (xy 117.942487 -277.119495)
			(xy 117.977827 -277.084155) (xy 118.01826 -277.054779) (xy 118.062792 -277.032089) (xy 118.110324 -277.016645)
			(xy 118.159687 -277.008826) (xy 118.209665 -277.008826) (xy 118.259028 -277.016645) (xy 118.30656 -277.032089)
			(xy 118.351092 -277.054779) (xy 118.391525 -277.084155) (xy 118.426865 -277.119495) (xy 118.456241 -277.159928)
			(xy 118.478931 -277.20446) (xy 118.494375 -277.251992) (xy 118.502194 -277.301355) (xy 118.502684 -277.326344)
			(xy 118.502194 -277.351333) (xy 118.807212 -277.351333) (xy 118.807212 -277.301355) (xy 118.815031 -277.251992)
			(xy 118.830475 -277.20446) (xy 118.853165 -277.159928) (xy 118.882541 -277.119495) (xy 118.917881 -277.084155)
			(xy 118.958314 -277.054779) (xy 119.002846 -277.032089) (xy 119.050378 -277.016645) (xy 119.099741 -277.008826)
			(xy 119.149719 -277.008826) (xy 119.199082 -277.016645) (xy 119.246614 -277.032089) (xy 119.291146 -277.054779)
			(xy 119.331579 -277.084155) (xy 119.366919 -277.119495) (xy 119.396295 -277.159928) (xy 119.418985 -277.20446)
			(xy 119.434429 -277.251992) (xy 119.442248 -277.301355) (xy 119.442738 -277.326344) (xy 119.442248 -277.351333)
			(xy 119.747266 -277.351333) (xy 119.747266 -277.301355) (xy 119.755085 -277.251992) (xy 119.770529 -277.20446)
			(xy 119.793219 -277.159928) (xy 119.822595 -277.119495) (xy 119.857935 -277.084155) (xy 119.898368 -277.054779)
			(xy 119.9429 -277.032089) (xy 119.990432 -277.016645) (xy 120.039795 -277.008826) (xy 120.089773 -277.008826)
			(xy 120.139136 -277.016645) (xy 120.186668 -277.032089) (xy 120.2312 -277.054779) (xy 120.271633 -277.084155)
			(xy 120.306973 -277.119495) (xy 120.336349 -277.159928) (xy 120.359039 -277.20446) (xy 120.374483 -277.251992)
			(xy 120.382302 -277.301355) (xy 120.382792 -277.326344) (xy 120.382302 -277.351333) (xy 120.68732 -277.351333)
			(xy 120.68732 -277.301355) (xy 120.695139 -277.251992) (xy 120.710583 -277.20446) (xy 120.733273 -277.159928)
			(xy 120.762649 -277.119495) (xy 120.797989 -277.084155) (xy 120.838422 -277.054779) (xy 120.882954 -277.032089)
			(xy 120.930486 -277.016645) (xy 120.979849 -277.008826) (xy 121.029827 -277.008826) (xy 121.07919 -277.016645)
			(xy 121.126722 -277.032089) (xy 121.171254 -277.054779) (xy 121.211687 -277.084155) (xy 121.247027 -277.119495)
			(xy 121.276403 -277.159928) (xy 121.299093 -277.20446) (xy 121.314537 -277.251992) (xy 121.322356 -277.301355)
			(xy 121.322846 -277.326344) (xy 121.322356 -277.351333) (xy 121.62712 -277.351333) (xy 121.62712 -277.301355)
			(xy 121.634939 -277.251992) (xy 121.650383 -277.20446) (xy 121.673073 -277.159928) (xy 121.702449 -277.119495)
			(xy 121.737789 -277.084155) (xy 121.778222 -277.054779) (xy 121.822754 -277.032089) (xy 121.870286 -277.016645)
			(xy 121.919649 -277.008826) (xy 121.969627 -277.008826) (xy 122.01899 -277.016645) (xy 122.066522 -277.032089)
			(xy 122.111054 -277.054779) (xy 122.151487 -277.084155) (xy 122.186827 -277.119495) (xy 122.216203 -277.159928)
			(xy 122.238893 -277.20446) (xy 122.254337 -277.251992) (xy 122.262156 -277.301355) (xy 122.262646 -277.326344)
			(xy 122.262156 -277.351333) (xy 122.567174 -277.351333) (xy 122.567174 -277.301355) (xy 122.574993 -277.251992)
			(xy 122.590437 -277.20446) (xy 122.613127 -277.159928) (xy 122.642503 -277.119495) (xy 122.677843 -277.084155)
			(xy 122.718276 -277.054779) (xy 122.762808 -277.032089) (xy 122.81034 -277.016645) (xy 122.859703 -277.008826)
			(xy 122.909681 -277.008826) (xy 122.959044 -277.016645) (xy 123.006576 -277.032089) (xy 123.051108 -277.054779)
			(xy 123.091541 -277.084155) (xy 123.126881 -277.119495) (xy 123.156257 -277.159928) (xy 123.178947 -277.20446)
			(xy 123.194391 -277.251992) (xy 123.20221 -277.301355) (xy 123.2027 -277.326344) (xy 123.20221 -277.351333)
			(xy 123.507228 -277.351333) (xy 123.507228 -277.301355) (xy 123.515047 -277.251992) (xy 123.530491 -277.20446)
			(xy 123.553181 -277.159928) (xy 123.582557 -277.119495) (xy 123.617897 -277.084155) (xy 123.65833 -277.054779)
			(xy 123.702862 -277.032089) (xy 123.750394 -277.016645) (xy 123.799757 -277.008826) (xy 123.849735 -277.008826)
			(xy 123.899098 -277.016645) (xy 123.94663 -277.032089) (xy 123.991162 -277.054779) (xy 124.031595 -277.084155)
			(xy 124.066935 -277.119495) (xy 124.096311 -277.159928) (xy 124.119001 -277.20446) (xy 124.134445 -277.251992)
			(xy 124.142264 -277.301355) (xy 124.142754 -277.326344) (xy 124.142264 -277.351333) (xy 124.447282 -277.351333)
			(xy 124.447282 -277.301355) (xy 124.455101 -277.251992) (xy 124.470545 -277.20446) (xy 124.493235 -277.159928)
			(xy 124.522611 -277.119495) (xy 124.557951 -277.084155) (xy 124.598384 -277.054779) (xy 124.642916 -277.032089)
			(xy 124.690448 -277.016645) (xy 124.739811 -277.008826) (xy 124.789789 -277.008826) (xy 124.839152 -277.016645)
			(xy 124.886684 -277.032089) (xy 124.931216 -277.054779) (xy 124.971649 -277.084155) (xy 125.006989 -277.119495)
			(xy 125.036365 -277.159928) (xy 125.059055 -277.20446) (xy 125.074499 -277.251992) (xy 125.082318 -277.301355)
			(xy 125.082808 -277.326344) (xy 125.082318 -277.351333) (xy 125.387336 -277.351333) (xy 125.387336 -277.301355)
			(xy 125.395155 -277.251992) (xy 125.410599 -277.20446) (xy 125.433289 -277.159928) (xy 125.462665 -277.119495)
			(xy 125.498005 -277.084155) (xy 125.538438 -277.054779) (xy 125.58297 -277.032089) (xy 125.630502 -277.016645)
			(xy 125.679865 -277.008826) (xy 125.729843 -277.008826) (xy 125.779206 -277.016645) (xy 125.826738 -277.032089)
			(xy 125.87127 -277.054779) (xy 125.911703 -277.084155) (xy 125.947043 -277.119495) (xy 125.976419 -277.159928)
			(xy 125.999109 -277.20446) (xy 126.014553 -277.251992) (xy 126.022372 -277.301355) (xy 126.022862 -277.326344)
			(xy 126.022372 -277.351333) (xy 126.014553 -277.400696) (xy 125.999109 -277.448228) (xy 125.976419 -277.49276)
			(xy 125.947043 -277.533193) (xy 125.911703 -277.568533) (xy 125.87127 -277.597909) (xy 125.826738 -277.620599)
			(xy 125.779206 -277.636043) (xy 125.729843 -277.643862) (xy 125.679865 -277.643862) (xy 125.630502 -277.636043)
			(xy 125.58297 -277.620599) (xy 125.538438 -277.597909) (xy 125.498005 -277.568533) (xy 125.462665 -277.533193)
			(xy 125.433289 -277.49276) (xy 125.410599 -277.448228) (xy 125.395155 -277.400696) (xy 125.387336 -277.351333)
			(xy 125.082318 -277.351333) (xy 125.074499 -277.400696) (xy 125.059055 -277.448228) (xy 125.036365 -277.49276)
			(xy 125.006989 -277.533193) (xy 124.971649 -277.568533) (xy 124.931216 -277.597909) (xy 124.886684 -277.620599)
			(xy 124.839152 -277.636043) (xy 124.789789 -277.643862) (xy 124.739811 -277.643862) (xy 124.690448 -277.636043)
			(xy 124.642916 -277.620599) (xy 124.598384 -277.597909) (xy 124.557951 -277.568533) (xy 124.522611 -277.533193)
			(xy 124.493235 -277.49276) (xy 124.470545 -277.448228) (xy 124.455101 -277.400696) (xy 124.447282 -277.351333)
			(xy 124.142264 -277.351333) (xy 124.134445 -277.400696) (xy 124.119001 -277.448228) (xy 124.096311 -277.49276)
			(xy 124.066935 -277.533193) (xy 124.031595 -277.568533) (xy 123.991162 -277.597909) (xy 123.94663 -277.620599)
			(xy 123.899098 -277.636043) (xy 123.849735 -277.643862) (xy 123.799757 -277.643862) (xy 123.750394 -277.636043)
			(xy 123.702862 -277.620599) (xy 123.65833 -277.597909) (xy 123.617897 -277.568533) (xy 123.582557 -277.533193)
			(xy 123.553181 -277.49276) (xy 123.530491 -277.448228) (xy 123.515047 -277.400696) (xy 123.507228 -277.351333)
			(xy 123.20221 -277.351333) (xy 123.194391 -277.400696) (xy 123.178947 -277.448228) (xy 123.156257 -277.49276)
			(xy 123.126881 -277.533193) (xy 123.091541 -277.568533) (xy 123.051108 -277.597909) (xy 123.006576 -277.620599)
			(xy 122.959044 -277.636043) (xy 122.909681 -277.643862) (xy 122.859703 -277.643862) (xy 122.81034 -277.636043)
			(xy 122.762808 -277.620599) (xy 122.718276 -277.597909) (xy 122.677843 -277.568533) (xy 122.642503 -277.533193)
			(xy 122.613127 -277.49276) (xy 122.590437 -277.448228) (xy 122.574993 -277.400696) (xy 122.567174 -277.351333)
			(xy 122.262156 -277.351333) (xy 122.254337 -277.400696) (xy 122.238893 -277.448228) (xy 122.216203 -277.49276)
			(xy 122.186827 -277.533193) (xy 122.151487 -277.568533) (xy 122.111054 -277.597909) (xy 122.066522 -277.620599)
			(xy 122.01899 -277.636043) (xy 121.969627 -277.643862) (xy 121.919649 -277.643862) (xy 121.870286 -277.636043)
			(xy 121.822754 -277.620599) (xy 121.778222 -277.597909) (xy 121.737789 -277.568533) (xy 121.702449 -277.533193)
			(xy 121.673073 -277.49276) (xy 121.650383 -277.448228) (xy 121.634939 -277.400696) (xy 121.62712 -277.351333)
			(xy 121.322356 -277.351333) (xy 121.314537 -277.400696) (xy 121.299093 -277.448228) (xy 121.276403 -277.49276)
			(xy 121.247027 -277.533193) (xy 121.211687 -277.568533) (xy 121.171254 -277.597909) (xy 121.126722 -277.620599)
			(xy 121.07919 -277.636043) (xy 121.029827 -277.643862) (xy 120.979849 -277.643862) (xy 120.930486 -277.636043)
			(xy 120.882954 -277.620599) (xy 120.838422 -277.597909) (xy 120.797989 -277.568533) (xy 120.762649 -277.533193)
			(xy 120.733273 -277.49276) (xy 120.710583 -277.448228) (xy 120.695139 -277.400696) (xy 120.68732 -277.351333)
			(xy 120.382302 -277.351333) (xy 120.374483 -277.400696) (xy 120.359039 -277.448228) (xy 120.336349 -277.49276)
			(xy 120.306973 -277.533193) (xy 120.271633 -277.568533) (xy 120.2312 -277.597909) (xy 120.186668 -277.620599)
			(xy 120.139136 -277.636043) (xy 120.089773 -277.643862) (xy 120.039795 -277.643862) (xy 119.990432 -277.636043)
			(xy 119.9429 -277.620599) (xy 119.898368 -277.597909) (xy 119.857935 -277.568533) (xy 119.822595 -277.533193)
			(xy 119.793219 -277.49276) (xy 119.770529 -277.448228) (xy 119.755085 -277.400696) (xy 119.747266 -277.351333)
			(xy 119.442248 -277.351333) (xy 119.434429 -277.400696) (xy 119.418985 -277.448228) (xy 119.396295 -277.49276)
			(xy 119.366919 -277.533193) (xy 119.331579 -277.568533) (xy 119.291146 -277.597909) (xy 119.246614 -277.620599)
			(xy 119.199082 -277.636043) (xy 119.149719 -277.643862) (xy 119.099741 -277.643862) (xy 119.050378 -277.636043)
			(xy 119.002846 -277.620599) (xy 118.958314 -277.597909) (xy 118.917881 -277.568533) (xy 118.882541 -277.533193)
			(xy 118.853165 -277.49276) (xy 118.830475 -277.448228) (xy 118.815031 -277.400696) (xy 118.807212 -277.351333)
			(xy 118.502194 -277.351333) (xy 118.494375 -277.400696) (xy 118.478931 -277.448228) (xy 118.456241 -277.49276)
			(xy 118.426865 -277.533193) (xy 118.391525 -277.568533) (xy 118.351092 -277.597909) (xy 118.30656 -277.620599)
			(xy 118.259028 -277.636043) (xy 118.209665 -277.643862) (xy 118.159687 -277.643862) (xy 118.110324 -277.636043)
			(xy 118.062792 -277.620599) (xy 118.01826 -277.597909) (xy 117.977827 -277.568533) (xy 117.942487 -277.533193)
			(xy 117.913111 -277.49276) (xy 117.890421 -277.448228) (xy 117.874977 -277.400696) (xy 117.867158 -277.351333)
			(xy 117.56214 -277.351333) (xy 117.554321 -277.400696) (xy 117.538877 -277.448228) (xy 117.516187 -277.49276)
			(xy 117.486811 -277.533193) (xy 117.451471 -277.568533) (xy 117.411038 -277.597909) (xy 117.366506 -277.620599)
			(xy 117.318974 -277.636043) (xy 117.269611 -277.643862) (xy 117.219633 -277.643862) (xy 117.17027 -277.636043)
			(xy 117.122738 -277.620599) (xy 117.078206 -277.597909) (xy 117.037773 -277.568533) (xy 117.002433 -277.533193)
			(xy 116.973057 -277.49276) (xy 116.950367 -277.448228) (xy 116.934923 -277.400696) (xy 116.927104 -277.351333)
			(xy 116.62234 -277.351333) (xy 116.614521 -277.400696) (xy 116.599077 -277.448228) (xy 116.576387 -277.49276)
			(xy 116.547011 -277.533193) (xy 116.511671 -277.568533) (xy 116.471238 -277.597909) (xy 116.426706 -277.620599)
			(xy 116.379174 -277.636043) (xy 116.329811 -277.643862) (xy 116.279833 -277.643862) (xy 116.23047 -277.636043)
			(xy 116.182938 -277.620599) (xy 116.138406 -277.597909) (xy 116.097973 -277.568533) (xy 116.062633 -277.533193)
			(xy 116.033257 -277.49276) (xy 116.010567 -277.448228) (xy 115.995123 -277.400696) (xy 115.987304 -277.351333)
			(xy 115.679987 -277.351333) (xy 115.679978 -277.35179) (xy 115.671814 -277.402024) (xy 115.655698 -277.450298)
			(xy 115.632047 -277.495361) (xy 115.601474 -277.536047) (xy 115.56477 -277.571302) (xy 115.522886 -277.600212)
			(xy 115.476907 -277.622029) (xy 115.428023 -277.636189) (xy 115.377502 -277.642323) (xy 115.32665 -277.640274)
			(xy 115.276786 -277.630094) (xy 115.2292 -277.612047) (xy 115.185126 -277.586601) (xy 115.145704 -277.554414)
			(xy 115.111956 -277.51632) (xy 115.084755 -277.473306) (xy 115.064807 -277.426486) (xy 115.052628 -277.377072)
			(xy 115.048533 -277.326344) (xy 114.740436 -277.326344) (xy 114.739924 -277.35179) (xy 114.73176 -277.402024)
			(xy 114.715644 -277.450298) (xy 114.691993 -277.495361) (xy 114.66142 -277.536047) (xy 114.624716 -277.571302)
			(xy 114.582832 -277.600212) (xy 114.536853 -277.622029) (xy 114.487969 -277.636189) (xy 114.437448 -277.642323)
			(xy 114.386596 -277.640274) (xy 114.336732 -277.630094) (xy 114.289146 -277.612047) (xy 114.245072 -277.586601)
			(xy 114.20565 -277.554414) (xy 114.171902 -277.51632) (xy 114.144701 -277.473306) (xy 114.124753 -277.426486)
			(xy 114.112574 -277.377072) (xy 114.108479 -277.326344) (xy 113.802668 -277.326344) (xy 113.802178 -277.351333)
			(xy 113.794359 -277.400696) (xy 113.778915 -277.448228) (xy 113.756225 -277.49276) (xy 113.726849 -277.533193)
			(xy 113.691509 -277.568533) (xy 113.651076 -277.597909) (xy 113.606544 -277.620599) (xy 113.559012 -277.636043)
			(xy 113.509649 -277.643862) (xy 113.459671 -277.643862) (xy 113.410308 -277.636043) (xy 113.362776 -277.620599)
			(xy 113.318244 -277.597909) (xy 113.277811 -277.568533) (xy 113.242471 -277.533193) (xy 113.213095 -277.49276)
			(xy 113.190405 -277.448228) (xy 113.174961 -277.400696) (xy 113.167142 -277.351333) (xy 110.98862 -277.351333)
			(xy 110.980801 -277.400696) (xy 110.965357 -277.448228) (xy 110.942667 -277.49276) (xy 110.913291 -277.533193)
			(xy 110.877951 -277.568533) (xy 110.837518 -277.597909) (xy 110.792986 -277.620599) (xy 110.745454 -277.636043)
			(xy 110.696091 -277.643862) (xy 110.646113 -277.643862) (xy 110.59675 -277.636043) (xy 110.549218 -277.620599)
			(xy 110.504686 -277.597909) (xy 110.464253 -277.568533) (xy 110.428913 -277.533193) (xy 110.399537 -277.49276)
			(xy 110.376847 -277.448228) (xy 110.361403 -277.400696) (xy 110.353584 -277.351333) (xy 110.046267 -277.351333)
			(xy 110.046258 -277.35179) (xy 110.038094 -277.402024) (xy 110.021978 -277.450298) (xy 109.998327 -277.495361)
			(xy 109.967754 -277.536047) (xy 109.93105 -277.571302) (xy 109.889166 -277.600212) (xy 109.843187 -277.622029)
			(xy 109.794303 -277.636189) (xy 109.743782 -277.642323) (xy 109.69293 -277.640274) (xy 109.643066 -277.630094)
			(xy 109.59548 -277.612047) (xy 109.551406 -277.586601) (xy 109.511984 -277.554414) (xy 109.478236 -277.51632)
			(xy 109.451035 -277.473306) (xy 109.431087 -277.426486) (xy 109.418908 -277.377072) (xy 109.414813 -277.326344)
			(xy 109.106716 -277.326344) (xy 109.106204 -277.35179) (xy 109.09804 -277.402024) (xy 109.081924 -277.450298)
			(xy 109.058273 -277.495361) (xy 109.0277 -277.536047) (xy 108.990996 -277.571302) (xy 108.949112 -277.600212)
			(xy 108.903133 -277.622029) (xy 108.854249 -277.636189) (xy 108.803728 -277.642323) (xy 108.752876 -277.640274)
			(xy 108.703012 -277.630094) (xy 108.655426 -277.612047) (xy 108.611352 -277.586601) (xy 108.57193 -277.554414)
			(xy 108.538182 -277.51632) (xy 108.510981 -277.473306) (xy 108.491033 -277.426486) (xy 108.478854 -277.377072)
			(xy 108.474759 -277.326344) (xy 108.168948 -277.326344) (xy 108.168458 -277.351333) (xy 108.160639 -277.400696)
			(xy 108.145195 -277.448228) (xy 108.122505 -277.49276) (xy 108.093129 -277.533193) (xy 108.057789 -277.568533)
			(xy 108.017356 -277.597909) (xy 107.972824 -277.620599) (xy 107.925292 -277.636043) (xy 107.875929 -277.643862)
			(xy 107.825951 -277.643862) (xy 107.776588 -277.636043) (xy 107.729056 -277.620599) (xy 107.684524 -277.597909)
			(xy 107.644091 -277.568533) (xy 107.608751 -277.533193) (xy 107.579375 -277.49276) (xy 107.556685 -277.448228)
			(xy 107.541241 -277.400696) (xy 107.533422 -277.351333) (xy 107.228658 -277.351333) (xy 107.220839 -277.400696)
			(xy 107.205395 -277.448228) (xy 107.182705 -277.49276) (xy 107.153329 -277.533193) (xy 107.117989 -277.568533)
			(xy 107.077556 -277.597909) (xy 107.033024 -277.620599) (xy 106.985492 -277.636043) (xy 106.936129 -277.643862)
			(xy 106.886151 -277.643862) (xy 106.836788 -277.636043) (xy 106.789256 -277.620599) (xy 106.744724 -277.597909)
			(xy 106.704291 -277.568533) (xy 106.668951 -277.533193) (xy 106.639575 -277.49276) (xy 106.616885 -277.448228)
			(xy 106.601441 -277.400696) (xy 106.593622 -277.351333) (xy 106.288604 -277.351333) (xy 106.280785 -277.400696)
			(xy 106.265341 -277.448228) (xy 106.242651 -277.49276) (xy 106.213275 -277.533193) (xy 106.177935 -277.568533)
			(xy 106.137502 -277.597909) (xy 106.09297 -277.620599) (xy 106.045438 -277.636043) (xy 105.996075 -277.643862)
			(xy 105.946097 -277.643862) (xy 105.896734 -277.636043) (xy 105.849202 -277.620599) (xy 105.80467 -277.597909)
			(xy 105.764237 -277.568533) (xy 105.728897 -277.533193) (xy 105.699521 -277.49276) (xy 105.676831 -277.448228)
			(xy 105.661387 -277.400696) (xy 105.653568 -277.351333) (xy 105.34855 -277.351333) (xy 105.340731 -277.400696)
			(xy 105.325287 -277.448228) (xy 105.302597 -277.49276) (xy 105.273221 -277.533193) (xy 105.237881 -277.568533)
			(xy 105.197448 -277.597909) (xy 105.152916 -277.620599) (xy 105.105384 -277.636043) (xy 105.056021 -277.643862)
			(xy 105.006043 -277.643862) (xy 104.95668 -277.636043) (xy 104.909148 -277.620599) (xy 104.864616 -277.597909)
			(xy 104.824183 -277.568533) (xy 104.788843 -277.533193) (xy 104.759467 -277.49276) (xy 104.736777 -277.448228)
			(xy 104.721333 -277.400696) (xy 104.713514 -277.351333) (xy 104.408496 -277.351333) (xy 104.400677 -277.400696)
			(xy 104.385233 -277.448228) (xy 104.362543 -277.49276) (xy 104.333167 -277.533193) (xy 104.297827 -277.568533)
			(xy 104.257394 -277.597909) (xy 104.212862 -277.620599) (xy 104.16533 -277.636043) (xy 104.115967 -277.643862)
			(xy 104.065989 -277.643862) (xy 104.016626 -277.636043) (xy 103.969094 -277.620599) (xy 103.924562 -277.597909)
			(xy 103.884129 -277.568533) (xy 103.848789 -277.533193) (xy 103.819413 -277.49276) (xy 103.796723 -277.448228)
			(xy 103.781279 -277.400696) (xy 103.77346 -277.351333) (xy 103.468696 -277.351333) (xy 103.460877 -277.400696)
			(xy 103.445433 -277.448228) (xy 103.422743 -277.49276) (xy 103.393367 -277.533193) (xy 103.358027 -277.568533)
			(xy 103.317594 -277.597909) (xy 103.273062 -277.620599) (xy 103.22553 -277.636043) (xy 103.176167 -277.643862)
			(xy 103.126189 -277.643862) (xy 103.076826 -277.636043) (xy 103.029294 -277.620599) (xy 102.984762 -277.597909)
			(xy 102.944329 -277.568533) (xy 102.908989 -277.533193) (xy 102.879613 -277.49276) (xy 102.856923 -277.448228)
			(xy 102.841479 -277.400696) (xy 102.83366 -277.351333) (xy 102.528642 -277.351333) (xy 102.520823 -277.400696)
			(xy 102.505379 -277.448228) (xy 102.482689 -277.49276) (xy 102.453313 -277.533193) (xy 102.417973 -277.568533)
			(xy 102.37754 -277.597909) (xy 102.333008 -277.620599) (xy 102.285476 -277.636043) (xy 102.236113 -277.643862)
			(xy 102.186135 -277.643862) (xy 102.136772 -277.636043) (xy 102.08924 -277.620599) (xy 102.044708 -277.597909)
			(xy 102.004275 -277.568533) (xy 101.968935 -277.533193) (xy 101.939559 -277.49276) (xy 101.916869 -277.448228)
			(xy 101.901425 -277.400696) (xy 101.893606 -277.351333) (xy 101.588588 -277.351333) (xy 101.580769 -277.400696)
			(xy 101.565325 -277.448228) (xy 101.542635 -277.49276) (xy 101.513259 -277.533193) (xy 101.477919 -277.568533)
			(xy 101.437486 -277.597909) (xy 101.392954 -277.620599) (xy 101.345422 -277.636043) (xy 101.296059 -277.643862)
			(xy 101.246081 -277.643862) (xy 101.196718 -277.636043) (xy 101.149186 -277.620599) (xy 101.104654 -277.597909)
			(xy 101.064221 -277.568533) (xy 101.028881 -277.533193) (xy 100.999505 -277.49276) (xy 100.976815 -277.448228)
			(xy 100.961371 -277.400696) (xy 100.953552 -277.351333) (xy 100.648534 -277.351333) (xy 100.640715 -277.400696)
			(xy 100.625271 -277.448228) (xy 100.602581 -277.49276) (xy 100.573205 -277.533193) (xy 100.537865 -277.568533)
			(xy 100.497432 -277.597909) (xy 100.4529 -277.620599) (xy 100.405368 -277.636043) (xy 100.356005 -277.643862)
			(xy 100.306027 -277.643862) (xy 100.256664 -277.636043) (xy 100.209132 -277.620599) (xy 100.1646 -277.597909)
			(xy 100.124167 -277.568533) (xy 100.088827 -277.533193) (xy 100.059451 -277.49276) (xy 100.036761 -277.448228)
			(xy 100.021317 -277.400696) (xy 100.013498 -277.351333) (xy 99.70848 -277.351333) (xy 99.700661 -277.400696)
			(xy 99.685217 -277.448228) (xy 99.662527 -277.49276) (xy 99.633151 -277.533193) (xy 99.597811 -277.568533)
			(xy 99.557378 -277.597909) (xy 99.512846 -277.620599) (xy 99.465314 -277.636043) (xy 99.415951 -277.643862)
			(xy 99.365973 -277.643862) (xy 99.31661 -277.636043) (xy 99.269078 -277.620599) (xy 99.224546 -277.597909)
			(xy 99.184113 -277.568533) (xy 99.148773 -277.533193) (xy 99.119397 -277.49276) (xy 99.096707 -277.448228)
			(xy 99.081263 -277.400696) (xy 99.073444 -277.351333) (xy 98.76868 -277.351333) (xy 98.760861 -277.400696)
			(xy 98.745417 -277.448228) (xy 98.722727 -277.49276) (xy 98.693351 -277.533193) (xy 98.658011 -277.568533)
			(xy 98.617578 -277.597909) (xy 98.573046 -277.620599) (xy 98.525514 -277.636043) (xy 98.476151 -277.643862)
			(xy 98.426173 -277.643862) (xy 98.37681 -277.636043) (xy 98.329278 -277.620599) (xy 98.284746 -277.597909)
			(xy 98.244313 -277.568533) (xy 98.208973 -277.533193) (xy 98.179597 -277.49276) (xy 98.156907 -277.448228)
			(xy 98.141463 -277.400696) (xy 98.133644 -277.351333) (xy 97.828626 -277.351333) (xy 97.820807 -277.400696)
			(xy 97.805363 -277.448228) (xy 97.782673 -277.49276) (xy 97.753297 -277.533193) (xy 97.717957 -277.568533)
			(xy 97.677524 -277.597909) (xy 97.632992 -277.620599) (xy 97.58546 -277.636043) (xy 97.536097 -277.643862)
			(xy 97.486119 -277.643862) (xy 97.436756 -277.636043) (xy 97.389224 -277.620599) (xy 97.344692 -277.597909)
			(xy 97.304259 -277.568533) (xy 97.268919 -277.533193) (xy 97.239543 -277.49276) (xy 97.216853 -277.448228)
			(xy 97.201409 -277.400696) (xy 97.19359 -277.351333) (xy 96.888572 -277.351333) (xy 96.880753 -277.400696)
			(xy 96.865309 -277.448228) (xy 96.842619 -277.49276) (xy 96.813243 -277.533193) (xy 96.777903 -277.568533)
			(xy 96.73747 -277.597909) (xy 96.692938 -277.620599) (xy 96.645406 -277.636043) (xy 96.596043 -277.643862)
			(xy 96.546065 -277.643862) (xy 96.496702 -277.636043) (xy 96.44917 -277.620599) (xy 96.404638 -277.597909)
			(xy 96.364205 -277.568533) (xy 96.328865 -277.533193) (xy 96.299489 -277.49276) (xy 96.276799 -277.448228)
			(xy 96.261355 -277.400696) (xy 96.253536 -277.351333) (xy 95.946219 -277.351333) (xy 95.94621 -277.35179)
			(xy 95.938046 -277.402024) (xy 95.92193 -277.450298) (xy 95.898279 -277.495361) (xy 95.867706 -277.536047)
			(xy 95.831002 -277.571302) (xy 95.789118 -277.600212) (xy 95.743139 -277.622029) (xy 95.694255 -277.636189)
			(xy 95.643734 -277.642323) (xy 95.592882 -277.640274) (xy 95.543018 -277.630094) (xy 95.495432 -277.612047)
			(xy 95.451358 -277.586601) (xy 95.411936 -277.554414) (xy 95.378188 -277.51632) (xy 95.350987 -277.473306)
			(xy 95.331039 -277.426486) (xy 95.31886 -277.377072) (xy 95.314765 -277.326344) (xy 95.006668 -277.326344)
			(xy 95.006156 -277.35179) (xy 94.997992 -277.402024) (xy 94.981876 -277.450298) (xy 94.958225 -277.495361)
			(xy 94.927652 -277.536047) (xy 94.890948 -277.571302) (xy 94.849064 -277.600212) (xy 94.803085 -277.622029)
			(xy 94.754201 -277.636189) (xy 94.70368 -277.642323) (xy 94.652828 -277.640274) (xy 94.602964 -277.630094)
			(xy 94.555378 -277.612047) (xy 94.511304 -277.586601) (xy 94.471882 -277.554414) (xy 94.438134 -277.51632)
			(xy 94.410933 -277.473306) (xy 94.390985 -277.426486) (xy 94.378806 -277.377072) (xy 94.374711 -277.326344)
			(xy 94.132146 -277.326344) (xy 94.131609 -277.355334) (xy 94.122838 -277.412646) (xy 94.105491 -277.46797)
			(xy 94.079966 -277.520029) (xy 94.046853 -277.567623) (xy 94.027244 -277.58898) (xy 94.020386 -277.596092)
			(xy 94.013274 -277.614126) (xy 94.013274 -277.638002) (xy 94.01342 -277.643871) (xy 94.016107 -277.655297)
			(xy 94.018608 -277.660608) (xy 94.021402 -277.666196) (xy 94.022672 -277.668228) (xy 94.038405 -277.693771)
			(xy 94.066751 -277.74665) (xy 94.079314 -277.773892) (xy 94.083124 -277.782274) (xy 94.100904 -277.800308)
			(xy 94.107 -277.806658) (xy 94.144338 -277.824946) (xy 94.158308 -277.82393) (xy 94.16415 -277.823676)
			(xy 94.166944 -277.823168) (xy 94.180361 -277.820954) (xy 94.207449 -277.818539) (xy 94.221046 -277.818342)
			(xy 94.246029 -277.818836) (xy 94.295379 -277.826658) (xy 94.342897 -277.842104) (xy 94.387415 -277.864793)
			(xy 94.427836 -277.894166) (xy 94.463164 -277.929499) (xy 94.492531 -277.969924) (xy 94.515213 -278.014445)
			(xy 94.530652 -278.061966) (xy 94.538468 -278.111317) (xy 94.538468 -278.161283) (xy 94.538459 -278.161339)
			(xy 94.843582 -278.161339) (xy 94.843582 -278.111361) (xy 94.851401 -278.061998) (xy 94.866845 -278.014466)
			(xy 94.889535 -277.969934) (xy 94.918911 -277.929501) (xy 94.954251 -277.894161) (xy 94.994684 -277.864785)
			(xy 95.039216 -277.842095) (xy 95.086748 -277.826651) (xy 95.136111 -277.818832) (xy 95.186089 -277.818832)
			(xy 95.235452 -277.826651) (xy 95.282984 -277.842095) (xy 95.327516 -277.864785) (xy 95.367949 -277.894161)
			(xy 95.403289 -277.929501) (xy 95.432665 -277.969934) (xy 95.455355 -278.014466) (xy 95.470799 -278.061998)
			(xy 95.478618 -278.111361) (xy 95.479108 -278.13635) (xy 95.784919 -278.13635) (xy 95.789014 -278.085622)
			(xy 95.801193 -278.036208) (xy 95.821141 -277.989388) (xy 95.848342 -277.946374) (xy 95.88209 -277.90828)
			(xy 95.921512 -277.876093) (xy 95.965586 -277.850647) (xy 96.013172 -277.8326) (xy 96.063036 -277.82242)
			(xy 96.113888 -277.820371) (xy 96.164409 -277.826505) (xy 96.213293 -277.840665) (xy 96.259272 -277.862482)
			(xy 96.301156 -277.891392) (xy 96.33786 -277.926647) (xy 96.368433 -277.967333) (xy 96.392084 -278.012396)
			(xy 96.4082 -278.06067) (xy 96.416364 -278.110904) (xy 96.416876 -278.13635) (xy 96.416373 -278.161339)
			(xy 96.723436 -278.161339) (xy 96.723436 -278.111361) (xy 96.731255 -278.061998) (xy 96.746699 -278.014466)
			(xy 96.769389 -277.969934) (xy 96.798765 -277.929501) (xy 96.834105 -277.894161) (xy 96.874538 -277.864785)
			(xy 96.91907 -277.842095) (xy 96.966602 -277.826651) (xy 97.015965 -277.818832) (xy 97.065943 -277.818832)
			(xy 97.115306 -277.826651) (xy 97.162838 -277.842095) (xy 97.20737 -277.864785) (xy 97.247803 -277.894161)
			(xy 97.283143 -277.929501) (xy 97.312519 -277.969934) (xy 97.335209 -278.014466) (xy 97.350653 -278.061998)
			(xy 97.358472 -278.111361) (xy 97.358962 -278.13635) (xy 97.664773 -278.13635) (xy 97.668868 -278.085622)
			(xy 97.681047 -278.036208) (xy 97.700995 -277.989388) (xy 97.728196 -277.946374) (xy 97.761944 -277.90828)
			(xy 97.801366 -277.876093) (xy 97.84544 -277.850647) (xy 97.893026 -277.8326) (xy 97.94289 -277.82242)
			(xy 97.993742 -277.820371) (xy 98.044263 -277.826505) (xy 98.093147 -277.840665) (xy 98.139126 -277.862482)
			(xy 98.18101 -277.891392) (xy 98.217714 -277.926647) (xy 98.248287 -277.967333) (xy 98.271938 -278.012396)
			(xy 98.288054 -278.06067) (xy 98.296218 -278.110904) (xy 98.29673 -278.13635) (xy 98.604827 -278.13635)
			(xy 98.608922 -278.085622) (xy 98.621101 -278.036208) (xy 98.641049 -277.989388) (xy 98.66825 -277.946374)
			(xy 98.701998 -277.90828) (xy 98.74142 -277.876093) (xy 98.785494 -277.850647) (xy 98.83308 -277.8326)
			(xy 98.882944 -277.82242) (xy 98.933796 -277.820371) (xy 98.984317 -277.826505) (xy 99.033201 -277.840665)
			(xy 99.07918 -277.862482) (xy 99.121064 -277.891392) (xy 99.157768 -277.926647) (xy 99.188341 -277.967333)
			(xy 99.211992 -278.012396) (xy 99.228108 -278.06067) (xy 99.236272 -278.110904) (xy 99.236784 -278.13635)
			(xy 99.236281 -278.161339) (xy 99.543598 -278.161339) (xy 99.543598 -278.111361) (xy 99.551417 -278.061998)
			(xy 99.566861 -278.014466) (xy 99.589551 -277.969934) (xy 99.618927 -277.929501) (xy 99.654267 -277.894161)
			(xy 99.6947 -277.864785) (xy 99.739232 -277.842095) (xy 99.786764 -277.826651) (xy 99.836127 -277.818832)
			(xy 99.886105 -277.818832) (xy 99.935468 -277.826651) (xy 99.983 -277.842095) (xy 100.027532 -277.864785)
			(xy 100.067965 -277.894161) (xy 100.103305 -277.929501) (xy 100.132681 -277.969934) (xy 100.155371 -278.014466)
			(xy 100.170815 -278.061998) (xy 100.178634 -278.111361) (xy 100.179124 -278.13635) (xy 100.484935 -278.13635)
			(xy 100.48903 -278.085622) (xy 100.501209 -278.036208) (xy 100.521157 -277.989388) (xy 100.548358 -277.946374)
			(xy 100.582106 -277.90828) (xy 100.621528 -277.876093) (xy 100.665602 -277.850647) (xy 100.713188 -277.8326)
			(xy 100.763052 -277.82242) (xy 100.813904 -277.820371) (xy 100.864425 -277.826505) (xy 100.913309 -277.840665)
			(xy 100.959288 -277.862482) (xy 101.001172 -277.891392) (xy 101.037876 -277.926647) (xy 101.068449 -277.967333)
			(xy 101.0921 -278.012396) (xy 101.108216 -278.06067) (xy 101.11638 -278.110904) (xy 101.116892 -278.13635)
			(xy 101.424735 -278.13635) (xy 101.42883 -278.085622) (xy 101.441009 -278.036208) (xy 101.460957 -277.989388)
			(xy 101.488158 -277.946374) (xy 101.521906 -277.90828) (xy 101.561328 -277.876093) (xy 101.605402 -277.850647)
			(xy 101.652988 -277.8326) (xy 101.702852 -277.82242) (xy 101.753704 -277.820371) (xy 101.804225 -277.826505)
			(xy 101.853109 -277.840665) (xy 101.899088 -277.862482) (xy 101.940972 -277.891392) (xy 101.977676 -277.926647)
			(xy 102.008249 -277.967333) (xy 102.0319 -278.012396) (xy 102.048016 -278.06067) (xy 102.05618 -278.110904)
			(xy 102.056692 -278.13635) (xy 102.056189 -278.161339) (xy 102.363506 -278.161339) (xy 102.363506 -278.111361)
			(xy 102.371325 -278.061998) (xy 102.386769 -278.014466) (xy 102.409459 -277.969934) (xy 102.438835 -277.929501)
			(xy 102.474175 -277.894161) (xy 102.514608 -277.864785) (xy 102.55914 -277.842095) (xy 102.606672 -277.826651)
			(xy 102.656035 -277.818832) (xy 102.706013 -277.818832) (xy 102.755376 -277.826651) (xy 102.802908 -277.842095)
			(xy 102.84744 -277.864785) (xy 102.887873 -277.894161) (xy 102.923213 -277.929501) (xy 102.952589 -277.969934)
			(xy 102.975279 -278.014466) (xy 102.990723 -278.061998) (xy 102.998542 -278.111361) (xy 102.999032 -278.13635)
			(xy 103.304843 -278.13635) (xy 103.308938 -278.085622) (xy 103.321117 -278.036208) (xy 103.341065 -277.989388)
			(xy 103.368266 -277.946374) (xy 103.402014 -277.90828) (xy 103.441436 -277.876093) (xy 103.48551 -277.850647)
			(xy 103.533096 -277.8326) (xy 103.58296 -277.82242) (xy 103.633812 -277.820371) (xy 103.684333 -277.826505)
			(xy 103.733217 -277.840665) (xy 103.779196 -277.862482) (xy 103.82108 -277.891392) (xy 103.857784 -277.926647)
			(xy 103.888357 -277.967333) (xy 103.912008 -278.012396) (xy 103.928124 -278.06067) (xy 103.936288 -278.110904)
			(xy 103.9368 -278.13635) (xy 104.244897 -278.13635) (xy 104.248992 -278.085622) (xy 104.261171 -278.036208)
			(xy 104.281119 -277.989388) (xy 104.30832 -277.946374) (xy 104.342068 -277.90828) (xy 104.38149 -277.876093)
			(xy 104.425564 -277.850647) (xy 104.47315 -277.8326) (xy 104.523014 -277.82242) (xy 104.573866 -277.820371)
			(xy 104.624387 -277.826505) (xy 104.673271 -277.840665) (xy 104.71925 -277.862482) (xy 104.761134 -277.891392)
			(xy 104.797838 -277.926647) (xy 104.828411 -277.967333) (xy 104.852062 -278.012396) (xy 104.868178 -278.06067)
			(xy 104.876342 -278.110904) (xy 104.876854 -278.13635) (xy 104.876351 -278.161339) (xy 105.183414 -278.161339)
			(xy 105.183414 -278.111361) (xy 105.191233 -278.061998) (xy 105.206677 -278.014466) (xy 105.229367 -277.969934)
			(xy 105.258743 -277.929501) (xy 105.294083 -277.894161) (xy 105.334516 -277.864785) (xy 105.379048 -277.842095)
			(xy 105.42658 -277.826651) (xy 105.475943 -277.818832) (xy 105.525921 -277.818832) (xy 105.575284 -277.826651)
			(xy 105.622816 -277.842095) (xy 105.667348 -277.864785) (xy 105.707781 -277.894161) (xy 105.743121 -277.929501)
			(xy 105.772497 -277.969934) (xy 105.795187 -278.014466) (xy 105.810631 -278.061998) (xy 105.81845 -278.111361)
			(xy 105.81894 -278.13635) (xy 106.124751 -278.13635) (xy 106.128846 -278.085622) (xy 106.141025 -278.036208)
			(xy 106.160973 -277.989388) (xy 106.188174 -277.946374) (xy 106.221922 -277.90828) (xy 106.261344 -277.876093)
			(xy 106.305418 -277.850647) (xy 106.353004 -277.8326) (xy 106.402868 -277.82242) (xy 106.45372 -277.820371)
			(xy 106.504241 -277.826505) (xy 106.553125 -277.840665) (xy 106.599104 -277.862482) (xy 106.640988 -277.891392)
			(xy 106.677692 -277.926647) (xy 106.708265 -277.967333) (xy 106.731916 -278.012396) (xy 106.748032 -278.06067)
			(xy 106.756196 -278.110904) (xy 106.756708 -278.13635) (xy 107.064805 -278.13635) (xy 107.0689 -278.085622)
			(xy 107.081079 -278.036208) (xy 107.101027 -277.989388) (xy 107.128228 -277.946374) (xy 107.161976 -277.90828)
			(xy 107.201398 -277.876093) (xy 107.245472 -277.850647) (xy 107.293058 -277.8326) (xy 107.342922 -277.82242)
			(xy 107.393774 -277.820371) (xy 107.444295 -277.826505) (xy 107.493179 -277.840665) (xy 107.539158 -277.862482)
			(xy 107.581042 -277.891392) (xy 107.617746 -277.926647) (xy 107.648319 -277.967333) (xy 107.67197 -278.012396)
			(xy 107.688086 -278.06067) (xy 107.69625 -278.110904) (xy 107.696762 -278.13635) (xy 107.696259 -278.161339)
			(xy 108.003576 -278.161339) (xy 108.003576 -278.111361) (xy 108.011395 -278.061998) (xy 108.026839 -278.014466)
			(xy 108.049529 -277.969934) (xy 108.078905 -277.929501) (xy 108.114245 -277.894161) (xy 108.154678 -277.864785)
			(xy 108.19921 -277.842095) (xy 108.246742 -277.826651) (xy 108.296105 -277.818832) (xy 108.346083 -277.818832)
			(xy 108.395446 -277.826651) (xy 108.442978 -277.842095) (xy 108.48751 -277.864785) (xy 108.527943 -277.894161)
			(xy 108.563283 -277.929501) (xy 108.592659 -277.969934) (xy 108.615349 -278.014466) (xy 108.630793 -278.061998)
			(xy 108.638612 -278.111361) (xy 108.639102 -278.13635) (xy 108.638612 -278.161339) (xy 115.51715 -278.161339)
			(xy 115.51715 -278.111361) (xy 115.524969 -278.061998) (xy 115.540413 -278.014466) (xy 115.563103 -277.969934)
			(xy 115.592479 -277.929501) (xy 115.627819 -277.894161) (xy 115.668252 -277.864785) (xy 115.712784 -277.842095)
			(xy 115.760316 -277.826651) (xy 115.809679 -277.818832) (xy 115.859657 -277.818832) (xy 115.90902 -277.826651)
			(xy 115.956552 -277.842095) (xy 116.001084 -277.864785) (xy 116.041517 -277.894161) (xy 116.076857 -277.929501)
			(xy 116.106233 -277.969934) (xy 116.128923 -278.014466) (xy 116.144367 -278.061998) (xy 116.152186 -278.111361)
			(xy 116.152676 -278.13635) (xy 116.458487 -278.13635) (xy 116.462582 -278.085622) (xy 116.474761 -278.036208)
			(xy 116.494709 -277.989388) (xy 116.52191 -277.946374) (xy 116.555658 -277.90828) (xy 116.59508 -277.876093)
			(xy 116.639154 -277.850647) (xy 116.68674 -277.8326) (xy 116.736604 -277.82242) (xy 116.787456 -277.820371)
			(xy 116.837977 -277.826505) (xy 116.886861 -277.840665) (xy 116.93284 -277.862482) (xy 116.974724 -277.891392)
			(xy 117.011428 -277.926647) (xy 117.042001 -277.967333) (xy 117.065652 -278.012396) (xy 117.081768 -278.06067)
			(xy 117.089932 -278.110904) (xy 117.090444 -278.13635) (xy 117.398541 -278.13635) (xy 117.402636 -278.085622)
			(xy 117.414815 -278.036208) (xy 117.434763 -277.989388) (xy 117.461964 -277.946374) (xy 117.495712 -277.90828)
			(xy 117.535134 -277.876093) (xy 117.579208 -277.850647) (xy 117.626794 -277.8326) (xy 117.676658 -277.82242)
			(xy 117.72751 -277.820371) (xy 117.778031 -277.826505) (xy 117.826915 -277.840665) (xy 117.872894 -277.862482)
			(xy 117.914778 -277.891392) (xy 117.951482 -277.926647) (xy 117.982055 -277.967333) (xy 118.005706 -278.012396)
			(xy 118.021822 -278.06067) (xy 118.029986 -278.110904) (xy 118.030498 -278.13635) (xy 118.029995 -278.161339)
			(xy 118.337312 -278.161339) (xy 118.337312 -278.111361) (xy 118.345131 -278.061998) (xy 118.360575 -278.014466)
			(xy 118.383265 -277.969934) (xy 118.412641 -277.929501) (xy 118.447981 -277.894161) (xy 118.488414 -277.864785)
			(xy 118.532946 -277.842095) (xy 118.580478 -277.826651) (xy 118.629841 -277.818832) (xy 118.679819 -277.818832)
			(xy 118.729182 -277.826651) (xy 118.776714 -277.842095) (xy 118.821246 -277.864785) (xy 118.861679 -277.894161)
			(xy 118.897019 -277.929501) (xy 118.926395 -277.969934) (xy 118.949085 -278.014466) (xy 118.964529 -278.061998)
			(xy 118.972348 -278.111361) (xy 118.972838 -278.13635) (xy 119.278395 -278.13635) (xy 119.28249 -278.085622)
			(xy 119.294669 -278.036208) (xy 119.314617 -277.989388) (xy 119.341818 -277.946374) (xy 119.375566 -277.90828)
			(xy 119.414988 -277.876093) (xy 119.459062 -277.850647) (xy 119.506648 -277.8326) (xy 119.556512 -277.82242)
			(xy 119.607364 -277.820371) (xy 119.657885 -277.826505) (xy 119.706769 -277.840665) (xy 119.752748 -277.862482)
			(xy 119.794632 -277.891392) (xy 119.831336 -277.926647) (xy 119.861909 -277.967333) (xy 119.88556 -278.012396)
			(xy 119.901676 -278.06067) (xy 119.90984 -278.110904) (xy 119.910352 -278.13635) (xy 120.218449 -278.13635)
			(xy 120.222544 -278.085622) (xy 120.234723 -278.036208) (xy 120.254671 -277.989388) (xy 120.281872 -277.946374)
			(xy 120.31562 -277.90828) (xy 120.355042 -277.876093) (xy 120.399116 -277.850647) (xy 120.446702 -277.8326)
			(xy 120.496566 -277.82242) (xy 120.547418 -277.820371) (xy 120.597939 -277.826505) (xy 120.646823 -277.840665)
			(xy 120.692802 -277.862482) (xy 120.734686 -277.891392) (xy 120.77139 -277.926647) (xy 120.801963 -277.967333)
			(xy 120.825614 -278.012396) (xy 120.84173 -278.06067) (xy 120.849894 -278.110904) (xy 120.850406 -278.13635)
			(xy 120.849903 -278.161339) (xy 121.15722 -278.161339) (xy 121.15722 -278.111361) (xy 121.165039 -278.061998)
			(xy 121.180483 -278.014466) (xy 121.203173 -277.969934) (xy 121.232549 -277.929501) (xy 121.267889 -277.894161)
			(xy 121.308322 -277.864785) (xy 121.352854 -277.842095) (xy 121.400386 -277.826651) (xy 121.449749 -277.818832)
			(xy 121.499727 -277.818832) (xy 121.54909 -277.826651) (xy 121.596622 -277.842095) (xy 121.641154 -277.864785)
			(xy 121.681587 -277.894161) (xy 121.716927 -277.929501) (xy 121.746303 -277.969934) (xy 121.768993 -278.014466)
			(xy 121.784437 -278.061998) (xy 121.792256 -278.111361) (xy 121.792746 -278.13635) (xy 122.098557 -278.13635)
			(xy 122.102652 -278.085622) (xy 122.114831 -278.036208) (xy 122.134779 -277.989388) (xy 122.16198 -277.946374)
			(xy 122.195728 -277.90828) (xy 122.23515 -277.876093) (xy 122.279224 -277.850647) (xy 122.32681 -277.8326)
			(xy 122.376674 -277.82242) (xy 122.427526 -277.820371) (xy 122.478047 -277.826505) (xy 122.526931 -277.840665)
			(xy 122.57291 -277.862482) (xy 122.614794 -277.891392) (xy 122.651498 -277.926647) (xy 122.682071 -277.967333)
			(xy 122.705722 -278.012396) (xy 122.721838 -278.06067) (xy 122.730002 -278.110904) (xy 122.730514 -278.13635)
			(xy 123.038611 -278.13635) (xy 123.042706 -278.085622) (xy 123.054885 -278.036208) (xy 123.074833 -277.989388)
			(xy 123.102034 -277.946374) (xy 123.135782 -277.90828) (xy 123.175204 -277.876093) (xy 123.219278 -277.850647)
			(xy 123.266864 -277.8326) (xy 123.316728 -277.82242) (xy 123.36758 -277.820371) (xy 123.418101 -277.826505)
			(xy 123.466985 -277.840665) (xy 123.512964 -277.862482) (xy 123.554848 -277.891392) (xy 123.591552 -277.926647)
			(xy 123.622125 -277.967333) (xy 123.645776 -278.012396) (xy 123.661892 -278.06067) (xy 123.670056 -278.110904)
			(xy 123.670568 -278.13635) (xy 123.670065 -278.161339) (xy 123.977128 -278.161339) (xy 123.977128 -278.111361)
			(xy 123.984947 -278.061998) (xy 124.000391 -278.014466) (xy 124.023081 -277.969934) (xy 124.052457 -277.929501)
			(xy 124.087797 -277.894161) (xy 124.12823 -277.864785) (xy 124.172762 -277.842095) (xy 124.220294 -277.826651)
			(xy 124.269657 -277.818832) (xy 124.319635 -277.818832) (xy 124.368998 -277.826651) (xy 124.41653 -277.842095)
			(xy 124.461062 -277.864785) (xy 124.501495 -277.894161) (xy 124.536835 -277.929501) (xy 124.566211 -277.969934)
			(xy 124.588901 -278.014466) (xy 124.604345 -278.061998) (xy 124.612164 -278.111361) (xy 124.612654 -278.13635)
			(xy 124.918465 -278.13635) (xy 124.92256 -278.085622) (xy 124.934739 -278.036208) (xy 124.954687 -277.989388)
			(xy 124.981888 -277.946374) (xy 125.015636 -277.90828) (xy 125.055058 -277.876093) (xy 125.099132 -277.850647)
			(xy 125.146718 -277.8326) (xy 125.196582 -277.82242) (xy 125.247434 -277.820371) (xy 125.297955 -277.826505)
			(xy 125.346839 -277.840665) (xy 125.392818 -277.862482) (xy 125.434702 -277.891392) (xy 125.471406 -277.926647)
			(xy 125.501979 -277.967333) (xy 125.52563 -278.012396) (xy 125.541746 -278.06067) (xy 125.54991 -278.110904)
			(xy 125.550422 -278.13635) (xy 125.858519 -278.13635) (xy 125.862614 -278.085622) (xy 125.874793 -278.036208)
			(xy 125.894741 -277.989388) (xy 125.921942 -277.946374) (xy 125.95569 -277.90828) (xy 125.995112 -277.876093)
			(xy 126.039186 -277.850647) (xy 126.086772 -277.8326) (xy 126.136636 -277.82242) (xy 126.187488 -277.820371)
			(xy 126.238009 -277.826505) (xy 126.286893 -277.840665) (xy 126.332872 -277.862482) (xy 126.374756 -277.891392)
			(xy 126.41146 -277.926647) (xy 126.442033 -277.967333) (xy 126.465684 -278.012396) (xy 126.4818 -278.06067)
			(xy 126.489964 -278.110904) (xy 126.490476 -278.13635) (xy 126.489964 -278.161796) (xy 126.4818 -278.21203)
			(xy 126.465684 -278.260304) (xy 126.442033 -278.305367) (xy 126.41146 -278.346053) (xy 126.374756 -278.381308)
			(xy 126.332872 -278.410218) (xy 126.286893 -278.432035) (xy 126.238009 -278.446195) (xy 126.187488 -278.452329)
			(xy 126.136636 -278.45028) (xy 126.086772 -278.4401) (xy 126.039186 -278.422053) (xy 125.995112 -278.396607)
			(xy 125.95569 -278.36442) (xy 125.921942 -278.326326) (xy 125.894741 -278.283312) (xy 125.874793 -278.236492)
			(xy 125.862614 -278.187078) (xy 125.858519 -278.13635) (xy 125.550422 -278.13635) (xy 125.54991 -278.161796)
			(xy 125.541746 -278.21203) (xy 125.52563 -278.260304) (xy 125.501979 -278.305367) (xy 125.471406 -278.346053)
			(xy 125.434702 -278.381308) (xy 125.392818 -278.410218) (xy 125.346839 -278.432035) (xy 125.297955 -278.446195)
			(xy 125.247434 -278.452329) (xy 125.196582 -278.45028) (xy 125.146718 -278.4401) (xy 125.099132 -278.422053)
			(xy 125.055058 -278.396607) (xy 125.015636 -278.36442) (xy 124.981888 -278.326326) (xy 124.954687 -278.283312)
			(xy 124.934739 -278.236492) (xy 124.92256 -278.187078) (xy 124.918465 -278.13635) (xy 124.612654 -278.13635)
			(xy 124.612164 -278.161339) (xy 124.604345 -278.210702) (xy 124.588901 -278.258234) (xy 124.566211 -278.302766)
			(xy 124.536835 -278.343199) (xy 124.501495 -278.378539) (xy 124.461062 -278.407915) (xy 124.41653 -278.430605)
			(xy 124.368998 -278.446049) (xy 124.319635 -278.453868) (xy 124.269657 -278.453868) (xy 124.220294 -278.446049)
			(xy 124.172762 -278.430605) (xy 124.12823 -278.407915) (xy 124.087797 -278.378539) (xy 124.052457 -278.343199)
			(xy 124.023081 -278.302766) (xy 124.000391 -278.258234) (xy 123.984947 -278.210702) (xy 123.977128 -278.161339)
			(xy 123.670065 -278.161339) (xy 123.670056 -278.161796) (xy 123.661892 -278.21203) (xy 123.645776 -278.260304)
			(xy 123.622125 -278.305367) (xy 123.591552 -278.346053) (xy 123.554848 -278.381308) (xy 123.512964 -278.410218)
			(xy 123.466985 -278.432035) (xy 123.418101 -278.446195) (xy 123.36758 -278.452329) (xy 123.316728 -278.45028)
			(xy 123.266864 -278.4401) (xy 123.219278 -278.422053) (xy 123.175204 -278.396607) (xy 123.135782 -278.36442)
			(xy 123.102034 -278.326326) (xy 123.074833 -278.283312) (xy 123.054885 -278.236492) (xy 123.042706 -278.187078)
			(xy 123.038611 -278.13635) (xy 122.730514 -278.13635) (xy 122.730002 -278.161796) (xy 122.721838 -278.21203)
			(xy 122.705722 -278.260304) (xy 122.682071 -278.305367) (xy 122.651498 -278.346053) (xy 122.614794 -278.381308)
			(xy 122.57291 -278.410218) (xy 122.526931 -278.432035) (xy 122.478047 -278.446195) (xy 122.427526 -278.452329)
			(xy 122.376674 -278.45028) (xy 122.32681 -278.4401) (xy 122.279224 -278.422053) (xy 122.23515 -278.396607)
			(xy 122.195728 -278.36442) (xy 122.16198 -278.326326) (xy 122.134779 -278.283312) (xy 122.114831 -278.236492)
			(xy 122.102652 -278.187078) (xy 122.098557 -278.13635) (xy 121.792746 -278.13635) (xy 121.792256 -278.161339)
			(xy 121.784437 -278.210702) (xy 121.768993 -278.258234) (xy 121.746303 -278.302766) (xy 121.716927 -278.343199)
			(xy 121.681587 -278.378539) (xy 121.641154 -278.407915) (xy 121.596622 -278.430605) (xy 121.54909 -278.446049)
			(xy 121.499727 -278.453868) (xy 121.449749 -278.453868) (xy 121.400386 -278.446049) (xy 121.352854 -278.430605)
			(xy 121.308322 -278.407915) (xy 121.267889 -278.378539) (xy 121.232549 -278.343199) (xy 121.203173 -278.302766)
			(xy 121.180483 -278.258234) (xy 121.165039 -278.210702) (xy 121.15722 -278.161339) (xy 120.849903 -278.161339)
			(xy 120.849894 -278.161796) (xy 120.84173 -278.21203) (xy 120.825614 -278.260304) (xy 120.801963 -278.305367)
			(xy 120.77139 -278.346053) (xy 120.734686 -278.381308) (xy 120.692802 -278.410218) (xy 120.646823 -278.432035)
			(xy 120.597939 -278.446195) (xy 120.547418 -278.452329) (xy 120.496566 -278.45028) (xy 120.446702 -278.4401)
			(xy 120.399116 -278.422053) (xy 120.355042 -278.396607) (xy 120.31562 -278.36442) (xy 120.281872 -278.326326)
			(xy 120.254671 -278.283312) (xy 120.234723 -278.236492) (xy 120.222544 -278.187078) (xy 120.218449 -278.13635)
			(xy 119.910352 -278.13635) (xy 119.90984 -278.161796) (xy 119.901676 -278.21203) (xy 119.88556 -278.260304)
			(xy 119.861909 -278.305367) (xy 119.831336 -278.346053) (xy 119.794632 -278.381308) (xy 119.752748 -278.410218)
			(xy 119.706769 -278.432035) (xy 119.657885 -278.446195) (xy 119.607364 -278.452329) (xy 119.556512 -278.45028)
			(xy 119.506648 -278.4401) (xy 119.459062 -278.422053) (xy 119.414988 -278.396607) (xy 119.375566 -278.36442)
			(xy 119.341818 -278.326326) (xy 119.314617 -278.283312) (xy 119.294669 -278.236492) (xy 119.28249 -278.187078)
			(xy 119.278395 -278.13635) (xy 118.972838 -278.13635) (xy 118.972348 -278.161339) (xy 118.964529 -278.210702)
			(xy 118.949085 -278.258234) (xy 118.926395 -278.302766) (xy 118.897019 -278.343199) (xy 118.861679 -278.378539)
			(xy 118.821246 -278.407915) (xy 118.776714 -278.430605) (xy 118.729182 -278.446049) (xy 118.679819 -278.453868)
			(xy 118.629841 -278.453868) (xy 118.580478 -278.446049) (xy 118.532946 -278.430605) (xy 118.488414 -278.407915)
			(xy 118.447981 -278.378539) (xy 118.412641 -278.343199) (xy 118.383265 -278.302766) (xy 118.360575 -278.258234)
			(xy 118.345131 -278.210702) (xy 118.337312 -278.161339) (xy 118.029995 -278.161339) (xy 118.029986 -278.161796)
			(xy 118.021822 -278.21203) (xy 118.005706 -278.260304) (xy 117.982055 -278.305367) (xy 117.951482 -278.346053)
			(xy 117.914778 -278.381308) (xy 117.872894 -278.410218) (xy 117.826915 -278.432035) (xy 117.778031 -278.446195)
			(xy 117.72751 -278.452329) (xy 117.676658 -278.45028) (xy 117.626794 -278.4401) (xy 117.579208 -278.422053)
			(xy 117.535134 -278.396607) (xy 117.495712 -278.36442) (xy 117.461964 -278.326326) (xy 117.434763 -278.283312)
			(xy 117.414815 -278.236492) (xy 117.402636 -278.187078) (xy 117.398541 -278.13635) (xy 117.090444 -278.13635)
			(xy 117.089932 -278.161796) (xy 117.081768 -278.21203) (xy 117.065652 -278.260304) (xy 117.042001 -278.305367)
			(xy 117.011428 -278.346053) (xy 116.974724 -278.381308) (xy 116.93284 -278.410218) (xy 116.886861 -278.432035)
			(xy 116.837977 -278.446195) (xy 116.787456 -278.452329) (xy 116.736604 -278.45028) (xy 116.68674 -278.4401)
			(xy 116.639154 -278.422053) (xy 116.59508 -278.396607) (xy 116.555658 -278.36442) (xy 116.52191 -278.326326)
			(xy 116.494709 -278.283312) (xy 116.474761 -278.236492) (xy 116.462582 -278.187078) (xy 116.458487 -278.13635)
			(xy 116.152676 -278.13635) (xy 116.152186 -278.161339) (xy 116.144367 -278.210702) (xy 116.128923 -278.258234)
			(xy 116.106233 -278.302766) (xy 116.076857 -278.343199) (xy 116.041517 -278.378539) (xy 116.001084 -278.407915)
			(xy 115.956552 -278.430605) (xy 115.90902 -278.446049) (xy 115.859657 -278.453868) (xy 115.809679 -278.453868)
			(xy 115.760316 -278.446049) (xy 115.712784 -278.430605) (xy 115.668252 -278.407915) (xy 115.627819 -278.378539)
			(xy 115.592479 -278.343199) (xy 115.563103 -278.302766) (xy 115.540413 -278.258234) (xy 115.524969 -278.210702)
			(xy 115.51715 -278.161339) (xy 108.638612 -278.161339) (xy 108.630793 -278.210702) (xy 108.615349 -278.258234)
			(xy 108.592659 -278.302766) (xy 108.563283 -278.343199) (xy 108.527943 -278.378539) (xy 108.48751 -278.407915)
			(xy 108.442978 -278.430605) (xy 108.395446 -278.446049) (xy 108.346083 -278.453868) (xy 108.296105 -278.453868)
			(xy 108.246742 -278.446049) (xy 108.19921 -278.430605) (xy 108.154678 -278.407915) (xy 108.114245 -278.378539)
			(xy 108.078905 -278.343199) (xy 108.049529 -278.302766) (xy 108.026839 -278.258234) (xy 108.011395 -278.210702)
			(xy 108.003576 -278.161339) (xy 107.696259 -278.161339) (xy 107.69625 -278.161796) (xy 107.688086 -278.21203)
			(xy 107.67197 -278.260304) (xy 107.648319 -278.305367) (xy 107.617746 -278.346053) (xy 107.581042 -278.381308)
			(xy 107.539158 -278.410218) (xy 107.493179 -278.432035) (xy 107.444295 -278.446195) (xy 107.393774 -278.452329)
			(xy 107.342922 -278.45028) (xy 107.293058 -278.4401) (xy 107.245472 -278.422053) (xy 107.201398 -278.396607)
			(xy 107.161976 -278.36442) (xy 107.128228 -278.326326) (xy 107.101027 -278.283312) (xy 107.081079 -278.236492)
			(xy 107.0689 -278.187078) (xy 107.064805 -278.13635) (xy 106.756708 -278.13635) (xy 106.756196 -278.161796)
			(xy 106.748032 -278.21203) (xy 106.731916 -278.260304) (xy 106.708265 -278.305367) (xy 106.677692 -278.346053)
			(xy 106.640988 -278.381308) (xy 106.599104 -278.410218) (xy 106.553125 -278.432035) (xy 106.504241 -278.446195)
			(xy 106.45372 -278.452329) (xy 106.402868 -278.45028) (xy 106.353004 -278.4401) (xy 106.305418 -278.422053)
			(xy 106.261344 -278.396607) (xy 106.221922 -278.36442) (xy 106.188174 -278.326326) (xy 106.160973 -278.283312)
			(xy 106.141025 -278.236492) (xy 106.128846 -278.187078) (xy 106.124751 -278.13635) (xy 105.81894 -278.13635)
			(xy 105.81845 -278.161339) (xy 105.810631 -278.210702) (xy 105.795187 -278.258234) (xy 105.772497 -278.302766)
			(xy 105.743121 -278.343199) (xy 105.707781 -278.378539) (xy 105.667348 -278.407915) (xy 105.622816 -278.430605)
			(xy 105.575284 -278.446049) (xy 105.525921 -278.453868) (xy 105.475943 -278.453868) (xy 105.42658 -278.446049)
			(xy 105.379048 -278.430605) (xy 105.334516 -278.407915) (xy 105.294083 -278.378539) (xy 105.258743 -278.343199)
			(xy 105.229367 -278.302766) (xy 105.206677 -278.258234) (xy 105.191233 -278.210702) (xy 105.183414 -278.161339)
			(xy 104.876351 -278.161339) (xy 104.876342 -278.161796) (xy 104.868178 -278.21203) (xy 104.852062 -278.260304)
			(xy 104.828411 -278.305367) (xy 104.797838 -278.346053) (xy 104.761134 -278.381308) (xy 104.71925 -278.410218)
			(xy 104.673271 -278.432035) (xy 104.624387 -278.446195) (xy 104.573866 -278.452329) (xy 104.523014 -278.45028)
			(xy 104.47315 -278.4401) (xy 104.425564 -278.422053) (xy 104.38149 -278.396607) (xy 104.342068 -278.36442)
			(xy 104.30832 -278.326326) (xy 104.281119 -278.283312) (xy 104.261171 -278.236492) (xy 104.248992 -278.187078)
			(xy 104.244897 -278.13635) (xy 103.9368 -278.13635) (xy 103.936288 -278.161796) (xy 103.928124 -278.21203)
			(xy 103.912008 -278.260304) (xy 103.888357 -278.305367) (xy 103.857784 -278.346053) (xy 103.82108 -278.381308)
			(xy 103.779196 -278.410218) (xy 103.733217 -278.432035) (xy 103.684333 -278.446195) (xy 103.633812 -278.452329)
			(xy 103.58296 -278.45028) (xy 103.533096 -278.4401) (xy 103.48551 -278.422053) (xy 103.441436 -278.396607)
			(xy 103.402014 -278.36442) (xy 103.368266 -278.326326) (xy 103.341065 -278.283312) (xy 103.321117 -278.236492)
			(xy 103.308938 -278.187078) (xy 103.304843 -278.13635) (xy 102.999032 -278.13635) (xy 102.998542 -278.161339)
			(xy 102.990723 -278.210702) (xy 102.975279 -278.258234) (xy 102.952589 -278.302766) (xy 102.923213 -278.343199)
			(xy 102.887873 -278.378539) (xy 102.84744 -278.407915) (xy 102.802908 -278.430605) (xy 102.755376 -278.446049)
			(xy 102.706013 -278.453868) (xy 102.656035 -278.453868) (xy 102.606672 -278.446049) (xy 102.55914 -278.430605)
			(xy 102.514608 -278.407915) (xy 102.474175 -278.378539) (xy 102.438835 -278.343199) (xy 102.409459 -278.302766)
			(xy 102.386769 -278.258234) (xy 102.371325 -278.210702) (xy 102.363506 -278.161339) (xy 102.056189 -278.161339)
			(xy 102.05618 -278.161796) (xy 102.048016 -278.21203) (xy 102.0319 -278.260304) (xy 102.008249 -278.305367)
			(xy 101.977676 -278.346053) (xy 101.940972 -278.381308) (xy 101.899088 -278.410218) (xy 101.853109 -278.432035)
			(xy 101.804225 -278.446195) (xy 101.753704 -278.452329) (xy 101.702852 -278.45028) (xy 101.652988 -278.4401)
			(xy 101.605402 -278.422053) (xy 101.561328 -278.396607) (xy 101.521906 -278.36442) (xy 101.488158 -278.326326)
			(xy 101.460957 -278.283312) (xy 101.441009 -278.236492) (xy 101.42883 -278.187078) (xy 101.424735 -278.13635)
			(xy 101.116892 -278.13635) (xy 101.11638 -278.161796) (xy 101.108216 -278.21203) (xy 101.0921 -278.260304)
			(xy 101.068449 -278.305367) (xy 101.037876 -278.346053) (xy 101.001172 -278.381308) (xy 100.959288 -278.410218)
			(xy 100.913309 -278.432035) (xy 100.864425 -278.446195) (xy 100.813904 -278.452329) (xy 100.763052 -278.45028)
			(xy 100.713188 -278.4401) (xy 100.665602 -278.422053) (xy 100.621528 -278.396607) (xy 100.582106 -278.36442)
			(xy 100.548358 -278.326326) (xy 100.521157 -278.283312) (xy 100.501209 -278.236492) (xy 100.48903 -278.187078)
			(xy 100.484935 -278.13635) (xy 100.179124 -278.13635) (xy 100.178634 -278.161339) (xy 100.170815 -278.210702)
			(xy 100.155371 -278.258234) (xy 100.132681 -278.302766) (xy 100.103305 -278.343199) (xy 100.067965 -278.378539)
			(xy 100.027532 -278.407915) (xy 99.983 -278.430605) (xy 99.935468 -278.446049) (xy 99.886105 -278.453868)
			(xy 99.836127 -278.453868) (xy 99.786764 -278.446049) (xy 99.739232 -278.430605) (xy 99.6947 -278.407915)
			(xy 99.654267 -278.378539) (xy 99.618927 -278.343199) (xy 99.589551 -278.302766) (xy 99.566861 -278.258234)
			(xy 99.551417 -278.210702) (xy 99.543598 -278.161339) (xy 99.236281 -278.161339) (xy 99.236272 -278.161796)
			(xy 99.228108 -278.21203) (xy 99.211992 -278.260304) (xy 99.188341 -278.305367) (xy 99.157768 -278.346053)
			(xy 99.121064 -278.381308) (xy 99.07918 -278.410218) (xy 99.033201 -278.432035) (xy 98.984317 -278.446195)
			(xy 98.933796 -278.452329) (xy 98.882944 -278.45028) (xy 98.83308 -278.4401) (xy 98.785494 -278.422053)
			(xy 98.74142 -278.396607) (xy 98.701998 -278.36442) (xy 98.66825 -278.326326) (xy 98.641049 -278.283312)
			(xy 98.621101 -278.236492) (xy 98.608922 -278.187078) (xy 98.604827 -278.13635) (xy 98.29673 -278.13635)
			(xy 98.296218 -278.161796) (xy 98.288054 -278.21203) (xy 98.271938 -278.260304) (xy 98.248287 -278.305367)
			(xy 98.217714 -278.346053) (xy 98.18101 -278.381308) (xy 98.139126 -278.410218) (xy 98.093147 -278.432035)
			(xy 98.044263 -278.446195) (xy 97.993742 -278.452329) (xy 97.94289 -278.45028) (xy 97.893026 -278.4401)
			(xy 97.84544 -278.422053) (xy 97.801366 -278.396607) (xy 97.761944 -278.36442) (xy 97.728196 -278.326326)
			(xy 97.700995 -278.283312) (xy 97.681047 -278.236492) (xy 97.668868 -278.187078) (xy 97.664773 -278.13635)
			(xy 97.358962 -278.13635) (xy 97.358472 -278.161339) (xy 97.350653 -278.210702) (xy 97.335209 -278.258234)
			(xy 97.312519 -278.302766) (xy 97.283143 -278.343199) (xy 97.247803 -278.378539) (xy 97.20737 -278.407915)
			(xy 97.162838 -278.430605) (xy 97.115306 -278.446049) (xy 97.065943 -278.453868) (xy 97.015965 -278.453868)
			(xy 96.966602 -278.446049) (xy 96.91907 -278.430605) (xy 96.874538 -278.407915) (xy 96.834105 -278.378539)
			(xy 96.798765 -278.343199) (xy 96.769389 -278.302766) (xy 96.746699 -278.258234) (xy 96.731255 -278.210702)
			(xy 96.723436 -278.161339) (xy 96.416373 -278.161339) (xy 96.416364 -278.161796) (xy 96.4082 -278.21203)
			(xy 96.392084 -278.260304) (xy 96.368433 -278.305367) (xy 96.33786 -278.346053) (xy 96.301156 -278.381308)
			(xy 96.259272 -278.410218) (xy 96.213293 -278.432035) (xy 96.164409 -278.446195) (xy 96.113888 -278.452329)
			(xy 96.063036 -278.45028) (xy 96.013172 -278.4401) (xy 95.965586 -278.422053) (xy 95.921512 -278.396607)
			(xy 95.88209 -278.36442) (xy 95.848342 -278.326326) (xy 95.821141 -278.283312) (xy 95.801193 -278.236492)
			(xy 95.789014 -278.187078) (xy 95.784919 -278.13635) (xy 95.479108 -278.13635) (xy 95.478618 -278.161339)
			(xy 95.470799 -278.210702) (xy 95.455355 -278.258234) (xy 95.432665 -278.302766) (xy 95.403289 -278.343199)
			(xy 95.367949 -278.378539) (xy 95.327516 -278.407915) (xy 95.282984 -278.430605) (xy 95.235452 -278.446049)
			(xy 95.186089 -278.453868) (xy 95.136111 -278.453868) (xy 95.086748 -278.446049) (xy 95.039216 -278.430605)
			(xy 94.994684 -278.407915) (xy 94.954251 -278.378539) (xy 94.918911 -278.343199) (xy 94.889535 -278.302766)
			(xy 94.866845 -278.258234) (xy 94.851401 -278.210702) (xy 94.843582 -278.161339) (xy 94.538459 -278.161339)
			(xy 94.530652 -278.210634) (xy 94.515213 -278.258155) (xy 94.492531 -278.302676) (xy 94.463164 -278.343101)
			(xy 94.427836 -278.378434) (xy 94.387415 -278.407807) (xy 94.342897 -278.430496) (xy 94.295379 -278.445942)
			(xy 94.246029 -278.453764) (xy 94.221046 -278.454358) (xy 94.207449 -278.454171) (xy 94.18036 -278.451753)
			(xy 94.166944 -278.449532) (xy 94.16415 -278.449024) (xy 94.157546 -278.44877) (xy 94.150923 -278.448547)
			(xy 94.137927 -278.451114) (xy 94.131892 -278.45385) (xy 94.107 -278.466042) (xy 94.100904 -278.472392)
			(xy 94.083124 -278.490426) (xy 94.079314 -278.498808) (xy 94.066443 -278.526663) (xy 94.037332 -278.580688)
			(xy 94.021148 -278.606758) (xy 94.020894 -278.607012) (xy 94.017373 -278.613178) (xy 94.013521 -278.626839)
			(xy 94.013274 -278.633936) (xy 94.013274 -278.758396) (xy 94.017084 -278.771858) (xy 94.020894 -278.777954)
			(xy 94.032317 -278.796985) (xy 94.050356 -278.83754) (xy 94.062581 -278.880209) (xy 94.068757 -278.924163)
			(xy 94.069154 -278.946356) (xy 94.374711 -278.946356) (xy 94.378806 -278.895628) (xy 94.390985 -278.846214)
			(xy 94.410933 -278.799394) (xy 94.438134 -278.75638) (xy 94.471882 -278.718286) (xy 94.511304 -278.686099)
			(xy 94.555378 -278.660653) (xy 94.602964 -278.642606) (xy 94.652828 -278.632426) (xy 94.70368 -278.630377)
			(xy 94.754201 -278.636511) (xy 94.803085 -278.650671) (xy 94.849064 -278.672488) (xy 94.890948 -278.701398)
			(xy 94.927652 -278.736653) (xy 94.958225 -278.777339) (xy 94.981876 -278.822402) (xy 94.997992 -278.870676)
			(xy 95.006156 -278.92091) (xy 95.006668 -278.946356) (xy 95.314765 -278.946356) (xy 95.31886 -278.895628)
			(xy 95.331039 -278.846214) (xy 95.350987 -278.799394) (xy 95.378188 -278.75638) (xy 95.411936 -278.718286)
			(xy 95.451358 -278.686099) (xy 95.495432 -278.660653) (xy 95.543018 -278.642606) (xy 95.592882 -278.632426)
			(xy 95.643734 -278.630377) (xy 95.694255 -278.636511) (xy 95.743139 -278.650671) (xy 95.789118 -278.672488)
			(xy 95.831002 -278.701398) (xy 95.867706 -278.736653) (xy 95.898279 -278.777339) (xy 95.92193 -278.822402)
			(xy 95.938046 -278.870676) (xy 95.94621 -278.92091) (xy 95.946722 -278.946356) (xy 95.946219 -278.971345)
			(xy 96.253536 -278.971345) (xy 96.253536 -278.921367) (xy 96.261355 -278.872004) (xy 96.276799 -278.824472)
			(xy 96.299489 -278.77994) (xy 96.328865 -278.739507) (xy 96.364205 -278.704167) (xy 96.404638 -278.674791)
			(xy 96.44917 -278.652101) (xy 96.496702 -278.636657) (xy 96.546065 -278.628838) (xy 96.596043 -278.628838)
			(xy 96.645406 -278.636657) (xy 96.692938 -278.652101) (xy 96.73747 -278.674791) (xy 96.777903 -278.704167)
			(xy 96.813243 -278.739507) (xy 96.842619 -278.77994) (xy 96.865309 -278.824472) (xy 96.880753 -278.872004)
			(xy 96.888572 -278.921367) (xy 96.889062 -278.946356) (xy 96.888572 -278.971345) (xy 99.073444 -278.971345)
			(xy 99.073444 -278.921367) (xy 99.081263 -278.872004) (xy 99.096707 -278.824472) (xy 99.119397 -278.77994)
			(xy 99.148773 -278.739507) (xy 99.184113 -278.704167) (xy 99.224546 -278.674791) (xy 99.269078 -278.652101)
			(xy 99.31661 -278.636657) (xy 99.365973 -278.628838) (xy 99.415951 -278.628838) (xy 99.465314 -278.636657)
			(xy 99.512846 -278.652101) (xy 99.557378 -278.674791) (xy 99.597811 -278.704167) (xy 99.633151 -278.739507)
			(xy 99.662527 -278.77994) (xy 99.685217 -278.824472) (xy 99.700661 -278.872004) (xy 99.70848 -278.921367)
			(xy 99.70897 -278.946356) (xy 99.70848 -278.971345) (xy 101.893606 -278.971345) (xy 101.893606 -278.921367)
			(xy 101.901425 -278.872004) (xy 101.916869 -278.824472) (xy 101.939559 -278.77994) (xy 101.968935 -278.739507)
			(xy 102.004275 -278.704167) (xy 102.044708 -278.674791) (xy 102.08924 -278.652101) (xy 102.136772 -278.636657)
			(xy 102.186135 -278.628838) (xy 102.236113 -278.628838) (xy 102.285476 -278.636657) (xy 102.333008 -278.652101)
			(xy 102.37754 -278.674791) (xy 102.417973 -278.704167) (xy 102.453313 -278.739507) (xy 102.482689 -278.77994)
			(xy 102.505379 -278.824472) (xy 102.520823 -278.872004) (xy 102.528642 -278.921367) (xy 102.529132 -278.946356)
			(xy 102.528642 -278.971345) (xy 104.713514 -278.971345) (xy 104.713514 -278.921367) (xy 104.721333 -278.872004)
			(xy 104.736777 -278.824472) (xy 104.759467 -278.77994) (xy 104.788843 -278.739507) (xy 104.824183 -278.704167)
			(xy 104.864616 -278.674791) (xy 104.909148 -278.652101) (xy 104.95668 -278.636657) (xy 105.006043 -278.628838)
			(xy 105.056021 -278.628838) (xy 105.105384 -278.636657) (xy 105.152916 -278.652101) (xy 105.197448 -278.674791)
			(xy 105.237881 -278.704167) (xy 105.273221 -278.739507) (xy 105.302597 -278.77994) (xy 105.325287 -278.824472)
			(xy 105.340731 -278.872004) (xy 105.34855 -278.921367) (xy 105.34904 -278.946356) (xy 105.34855 -278.971345)
			(xy 107.533422 -278.971345) (xy 107.533422 -278.921367) (xy 107.541241 -278.872004) (xy 107.556685 -278.824472)
			(xy 107.579375 -278.77994) (xy 107.608751 -278.739507) (xy 107.644091 -278.704167) (xy 107.684524 -278.674791)
			(xy 107.729056 -278.652101) (xy 107.776588 -278.636657) (xy 107.825951 -278.628838) (xy 107.875929 -278.628838)
			(xy 107.925292 -278.636657) (xy 107.972824 -278.652101) (xy 108.017356 -278.674791) (xy 108.057789 -278.704167)
			(xy 108.093129 -278.739507) (xy 108.122505 -278.77994) (xy 108.145195 -278.824472) (xy 108.160639 -278.872004)
			(xy 108.168458 -278.921367) (xy 108.168948 -278.946356) (xy 108.474759 -278.946356) (xy 108.478854 -278.895628)
			(xy 108.491033 -278.846214) (xy 108.510981 -278.799394) (xy 108.538182 -278.75638) (xy 108.57193 -278.718286)
			(xy 108.611352 -278.686099) (xy 108.655426 -278.660653) (xy 108.703012 -278.642606) (xy 108.752876 -278.632426)
			(xy 108.803728 -278.630377) (xy 108.854249 -278.636511) (xy 108.903133 -278.650671) (xy 108.949112 -278.672488)
			(xy 108.990996 -278.701398) (xy 109.0277 -278.736653) (xy 109.058273 -278.777339) (xy 109.081924 -278.822402)
			(xy 109.09804 -278.870676) (xy 109.106204 -278.92091) (xy 109.106716 -278.946356) (xy 109.414813 -278.946356)
			(xy 109.418908 -278.895628) (xy 109.431087 -278.846214) (xy 109.451035 -278.799394) (xy 109.478236 -278.75638)
			(xy 109.511984 -278.718286) (xy 109.551406 -278.686099) (xy 109.59548 -278.660653) (xy 109.643066 -278.642606)
			(xy 109.69293 -278.632426) (xy 109.743782 -278.630377) (xy 109.794303 -278.636511) (xy 109.843187 -278.650671)
			(xy 109.889166 -278.672488) (xy 109.93105 -278.701398) (xy 109.967754 -278.736653) (xy 109.998327 -278.777339)
			(xy 110.021978 -278.822402) (xy 110.038094 -278.870676) (xy 110.046258 -278.92091) (xy 110.04677 -278.946356)
			(xy 110.046267 -278.971345) (xy 110.353584 -278.971345) (xy 110.353584 -278.921367) (xy 110.361403 -278.872004)
			(xy 110.376847 -278.824472) (xy 110.399537 -278.77994) (xy 110.428913 -278.739507) (xy 110.464253 -278.704167)
			(xy 110.504686 -278.674791) (xy 110.549218 -278.652101) (xy 110.59675 -278.636657) (xy 110.646113 -278.628838)
			(xy 110.696091 -278.628838) (xy 110.745454 -278.636657) (xy 110.792986 -278.652101) (xy 110.837518 -278.674791)
			(xy 110.877951 -278.704167) (xy 110.913291 -278.739507) (xy 110.942667 -278.77994) (xy 110.965357 -278.824472)
			(xy 110.980801 -278.872004) (xy 110.98862 -278.921367) (xy 110.98911 -278.946356) (xy 110.98862 -278.971345)
			(xy 113.167142 -278.971345) (xy 113.167142 -278.921367) (xy 113.174961 -278.872004) (xy 113.190405 -278.824472)
			(xy 113.213095 -278.77994) (xy 113.242471 -278.739507) (xy 113.277811 -278.704167) (xy 113.318244 -278.674791)
			(xy 113.362776 -278.652101) (xy 113.410308 -278.636657) (xy 113.459671 -278.628838) (xy 113.509649 -278.628838)
			(xy 113.559012 -278.636657) (xy 113.606544 -278.652101) (xy 113.651076 -278.674791) (xy 113.691509 -278.704167)
			(xy 113.726849 -278.739507) (xy 113.756225 -278.77994) (xy 113.778915 -278.824472) (xy 113.794359 -278.872004)
			(xy 113.802178 -278.921367) (xy 113.802668 -278.946356) (xy 114.108479 -278.946356) (xy 114.112574 -278.895628)
			(xy 114.124753 -278.846214) (xy 114.144701 -278.799394) (xy 114.171902 -278.75638) (xy 114.20565 -278.718286)
			(xy 114.245072 -278.686099) (xy 114.289146 -278.660653) (xy 114.336732 -278.642606) (xy 114.386596 -278.632426)
			(xy 114.437448 -278.630377) (xy 114.487969 -278.636511) (xy 114.536853 -278.650671) (xy 114.582832 -278.672488)
			(xy 114.624716 -278.701398) (xy 114.66142 -278.736653) (xy 114.691993 -278.777339) (xy 114.715644 -278.822402)
			(xy 114.73176 -278.870676) (xy 114.739924 -278.92091) (xy 114.740436 -278.946356) (xy 115.048533 -278.946356)
			(xy 115.052628 -278.895628) (xy 115.064807 -278.846214) (xy 115.084755 -278.799394) (xy 115.111956 -278.75638)
			(xy 115.145704 -278.718286) (xy 115.185126 -278.686099) (xy 115.2292 -278.660653) (xy 115.276786 -278.642606)
			(xy 115.32665 -278.632426) (xy 115.377502 -278.630377) (xy 115.428023 -278.636511) (xy 115.476907 -278.650671)
			(xy 115.522886 -278.672488) (xy 115.56477 -278.701398) (xy 115.601474 -278.736653) (xy 115.632047 -278.777339)
			(xy 115.655698 -278.822402) (xy 115.671814 -278.870676) (xy 115.679978 -278.92091) (xy 115.68049 -278.946356)
			(xy 115.679987 -278.971345) (xy 115.987304 -278.971345) (xy 115.987304 -278.921367) (xy 115.995123 -278.872004)
			(xy 116.010567 -278.824472) (xy 116.033257 -278.77994) (xy 116.062633 -278.739507) (xy 116.097973 -278.704167)
			(xy 116.138406 -278.674791) (xy 116.182938 -278.652101) (xy 116.23047 -278.636657) (xy 116.279833 -278.628838)
			(xy 116.329811 -278.628838) (xy 116.379174 -278.636657) (xy 116.426706 -278.652101) (xy 116.471238 -278.674791)
			(xy 116.511671 -278.704167) (xy 116.547011 -278.739507) (xy 116.576387 -278.77994) (xy 116.599077 -278.824472)
			(xy 116.614521 -278.872004) (xy 116.62234 -278.921367) (xy 116.62283 -278.946356) (xy 116.62234 -278.971345)
			(xy 118.807212 -278.971345) (xy 118.807212 -278.921367) (xy 118.815031 -278.872004) (xy 118.830475 -278.824472)
			(xy 118.853165 -278.77994) (xy 118.882541 -278.739507) (xy 118.917881 -278.704167) (xy 118.958314 -278.674791)
			(xy 119.002846 -278.652101) (xy 119.050378 -278.636657) (xy 119.099741 -278.628838) (xy 119.149719 -278.628838)
			(xy 119.199082 -278.636657) (xy 119.246614 -278.652101) (xy 119.291146 -278.674791) (xy 119.331579 -278.704167)
			(xy 119.366919 -278.739507) (xy 119.396295 -278.77994) (xy 119.418985 -278.824472) (xy 119.434429 -278.872004)
			(xy 119.442248 -278.921367) (xy 119.442738 -278.946356) (xy 119.442248 -278.971345) (xy 121.62712 -278.971345)
			(xy 121.62712 -278.921367) (xy 121.634939 -278.872004) (xy 121.650383 -278.824472) (xy 121.673073 -278.77994)
			(xy 121.702449 -278.739507) (xy 121.737789 -278.704167) (xy 121.778222 -278.674791) (xy 121.822754 -278.652101)
			(xy 121.870286 -278.636657) (xy 121.919649 -278.628838) (xy 121.969627 -278.628838) (xy 122.01899 -278.636657)
			(xy 122.066522 -278.652101) (xy 122.111054 -278.674791) (xy 122.151487 -278.704167) (xy 122.186827 -278.739507)
			(xy 122.216203 -278.77994) (xy 122.238893 -278.824472) (xy 122.254337 -278.872004) (xy 122.262156 -278.921367)
			(xy 122.262646 -278.946356) (xy 122.262156 -278.971345) (xy 124.447282 -278.971345) (xy 124.447282 -278.921367)
			(xy 124.455101 -278.872004) (xy 124.470545 -278.824472) (xy 124.493235 -278.77994) (xy 124.522611 -278.739507)
			(xy 124.557951 -278.704167) (xy 124.598384 -278.674791) (xy 124.642916 -278.652101) (xy 124.690448 -278.636657)
			(xy 124.739811 -278.628838) (xy 124.789789 -278.628838) (xy 124.839152 -278.636657) (xy 124.886684 -278.652101)
			(xy 124.931216 -278.674791) (xy 124.971649 -278.704167) (xy 125.006989 -278.739507) (xy 125.036365 -278.77994)
			(xy 125.059055 -278.824472) (xy 125.074499 -278.872004) (xy 125.082318 -278.921367) (xy 125.082808 -278.946356)
			(xy 125.082318 -278.971345) (xy 125.074499 -279.020708) (xy 125.059055 -279.06824) (xy 125.036365 -279.112772)
			(xy 125.006989 -279.153205) (xy 124.971649 -279.188545) (xy 124.931216 -279.217921) (xy 124.886684 -279.240611)
			(xy 124.839152 -279.256055) (xy 124.789789 -279.263874) (xy 124.739811 -279.263874) (xy 124.690448 -279.256055)
			(xy 124.642916 -279.240611) (xy 124.598384 -279.217921) (xy 124.557951 -279.188545) (xy 124.522611 -279.153205)
			(xy 124.493235 -279.112772) (xy 124.470545 -279.06824) (xy 124.455101 -279.020708) (xy 124.447282 -278.971345)
			(xy 122.262156 -278.971345) (xy 122.254337 -279.020708) (xy 122.238893 -279.06824) (xy 122.216203 -279.112772)
			(xy 122.186827 -279.153205) (xy 122.151487 -279.188545) (xy 122.111054 -279.217921) (xy 122.066522 -279.240611)
			(xy 122.01899 -279.256055) (xy 121.969627 -279.263874) (xy 121.919649 -279.263874) (xy 121.870286 -279.256055)
			(xy 121.822754 -279.240611) (xy 121.778222 -279.217921) (xy 121.737789 -279.188545) (xy 121.702449 -279.153205)
			(xy 121.673073 -279.112772) (xy 121.650383 -279.06824) (xy 121.634939 -279.020708) (xy 121.62712 -278.971345)
			(xy 119.442248 -278.971345) (xy 119.434429 -279.020708) (xy 119.418985 -279.06824) (xy 119.396295 -279.112772)
			(xy 119.366919 -279.153205) (xy 119.331579 -279.188545) (xy 119.291146 -279.217921) (xy 119.246614 -279.240611)
			(xy 119.199082 -279.256055) (xy 119.149719 -279.263874) (xy 119.099741 -279.263874) (xy 119.050378 -279.256055)
			(xy 119.002846 -279.240611) (xy 118.958314 -279.217921) (xy 118.917881 -279.188545) (xy 118.882541 -279.153205)
			(xy 118.853165 -279.112772) (xy 118.830475 -279.06824) (xy 118.815031 -279.020708) (xy 118.807212 -278.971345)
			(xy 116.62234 -278.971345) (xy 116.614521 -279.020708) (xy 116.599077 -279.06824) (xy 116.576387 -279.112772)
			(xy 116.547011 -279.153205) (xy 116.511671 -279.188545) (xy 116.471238 -279.217921) (xy 116.426706 -279.240611)
			(xy 116.379174 -279.256055) (xy 116.329811 -279.263874) (xy 116.279833 -279.263874) (xy 116.23047 -279.256055)
			(xy 116.182938 -279.240611) (xy 116.138406 -279.217921) (xy 116.097973 -279.188545) (xy 116.062633 -279.153205)
			(xy 116.033257 -279.112772) (xy 116.010567 -279.06824) (xy 115.995123 -279.020708) (xy 115.987304 -278.971345)
			(xy 115.679987 -278.971345) (xy 115.679978 -278.971802) (xy 115.671814 -279.022036) (xy 115.655698 -279.07031)
			(xy 115.632047 -279.115373) (xy 115.601474 -279.156059) (xy 115.56477 -279.191314) (xy 115.522886 -279.220224)
			(xy 115.476907 -279.242041) (xy 115.428023 -279.256201) (xy 115.377502 -279.262335) (xy 115.32665 -279.260286)
			(xy 115.276786 -279.250106) (xy 115.2292 -279.232059) (xy 115.185126 -279.206613) (xy 115.145704 -279.174426)
			(xy 115.111956 -279.136332) (xy 115.084755 -279.093318) (xy 115.064807 -279.046498) (xy 115.052628 -278.997084)
			(xy 115.048533 -278.946356) (xy 114.740436 -278.946356) (xy 114.739924 -278.971802) (xy 114.73176 -279.022036)
			(xy 114.715644 -279.07031) (xy 114.691993 -279.115373) (xy 114.66142 -279.156059) (xy 114.624716 -279.191314)
			(xy 114.582832 -279.220224) (xy 114.536853 -279.242041) (xy 114.487969 -279.256201) (xy 114.437448 -279.262335)
			(xy 114.386596 -279.260286) (xy 114.336732 -279.250106) (xy 114.289146 -279.232059) (xy 114.245072 -279.206613)
			(xy 114.20565 -279.174426) (xy 114.171902 -279.136332) (xy 114.144701 -279.093318) (xy 114.124753 -279.046498)
			(xy 114.112574 -278.997084) (xy 114.108479 -278.946356) (xy 113.802668 -278.946356) (xy 113.802178 -278.971345)
			(xy 113.794359 -279.020708) (xy 113.778915 -279.06824) (xy 113.756225 -279.112772) (xy 113.726849 -279.153205)
			(xy 113.691509 -279.188545) (xy 113.651076 -279.217921) (xy 113.606544 -279.240611) (xy 113.559012 -279.256055)
			(xy 113.509649 -279.263874) (xy 113.459671 -279.263874) (xy 113.410308 -279.256055) (xy 113.362776 -279.240611)
			(xy 113.318244 -279.217921) (xy 113.277811 -279.188545) (xy 113.242471 -279.153205) (xy 113.213095 -279.112772)
			(xy 113.190405 -279.06824) (xy 113.174961 -279.020708) (xy 113.167142 -278.971345) (xy 110.98862 -278.971345)
			(xy 110.980801 -279.020708) (xy 110.965357 -279.06824) (xy 110.942667 -279.112772) (xy 110.913291 -279.153205)
			(xy 110.877951 -279.188545) (xy 110.837518 -279.217921) (xy 110.792986 -279.240611) (xy 110.745454 -279.256055)
			(xy 110.696091 -279.263874) (xy 110.646113 -279.263874) (xy 110.59675 -279.256055) (xy 110.549218 -279.240611)
			(xy 110.504686 -279.217921) (xy 110.464253 -279.188545) (xy 110.428913 -279.153205) (xy 110.399537 -279.112772)
			(xy 110.376847 -279.06824) (xy 110.361403 -279.020708) (xy 110.353584 -278.971345) (xy 110.046267 -278.971345)
			(xy 110.046258 -278.971802) (xy 110.038094 -279.022036) (xy 110.021978 -279.07031) (xy 109.998327 -279.115373)
			(xy 109.967754 -279.156059) (xy 109.93105 -279.191314) (xy 109.889166 -279.220224) (xy 109.843187 -279.242041)
			(xy 109.794303 -279.256201) (xy 109.743782 -279.262335) (xy 109.69293 -279.260286) (xy 109.643066 -279.250106)
			(xy 109.59548 -279.232059) (xy 109.551406 -279.206613) (xy 109.511984 -279.174426) (xy 109.478236 -279.136332)
			(xy 109.451035 -279.093318) (xy 109.431087 -279.046498) (xy 109.418908 -278.997084) (xy 109.414813 -278.946356)
			(xy 109.106716 -278.946356) (xy 109.106204 -278.971802) (xy 109.09804 -279.022036) (xy 109.081924 -279.07031)
			(xy 109.058273 -279.115373) (xy 109.0277 -279.156059) (xy 108.990996 -279.191314) (xy 108.949112 -279.220224)
			(xy 108.903133 -279.242041) (xy 108.854249 -279.256201) (xy 108.803728 -279.262335) (xy 108.752876 -279.260286)
			(xy 108.703012 -279.250106) (xy 108.655426 -279.232059) (xy 108.611352 -279.206613) (xy 108.57193 -279.174426)
			(xy 108.538182 -279.136332) (xy 108.510981 -279.093318) (xy 108.491033 -279.046498) (xy 108.478854 -278.997084)
			(xy 108.474759 -278.946356) (xy 108.168948 -278.946356) (xy 108.168458 -278.971345) (xy 108.160639 -279.020708)
			(xy 108.145195 -279.06824) (xy 108.122505 -279.112772) (xy 108.093129 -279.153205) (xy 108.057789 -279.188545)
			(xy 108.017356 -279.217921) (xy 107.972824 -279.240611) (xy 107.925292 -279.256055) (xy 107.875929 -279.263874)
			(xy 107.825951 -279.263874) (xy 107.776588 -279.256055) (xy 107.729056 -279.240611) (xy 107.684524 -279.217921)
			(xy 107.644091 -279.188545) (xy 107.608751 -279.153205) (xy 107.579375 -279.112772) (xy 107.556685 -279.06824)
			(xy 107.541241 -279.020708) (xy 107.533422 -278.971345) (xy 105.34855 -278.971345) (xy 105.340731 -279.020708)
			(xy 105.325287 -279.06824) (xy 105.302597 -279.112772) (xy 105.273221 -279.153205) (xy 105.237881 -279.188545)
			(xy 105.197448 -279.217921) (xy 105.152916 -279.240611) (xy 105.105384 -279.256055) (xy 105.056021 -279.263874)
			(xy 105.006043 -279.263874) (xy 104.95668 -279.256055) (xy 104.909148 -279.240611) (xy 104.864616 -279.217921)
			(xy 104.824183 -279.188545) (xy 104.788843 -279.153205) (xy 104.759467 -279.112772) (xy 104.736777 -279.06824)
			(xy 104.721333 -279.020708) (xy 104.713514 -278.971345) (xy 102.528642 -278.971345) (xy 102.520823 -279.020708)
			(xy 102.505379 -279.06824) (xy 102.482689 -279.112772) (xy 102.453313 -279.153205) (xy 102.417973 -279.188545)
			(xy 102.37754 -279.217921) (xy 102.333008 -279.240611) (xy 102.285476 -279.256055) (xy 102.236113 -279.263874)
			(xy 102.186135 -279.263874) (xy 102.136772 -279.256055) (xy 102.08924 -279.240611) (xy 102.044708 -279.217921)
			(xy 102.004275 -279.188545) (xy 101.968935 -279.153205) (xy 101.939559 -279.112772) (xy 101.916869 -279.06824)
			(xy 101.901425 -279.020708) (xy 101.893606 -278.971345) (xy 99.70848 -278.971345) (xy 99.700661 -279.020708)
			(xy 99.685217 -279.06824) (xy 99.662527 -279.112772) (xy 99.633151 -279.153205) (xy 99.597811 -279.188545)
			(xy 99.557378 -279.217921) (xy 99.512846 -279.240611) (xy 99.465314 -279.256055) (xy 99.415951 -279.263874)
			(xy 99.365973 -279.263874) (xy 99.31661 -279.256055) (xy 99.269078 -279.240611) (xy 99.224546 -279.217921)
			(xy 99.184113 -279.188545) (xy 99.148773 -279.153205) (xy 99.119397 -279.112772) (xy 99.096707 -279.06824)
			(xy 99.081263 -279.020708) (xy 99.073444 -278.971345) (xy 96.888572 -278.971345) (xy 96.880753 -279.020708)
			(xy 96.865309 -279.06824) (xy 96.842619 -279.112772) (xy 96.813243 -279.153205) (xy 96.777903 -279.188545)
			(xy 96.73747 -279.217921) (xy 96.692938 -279.240611) (xy 96.645406 -279.256055) (xy 96.596043 -279.263874)
			(xy 96.546065 -279.263874) (xy 96.496702 -279.256055) (xy 96.44917 -279.240611) (xy 96.404638 -279.217921)
			(xy 96.364205 -279.188545) (xy 96.328865 -279.153205) (xy 96.299489 -279.112772) (xy 96.276799 -279.06824)
			(xy 96.261355 -279.020708) (xy 96.253536 -278.971345) (xy 95.946219 -278.971345) (xy 95.94621 -278.971802)
			(xy 95.938046 -279.022036) (xy 95.92193 -279.07031) (xy 95.898279 -279.115373) (xy 95.867706 -279.156059)
			(xy 95.831002 -279.191314) (xy 95.789118 -279.220224) (xy 95.743139 -279.242041) (xy 95.694255 -279.256201)
			(xy 95.643734 -279.262335) (xy 95.592882 -279.260286) (xy 95.543018 -279.250106) (xy 95.495432 -279.232059)
			(xy 95.451358 -279.206613) (xy 95.411936 -279.174426) (xy 95.378188 -279.136332) (xy 95.350987 -279.093318)
			(xy 95.331039 -279.046498) (xy 95.31886 -278.997084) (xy 95.314765 -278.946356) (xy 95.006668 -278.946356)
			(xy 95.006156 -278.971802) (xy 94.997992 -279.022036) (xy 94.981876 -279.07031) (xy 94.958225 -279.115373)
			(xy 94.927652 -279.156059) (xy 94.890948 -279.191314) (xy 94.849064 -279.220224) (xy 94.803085 -279.242041)
			(xy 94.754201 -279.256201) (xy 94.70368 -279.262335) (xy 94.652828 -279.260286) (xy 94.602964 -279.250106)
			(xy 94.555378 -279.232059) (xy 94.511304 -279.206613) (xy 94.471882 -279.174426) (xy 94.438134 -279.136332)
			(xy 94.410933 -279.093318) (xy 94.390985 -279.046498) (xy 94.378806 -278.997084) (xy 94.374711 -278.946356)
			(xy 94.069154 -278.946356) (xy 94.06852 -278.974911) (xy 94.058338 -279.031106) (xy 94.038292 -279.084583)
			(xy 94.024196 -279.109424) (xy 94.020894 -279.115012) (xy 94.015306 -279.134316) (xy 94.01436 -279.137796)
			(xy 94.013346 -279.144935) (xy 94.013274 -279.14854) (xy 94.013274 -279.352248) (xy 94.013836 -279.363918)
			(xy 94.024154 -279.384851) (xy 94.033086 -279.39238) (xy 94.099888 -279.443688) (xy 94.11589 -279.449022)
			(xy 94.139004 -279.449022) (xy 94.1451 -279.447498) (xy 94.163605 -279.443245) (xy 94.201299 -279.438655)
			(xy 94.220284 -279.438354) (xy 94.221046 -279.438354) (xy 94.246036 -279.438848) (xy 94.295399 -279.446673)
			(xy 94.342931 -279.462123) (xy 94.387461 -279.484818) (xy 94.427893 -279.514199) (xy 94.463231 -279.549542)
			(xy 94.492606 -279.589978) (xy 94.515295 -279.634512) (xy 94.530738 -279.682046) (xy 94.538556 -279.73141)
			(xy 94.538556 -279.781351) (xy 94.843582 -279.781351) (xy 94.843582 -279.731373) (xy 94.851401 -279.68201)
			(xy 94.866845 -279.634478) (xy 94.889535 -279.589946) (xy 94.918911 -279.549513) (xy 94.954251 -279.514173)
			(xy 94.994684 -279.484797) (xy 95.039216 -279.462107) (xy 95.086748 -279.446663) (xy 95.136111 -279.438844)
			(xy 95.186089 -279.438844) (xy 95.235452 -279.446663) (xy 95.282984 -279.462107) (xy 95.327516 -279.484797)
			(xy 95.367949 -279.514173) (xy 95.403289 -279.549513) (xy 95.432665 -279.589946) (xy 95.455355 -279.634478)
			(xy 95.470799 -279.68201) (xy 95.478618 -279.731373) (xy 95.479108 -279.756362) (xy 95.784919 -279.756362)
			(xy 95.789014 -279.705634) (xy 95.801193 -279.65622) (xy 95.821141 -279.6094) (xy 95.848342 -279.566386)
			(xy 95.88209 -279.528292) (xy 95.921512 -279.496105) (xy 95.965586 -279.470659) (xy 96.013172 -279.452612)
			(xy 96.063036 -279.442432) (xy 96.113888 -279.440383) (xy 96.164409 -279.446517) (xy 96.213293 -279.460677)
			(xy 96.259272 -279.482494) (xy 96.301156 -279.511404) (xy 96.33786 -279.546659) (xy 96.368433 -279.587345)
			(xy 96.392084 -279.632408) (xy 96.4082 -279.680682) (xy 96.416364 -279.730916) (xy 96.416876 -279.756362)
			(xy 96.416373 -279.781351) (xy 96.723436 -279.781351) (xy 96.723436 -279.731373) (xy 96.731255 -279.68201)
			(xy 96.746699 -279.634478) (xy 96.769389 -279.589946) (xy 96.798765 -279.549513) (xy 96.834105 -279.514173)
			(xy 96.874538 -279.484797) (xy 96.91907 -279.462107) (xy 96.966602 -279.446663) (xy 97.015965 -279.438844)
			(xy 97.065943 -279.438844) (xy 97.115306 -279.446663) (xy 97.162838 -279.462107) (xy 97.20737 -279.484797)
			(xy 97.247803 -279.514173) (xy 97.283143 -279.549513) (xy 97.312519 -279.589946) (xy 97.335209 -279.634478)
			(xy 97.350653 -279.68201) (xy 97.358472 -279.731373) (xy 97.358962 -279.756362) (xy 97.358472 -279.781351)
			(xy 97.66349 -279.781351) (xy 97.66349 -279.731373) (xy 97.671309 -279.68201) (xy 97.686753 -279.634478)
			(xy 97.709443 -279.589946) (xy 97.738819 -279.549513) (xy 97.774159 -279.514173) (xy 97.814592 -279.484797)
			(xy 97.859124 -279.462107) (xy 97.906656 -279.446663) (xy 97.956019 -279.438844) (xy 98.005997 -279.438844)
			(xy 98.05536 -279.446663) (xy 98.102892 -279.462107) (xy 98.147424 -279.484797) (xy 98.187857 -279.514173)
			(xy 98.223197 -279.549513) (xy 98.252573 -279.589946) (xy 98.275263 -279.634478) (xy 98.290707 -279.68201)
			(xy 98.298526 -279.731373) (xy 98.299016 -279.756362) (xy 98.298526 -279.781351) (xy 98.603544 -279.781351)
			(xy 98.603544 -279.731373) (xy 98.611363 -279.68201) (xy 98.626807 -279.634478) (xy 98.649497 -279.589946)
			(xy 98.678873 -279.549513) (xy 98.714213 -279.514173) (xy 98.754646 -279.484797) (xy 98.799178 -279.462107)
			(xy 98.84671 -279.446663) (xy 98.896073 -279.438844) (xy 98.946051 -279.438844) (xy 98.995414 -279.446663)
			(xy 99.042946 -279.462107) (xy 99.087478 -279.484797) (xy 99.127911 -279.514173) (xy 99.163251 -279.549513)
			(xy 99.192627 -279.589946) (xy 99.215317 -279.634478) (xy 99.230761 -279.68201) (xy 99.23858 -279.731373)
			(xy 99.23907 -279.756362) (xy 99.23858 -279.781351) (xy 99.543598 -279.781351) (xy 99.543598 -279.731373)
			(xy 99.551417 -279.68201) (xy 99.566861 -279.634478) (xy 99.589551 -279.589946) (xy 99.618927 -279.549513)
			(xy 99.654267 -279.514173) (xy 99.6947 -279.484797) (xy 99.739232 -279.462107) (xy 99.786764 -279.446663)
			(xy 99.836127 -279.438844) (xy 99.886105 -279.438844) (xy 99.935468 -279.446663) (xy 99.983 -279.462107)
			(xy 100.027532 -279.484797) (xy 100.067965 -279.514173) (xy 100.103305 -279.549513) (xy 100.132681 -279.589946)
			(xy 100.155371 -279.634478) (xy 100.170815 -279.68201) (xy 100.178634 -279.731373) (xy 100.179124 -279.756362)
			(xy 100.178634 -279.781351) (xy 100.483652 -279.781351) (xy 100.483652 -279.731373) (xy 100.491471 -279.68201)
			(xy 100.506915 -279.634478) (xy 100.529605 -279.589946) (xy 100.558981 -279.549513) (xy 100.594321 -279.514173)
			(xy 100.634754 -279.484797) (xy 100.679286 -279.462107) (xy 100.726818 -279.446663) (xy 100.776181 -279.438844)
			(xy 100.826159 -279.438844) (xy 100.875522 -279.446663) (xy 100.923054 -279.462107) (xy 100.967586 -279.484797)
			(xy 101.008019 -279.514173) (xy 101.043359 -279.549513) (xy 101.072735 -279.589946) (xy 101.095425 -279.634478)
			(xy 101.110869 -279.68201) (xy 101.118688 -279.731373) (xy 101.119178 -279.756362) (xy 101.118688 -279.781351)
			(xy 101.423452 -279.781351) (xy 101.423452 -279.731373) (xy 101.431271 -279.68201) (xy 101.446715 -279.634478)
			(xy 101.469405 -279.589946) (xy 101.498781 -279.549513) (xy 101.534121 -279.514173) (xy 101.574554 -279.484797)
			(xy 101.619086 -279.462107) (xy 101.666618 -279.446663) (xy 101.715981 -279.438844) (xy 101.765959 -279.438844)
			(xy 101.815322 -279.446663) (xy 101.862854 -279.462107) (xy 101.907386 -279.484797) (xy 101.947819 -279.514173)
			(xy 101.983159 -279.549513) (xy 102.012535 -279.589946) (xy 102.035225 -279.634478) (xy 102.050669 -279.68201)
			(xy 102.058488 -279.731373) (xy 102.058978 -279.756362) (xy 102.058488 -279.781351) (xy 102.363506 -279.781351)
			(xy 102.363506 -279.731373) (xy 102.371325 -279.68201) (xy 102.386769 -279.634478) (xy 102.409459 -279.589946)
			(xy 102.438835 -279.549513) (xy 102.474175 -279.514173) (xy 102.514608 -279.484797) (xy 102.55914 -279.462107)
			(xy 102.606672 -279.446663) (xy 102.656035 -279.438844) (xy 102.706013 -279.438844) (xy 102.755376 -279.446663)
			(xy 102.802908 -279.462107) (xy 102.84744 -279.484797) (xy 102.887873 -279.514173) (xy 102.923213 -279.549513)
			(xy 102.952589 -279.589946) (xy 102.975279 -279.634478) (xy 102.990723 -279.68201) (xy 102.998542 -279.731373)
			(xy 102.999032 -279.756362) (xy 102.998542 -279.781351) (xy 103.30356 -279.781351) (xy 103.30356 -279.731373)
			(xy 103.311379 -279.68201) (xy 103.326823 -279.634478) (xy 103.349513 -279.589946) (xy 103.378889 -279.549513)
			(xy 103.414229 -279.514173) (xy 103.454662 -279.484797) (xy 103.499194 -279.462107) (xy 103.546726 -279.446663)
			(xy 103.596089 -279.438844) (xy 103.646067 -279.438844) (xy 103.69543 -279.446663) (xy 103.742962 -279.462107)
			(xy 103.787494 -279.484797) (xy 103.827927 -279.514173) (xy 103.863267 -279.549513) (xy 103.892643 -279.589946)
			(xy 103.915333 -279.634478) (xy 103.930777 -279.68201) (xy 103.938596 -279.731373) (xy 103.939086 -279.756362)
			(xy 103.938596 -279.781351) (xy 104.243614 -279.781351) (xy 104.243614 -279.731373) (xy 104.251433 -279.68201)
			(xy 104.266877 -279.634478) (xy 104.289567 -279.589946) (xy 104.318943 -279.549513) (xy 104.354283 -279.514173)
			(xy 104.394716 -279.484797) (xy 104.439248 -279.462107) (xy 104.48678 -279.446663) (xy 104.536143 -279.438844)
			(xy 104.586121 -279.438844) (xy 104.635484 -279.446663) (xy 104.683016 -279.462107) (xy 104.727548 -279.484797)
			(xy 104.767981 -279.514173) (xy 104.803321 -279.549513) (xy 104.832697 -279.589946) (xy 104.855387 -279.634478)
			(xy 104.870831 -279.68201) (xy 104.87865 -279.731373) (xy 104.87914 -279.756362) (xy 104.87865 -279.781351)
			(xy 105.183414 -279.781351) (xy 105.183414 -279.731373) (xy 105.191233 -279.68201) (xy 105.206677 -279.634478)
			(xy 105.229367 -279.589946) (xy 105.258743 -279.549513) (xy 105.294083 -279.514173) (xy 105.334516 -279.484797)
			(xy 105.379048 -279.462107) (xy 105.42658 -279.446663) (xy 105.475943 -279.438844) (xy 105.525921 -279.438844)
			(xy 105.575284 -279.446663) (xy 105.622816 -279.462107) (xy 105.667348 -279.484797) (xy 105.707781 -279.514173)
			(xy 105.743121 -279.549513) (xy 105.772497 -279.589946) (xy 105.795187 -279.634478) (xy 105.810631 -279.68201)
			(xy 105.81845 -279.731373) (xy 105.81894 -279.756362) (xy 106.124751 -279.756362) (xy 106.128846 -279.705634)
			(xy 106.141025 -279.65622) (xy 106.160973 -279.6094) (xy 106.188174 -279.566386) (xy 106.221922 -279.528292)
			(xy 106.261344 -279.496105) (xy 106.305418 -279.470659) (xy 106.353004 -279.452612) (xy 106.402868 -279.442432)
			(xy 106.45372 -279.440383) (xy 106.504241 -279.446517) (xy 106.553125 -279.460677) (xy 106.599104 -279.482494)
			(xy 106.640988 -279.511404) (xy 106.677692 -279.546659) (xy 106.708265 -279.587345) (xy 106.731916 -279.632408)
			(xy 106.748032 -279.680682) (xy 106.756196 -279.730916) (xy 106.756708 -279.756362) (xy 107.064805 -279.756362)
			(xy 107.0689 -279.705634) (xy 107.081079 -279.65622) (xy 107.101027 -279.6094) (xy 107.128228 -279.566386)
			(xy 107.161976 -279.528292) (xy 107.201398 -279.496105) (xy 107.245472 -279.470659) (xy 107.293058 -279.452612)
			(xy 107.342922 -279.442432) (xy 107.393774 -279.440383) (xy 107.444295 -279.446517) (xy 107.493179 -279.460677)
			(xy 107.539158 -279.482494) (xy 107.581042 -279.511404) (xy 107.617746 -279.546659) (xy 107.648319 -279.587345)
			(xy 107.67197 -279.632408) (xy 107.688086 -279.680682) (xy 107.69625 -279.730916) (xy 107.696762 -279.756362)
			(xy 107.696259 -279.781351) (xy 108.003576 -279.781351) (xy 108.003576 -279.731373) (xy 108.011395 -279.68201)
			(xy 108.026839 -279.634478) (xy 108.049529 -279.589946) (xy 108.078905 -279.549513) (xy 108.114245 -279.514173)
			(xy 108.154678 -279.484797) (xy 108.19921 -279.462107) (xy 108.246742 -279.446663) (xy 108.296105 -279.438844)
			(xy 108.346083 -279.438844) (xy 108.395446 -279.446663) (xy 108.442978 -279.462107) (xy 108.48751 -279.484797)
			(xy 108.527943 -279.514173) (xy 108.563283 -279.549513) (xy 108.592659 -279.589946) (xy 108.615349 -279.634478)
			(xy 108.630793 -279.68201) (xy 108.638612 -279.731373) (xy 108.639102 -279.756362) (xy 108.638612 -279.781351)
			(xy 108.94363 -279.781351) (xy 108.94363 -279.731373) (xy 108.951449 -279.68201) (xy 108.966893 -279.634478)
			(xy 108.989583 -279.589946) (xy 109.018959 -279.549513) (xy 109.054299 -279.514173) (xy 109.094732 -279.484797)
			(xy 109.139264 -279.462107) (xy 109.186796 -279.446663) (xy 109.236159 -279.438844) (xy 109.286137 -279.438844)
			(xy 109.3355 -279.446663) (xy 109.383032 -279.462107) (xy 109.427564 -279.484797) (xy 109.467997 -279.514173)
			(xy 109.503337 -279.549513) (xy 109.532713 -279.589946) (xy 109.555403 -279.634478) (xy 109.570847 -279.68201)
			(xy 109.578666 -279.731373) (xy 109.579156 -279.756362) (xy 109.578666 -279.781351) (xy 109.88343 -279.781351)
			(xy 109.88343 -279.731373) (xy 109.891249 -279.68201) (xy 109.906693 -279.634478) (xy 109.929383 -279.589946)
			(xy 109.958759 -279.549513) (xy 109.994099 -279.514173) (xy 110.034532 -279.484797) (xy 110.079064 -279.462107)
			(xy 110.126596 -279.446663) (xy 110.175959 -279.438844) (xy 110.225937 -279.438844) (xy 110.2753 -279.446663)
			(xy 110.322832 -279.462107) (xy 110.367364 -279.484797) (xy 110.407797 -279.514173) (xy 110.443137 -279.549513)
			(xy 110.472513 -279.589946) (xy 110.495203 -279.634478) (xy 110.510647 -279.68201) (xy 110.518466 -279.731373)
			(xy 110.518956 -279.756362) (xy 110.518466 -279.781351) (xy 113.637296 -279.781351) (xy 113.637296 -279.731373)
			(xy 113.645115 -279.68201) (xy 113.660559 -279.634478) (xy 113.683249 -279.589946) (xy 113.712625 -279.549513)
			(xy 113.747965 -279.514173) (xy 113.788398 -279.484797) (xy 113.83293 -279.462107) (xy 113.880462 -279.446663)
			(xy 113.929825 -279.438844) (xy 113.979803 -279.438844) (xy 114.029166 -279.446663) (xy 114.076698 -279.462107)
			(xy 114.12123 -279.484797) (xy 114.161663 -279.514173) (xy 114.197003 -279.549513) (xy 114.226379 -279.589946)
			(xy 114.249069 -279.634478) (xy 114.264513 -279.68201) (xy 114.272332 -279.731373) (xy 114.272822 -279.756362)
			(xy 114.272332 -279.781351) (xy 114.577096 -279.781351) (xy 114.577096 -279.731373) (xy 114.584915 -279.68201)
			(xy 114.600359 -279.634478) (xy 114.623049 -279.589946) (xy 114.652425 -279.549513) (xy 114.687765 -279.514173)
			(xy 114.728198 -279.484797) (xy 114.77273 -279.462107) (xy 114.820262 -279.446663) (xy 114.869625 -279.438844)
			(xy 114.919603 -279.438844) (xy 114.968966 -279.446663) (xy 115.016498 -279.462107) (xy 115.06103 -279.484797)
			(xy 115.101463 -279.514173) (xy 115.136803 -279.549513) (xy 115.166179 -279.589946) (xy 115.188869 -279.634478)
			(xy 115.204313 -279.68201) (xy 115.212132 -279.731373) (xy 115.212622 -279.756362) (xy 115.212132 -279.781351)
			(xy 115.51715 -279.781351) (xy 115.51715 -279.731373) (xy 115.524969 -279.68201) (xy 115.540413 -279.634478)
			(xy 115.563103 -279.589946) (xy 115.592479 -279.549513) (xy 115.627819 -279.514173) (xy 115.668252 -279.484797)
			(xy 115.712784 -279.462107) (xy 115.760316 -279.446663) (xy 115.809679 -279.438844) (xy 115.859657 -279.438844)
			(xy 115.90902 -279.446663) (xy 115.956552 -279.462107) (xy 116.001084 -279.484797) (xy 116.041517 -279.514173)
			(xy 116.076857 -279.549513) (xy 116.106233 -279.589946) (xy 116.128923 -279.634478) (xy 116.144367 -279.68201)
			(xy 116.152186 -279.731373) (xy 116.152676 -279.756362) (xy 116.458487 -279.756362) (xy 116.462582 -279.705634)
			(xy 116.474761 -279.65622) (xy 116.494709 -279.6094) (xy 116.52191 -279.566386) (xy 116.555658 -279.528292)
			(xy 116.59508 -279.496105) (xy 116.639154 -279.470659) (xy 116.68674 -279.452612) (xy 116.736604 -279.442432)
			(xy 116.787456 -279.440383) (xy 116.837977 -279.446517) (xy 116.886861 -279.460677) (xy 116.93284 -279.482494)
			(xy 116.974724 -279.511404) (xy 117.011428 -279.546659) (xy 117.042001 -279.587345) (xy 117.065652 -279.632408)
			(xy 117.081768 -279.680682) (xy 117.089932 -279.730916) (xy 117.090444 -279.756362) (xy 117.398541 -279.756362)
			(xy 117.402636 -279.705634) (xy 117.414815 -279.65622) (xy 117.434763 -279.6094) (xy 117.461964 -279.566386)
			(xy 117.495712 -279.528292) (xy 117.535134 -279.496105) (xy 117.579208 -279.470659) (xy 117.626794 -279.452612)
			(xy 117.676658 -279.442432) (xy 117.72751 -279.440383) (xy 117.778031 -279.446517) (xy 117.826915 -279.460677)
			(xy 117.872894 -279.482494) (xy 117.914778 -279.511404) (xy 117.951482 -279.546659) (xy 117.982055 -279.587345)
			(xy 118.005706 -279.632408) (xy 118.021822 -279.680682) (xy 118.029986 -279.730916) (xy 118.030498 -279.756362)
			(xy 118.029995 -279.781351) (xy 118.337312 -279.781351) (xy 118.337312 -279.731373) (xy 118.345131 -279.68201)
			(xy 118.360575 -279.634478) (xy 118.383265 -279.589946) (xy 118.412641 -279.549513) (xy 118.447981 -279.514173)
			(xy 118.488414 -279.484797) (xy 118.532946 -279.462107) (xy 118.580478 -279.446663) (xy 118.629841 -279.438844)
			(xy 118.679819 -279.438844) (xy 118.729182 -279.446663) (xy 118.776714 -279.462107) (xy 118.821246 -279.484797)
			(xy 118.861679 -279.514173) (xy 118.897019 -279.549513) (xy 118.926395 -279.589946) (xy 118.949085 -279.634478)
			(xy 118.964529 -279.68201) (xy 118.972348 -279.731373) (xy 118.972838 -279.756362) (xy 118.972348 -279.781351)
			(xy 119.277112 -279.781351) (xy 119.277112 -279.731373) (xy 119.284931 -279.68201) (xy 119.300375 -279.634478)
			(xy 119.323065 -279.589946) (xy 119.352441 -279.549513) (xy 119.387781 -279.514173) (xy 119.428214 -279.484797)
			(xy 119.472746 -279.462107) (xy 119.520278 -279.446663) (xy 119.569641 -279.438844) (xy 119.619619 -279.438844)
			(xy 119.668982 -279.446663) (xy 119.716514 -279.462107) (xy 119.761046 -279.484797) (xy 119.801479 -279.514173)
			(xy 119.836819 -279.549513) (xy 119.866195 -279.589946) (xy 119.888885 -279.634478) (xy 119.904329 -279.68201)
			(xy 119.912148 -279.731373) (xy 119.912638 -279.756362) (xy 119.912148 -279.781351) (xy 120.217166 -279.781351)
			(xy 120.217166 -279.731373) (xy 120.224985 -279.68201) (xy 120.240429 -279.634478) (xy 120.263119 -279.589946)
			(xy 120.292495 -279.549513) (xy 120.327835 -279.514173) (xy 120.368268 -279.484797) (xy 120.4128 -279.462107)
			(xy 120.460332 -279.446663) (xy 120.509695 -279.438844) (xy 120.559673 -279.438844) (xy 120.609036 -279.446663)
			(xy 120.656568 -279.462107) (xy 120.7011 -279.484797) (xy 120.741533 -279.514173) (xy 120.776873 -279.549513)
			(xy 120.806249 -279.589946) (xy 120.828939 -279.634478) (xy 120.844383 -279.68201) (xy 120.852202 -279.731373)
			(xy 120.852692 -279.756362) (xy 120.852202 -279.781351) (xy 121.15722 -279.781351) (xy 121.15722 -279.731373)
			(xy 121.165039 -279.68201) (xy 121.180483 -279.634478) (xy 121.203173 -279.589946) (xy 121.232549 -279.549513)
			(xy 121.267889 -279.514173) (xy 121.308322 -279.484797) (xy 121.352854 -279.462107) (xy 121.400386 -279.446663)
			(xy 121.449749 -279.438844) (xy 121.499727 -279.438844) (xy 121.54909 -279.446663) (xy 121.596622 -279.462107)
			(xy 121.641154 -279.484797) (xy 121.681587 -279.514173) (xy 121.716927 -279.549513) (xy 121.746303 -279.589946)
			(xy 121.768993 -279.634478) (xy 121.784437 -279.68201) (xy 121.792256 -279.731373) (xy 121.792746 -279.756362)
			(xy 121.792256 -279.781351) (xy 122.097274 -279.781351) (xy 122.097274 -279.731373) (xy 122.105093 -279.68201)
			(xy 122.120537 -279.634478) (xy 122.143227 -279.589946) (xy 122.172603 -279.549513) (xy 122.207943 -279.514173)
			(xy 122.248376 -279.484797) (xy 122.292908 -279.462107) (xy 122.34044 -279.446663) (xy 122.389803 -279.438844)
			(xy 122.439781 -279.438844) (xy 122.489144 -279.446663) (xy 122.536676 -279.462107) (xy 122.581208 -279.484797)
			(xy 122.621641 -279.514173) (xy 122.656981 -279.549513) (xy 122.686357 -279.589946) (xy 122.709047 -279.634478)
			(xy 122.724491 -279.68201) (xy 122.73231 -279.731373) (xy 122.7328 -279.756362) (xy 122.73231 -279.781351)
			(xy 123.037328 -279.781351) (xy 123.037328 -279.731373) (xy 123.045147 -279.68201) (xy 123.060591 -279.634478)
			(xy 123.083281 -279.589946) (xy 123.112657 -279.549513) (xy 123.147997 -279.514173) (xy 123.18843 -279.484797)
			(xy 123.232962 -279.462107) (xy 123.280494 -279.446663) (xy 123.329857 -279.438844) (xy 123.379835 -279.438844)
			(xy 123.429198 -279.446663) (xy 123.47673 -279.462107) (xy 123.521262 -279.484797) (xy 123.561695 -279.514173)
			(xy 123.597035 -279.549513) (xy 123.626411 -279.589946) (xy 123.649101 -279.634478) (xy 123.664545 -279.68201)
			(xy 123.672364 -279.731373) (xy 123.672854 -279.756362) (xy 123.672364 -279.781351) (xy 123.977128 -279.781351)
			(xy 123.977128 -279.731373) (xy 123.984947 -279.68201) (xy 124.000391 -279.634478) (xy 124.023081 -279.589946)
			(xy 124.052457 -279.549513) (xy 124.087797 -279.514173) (xy 124.12823 -279.484797) (xy 124.172762 -279.462107)
			(xy 124.220294 -279.446663) (xy 124.269657 -279.438844) (xy 124.319635 -279.438844) (xy 124.368998 -279.446663)
			(xy 124.41653 -279.462107) (xy 124.461062 -279.484797) (xy 124.501495 -279.514173) (xy 124.536835 -279.549513)
			(xy 124.566211 -279.589946) (xy 124.588901 -279.634478) (xy 124.604345 -279.68201) (xy 124.612164 -279.731373)
			(xy 124.612654 -279.756362) (xy 124.612164 -279.781351) (xy 124.917182 -279.781351) (xy 124.917182 -279.731373)
			(xy 124.925001 -279.68201) (xy 124.940445 -279.634478) (xy 124.963135 -279.589946) (xy 124.992511 -279.549513)
			(xy 125.027851 -279.514173) (xy 125.068284 -279.484797) (xy 125.112816 -279.462107) (xy 125.160348 -279.446663)
			(xy 125.209711 -279.438844) (xy 125.259689 -279.438844) (xy 125.309052 -279.446663) (xy 125.356584 -279.462107)
			(xy 125.401116 -279.484797) (xy 125.441549 -279.514173) (xy 125.476889 -279.549513) (xy 125.506265 -279.589946)
			(xy 125.528955 -279.634478) (xy 125.544399 -279.68201) (xy 125.552218 -279.731373) (xy 125.552708 -279.756362)
			(xy 125.552218 -279.781351) (xy 125.544399 -279.830714) (xy 125.528955 -279.878246) (xy 125.506265 -279.922778)
			(xy 125.476889 -279.963211) (xy 125.441549 -279.998551) (xy 125.401116 -280.027927) (xy 125.356584 -280.050617)
			(xy 125.309052 -280.066061) (xy 125.259689 -280.07388) (xy 125.209711 -280.07388) (xy 125.160348 -280.066061)
			(xy 125.112816 -280.050617) (xy 125.068284 -280.027927) (xy 125.027851 -279.998551) (xy 124.992511 -279.963211)
			(xy 124.963135 -279.922778) (xy 124.940445 -279.878246) (xy 124.925001 -279.830714) (xy 124.917182 -279.781351)
			(xy 124.612164 -279.781351) (xy 124.604345 -279.830714) (xy 124.588901 -279.878246) (xy 124.566211 -279.922778)
			(xy 124.536835 -279.963211) (xy 124.501495 -279.998551) (xy 124.461062 -280.027927) (xy 124.41653 -280.050617)
			(xy 124.368998 -280.066061) (xy 124.319635 -280.07388) (xy 124.269657 -280.07388) (xy 124.220294 -280.066061)
			(xy 124.172762 -280.050617) (xy 124.12823 -280.027927) (xy 124.087797 -279.998551) (xy 124.052457 -279.963211)
			(xy 124.023081 -279.922778) (xy 124.000391 -279.878246) (xy 123.984947 -279.830714) (xy 123.977128 -279.781351)
			(xy 123.672364 -279.781351) (xy 123.664545 -279.830714) (xy 123.649101 -279.878246) (xy 123.626411 -279.922778)
			(xy 123.597035 -279.963211) (xy 123.561695 -279.998551) (xy 123.521262 -280.027927) (xy 123.47673 -280.050617)
			(xy 123.429198 -280.066061) (xy 123.379835 -280.07388) (xy 123.329857 -280.07388) (xy 123.280494 -280.066061)
			(xy 123.232962 -280.050617) (xy 123.18843 -280.027927) (xy 123.147997 -279.998551) (xy 123.112657 -279.963211)
			(xy 123.083281 -279.922778) (xy 123.060591 -279.878246) (xy 123.045147 -279.830714) (xy 123.037328 -279.781351)
			(xy 122.73231 -279.781351) (xy 122.724491 -279.830714) (xy 122.709047 -279.878246) (xy 122.686357 -279.922778)
			(xy 122.656981 -279.963211) (xy 122.621641 -279.998551) (xy 122.581208 -280.027927) (xy 122.536676 -280.050617)
			(xy 122.489144 -280.066061) (xy 122.439781 -280.07388) (xy 122.389803 -280.07388) (xy 122.34044 -280.066061)
			(xy 122.292908 -280.050617) (xy 122.248376 -280.027927) (xy 122.207943 -279.998551) (xy 122.172603 -279.963211)
			(xy 122.143227 -279.922778) (xy 122.120537 -279.878246) (xy 122.105093 -279.830714) (xy 122.097274 -279.781351)
			(xy 121.792256 -279.781351) (xy 121.784437 -279.830714) (xy 121.768993 -279.878246) (xy 121.746303 -279.922778)
			(xy 121.716927 -279.963211) (xy 121.681587 -279.998551) (xy 121.641154 -280.027927) (xy 121.596622 -280.050617)
			(xy 121.54909 -280.066061) (xy 121.499727 -280.07388) (xy 121.449749 -280.07388) (xy 121.400386 -280.066061)
			(xy 121.352854 -280.050617) (xy 121.308322 -280.027927) (xy 121.267889 -279.998551) (xy 121.232549 -279.963211)
			(xy 121.203173 -279.922778) (xy 121.180483 -279.878246) (xy 121.165039 -279.830714) (xy 121.15722 -279.781351)
			(xy 120.852202 -279.781351) (xy 120.844383 -279.830714) (xy 120.828939 -279.878246) (xy 120.806249 -279.922778)
			(xy 120.776873 -279.963211) (xy 120.741533 -279.998551) (xy 120.7011 -280.027927) (xy 120.656568 -280.050617)
			(xy 120.609036 -280.066061) (xy 120.559673 -280.07388) (xy 120.509695 -280.07388) (xy 120.460332 -280.066061)
			(xy 120.4128 -280.050617) (xy 120.368268 -280.027927) (xy 120.327835 -279.998551) (xy 120.292495 -279.963211)
			(xy 120.263119 -279.922778) (xy 120.240429 -279.878246) (xy 120.224985 -279.830714) (xy 120.217166 -279.781351)
			(xy 119.912148 -279.781351) (xy 119.904329 -279.830714) (xy 119.888885 -279.878246) (xy 119.866195 -279.922778)
			(xy 119.836819 -279.963211) (xy 119.801479 -279.998551) (xy 119.761046 -280.027927) (xy 119.716514 -280.050617)
			(xy 119.668982 -280.066061) (xy 119.619619 -280.07388) (xy 119.569641 -280.07388) (xy 119.520278 -280.066061)
			(xy 119.472746 -280.050617) (xy 119.428214 -280.027927) (xy 119.387781 -279.998551) (xy 119.352441 -279.963211)
			(xy 119.323065 -279.922778) (xy 119.300375 -279.878246) (xy 119.284931 -279.830714) (xy 119.277112 -279.781351)
			(xy 118.972348 -279.781351) (xy 118.964529 -279.830714) (xy 118.949085 -279.878246) (xy 118.926395 -279.922778)
			(xy 118.897019 -279.963211) (xy 118.861679 -279.998551) (xy 118.821246 -280.027927) (xy 118.776714 -280.050617)
			(xy 118.729182 -280.066061) (xy 118.679819 -280.07388) (xy 118.629841 -280.07388) (xy 118.580478 -280.066061)
			(xy 118.532946 -280.050617) (xy 118.488414 -280.027927) (xy 118.447981 -279.998551) (xy 118.412641 -279.963211)
			(xy 118.383265 -279.922778) (xy 118.360575 -279.878246) (xy 118.345131 -279.830714) (xy 118.337312 -279.781351)
			(xy 118.029995 -279.781351) (xy 118.029986 -279.781808) (xy 118.021822 -279.832042) (xy 118.005706 -279.880316)
			(xy 117.982055 -279.925379) (xy 117.951482 -279.966065) (xy 117.914778 -280.00132) (xy 117.872894 -280.03023)
			(xy 117.826915 -280.052047) (xy 117.778031 -280.066207) (xy 117.72751 -280.072341) (xy 117.676658 -280.070292)
			(xy 117.626794 -280.060112) (xy 117.579208 -280.042065) (xy 117.535134 -280.016619) (xy 117.495712 -279.984432)
			(xy 117.461964 -279.946338) (xy 117.434763 -279.903324) (xy 117.414815 -279.856504) (xy 117.402636 -279.80709)
			(xy 117.398541 -279.756362) (xy 117.090444 -279.756362) (xy 117.089932 -279.781808) (xy 117.081768 -279.832042)
			(xy 117.065652 -279.880316) (xy 117.042001 -279.925379) (xy 117.011428 -279.966065) (xy 116.974724 -280.00132)
			(xy 116.93284 -280.03023) (xy 116.886861 -280.052047) (xy 116.837977 -280.066207) (xy 116.787456 -280.072341)
			(xy 116.736604 -280.070292) (xy 116.68674 -280.060112) (xy 116.639154 -280.042065) (xy 116.59508 -280.016619)
			(xy 116.555658 -279.984432) (xy 116.52191 -279.946338) (xy 116.494709 -279.903324) (xy 116.474761 -279.856504)
			(xy 116.462582 -279.80709) (xy 116.458487 -279.756362) (xy 116.152676 -279.756362) (xy 116.152186 -279.781351)
			(xy 116.144367 -279.830714) (xy 116.128923 -279.878246) (xy 116.106233 -279.922778) (xy 116.076857 -279.963211)
			(xy 116.041517 -279.998551) (xy 116.001084 -280.027927) (xy 115.956552 -280.050617) (xy 115.90902 -280.066061)
			(xy 115.859657 -280.07388) (xy 115.809679 -280.07388) (xy 115.760316 -280.066061) (xy 115.712784 -280.050617)
			(xy 115.668252 -280.027927) (xy 115.627819 -279.998551) (xy 115.592479 -279.963211) (xy 115.563103 -279.922778)
			(xy 115.540413 -279.878246) (xy 115.524969 -279.830714) (xy 115.51715 -279.781351) (xy 115.212132 -279.781351)
			(xy 115.204313 -279.830714) (xy 115.188869 -279.878246) (xy 115.166179 -279.922778) (xy 115.136803 -279.963211)
			(xy 115.101463 -279.998551) (xy 115.06103 -280.027927) (xy 115.016498 -280.050617) (xy 114.968966 -280.066061)
			(xy 114.919603 -280.07388) (xy 114.869625 -280.07388) (xy 114.820262 -280.066061) (xy 114.77273 -280.050617)
			(xy 114.728198 -280.027927) (xy 114.687765 -279.998551) (xy 114.652425 -279.963211) (xy 114.623049 -279.922778)
			(xy 114.600359 -279.878246) (xy 114.584915 -279.830714) (xy 114.577096 -279.781351) (xy 114.272332 -279.781351)
			(xy 114.264513 -279.830714) (xy 114.249069 -279.878246) (xy 114.226379 -279.922778) (xy 114.197003 -279.963211)
			(xy 114.161663 -279.998551) (xy 114.12123 -280.027927) (xy 114.076698 -280.050617) (xy 114.029166 -280.066061)
			(xy 113.979803 -280.07388) (xy 113.929825 -280.07388) (xy 113.880462 -280.066061) (xy 113.83293 -280.050617)
			(xy 113.788398 -280.027927) (xy 113.747965 -279.998551) (xy 113.712625 -279.963211) (xy 113.683249 -279.922778)
			(xy 113.660559 -279.878246) (xy 113.645115 -279.830714) (xy 113.637296 -279.781351) (xy 110.518466 -279.781351)
			(xy 110.510647 -279.830714) (xy 110.495203 -279.878246) (xy 110.472513 -279.922778) (xy 110.443137 -279.963211)
			(xy 110.407797 -279.998551) (xy 110.367364 -280.027927) (xy 110.322832 -280.050617) (xy 110.2753 -280.066061)
			(xy 110.225937 -280.07388) (xy 110.175959 -280.07388) (xy 110.126596 -280.066061) (xy 110.079064 -280.050617)
			(xy 110.034532 -280.027927) (xy 109.994099 -279.998551) (xy 109.958759 -279.963211) (xy 109.929383 -279.922778)
			(xy 109.906693 -279.878246) (xy 109.891249 -279.830714) (xy 109.88343 -279.781351) (xy 109.578666 -279.781351)
			(xy 109.570847 -279.830714) (xy 109.555403 -279.878246) (xy 109.532713 -279.922778) (xy 109.503337 -279.963211)
			(xy 109.467997 -279.998551) (xy 109.427564 -280.027927) (xy 109.383032 -280.050617) (xy 109.3355 -280.066061)
			(xy 109.286137 -280.07388) (xy 109.236159 -280.07388) (xy 109.186796 -280.066061) (xy 109.139264 -280.050617)
			(xy 109.094732 -280.027927) (xy 109.054299 -279.998551) (xy 109.018959 -279.963211) (xy 108.989583 -279.922778)
			(xy 108.966893 -279.878246) (xy 108.951449 -279.830714) (xy 108.94363 -279.781351) (xy 108.638612 -279.781351)
			(xy 108.630793 -279.830714) (xy 108.615349 -279.878246) (xy 108.592659 -279.922778) (xy 108.563283 -279.963211)
			(xy 108.527943 -279.998551) (xy 108.48751 -280.027927) (xy 108.442978 -280.050617) (xy 108.395446 -280.066061)
			(xy 108.346083 -280.07388) (xy 108.296105 -280.07388) (xy 108.246742 -280.066061) (xy 108.19921 -280.050617)
			(xy 108.154678 -280.027927) (xy 108.114245 -279.998551) (xy 108.078905 -279.963211) (xy 108.049529 -279.922778)
			(xy 108.026839 -279.878246) (xy 108.011395 -279.830714) (xy 108.003576 -279.781351) (xy 107.696259 -279.781351)
			(xy 107.69625 -279.781808) (xy 107.688086 -279.832042) (xy 107.67197 -279.880316) (xy 107.648319 -279.925379)
			(xy 107.617746 -279.966065) (xy 107.581042 -280.00132) (xy 107.539158 -280.03023) (xy 107.493179 -280.052047)
			(xy 107.444295 -280.066207) (xy 107.393774 -280.072341) (xy 107.342922 -280.070292) (xy 107.293058 -280.060112)
			(xy 107.245472 -280.042065) (xy 107.201398 -280.016619) (xy 107.161976 -279.984432) (xy 107.128228 -279.946338)
			(xy 107.101027 -279.903324) (xy 107.081079 -279.856504) (xy 107.0689 -279.80709) (xy 107.064805 -279.756362)
			(xy 106.756708 -279.756362) (xy 106.756196 -279.781808) (xy 106.748032 -279.832042) (xy 106.731916 -279.880316)
			(xy 106.708265 -279.925379) (xy 106.677692 -279.966065) (xy 106.640988 -280.00132) (xy 106.599104 -280.03023)
			(xy 106.553125 -280.052047) (xy 106.504241 -280.066207) (xy 106.45372 -280.072341) (xy 106.402868 -280.070292)
			(xy 106.353004 -280.060112) (xy 106.305418 -280.042065) (xy 106.261344 -280.016619) (xy 106.221922 -279.984432)
			(xy 106.188174 -279.946338) (xy 106.160973 -279.903324) (xy 106.141025 -279.856504) (xy 106.128846 -279.80709)
			(xy 106.124751 -279.756362) (xy 105.81894 -279.756362) (xy 105.81845 -279.781351) (xy 105.810631 -279.830714)
			(xy 105.795187 -279.878246) (xy 105.772497 -279.922778) (xy 105.743121 -279.963211) (xy 105.707781 -279.998551)
			(xy 105.667348 -280.027927) (xy 105.622816 -280.050617) (xy 105.575284 -280.066061) (xy 105.525921 -280.07388)
			(xy 105.475943 -280.07388) (xy 105.42658 -280.066061) (xy 105.379048 -280.050617) (xy 105.334516 -280.027927)
			(xy 105.294083 -279.998551) (xy 105.258743 -279.963211) (xy 105.229367 -279.922778) (xy 105.206677 -279.878246)
			(xy 105.191233 -279.830714) (xy 105.183414 -279.781351) (xy 104.87865 -279.781351) (xy 104.870831 -279.830714)
			(xy 104.855387 -279.878246) (xy 104.832697 -279.922778) (xy 104.803321 -279.963211) (xy 104.767981 -279.998551)
			(xy 104.727548 -280.027927) (xy 104.683016 -280.050617) (xy 104.635484 -280.066061) (xy 104.586121 -280.07388)
			(xy 104.536143 -280.07388) (xy 104.48678 -280.066061) (xy 104.439248 -280.050617) (xy 104.394716 -280.027927)
			(xy 104.354283 -279.998551) (xy 104.318943 -279.963211) (xy 104.289567 -279.922778) (xy 104.266877 -279.878246)
			(xy 104.251433 -279.830714) (xy 104.243614 -279.781351) (xy 103.938596 -279.781351) (xy 103.930777 -279.830714)
			(xy 103.915333 -279.878246) (xy 103.892643 -279.922778) (xy 103.863267 -279.963211) (xy 103.827927 -279.998551)
			(xy 103.787494 -280.027927) (xy 103.742962 -280.050617) (xy 103.69543 -280.066061) (xy 103.646067 -280.07388)
			(xy 103.596089 -280.07388) (xy 103.546726 -280.066061) (xy 103.499194 -280.050617) (xy 103.454662 -280.027927)
			(xy 103.414229 -279.998551) (xy 103.378889 -279.963211) (xy 103.349513 -279.922778) (xy 103.326823 -279.878246)
			(xy 103.311379 -279.830714) (xy 103.30356 -279.781351) (xy 102.998542 -279.781351) (xy 102.990723 -279.830714)
			(xy 102.975279 -279.878246) (xy 102.952589 -279.922778) (xy 102.923213 -279.963211) (xy 102.887873 -279.998551)
			(xy 102.84744 -280.027927) (xy 102.802908 -280.050617) (xy 102.755376 -280.066061) (xy 102.706013 -280.07388)
			(xy 102.656035 -280.07388) (xy 102.606672 -280.066061) (xy 102.55914 -280.050617) (xy 102.514608 -280.027927)
			(xy 102.474175 -279.998551) (xy 102.438835 -279.963211) (xy 102.409459 -279.922778) (xy 102.386769 -279.878246)
			(xy 102.371325 -279.830714) (xy 102.363506 -279.781351) (xy 102.058488 -279.781351) (xy 102.050669 -279.830714)
			(xy 102.035225 -279.878246) (xy 102.012535 -279.922778) (xy 101.983159 -279.963211) (xy 101.947819 -279.998551)
			(xy 101.907386 -280.027927) (xy 101.862854 -280.050617) (xy 101.815322 -280.066061) (xy 101.765959 -280.07388)
			(xy 101.715981 -280.07388) (xy 101.666618 -280.066061) (xy 101.619086 -280.050617) (xy 101.574554 -280.027927)
			(xy 101.534121 -279.998551) (xy 101.498781 -279.963211) (xy 101.469405 -279.922778) (xy 101.446715 -279.878246)
			(xy 101.431271 -279.830714) (xy 101.423452 -279.781351) (xy 101.118688 -279.781351) (xy 101.110869 -279.830714)
			(xy 101.095425 -279.878246) (xy 101.072735 -279.922778) (xy 101.043359 -279.963211) (xy 101.008019 -279.998551)
			(xy 100.967586 -280.027927) (xy 100.923054 -280.050617) (xy 100.875522 -280.066061) (xy 100.826159 -280.07388)
			(xy 100.776181 -280.07388) (xy 100.726818 -280.066061) (xy 100.679286 -280.050617) (xy 100.634754 -280.027927)
			(xy 100.594321 -279.998551) (xy 100.558981 -279.963211) (xy 100.529605 -279.922778) (xy 100.506915 -279.878246)
			(xy 100.491471 -279.830714) (xy 100.483652 -279.781351) (xy 100.178634 -279.781351) (xy 100.170815 -279.830714)
			(xy 100.155371 -279.878246) (xy 100.132681 -279.922778) (xy 100.103305 -279.963211) (xy 100.067965 -279.998551)
			(xy 100.027532 -280.027927) (xy 99.983 -280.050617) (xy 99.935468 -280.066061) (xy 99.886105 -280.07388)
			(xy 99.836127 -280.07388) (xy 99.786764 -280.066061) (xy 99.739232 -280.050617) (xy 99.6947 -280.027927)
			(xy 99.654267 -279.998551) (xy 99.618927 -279.963211) (xy 99.589551 -279.922778) (xy 99.566861 -279.878246)
			(xy 99.551417 -279.830714) (xy 99.543598 -279.781351) (xy 99.23858 -279.781351) (xy 99.230761 -279.830714)
			(xy 99.215317 -279.878246) (xy 99.192627 -279.922778) (xy 99.163251 -279.963211) (xy 99.127911 -279.998551)
			(xy 99.087478 -280.027927) (xy 99.042946 -280.050617) (xy 98.995414 -280.066061) (xy 98.946051 -280.07388)
			(xy 98.896073 -280.07388) (xy 98.84671 -280.066061) (xy 98.799178 -280.050617) (xy 98.754646 -280.027927)
			(xy 98.714213 -279.998551) (xy 98.678873 -279.963211) (xy 98.649497 -279.922778) (xy 98.626807 -279.878246)
			(xy 98.611363 -279.830714) (xy 98.603544 -279.781351) (xy 98.298526 -279.781351) (xy 98.290707 -279.830714)
			(xy 98.275263 -279.878246) (xy 98.252573 -279.922778) (xy 98.223197 -279.963211) (xy 98.187857 -279.998551)
			(xy 98.147424 -280.027927) (xy 98.102892 -280.050617) (xy 98.05536 -280.066061) (xy 98.005997 -280.07388)
			(xy 97.956019 -280.07388) (xy 97.906656 -280.066061) (xy 97.859124 -280.050617) (xy 97.814592 -280.027927)
			(xy 97.774159 -279.998551) (xy 97.738819 -279.963211) (xy 97.709443 -279.922778) (xy 97.686753 -279.878246)
			(xy 97.671309 -279.830714) (xy 97.66349 -279.781351) (xy 97.358472 -279.781351) (xy 97.350653 -279.830714)
			(xy 97.335209 -279.878246) (xy 97.312519 -279.922778) (xy 97.283143 -279.963211) (xy 97.247803 -279.998551)
			(xy 97.20737 -280.027927) (xy 97.162838 -280.050617) (xy 97.115306 -280.066061) (xy 97.065943 -280.07388)
			(xy 97.015965 -280.07388) (xy 96.966602 -280.066061) (xy 96.91907 -280.050617) (xy 96.874538 -280.027927)
			(xy 96.834105 -279.998551) (xy 96.798765 -279.963211) (xy 96.769389 -279.922778) (xy 96.746699 -279.878246)
			(xy 96.731255 -279.830714) (xy 96.723436 -279.781351) (xy 96.416373 -279.781351) (xy 96.416364 -279.781808)
			(xy 96.4082 -279.832042) (xy 96.392084 -279.880316) (xy 96.368433 -279.925379) (xy 96.33786 -279.966065)
			(xy 96.301156 -280.00132) (xy 96.259272 -280.03023) (xy 96.213293 -280.052047) (xy 96.164409 -280.066207)
			(xy 96.113888 -280.072341) (xy 96.063036 -280.070292) (xy 96.013172 -280.060112) (xy 95.965586 -280.042065)
			(xy 95.921512 -280.016619) (xy 95.88209 -279.984432) (xy 95.848342 -279.946338) (xy 95.821141 -279.903324)
			(xy 95.801193 -279.856504) (xy 95.789014 -279.80709) (xy 95.784919 -279.756362) (xy 95.479108 -279.756362)
			(xy 95.478618 -279.781351) (xy 95.470799 -279.830714) (xy 95.455355 -279.878246) (xy 95.432665 -279.922778)
			(xy 95.403289 -279.963211) (xy 95.367949 -279.998551) (xy 95.327516 -280.027927) (xy 95.282984 -280.050617)
			(xy 95.235452 -280.066061) (xy 95.186089 -280.07388) (xy 95.136111 -280.07388) (xy 95.086748 -280.066061)
			(xy 95.039216 -280.050617) (xy 94.994684 -280.027927) (xy 94.954251 -279.998551) (xy 94.918911 -279.963211)
			(xy 94.889535 -279.922778) (xy 94.866845 -279.878246) (xy 94.851401 -279.830714) (xy 94.843582 -279.781351)
			(xy 94.538556 -279.781351) (xy 94.538556 -279.78139) (xy 94.530738 -279.830754) (xy 94.515295 -279.878288)
			(xy 94.492606 -279.922822) (xy 94.463231 -279.963258) (xy 94.427893 -279.998601) (xy 94.387461 -280.027982)
			(xy 94.342931 -280.050677) (xy 94.295399 -280.066127) (xy 94.246036 -280.073952) (xy 94.221046 -280.07437)
			(xy 94.197729 -280.073959) (xy 94.151594 -280.067148) (xy 94.106947 -280.053679) (xy 94.085664 -280.044144)
			(xy 94.075504 -280.039318) (xy 94.064074 -280.039318) (xy 94.054071 -280.039811) (xy 94.035591 -280.047476)
			(xy 94.021451 -280.061628) (xy 94.013802 -280.080115) (xy 94.013274 -280.090118) (xy 94.013274 -280.097738)
			(xy 94.012743 -280.107577) (xy 94.005161 -280.125745) (xy 93.998542 -280.133044) (xy 93.953076 -280.17851)
			(xy 93.946097 -280.186263) (xy 93.93851 -280.20567) (xy 93.938344 -280.216102) (xy 93.940884 -280.288238)
			(xy 93.941604 -280.29775) (xy 93.949161 -280.315251) (xy 93.955616 -280.322274) (xy 93.958156 -280.324814)
			(xy 93.95968 -280.326084) (xy 93.979869 -280.344387) (xy 94.014297 -280.386623) (xy 94.041041 -280.434099)
			(xy 94.059324 -280.48543) (xy 94.068611 -280.539123) (xy 94.069154 -280.566368) (xy 94.374711 -280.566368)
			(xy 94.378806 -280.51564) (xy 94.390985 -280.466226) (xy 94.410933 -280.419406) (xy 94.438134 -280.376392)
			(xy 94.471882 -280.338298) (xy 94.511304 -280.306111) (xy 94.555378 -280.280665) (xy 94.602964 -280.262618)
			(xy 94.652828 -280.252438) (xy 94.70368 -280.250389) (xy 94.754201 -280.256523) (xy 94.803085 -280.270683)
			(xy 94.849064 -280.2925) (xy 94.890948 -280.32141) (xy 94.927652 -280.356665) (xy 94.958225 -280.397351)
			(xy 94.981876 -280.442414) (xy 94.997992 -280.490688) (xy 95.006156 -280.540922) (xy 95.006668 -280.566368)
			(xy 95.314765 -280.566368) (xy 95.31886 -280.51564) (xy 95.331039 -280.466226) (xy 95.350987 -280.419406)
			(xy 95.378188 -280.376392) (xy 95.411936 -280.338298) (xy 95.451358 -280.306111) (xy 95.495432 -280.280665)
			(xy 95.543018 -280.262618) (xy 95.592882 -280.252438) (xy 95.643734 -280.250389) (xy 95.694255 -280.256523)
			(xy 95.743139 -280.270683) (xy 95.789118 -280.2925) (xy 95.831002 -280.32141) (xy 95.867706 -280.356665)
			(xy 95.898279 -280.397351) (xy 95.92193 -280.442414) (xy 95.938046 -280.490688) (xy 95.94621 -280.540922)
			(xy 95.946722 -280.566368) (xy 95.946219 -280.591357) (xy 96.253536 -280.591357) (xy 96.253536 -280.541379)
			(xy 96.261355 -280.492016) (xy 96.276799 -280.444484) (xy 96.299489 -280.399952) (xy 96.328865 -280.359519)
			(xy 96.364205 -280.324179) (xy 96.404638 -280.294803) (xy 96.44917 -280.272113) (xy 96.496702 -280.256669)
			(xy 96.546065 -280.24885) (xy 96.596043 -280.24885) (xy 96.645406 -280.256669) (xy 96.692938 -280.272113)
			(xy 96.73747 -280.294803) (xy 96.777903 -280.324179) (xy 96.813243 -280.359519) (xy 96.842619 -280.399952)
			(xy 96.865309 -280.444484) (xy 96.880753 -280.492016) (xy 96.888572 -280.541379) (xy 96.889062 -280.566368)
			(xy 96.888572 -280.591357) (xy 97.19359 -280.591357) (xy 97.19359 -280.541379) (xy 97.201409 -280.492016)
			(xy 97.216853 -280.444484) (xy 97.239543 -280.399952) (xy 97.268919 -280.359519) (xy 97.304259 -280.324179)
			(xy 97.344692 -280.294803) (xy 97.389224 -280.272113) (xy 97.436756 -280.256669) (xy 97.486119 -280.24885)
			(xy 97.536097 -280.24885) (xy 97.58546 -280.256669) (xy 97.632992 -280.272113) (xy 97.677524 -280.294803)
			(xy 97.717957 -280.324179) (xy 97.753297 -280.359519) (xy 97.782673 -280.399952) (xy 97.805363 -280.444484)
			(xy 97.820807 -280.492016) (xy 97.828626 -280.541379) (xy 97.829116 -280.566368) (xy 97.828626 -280.591357)
			(xy 98.133644 -280.591357) (xy 98.133644 -280.541379) (xy 98.141463 -280.492016) (xy 98.156907 -280.444484)
			(xy 98.179597 -280.399952) (xy 98.208973 -280.359519) (xy 98.244313 -280.324179) (xy 98.284746 -280.294803)
			(xy 98.329278 -280.272113) (xy 98.37681 -280.256669) (xy 98.426173 -280.24885) (xy 98.476151 -280.24885)
			(xy 98.525514 -280.256669) (xy 98.573046 -280.272113) (xy 98.617578 -280.294803) (xy 98.658011 -280.324179)
			(xy 98.693351 -280.359519) (xy 98.722727 -280.399952) (xy 98.745417 -280.444484) (xy 98.760861 -280.492016)
			(xy 98.76868 -280.541379) (xy 98.76917 -280.566368) (xy 98.76868 -280.591357) (xy 99.073444 -280.591357)
			(xy 99.073444 -280.541379) (xy 99.081263 -280.492016) (xy 99.096707 -280.444484) (xy 99.119397 -280.399952)
			(xy 99.148773 -280.359519) (xy 99.184113 -280.324179) (xy 99.224546 -280.294803) (xy 99.269078 -280.272113)
			(xy 99.31661 -280.256669) (xy 99.365973 -280.24885) (xy 99.415951 -280.24885) (xy 99.465314 -280.256669)
			(xy 99.512846 -280.272113) (xy 99.557378 -280.294803) (xy 99.597811 -280.324179) (xy 99.633151 -280.359519)
			(xy 99.662527 -280.399952) (xy 99.685217 -280.444484) (xy 99.700661 -280.492016) (xy 99.70848 -280.541379)
			(xy 99.70897 -280.566368) (xy 99.70848 -280.591357) (xy 100.013498 -280.591357) (xy 100.013498 -280.541379)
			(xy 100.021317 -280.492016) (xy 100.036761 -280.444484) (xy 100.059451 -280.399952) (xy 100.088827 -280.359519)
			(xy 100.124167 -280.324179) (xy 100.1646 -280.294803) (xy 100.209132 -280.272113) (xy 100.256664 -280.256669)
			(xy 100.306027 -280.24885) (xy 100.356005 -280.24885) (xy 100.405368 -280.256669) (xy 100.4529 -280.272113)
			(xy 100.497432 -280.294803) (xy 100.537865 -280.324179) (xy 100.573205 -280.359519) (xy 100.602581 -280.399952)
			(xy 100.625271 -280.444484) (xy 100.640715 -280.492016) (xy 100.648534 -280.541379) (xy 100.649024 -280.566368)
			(xy 100.648534 -280.591357) (xy 100.953552 -280.591357) (xy 100.953552 -280.541379) (xy 100.961371 -280.492016)
			(xy 100.976815 -280.444484) (xy 100.999505 -280.399952) (xy 101.028881 -280.359519) (xy 101.064221 -280.324179)
			(xy 101.104654 -280.294803) (xy 101.149186 -280.272113) (xy 101.196718 -280.256669) (xy 101.246081 -280.24885)
			(xy 101.296059 -280.24885) (xy 101.345422 -280.256669) (xy 101.392954 -280.272113) (xy 101.437486 -280.294803)
			(xy 101.477919 -280.324179) (xy 101.513259 -280.359519) (xy 101.542635 -280.399952) (xy 101.565325 -280.444484)
			(xy 101.580769 -280.492016) (xy 101.588588 -280.541379) (xy 101.589078 -280.566368) (xy 101.588588 -280.591357)
			(xy 101.893606 -280.591357) (xy 101.893606 -280.541379) (xy 101.901425 -280.492016) (xy 101.916869 -280.444484)
			(xy 101.939559 -280.399952) (xy 101.968935 -280.359519) (xy 102.004275 -280.324179) (xy 102.044708 -280.294803)
			(xy 102.08924 -280.272113) (xy 102.136772 -280.256669) (xy 102.186135 -280.24885) (xy 102.236113 -280.24885)
			(xy 102.285476 -280.256669) (xy 102.333008 -280.272113) (xy 102.37754 -280.294803) (xy 102.417973 -280.324179)
			(xy 102.453313 -280.359519) (xy 102.482689 -280.399952) (xy 102.505379 -280.444484) (xy 102.520823 -280.492016)
			(xy 102.528642 -280.541379) (xy 102.529132 -280.566368) (xy 102.528642 -280.591357) (xy 102.83366 -280.591357)
			(xy 102.83366 -280.541379) (xy 102.841479 -280.492016) (xy 102.856923 -280.444484) (xy 102.879613 -280.399952)
			(xy 102.908989 -280.359519) (xy 102.944329 -280.324179) (xy 102.984762 -280.294803) (xy 103.029294 -280.272113)
			(xy 103.076826 -280.256669) (xy 103.126189 -280.24885) (xy 103.176167 -280.24885) (xy 103.22553 -280.256669)
			(xy 103.273062 -280.272113) (xy 103.317594 -280.294803) (xy 103.358027 -280.324179) (xy 103.393367 -280.359519)
			(xy 103.422743 -280.399952) (xy 103.445433 -280.444484) (xy 103.460877 -280.492016) (xy 103.468696 -280.541379)
			(xy 103.469186 -280.566368) (xy 103.468696 -280.591357) (xy 103.77346 -280.591357) (xy 103.77346 -280.541379)
			(xy 103.781279 -280.492016) (xy 103.796723 -280.444484) (xy 103.819413 -280.399952) (xy 103.848789 -280.359519)
			(xy 103.884129 -280.324179) (xy 103.924562 -280.294803) (xy 103.969094 -280.272113) (xy 104.016626 -280.256669)
			(xy 104.065989 -280.24885) (xy 104.115967 -280.24885) (xy 104.16533 -280.256669) (xy 104.212862 -280.272113)
			(xy 104.257394 -280.294803) (xy 104.297827 -280.324179) (xy 104.333167 -280.359519) (xy 104.362543 -280.399952)
			(xy 104.385233 -280.444484) (xy 104.400677 -280.492016) (xy 104.408496 -280.541379) (xy 104.408986 -280.566368)
			(xy 104.408496 -280.591357) (xy 104.713514 -280.591357) (xy 104.713514 -280.541379) (xy 104.721333 -280.492016)
			(xy 104.736777 -280.444484) (xy 104.759467 -280.399952) (xy 104.788843 -280.359519) (xy 104.824183 -280.324179)
			(xy 104.864616 -280.294803) (xy 104.909148 -280.272113) (xy 104.95668 -280.256669) (xy 105.006043 -280.24885)
			(xy 105.056021 -280.24885) (xy 105.105384 -280.256669) (xy 105.152916 -280.272113) (xy 105.197448 -280.294803)
			(xy 105.237881 -280.324179) (xy 105.273221 -280.359519) (xy 105.302597 -280.399952) (xy 105.325287 -280.444484)
			(xy 105.340731 -280.492016) (xy 105.34855 -280.541379) (xy 105.34904 -280.566368) (xy 105.34855 -280.591357)
			(xy 105.653568 -280.591357) (xy 105.653568 -280.541379) (xy 105.661387 -280.492016) (xy 105.676831 -280.444484)
			(xy 105.699521 -280.399952) (xy 105.728897 -280.359519) (xy 105.764237 -280.324179) (xy 105.80467 -280.294803)
			(xy 105.849202 -280.272113) (xy 105.896734 -280.256669) (xy 105.946097 -280.24885) (xy 105.996075 -280.24885)
			(xy 106.045438 -280.256669) (xy 106.09297 -280.272113) (xy 106.137502 -280.294803) (xy 106.177935 -280.324179)
			(xy 106.213275 -280.359519) (xy 106.242651 -280.399952) (xy 106.265341 -280.444484) (xy 106.280785 -280.492016)
			(xy 106.288604 -280.541379) (xy 106.289094 -280.566368) (xy 106.288604 -280.591357) (xy 106.593622 -280.591357)
			(xy 106.593622 -280.541379) (xy 106.601441 -280.492016) (xy 106.616885 -280.444484) (xy 106.639575 -280.399952)
			(xy 106.668951 -280.359519) (xy 106.704291 -280.324179) (xy 106.744724 -280.294803) (xy 106.789256 -280.272113)
			(xy 106.836788 -280.256669) (xy 106.886151 -280.24885) (xy 106.936129 -280.24885) (xy 106.985492 -280.256669)
			(xy 107.033024 -280.272113) (xy 107.077556 -280.294803) (xy 107.117989 -280.324179) (xy 107.153329 -280.359519)
			(xy 107.182705 -280.399952) (xy 107.205395 -280.444484) (xy 107.220839 -280.492016) (xy 107.228658 -280.541379)
			(xy 107.229148 -280.566368) (xy 107.228658 -280.591357) (xy 107.533422 -280.591357) (xy 107.533422 -280.541379)
			(xy 107.541241 -280.492016) (xy 107.556685 -280.444484) (xy 107.579375 -280.399952) (xy 107.608751 -280.359519)
			(xy 107.644091 -280.324179) (xy 107.684524 -280.294803) (xy 107.729056 -280.272113) (xy 107.776588 -280.256669)
			(xy 107.825951 -280.24885) (xy 107.875929 -280.24885) (xy 107.925292 -280.256669) (xy 107.972824 -280.272113)
			(xy 108.017356 -280.294803) (xy 108.057789 -280.324179) (xy 108.093129 -280.359519) (xy 108.122505 -280.399952)
			(xy 108.145195 -280.444484) (xy 108.160639 -280.492016) (xy 108.168458 -280.541379) (xy 108.168948 -280.566368)
			(xy 108.168458 -280.591357) (xy 110.353584 -280.591357) (xy 110.353584 -280.541379) (xy 110.361403 -280.492016)
			(xy 110.376847 -280.444484) (xy 110.399537 -280.399952) (xy 110.428913 -280.359519) (xy 110.464253 -280.324179)
			(xy 110.504686 -280.294803) (xy 110.549218 -280.272113) (xy 110.59675 -280.256669) (xy 110.646113 -280.24885)
			(xy 110.696091 -280.24885) (xy 110.745454 -280.256669) (xy 110.792986 -280.272113) (xy 110.837518 -280.294803)
			(xy 110.877951 -280.324179) (xy 110.913291 -280.359519) (xy 110.942667 -280.399952) (xy 110.965357 -280.444484)
			(xy 110.980801 -280.492016) (xy 110.98862 -280.541379) (xy 110.98911 -280.566368) (xy 110.98862 -280.591357)
			(xy 113.167142 -280.591357) (xy 113.167142 -280.541379) (xy 113.174961 -280.492016) (xy 113.190405 -280.444484)
			(xy 113.213095 -280.399952) (xy 113.242471 -280.359519) (xy 113.277811 -280.324179) (xy 113.318244 -280.294803)
			(xy 113.362776 -280.272113) (xy 113.410308 -280.256669) (xy 113.459671 -280.24885) (xy 113.509649 -280.24885)
			(xy 113.559012 -280.256669) (xy 113.606544 -280.272113) (xy 113.651076 -280.294803) (xy 113.691509 -280.324179)
			(xy 113.726849 -280.359519) (xy 113.756225 -280.399952) (xy 113.778915 -280.444484) (xy 113.794359 -280.492016)
			(xy 113.802178 -280.541379) (xy 113.802668 -280.566368) (xy 113.802178 -280.591357) (xy 115.987304 -280.591357)
			(xy 115.987304 -280.541379) (xy 115.995123 -280.492016) (xy 116.010567 -280.444484) (xy 116.033257 -280.399952)
			(xy 116.062633 -280.359519) (xy 116.097973 -280.324179) (xy 116.138406 -280.294803) (xy 116.182938 -280.272113)
			(xy 116.23047 -280.256669) (xy 116.279833 -280.24885) (xy 116.329811 -280.24885) (xy 116.379174 -280.256669)
			(xy 116.426706 -280.272113) (xy 116.471238 -280.294803) (xy 116.511671 -280.324179) (xy 116.547011 -280.359519)
			(xy 116.576387 -280.399952) (xy 116.599077 -280.444484) (xy 116.614521 -280.492016) (xy 116.62234 -280.541379)
			(xy 116.62283 -280.566368) (xy 116.62234 -280.591357) (xy 116.927104 -280.591357) (xy 116.927104 -280.541379)
			(xy 116.934923 -280.492016) (xy 116.950367 -280.444484) (xy 116.973057 -280.399952) (xy 117.002433 -280.359519)
			(xy 117.037773 -280.324179) (xy 117.078206 -280.294803) (xy 117.122738 -280.272113) (xy 117.17027 -280.256669)
			(xy 117.219633 -280.24885) (xy 117.269611 -280.24885) (xy 117.318974 -280.256669) (xy 117.366506 -280.272113)
			(xy 117.411038 -280.294803) (xy 117.451471 -280.324179) (xy 117.486811 -280.359519) (xy 117.516187 -280.399952)
			(xy 117.538877 -280.444484) (xy 117.554321 -280.492016) (xy 117.56214 -280.541379) (xy 117.56263 -280.566368)
			(xy 117.56214 -280.591357) (xy 117.867158 -280.591357) (xy 117.867158 -280.541379) (xy 117.874977 -280.492016)
			(xy 117.890421 -280.444484) (xy 117.913111 -280.399952) (xy 117.942487 -280.359519) (xy 117.977827 -280.324179)
			(xy 118.01826 -280.294803) (xy 118.062792 -280.272113) (xy 118.110324 -280.256669) (xy 118.159687 -280.24885)
			(xy 118.209665 -280.24885) (xy 118.259028 -280.256669) (xy 118.30656 -280.272113) (xy 118.351092 -280.294803)
			(xy 118.391525 -280.324179) (xy 118.426865 -280.359519) (xy 118.456241 -280.399952) (xy 118.478931 -280.444484)
			(xy 118.494375 -280.492016) (xy 118.502194 -280.541379) (xy 118.502684 -280.566368) (xy 118.502194 -280.591357)
			(xy 118.807212 -280.591357) (xy 118.807212 -280.541379) (xy 118.815031 -280.492016) (xy 118.830475 -280.444484)
			(xy 118.853165 -280.399952) (xy 118.882541 -280.359519) (xy 118.917881 -280.324179) (xy 118.958314 -280.294803)
			(xy 119.002846 -280.272113) (xy 119.050378 -280.256669) (xy 119.099741 -280.24885) (xy 119.149719 -280.24885)
			(xy 119.199082 -280.256669) (xy 119.246614 -280.272113) (xy 119.291146 -280.294803) (xy 119.331579 -280.324179)
			(xy 119.366919 -280.359519) (xy 119.396295 -280.399952) (xy 119.418985 -280.444484) (xy 119.434429 -280.492016)
			(xy 119.442248 -280.541379) (xy 119.442738 -280.566368) (xy 119.442248 -280.591357) (xy 119.747266 -280.591357)
			(xy 119.747266 -280.541379) (xy 119.755085 -280.492016) (xy 119.770529 -280.444484) (xy 119.793219 -280.399952)
			(xy 119.822595 -280.359519) (xy 119.857935 -280.324179) (xy 119.898368 -280.294803) (xy 119.9429 -280.272113)
			(xy 119.990432 -280.256669) (xy 120.039795 -280.24885) (xy 120.089773 -280.24885) (xy 120.139136 -280.256669)
			(xy 120.186668 -280.272113) (xy 120.2312 -280.294803) (xy 120.271633 -280.324179) (xy 120.306973 -280.359519)
			(xy 120.336349 -280.399952) (xy 120.359039 -280.444484) (xy 120.374483 -280.492016) (xy 120.382302 -280.541379)
			(xy 120.382792 -280.566368) (xy 120.382302 -280.591357) (xy 120.68732 -280.591357) (xy 120.68732 -280.541379)
			(xy 120.695139 -280.492016) (xy 120.710583 -280.444484) (xy 120.733273 -280.399952) (xy 120.762649 -280.359519)
			(xy 120.797989 -280.324179) (xy 120.838422 -280.294803) (xy 120.882954 -280.272113) (xy 120.930486 -280.256669)
			(xy 120.979849 -280.24885) (xy 121.029827 -280.24885) (xy 121.07919 -280.256669) (xy 121.126722 -280.272113)
			(xy 121.171254 -280.294803) (xy 121.211687 -280.324179) (xy 121.247027 -280.359519) (xy 121.276403 -280.399952)
			(xy 121.299093 -280.444484) (xy 121.314537 -280.492016) (xy 121.322356 -280.541379) (xy 121.322846 -280.566368)
			(xy 121.322356 -280.591357) (xy 121.62712 -280.591357) (xy 121.62712 -280.541379) (xy 121.634939 -280.492016)
			(xy 121.650383 -280.444484) (xy 121.673073 -280.399952) (xy 121.702449 -280.359519) (xy 121.737789 -280.324179)
			(xy 121.778222 -280.294803) (xy 121.822754 -280.272113) (xy 121.870286 -280.256669) (xy 121.919649 -280.24885)
			(xy 121.969627 -280.24885) (xy 122.01899 -280.256669) (xy 122.066522 -280.272113) (xy 122.111054 -280.294803)
			(xy 122.151487 -280.324179) (xy 122.186827 -280.359519) (xy 122.216203 -280.399952) (xy 122.238893 -280.444484)
			(xy 122.254337 -280.492016) (xy 122.262156 -280.541379) (xy 122.262646 -280.566368) (xy 122.262156 -280.591357)
			(xy 122.567174 -280.591357) (xy 122.567174 -280.541379) (xy 122.574993 -280.492016) (xy 122.590437 -280.444484)
			(xy 122.613127 -280.399952) (xy 122.642503 -280.359519) (xy 122.677843 -280.324179) (xy 122.718276 -280.294803)
			(xy 122.762808 -280.272113) (xy 122.81034 -280.256669) (xy 122.859703 -280.24885) (xy 122.909681 -280.24885)
			(xy 122.959044 -280.256669) (xy 123.006576 -280.272113) (xy 123.051108 -280.294803) (xy 123.091541 -280.324179)
			(xy 123.126881 -280.359519) (xy 123.156257 -280.399952) (xy 123.178947 -280.444484) (xy 123.194391 -280.492016)
			(xy 123.20221 -280.541379) (xy 123.2027 -280.566368) (xy 123.20221 -280.591357) (xy 123.507228 -280.591357)
			(xy 123.507228 -280.541379) (xy 123.515047 -280.492016) (xy 123.530491 -280.444484) (xy 123.553181 -280.399952)
			(xy 123.582557 -280.359519) (xy 123.617897 -280.324179) (xy 123.65833 -280.294803) (xy 123.702862 -280.272113)
			(xy 123.750394 -280.256669) (xy 123.799757 -280.24885) (xy 123.849735 -280.24885) (xy 123.899098 -280.256669)
			(xy 123.94663 -280.272113) (xy 123.991162 -280.294803) (xy 124.031595 -280.324179) (xy 124.066935 -280.359519)
			(xy 124.096311 -280.399952) (xy 124.119001 -280.444484) (xy 124.134445 -280.492016) (xy 124.142264 -280.541379)
			(xy 124.142754 -280.566368) (xy 124.142264 -280.591357) (xy 124.447282 -280.591357) (xy 124.447282 -280.541379)
			(xy 124.455101 -280.492016) (xy 124.470545 -280.444484) (xy 124.493235 -280.399952) (xy 124.522611 -280.359519)
			(xy 124.557951 -280.324179) (xy 124.598384 -280.294803) (xy 124.642916 -280.272113) (xy 124.690448 -280.256669)
			(xy 124.739811 -280.24885) (xy 124.789789 -280.24885) (xy 124.839152 -280.256669) (xy 124.886684 -280.272113)
			(xy 124.931216 -280.294803) (xy 124.971649 -280.324179) (xy 125.006989 -280.359519) (xy 125.036365 -280.399952)
			(xy 125.059055 -280.444484) (xy 125.074499 -280.492016) (xy 125.082318 -280.541379) (xy 125.082808 -280.566368)
			(xy 125.082318 -280.591357) (xy 125.387336 -280.591357) (xy 125.387336 -280.541379) (xy 125.395155 -280.492016)
			(xy 125.410599 -280.444484) (xy 125.433289 -280.399952) (xy 125.462665 -280.359519) (xy 125.498005 -280.324179)
			(xy 125.538438 -280.294803) (xy 125.58297 -280.272113) (xy 125.630502 -280.256669) (xy 125.679865 -280.24885)
			(xy 125.729843 -280.24885) (xy 125.779206 -280.256669) (xy 125.826738 -280.272113) (xy 125.87127 -280.294803)
			(xy 125.911703 -280.324179) (xy 125.947043 -280.359519) (xy 125.976419 -280.399952) (xy 125.999109 -280.444484)
			(xy 126.014553 -280.492016) (xy 126.022372 -280.541379) (xy 126.022862 -280.566368) (xy 126.022372 -280.591357)
			(xy 126.014553 -280.64072) (xy 125.999109 -280.688252) (xy 125.976419 -280.732784) (xy 125.947043 -280.773217)
			(xy 125.911703 -280.808557) (xy 125.87127 -280.837933) (xy 125.826738 -280.860623) (xy 125.779206 -280.876067)
			(xy 125.729843 -280.883886) (xy 125.679865 -280.883886) (xy 125.630502 -280.876067) (xy 125.58297 -280.860623)
			(xy 125.538438 -280.837933) (xy 125.498005 -280.808557) (xy 125.462665 -280.773217) (xy 125.433289 -280.732784)
			(xy 125.410599 -280.688252) (xy 125.395155 -280.64072) (xy 125.387336 -280.591357) (xy 125.082318 -280.591357)
			(xy 125.074499 -280.64072) (xy 125.059055 -280.688252) (xy 125.036365 -280.732784) (xy 125.006989 -280.773217)
			(xy 124.971649 -280.808557) (xy 124.931216 -280.837933) (xy 124.886684 -280.860623) (xy 124.839152 -280.876067)
			(xy 124.789789 -280.883886) (xy 124.739811 -280.883886) (xy 124.690448 -280.876067) (xy 124.642916 -280.860623)
			(xy 124.598384 -280.837933) (xy 124.557951 -280.808557) (xy 124.522611 -280.773217) (xy 124.493235 -280.732784)
			(xy 124.470545 -280.688252) (xy 124.455101 -280.64072) (xy 124.447282 -280.591357) (xy 124.142264 -280.591357)
			(xy 124.134445 -280.64072) (xy 124.119001 -280.688252) (xy 124.096311 -280.732784) (xy 124.066935 -280.773217)
			(xy 124.031595 -280.808557) (xy 123.991162 -280.837933) (xy 123.94663 -280.860623) (xy 123.899098 -280.876067)
			(xy 123.849735 -280.883886) (xy 123.799757 -280.883886) (xy 123.750394 -280.876067) (xy 123.702862 -280.860623)
			(xy 123.65833 -280.837933) (xy 123.617897 -280.808557) (xy 123.582557 -280.773217) (xy 123.553181 -280.732784)
			(xy 123.530491 -280.688252) (xy 123.515047 -280.64072) (xy 123.507228 -280.591357) (xy 123.20221 -280.591357)
			(xy 123.194391 -280.64072) (xy 123.178947 -280.688252) (xy 123.156257 -280.732784) (xy 123.126881 -280.773217)
			(xy 123.091541 -280.808557) (xy 123.051108 -280.837933) (xy 123.006576 -280.860623) (xy 122.959044 -280.876067)
			(xy 122.909681 -280.883886) (xy 122.859703 -280.883886) (xy 122.81034 -280.876067) (xy 122.762808 -280.860623)
			(xy 122.718276 -280.837933) (xy 122.677843 -280.808557) (xy 122.642503 -280.773217) (xy 122.613127 -280.732784)
			(xy 122.590437 -280.688252) (xy 122.574993 -280.64072) (xy 122.567174 -280.591357) (xy 122.262156 -280.591357)
			(xy 122.254337 -280.64072) (xy 122.238893 -280.688252) (xy 122.216203 -280.732784) (xy 122.186827 -280.773217)
			(xy 122.151487 -280.808557) (xy 122.111054 -280.837933) (xy 122.066522 -280.860623) (xy 122.01899 -280.876067)
			(xy 121.969627 -280.883886) (xy 121.919649 -280.883886) (xy 121.870286 -280.876067) (xy 121.822754 -280.860623)
			(xy 121.778222 -280.837933) (xy 121.737789 -280.808557) (xy 121.702449 -280.773217) (xy 121.673073 -280.732784)
			(xy 121.650383 -280.688252) (xy 121.634939 -280.64072) (xy 121.62712 -280.591357) (xy 121.322356 -280.591357)
			(xy 121.314537 -280.64072) (xy 121.299093 -280.688252) (xy 121.276403 -280.732784) (xy 121.247027 -280.773217)
			(xy 121.211687 -280.808557) (xy 121.171254 -280.837933) (xy 121.126722 -280.860623) (xy 121.07919 -280.876067)
			(xy 121.029827 -280.883886) (xy 120.979849 -280.883886) (xy 120.930486 -280.876067) (xy 120.882954 -280.860623)
			(xy 120.838422 -280.837933) (xy 120.797989 -280.808557) (xy 120.762649 -280.773217) (xy 120.733273 -280.732784)
			(xy 120.710583 -280.688252) (xy 120.695139 -280.64072) (xy 120.68732 -280.591357) (xy 120.382302 -280.591357)
			(xy 120.374483 -280.64072) (xy 120.359039 -280.688252) (xy 120.336349 -280.732784) (xy 120.306973 -280.773217)
			(xy 120.271633 -280.808557) (xy 120.2312 -280.837933) (xy 120.186668 -280.860623) (xy 120.139136 -280.876067)
			(xy 120.089773 -280.883886) (xy 120.039795 -280.883886) (xy 119.990432 -280.876067) (xy 119.9429 -280.860623)
			(xy 119.898368 -280.837933) (xy 119.857935 -280.808557) (xy 119.822595 -280.773217) (xy 119.793219 -280.732784)
			(xy 119.770529 -280.688252) (xy 119.755085 -280.64072) (xy 119.747266 -280.591357) (xy 119.442248 -280.591357)
			(xy 119.434429 -280.64072) (xy 119.418985 -280.688252) (xy 119.396295 -280.732784) (xy 119.366919 -280.773217)
			(xy 119.331579 -280.808557) (xy 119.291146 -280.837933) (xy 119.246614 -280.860623) (xy 119.199082 -280.876067)
			(xy 119.149719 -280.883886) (xy 119.099741 -280.883886) (xy 119.050378 -280.876067) (xy 119.002846 -280.860623)
			(xy 118.958314 -280.837933) (xy 118.917881 -280.808557) (xy 118.882541 -280.773217) (xy 118.853165 -280.732784)
			(xy 118.830475 -280.688252) (xy 118.815031 -280.64072) (xy 118.807212 -280.591357) (xy 118.502194 -280.591357)
			(xy 118.494375 -280.64072) (xy 118.478931 -280.688252) (xy 118.456241 -280.732784) (xy 118.426865 -280.773217)
			(xy 118.391525 -280.808557) (xy 118.351092 -280.837933) (xy 118.30656 -280.860623) (xy 118.259028 -280.876067)
			(xy 118.209665 -280.883886) (xy 118.159687 -280.883886) (xy 118.110324 -280.876067) (xy 118.062792 -280.860623)
			(xy 118.01826 -280.837933) (xy 117.977827 -280.808557) (xy 117.942487 -280.773217) (xy 117.913111 -280.732784)
			(xy 117.890421 -280.688252) (xy 117.874977 -280.64072) (xy 117.867158 -280.591357) (xy 117.56214 -280.591357)
			(xy 117.554321 -280.64072) (xy 117.538877 -280.688252) (xy 117.516187 -280.732784) (xy 117.486811 -280.773217)
			(xy 117.451471 -280.808557) (xy 117.411038 -280.837933) (xy 117.366506 -280.860623) (xy 117.318974 -280.876067)
			(xy 117.269611 -280.883886) (xy 117.219633 -280.883886) (xy 117.17027 -280.876067) (xy 117.122738 -280.860623)
			(xy 117.078206 -280.837933) (xy 117.037773 -280.808557) (xy 117.002433 -280.773217) (xy 116.973057 -280.732784)
			(xy 116.950367 -280.688252) (xy 116.934923 -280.64072) (xy 116.927104 -280.591357) (xy 116.62234 -280.591357)
			(xy 116.614521 -280.64072) (xy 116.599077 -280.688252) (xy 116.576387 -280.732784) (xy 116.547011 -280.773217)
			(xy 116.511671 -280.808557) (xy 116.471238 -280.837933) (xy 116.426706 -280.860623) (xy 116.379174 -280.876067)
			(xy 116.329811 -280.883886) (xy 116.279833 -280.883886) (xy 116.23047 -280.876067) (xy 116.182938 -280.860623)
			(xy 116.138406 -280.837933) (xy 116.097973 -280.808557) (xy 116.062633 -280.773217) (xy 116.033257 -280.732784)
			(xy 116.010567 -280.688252) (xy 115.995123 -280.64072) (xy 115.987304 -280.591357) (xy 113.802178 -280.591357)
			(xy 113.794359 -280.64072) (xy 113.778915 -280.688252) (xy 113.756225 -280.732784) (xy 113.726849 -280.773217)
			(xy 113.691509 -280.808557) (xy 113.651076 -280.837933) (xy 113.606544 -280.860623) (xy 113.559012 -280.876067)
			(xy 113.509649 -280.883886) (xy 113.459671 -280.883886) (xy 113.410308 -280.876067) (xy 113.362776 -280.860623)
			(xy 113.318244 -280.837933) (xy 113.277811 -280.808557) (xy 113.242471 -280.773217) (xy 113.213095 -280.732784)
			(xy 113.190405 -280.688252) (xy 113.174961 -280.64072) (xy 113.167142 -280.591357) (xy 110.98862 -280.591357)
			(xy 110.980801 -280.64072) (xy 110.965357 -280.688252) (xy 110.942667 -280.732784) (xy 110.913291 -280.773217)
			(xy 110.877951 -280.808557) (xy 110.837518 -280.837933) (xy 110.792986 -280.860623) (xy 110.745454 -280.876067)
			(xy 110.696091 -280.883886) (xy 110.646113 -280.883886) (xy 110.59675 -280.876067) (xy 110.549218 -280.860623)
			(xy 110.504686 -280.837933) (xy 110.464253 -280.808557) (xy 110.428913 -280.773217) (xy 110.399537 -280.732784)
			(xy 110.376847 -280.688252) (xy 110.361403 -280.64072) (xy 110.353584 -280.591357) (xy 108.168458 -280.591357)
			(xy 108.160639 -280.64072) (xy 108.145195 -280.688252) (xy 108.122505 -280.732784) (xy 108.093129 -280.773217)
			(xy 108.057789 -280.808557) (xy 108.017356 -280.837933) (xy 107.972824 -280.860623) (xy 107.925292 -280.876067)
			(xy 107.875929 -280.883886) (xy 107.825951 -280.883886) (xy 107.776588 -280.876067) (xy 107.729056 -280.860623)
			(xy 107.684524 -280.837933) (xy 107.644091 -280.808557) (xy 107.608751 -280.773217) (xy 107.579375 -280.732784)
			(xy 107.556685 -280.688252) (xy 107.541241 -280.64072) (xy 107.533422 -280.591357) (xy 107.228658 -280.591357)
			(xy 107.220839 -280.64072) (xy 107.205395 -280.688252) (xy 107.182705 -280.732784) (xy 107.153329 -280.773217)
			(xy 107.117989 -280.808557) (xy 107.077556 -280.837933) (xy 107.033024 -280.860623) (xy 106.985492 -280.876067)
			(xy 106.936129 -280.883886) (xy 106.886151 -280.883886) (xy 106.836788 -280.876067) (xy 106.789256 -280.860623)
			(xy 106.744724 -280.837933) (xy 106.704291 -280.808557) (xy 106.668951 -280.773217) (xy 106.639575 -280.732784)
			(xy 106.616885 -280.688252) (xy 106.601441 -280.64072) (xy 106.593622 -280.591357) (xy 106.288604 -280.591357)
			(xy 106.280785 -280.64072) (xy 106.265341 -280.688252) (xy 106.242651 -280.732784) (xy 106.213275 -280.773217)
			(xy 106.177935 -280.808557) (xy 106.137502 -280.837933) (xy 106.09297 -280.860623) (xy 106.045438 -280.876067)
			(xy 105.996075 -280.883886) (xy 105.946097 -280.883886) (xy 105.896734 -280.876067) (xy 105.849202 -280.860623)
			(xy 105.80467 -280.837933) (xy 105.764237 -280.808557) (xy 105.728897 -280.773217) (xy 105.699521 -280.732784)
			(xy 105.676831 -280.688252) (xy 105.661387 -280.64072) (xy 105.653568 -280.591357) (xy 105.34855 -280.591357)
			(xy 105.340731 -280.64072) (xy 105.325287 -280.688252) (xy 105.302597 -280.732784) (xy 105.273221 -280.773217)
			(xy 105.237881 -280.808557) (xy 105.197448 -280.837933) (xy 105.152916 -280.860623) (xy 105.105384 -280.876067)
			(xy 105.056021 -280.883886) (xy 105.006043 -280.883886) (xy 104.95668 -280.876067) (xy 104.909148 -280.860623)
			(xy 104.864616 -280.837933) (xy 104.824183 -280.808557) (xy 104.788843 -280.773217) (xy 104.759467 -280.732784)
			(xy 104.736777 -280.688252) (xy 104.721333 -280.64072) (xy 104.713514 -280.591357) (xy 104.408496 -280.591357)
			(xy 104.400677 -280.64072) (xy 104.385233 -280.688252) (xy 104.362543 -280.732784) (xy 104.333167 -280.773217)
			(xy 104.297827 -280.808557) (xy 104.257394 -280.837933) (xy 104.212862 -280.860623) (xy 104.16533 -280.876067)
			(xy 104.115967 -280.883886) (xy 104.065989 -280.883886) (xy 104.016626 -280.876067) (xy 103.969094 -280.860623)
			(xy 103.924562 -280.837933) (xy 103.884129 -280.808557) (xy 103.848789 -280.773217) (xy 103.819413 -280.732784)
			(xy 103.796723 -280.688252) (xy 103.781279 -280.64072) (xy 103.77346 -280.591357) (xy 103.468696 -280.591357)
			(xy 103.460877 -280.64072) (xy 103.445433 -280.688252) (xy 103.422743 -280.732784) (xy 103.393367 -280.773217)
			(xy 103.358027 -280.808557) (xy 103.317594 -280.837933) (xy 103.273062 -280.860623) (xy 103.22553 -280.876067)
			(xy 103.176167 -280.883886) (xy 103.126189 -280.883886) (xy 103.076826 -280.876067) (xy 103.029294 -280.860623)
			(xy 102.984762 -280.837933) (xy 102.944329 -280.808557) (xy 102.908989 -280.773217) (xy 102.879613 -280.732784)
			(xy 102.856923 -280.688252) (xy 102.841479 -280.64072) (xy 102.83366 -280.591357) (xy 102.528642 -280.591357)
			(xy 102.520823 -280.64072) (xy 102.505379 -280.688252) (xy 102.482689 -280.732784) (xy 102.453313 -280.773217)
			(xy 102.417973 -280.808557) (xy 102.37754 -280.837933) (xy 102.333008 -280.860623) (xy 102.285476 -280.876067)
			(xy 102.236113 -280.883886) (xy 102.186135 -280.883886) (xy 102.136772 -280.876067) (xy 102.08924 -280.860623)
			(xy 102.044708 -280.837933) (xy 102.004275 -280.808557) (xy 101.968935 -280.773217) (xy 101.939559 -280.732784)
			(xy 101.916869 -280.688252) (xy 101.901425 -280.64072) (xy 101.893606 -280.591357) (xy 101.588588 -280.591357)
			(xy 101.580769 -280.64072) (xy 101.565325 -280.688252) (xy 101.542635 -280.732784) (xy 101.513259 -280.773217)
			(xy 101.477919 -280.808557) (xy 101.437486 -280.837933) (xy 101.392954 -280.860623) (xy 101.345422 -280.876067)
			(xy 101.296059 -280.883886) (xy 101.246081 -280.883886) (xy 101.196718 -280.876067) (xy 101.149186 -280.860623)
			(xy 101.104654 -280.837933) (xy 101.064221 -280.808557) (xy 101.028881 -280.773217) (xy 100.999505 -280.732784)
			(xy 100.976815 -280.688252) (xy 100.961371 -280.64072) (xy 100.953552 -280.591357) (xy 100.648534 -280.591357)
			(xy 100.640715 -280.64072) (xy 100.625271 -280.688252) (xy 100.602581 -280.732784) (xy 100.573205 -280.773217)
			(xy 100.537865 -280.808557) (xy 100.497432 -280.837933) (xy 100.4529 -280.860623) (xy 100.405368 -280.876067)
			(xy 100.356005 -280.883886) (xy 100.306027 -280.883886) (xy 100.256664 -280.876067) (xy 100.209132 -280.860623)
			(xy 100.1646 -280.837933) (xy 100.124167 -280.808557) (xy 100.088827 -280.773217) (xy 100.059451 -280.732784)
			(xy 100.036761 -280.688252) (xy 100.021317 -280.64072) (xy 100.013498 -280.591357) (xy 99.70848 -280.591357)
			(xy 99.700661 -280.64072) (xy 99.685217 -280.688252) (xy 99.662527 -280.732784) (xy 99.633151 -280.773217)
			(xy 99.597811 -280.808557) (xy 99.557378 -280.837933) (xy 99.512846 -280.860623) (xy 99.465314 -280.876067)
			(xy 99.415951 -280.883886) (xy 99.365973 -280.883886) (xy 99.31661 -280.876067) (xy 99.269078 -280.860623)
			(xy 99.224546 -280.837933) (xy 99.184113 -280.808557) (xy 99.148773 -280.773217) (xy 99.119397 -280.732784)
			(xy 99.096707 -280.688252) (xy 99.081263 -280.64072) (xy 99.073444 -280.591357) (xy 98.76868 -280.591357)
			(xy 98.760861 -280.64072) (xy 98.745417 -280.688252) (xy 98.722727 -280.732784) (xy 98.693351 -280.773217)
			(xy 98.658011 -280.808557) (xy 98.617578 -280.837933) (xy 98.573046 -280.860623) (xy 98.525514 -280.876067)
			(xy 98.476151 -280.883886) (xy 98.426173 -280.883886) (xy 98.37681 -280.876067) (xy 98.329278 -280.860623)
			(xy 98.284746 -280.837933) (xy 98.244313 -280.808557) (xy 98.208973 -280.773217) (xy 98.179597 -280.732784)
			(xy 98.156907 -280.688252) (xy 98.141463 -280.64072) (xy 98.133644 -280.591357) (xy 97.828626 -280.591357)
			(xy 97.820807 -280.64072) (xy 97.805363 -280.688252) (xy 97.782673 -280.732784) (xy 97.753297 -280.773217)
			(xy 97.717957 -280.808557) (xy 97.677524 -280.837933) (xy 97.632992 -280.860623) (xy 97.58546 -280.876067)
			(xy 97.536097 -280.883886) (xy 97.486119 -280.883886) (xy 97.436756 -280.876067) (xy 97.389224 -280.860623)
			(xy 97.344692 -280.837933) (xy 97.304259 -280.808557) (xy 97.268919 -280.773217) (xy 97.239543 -280.732784)
			(xy 97.216853 -280.688252) (xy 97.201409 -280.64072) (xy 97.19359 -280.591357) (xy 96.888572 -280.591357)
			(xy 96.880753 -280.64072) (xy 96.865309 -280.688252) (xy 96.842619 -280.732784) (xy 96.813243 -280.773217)
			(xy 96.777903 -280.808557) (xy 96.73747 -280.837933) (xy 96.692938 -280.860623) (xy 96.645406 -280.876067)
			(xy 96.596043 -280.883886) (xy 96.546065 -280.883886) (xy 96.496702 -280.876067) (xy 96.44917 -280.860623)
			(xy 96.404638 -280.837933) (xy 96.364205 -280.808557) (xy 96.328865 -280.773217) (xy 96.299489 -280.732784)
			(xy 96.276799 -280.688252) (xy 96.261355 -280.64072) (xy 96.253536 -280.591357) (xy 95.946219 -280.591357)
			(xy 95.94621 -280.591814) (xy 95.938046 -280.642048) (xy 95.92193 -280.690322) (xy 95.898279 -280.735385)
			(xy 95.867706 -280.776071) (xy 95.831002 -280.811326) (xy 95.789118 -280.840236) (xy 95.743139 -280.862053)
			(xy 95.694255 -280.876213) (xy 95.643734 -280.882347) (xy 95.592882 -280.880298) (xy 95.543018 -280.870118)
			(xy 95.495432 -280.852071) (xy 95.451358 -280.826625) (xy 95.411936 -280.794438) (xy 95.378188 -280.756344)
			(xy 95.350987 -280.71333) (xy 95.331039 -280.66651) (xy 95.31886 -280.617096) (xy 95.314765 -280.566368)
			(xy 95.006668 -280.566368) (xy 95.006156 -280.591814) (xy 94.997992 -280.642048) (xy 94.981876 -280.690322)
			(xy 94.958225 -280.735385) (xy 94.927652 -280.776071) (xy 94.890948 -280.811326) (xy 94.849064 -280.840236)
			(xy 94.803085 -280.862053) (xy 94.754201 -280.876213) (xy 94.70368 -280.882347) (xy 94.652828 -280.880298)
			(xy 94.602964 -280.870118) (xy 94.555378 -280.852071) (xy 94.511304 -280.826625) (xy 94.471882 -280.794438)
			(xy 94.438134 -280.756344) (xy 94.410933 -280.71333) (xy 94.390985 -280.66651) (xy 94.378806 -280.617096)
			(xy 94.374711 -280.566368) (xy 94.069154 -280.566368) (xy 94.068666 -280.59136) (xy 94.060852 -280.64073)
			(xy 94.045411 -280.688269) (xy 94.022724 -280.732808) (xy 93.993349 -280.77325) (xy 93.958009 -280.808598)
			(xy 93.917575 -280.837983) (xy 93.873041 -280.860681) (xy 93.825506 -280.876134) (xy 93.776138 -280.88396)
			(xy 93.751146 -280.884376) (xy 93.724084 -280.883828) (xy 93.670742 -280.874663) (xy 93.619719 -280.856606)
			(xy 93.572486 -280.830178) (xy 93.530405 -280.79614) (xy 93.512132 -280.776172) (xy 93.511116 -280.775156)
			(xy 93.507814 -280.7716) (xy 93.500687 -280.764869) (xy 93.482787 -280.756918) (xy 93.473016 -280.756106)
			(xy 93.40088 -280.753566) (xy 93.390447 -280.753702) (xy 93.371042 -280.761315) (xy 93.363288 -280.768298)
			(xy 93.243146 -280.88844) (xy 93.23665 -280.895576) (xy 93.229068 -280.913305) (xy 93.22855 -280.93258)
			(xy 93.231462 -280.94178) (xy 93.248988 -280.989532) (xy 93.248988 -280.99004) (xy 93.268038 -281.040586)
			(xy 93.291406 -281.058112) (xy 93.306392 -281.059382) (xy 93.331249 -281.061864) (xy 93.379807 -281.073588)
			(xy 93.425934 -281.092759) (xy 93.468497 -281.118906) (xy 93.506448 -281.151386) (xy 93.538855 -281.1894)
			(xy 93.56492 -281.232013) (xy 93.584002 -281.278177) (xy 93.595632 -281.326757) (xy 93.599511 -281.376374)
			(xy 93.904811 -281.376374) (xy 93.908906 -281.325646) (xy 93.921085 -281.276232) (xy 93.941033 -281.229412)
			(xy 93.968234 -281.186398) (xy 94.001982 -281.148304) (xy 94.041404 -281.116117) (xy 94.085478 -281.090671)
			(xy 94.133064 -281.072624) (xy 94.182928 -281.062444) (xy 94.23378 -281.060395) (xy 94.284301 -281.066529)
			(xy 94.333185 -281.080689) (xy 94.379164 -281.102506) (xy 94.421048 -281.131416) (xy 94.457752 -281.166671)
			(xy 94.488325 -281.207357) (xy 94.511976 -281.25242) (xy 94.528092 -281.300694) (xy 94.536256 -281.350928)
			(xy 94.536768 -281.376374) (xy 94.536265 -281.401363) (xy 94.843582 -281.401363) (xy 94.843582 -281.351385)
			(xy 94.851401 -281.302022) (xy 94.866845 -281.25449) (xy 94.889535 -281.209958) (xy 94.918911 -281.169525)
			(xy 94.954251 -281.134185) (xy 94.994684 -281.104809) (xy 95.039216 -281.082119) (xy 95.086748 -281.066675)
			(xy 95.136111 -281.058856) (xy 95.186089 -281.058856) (xy 95.235452 -281.066675) (xy 95.282984 -281.082119)
			(xy 95.327516 -281.104809) (xy 95.367949 -281.134185) (xy 95.403289 -281.169525) (xy 95.432665 -281.209958)
			(xy 95.455355 -281.25449) (xy 95.470799 -281.302022) (xy 95.478618 -281.351385) (xy 95.479108 -281.376374)
			(xy 95.784919 -281.376374) (xy 95.789014 -281.325646) (xy 95.801193 -281.276232) (xy 95.821141 -281.229412)
			(xy 95.848342 -281.186398) (xy 95.88209 -281.148304) (xy 95.921512 -281.116117) (xy 95.965586 -281.090671)
			(xy 96.013172 -281.072624) (xy 96.063036 -281.062444) (xy 96.113888 -281.060395) (xy 96.164409 -281.066529)
			(xy 96.213293 -281.080689) (xy 96.259272 -281.102506) (xy 96.301156 -281.131416) (xy 96.33786 -281.166671)
			(xy 96.368433 -281.207357) (xy 96.392084 -281.25242) (xy 96.4082 -281.300694) (xy 96.416364 -281.350928)
			(xy 96.416876 -281.376374) (xy 96.416373 -281.401363) (xy 96.723436 -281.401363) (xy 96.723436 -281.351385)
			(xy 96.731255 -281.302022) (xy 96.746699 -281.25449) (xy 96.769389 -281.209958) (xy 96.798765 -281.169525)
			(xy 96.834105 -281.134185) (xy 96.874538 -281.104809) (xy 96.91907 -281.082119) (xy 96.966602 -281.066675)
			(xy 97.015965 -281.058856) (xy 97.065943 -281.058856) (xy 97.115306 -281.066675) (xy 97.162838 -281.082119)
			(xy 97.20737 -281.104809) (xy 97.247803 -281.134185) (xy 97.283143 -281.169525) (xy 97.312519 -281.209958)
			(xy 97.335209 -281.25449) (xy 97.350653 -281.302022) (xy 97.358472 -281.351385) (xy 97.358962 -281.376374)
			(xy 97.664773 -281.376374) (xy 97.668868 -281.325646) (xy 97.681047 -281.276232) (xy 97.700995 -281.229412)
			(xy 97.728196 -281.186398) (xy 97.761944 -281.148304) (xy 97.801366 -281.116117) (xy 97.84544 -281.090671)
			(xy 97.893026 -281.072624) (xy 97.94289 -281.062444) (xy 97.993742 -281.060395) (xy 98.044263 -281.066529)
			(xy 98.093147 -281.080689) (xy 98.139126 -281.102506) (xy 98.18101 -281.131416) (xy 98.217714 -281.166671)
			(xy 98.248287 -281.207357) (xy 98.271938 -281.25242) (xy 98.288054 -281.300694) (xy 98.296218 -281.350928)
			(xy 98.29673 -281.376374) (xy 98.604827 -281.376374) (xy 98.608922 -281.325646) (xy 98.621101 -281.276232)
			(xy 98.641049 -281.229412) (xy 98.66825 -281.186398) (xy 98.701998 -281.148304) (xy 98.74142 -281.116117)
			(xy 98.785494 -281.090671) (xy 98.83308 -281.072624) (xy 98.882944 -281.062444) (xy 98.933796 -281.060395)
			(xy 98.984317 -281.066529) (xy 99.033201 -281.080689) (xy 99.07918 -281.102506) (xy 99.121064 -281.131416)
			(xy 99.157768 -281.166671) (xy 99.188341 -281.207357) (xy 99.211992 -281.25242) (xy 99.228108 -281.300694)
			(xy 99.236272 -281.350928) (xy 99.236784 -281.376374) (xy 99.236281 -281.401363) (xy 99.543598 -281.401363)
			(xy 99.543598 -281.351385) (xy 99.551417 -281.302022) (xy 99.566861 -281.25449) (xy 99.589551 -281.209958)
			(xy 99.618927 -281.169525) (xy 99.654267 -281.134185) (xy 99.6947 -281.104809) (xy 99.739232 -281.082119)
			(xy 99.786764 -281.066675) (xy 99.836127 -281.058856) (xy 99.886105 -281.058856) (xy 99.935468 -281.066675)
			(xy 99.983 -281.082119) (xy 100.027532 -281.104809) (xy 100.067965 -281.134185) (xy 100.103305 -281.169525)
			(xy 100.132681 -281.209958) (xy 100.155371 -281.25449) (xy 100.170815 -281.302022) (xy 100.178634 -281.351385)
			(xy 100.179124 -281.376374) (xy 100.484935 -281.376374) (xy 100.48903 -281.325646) (xy 100.501209 -281.276232)
			(xy 100.521157 -281.229412) (xy 100.548358 -281.186398) (xy 100.582106 -281.148304) (xy 100.621528 -281.116117)
			(xy 100.665602 -281.090671) (xy 100.713188 -281.072624) (xy 100.763052 -281.062444) (xy 100.813904 -281.060395)
			(xy 100.864425 -281.066529) (xy 100.913309 -281.080689) (xy 100.959288 -281.102506) (xy 101.001172 -281.131416)
			(xy 101.037876 -281.166671) (xy 101.068449 -281.207357) (xy 101.0921 -281.25242) (xy 101.108216 -281.300694)
			(xy 101.11638 -281.350928) (xy 101.116892 -281.376374) (xy 101.424735 -281.376374) (xy 101.42883 -281.325646)
			(xy 101.441009 -281.276232) (xy 101.460957 -281.229412) (xy 101.488158 -281.186398) (xy 101.521906 -281.148304)
			(xy 101.561328 -281.116117) (xy 101.605402 -281.090671) (xy 101.652988 -281.072624) (xy 101.702852 -281.062444)
			(xy 101.753704 -281.060395) (xy 101.804225 -281.066529) (xy 101.853109 -281.080689) (xy 101.899088 -281.102506)
			(xy 101.940972 -281.131416) (xy 101.977676 -281.166671) (xy 102.008249 -281.207357) (xy 102.0319 -281.25242)
			(xy 102.048016 -281.300694) (xy 102.05618 -281.350928) (xy 102.056692 -281.376374) (xy 102.056189 -281.401363)
			(xy 102.363506 -281.401363) (xy 102.363506 -281.351385) (xy 102.371325 -281.302022) (xy 102.386769 -281.25449)
			(xy 102.409459 -281.209958) (xy 102.438835 -281.169525) (xy 102.474175 -281.134185) (xy 102.514608 -281.104809)
			(xy 102.55914 -281.082119) (xy 102.606672 -281.066675) (xy 102.656035 -281.058856) (xy 102.706013 -281.058856)
			(xy 102.755376 -281.066675) (xy 102.802908 -281.082119) (xy 102.84744 -281.104809) (xy 102.887873 -281.134185)
			(xy 102.923213 -281.169525) (xy 102.952589 -281.209958) (xy 102.975279 -281.25449) (xy 102.990723 -281.302022)
			(xy 102.998542 -281.351385) (xy 102.999032 -281.376374) (xy 102.998542 -281.401363) (xy 105.183414 -281.401363)
			(xy 105.183414 -281.351385) (xy 105.191233 -281.302022) (xy 105.206677 -281.25449) (xy 105.229367 -281.209958)
			(xy 105.258743 -281.169525) (xy 105.294083 -281.134185) (xy 105.334516 -281.104809) (xy 105.379048 -281.082119)
			(xy 105.42658 -281.066675) (xy 105.475943 -281.058856) (xy 105.525921 -281.058856) (xy 105.575284 -281.066675)
			(xy 105.622816 -281.082119) (xy 105.667348 -281.104809) (xy 105.707781 -281.134185) (xy 105.743121 -281.169525)
			(xy 105.772497 -281.209958) (xy 105.795187 -281.25449) (xy 105.810631 -281.302022) (xy 105.81845 -281.351385)
			(xy 105.81894 -281.376374) (xy 105.81845 -281.401363) (xy 108.003576 -281.401363) (xy 108.003576 -281.351385)
			(xy 108.011395 -281.302022) (xy 108.026839 -281.25449) (xy 108.049529 -281.209958) (xy 108.078905 -281.169525)
			(xy 108.114245 -281.134185) (xy 108.154678 -281.104809) (xy 108.19921 -281.082119) (xy 108.246742 -281.066675)
			(xy 108.296105 -281.058856) (xy 108.346083 -281.058856) (xy 108.395446 -281.066675) (xy 108.442978 -281.082119)
			(xy 108.48751 -281.104809) (xy 108.527943 -281.134185) (xy 108.563283 -281.169525) (xy 108.592659 -281.209958)
			(xy 108.615349 -281.25449) (xy 108.630793 -281.302022) (xy 108.638612 -281.351385) (xy 108.639102 -281.376374)
			(xy 108.638612 -281.401363) (xy 108.94363 -281.401363) (xy 108.94363 -281.351385) (xy 108.951449 -281.302022)
			(xy 108.966893 -281.25449) (xy 108.989583 -281.209958) (xy 109.018959 -281.169525) (xy 109.054299 -281.134185)
			(xy 109.094732 -281.104809) (xy 109.139264 -281.082119) (xy 109.186796 -281.066675) (xy 109.236159 -281.058856)
			(xy 109.286137 -281.058856) (xy 109.3355 -281.066675) (xy 109.383032 -281.082119) (xy 109.427564 -281.104809)
			(xy 109.467997 -281.134185) (xy 109.503337 -281.169525) (xy 109.532713 -281.209958) (xy 109.555403 -281.25449)
			(xy 109.570847 -281.302022) (xy 109.578666 -281.351385) (xy 109.579156 -281.376374) (xy 109.578666 -281.401363)
			(xy 109.88343 -281.401363) (xy 109.88343 -281.351385) (xy 109.891249 -281.302022) (xy 109.906693 -281.25449)
			(xy 109.929383 -281.209958) (xy 109.958759 -281.169525) (xy 109.994099 -281.134185) (xy 110.034532 -281.104809)
			(xy 110.079064 -281.082119) (xy 110.126596 -281.066675) (xy 110.175959 -281.058856) (xy 110.225937 -281.058856)
			(xy 110.2753 -281.066675) (xy 110.322832 -281.082119) (xy 110.367364 -281.104809) (xy 110.407797 -281.134185)
			(xy 110.443137 -281.169525) (xy 110.472513 -281.209958) (xy 110.495203 -281.25449) (xy 110.510647 -281.302022)
			(xy 110.518466 -281.351385) (xy 110.518956 -281.376374) (xy 110.518466 -281.401363) (xy 113.637296 -281.401363)
			(xy 113.637296 -281.351385) (xy 113.645115 -281.302022) (xy 113.660559 -281.25449) (xy 113.683249 -281.209958)
			(xy 113.712625 -281.169525) (xy 113.747965 -281.134185) (xy 113.788398 -281.104809) (xy 113.83293 -281.082119)
			(xy 113.880462 -281.066675) (xy 113.929825 -281.058856) (xy 113.979803 -281.058856) (xy 114.029166 -281.066675)
			(xy 114.076698 -281.082119) (xy 114.12123 -281.104809) (xy 114.161663 -281.134185) (xy 114.197003 -281.169525)
			(xy 114.226379 -281.209958) (xy 114.249069 -281.25449) (xy 114.264513 -281.302022) (xy 114.272332 -281.351385)
			(xy 114.272822 -281.376374) (xy 114.272332 -281.401363) (xy 114.577096 -281.401363) (xy 114.577096 -281.351385)
			(xy 114.584915 -281.302022) (xy 114.600359 -281.25449) (xy 114.623049 -281.209958) (xy 114.652425 -281.169525)
			(xy 114.687765 -281.134185) (xy 114.728198 -281.104809) (xy 114.77273 -281.082119) (xy 114.820262 -281.066675)
			(xy 114.869625 -281.058856) (xy 114.919603 -281.058856) (xy 114.968966 -281.066675) (xy 115.016498 -281.082119)
			(xy 115.06103 -281.104809) (xy 115.101463 -281.134185) (xy 115.136803 -281.169525) (xy 115.166179 -281.209958)
			(xy 115.188869 -281.25449) (xy 115.204313 -281.302022) (xy 115.212132 -281.351385) (xy 115.212622 -281.376374)
			(xy 115.212132 -281.401363) (xy 115.51715 -281.401363) (xy 115.51715 -281.351385) (xy 115.524969 -281.302022)
			(xy 115.540413 -281.25449) (xy 115.563103 -281.209958) (xy 115.592479 -281.169525) (xy 115.627819 -281.134185)
			(xy 115.668252 -281.104809) (xy 115.712784 -281.082119) (xy 115.760316 -281.066675) (xy 115.809679 -281.058856)
			(xy 115.859657 -281.058856) (xy 115.90902 -281.066675) (xy 115.956552 -281.082119) (xy 116.001084 -281.104809)
			(xy 116.041517 -281.134185) (xy 116.076857 -281.169525) (xy 116.106233 -281.209958) (xy 116.128923 -281.25449)
			(xy 116.144367 -281.302022) (xy 116.152186 -281.351385) (xy 116.152676 -281.376374) (xy 116.152186 -281.401363)
			(xy 118.337312 -281.401363) (xy 118.337312 -281.351385) (xy 118.345131 -281.302022) (xy 118.360575 -281.25449)
			(xy 118.383265 -281.209958) (xy 118.412641 -281.169525) (xy 118.447981 -281.134185) (xy 118.488414 -281.104809)
			(xy 118.532946 -281.082119) (xy 118.580478 -281.066675) (xy 118.629841 -281.058856) (xy 118.679819 -281.058856)
			(xy 118.729182 -281.066675) (xy 118.776714 -281.082119) (xy 118.821246 -281.104809) (xy 118.861679 -281.134185)
			(xy 118.897019 -281.169525) (xy 118.926395 -281.209958) (xy 118.949085 -281.25449) (xy 118.964529 -281.302022)
			(xy 118.972348 -281.351385) (xy 118.972838 -281.376374) (xy 118.972348 -281.401363) (xy 121.15722 -281.401363)
			(xy 121.15722 -281.351385) (xy 121.165039 -281.302022) (xy 121.180483 -281.25449) (xy 121.203173 -281.209958)
			(xy 121.232549 -281.169525) (xy 121.267889 -281.134185) (xy 121.308322 -281.104809) (xy 121.352854 -281.082119)
			(xy 121.400386 -281.066675) (xy 121.449749 -281.058856) (xy 121.499727 -281.058856) (xy 121.54909 -281.066675)
			(xy 121.596622 -281.082119) (xy 121.641154 -281.104809) (xy 121.681587 -281.134185) (xy 121.716927 -281.169525)
			(xy 121.746303 -281.209958) (xy 121.768993 -281.25449) (xy 121.784437 -281.302022) (xy 121.792256 -281.351385)
			(xy 121.792746 -281.376374) (xy 122.098557 -281.376374) (xy 122.102652 -281.325646) (xy 122.114831 -281.276232)
			(xy 122.134779 -281.229412) (xy 122.16198 -281.186398) (xy 122.195728 -281.148304) (xy 122.23515 -281.116117)
			(xy 122.279224 -281.090671) (xy 122.32681 -281.072624) (xy 122.376674 -281.062444) (xy 122.427526 -281.060395)
			(xy 122.478047 -281.066529) (xy 122.526931 -281.080689) (xy 122.57291 -281.102506) (xy 122.614794 -281.131416)
			(xy 122.651498 -281.166671) (xy 122.682071 -281.207357) (xy 122.705722 -281.25242) (xy 122.721838 -281.300694)
			(xy 122.730002 -281.350928) (xy 122.730514 -281.376374) (xy 123.038611 -281.376374) (xy 123.042706 -281.325646)
			(xy 123.054885 -281.276232) (xy 123.074833 -281.229412) (xy 123.102034 -281.186398) (xy 123.135782 -281.148304)
			(xy 123.175204 -281.116117) (xy 123.219278 -281.090671) (xy 123.266864 -281.072624) (xy 123.316728 -281.062444)
			(xy 123.36758 -281.060395) (xy 123.418101 -281.066529) (xy 123.466985 -281.080689) (xy 123.512964 -281.102506)
			(xy 123.554848 -281.131416) (xy 123.591552 -281.166671) (xy 123.622125 -281.207357) (xy 123.645776 -281.25242)
			(xy 123.661892 -281.300694) (xy 123.670056 -281.350928) (xy 123.670568 -281.376374) (xy 123.670065 -281.401363)
			(xy 123.977128 -281.401363) (xy 123.977128 -281.351385) (xy 123.984947 -281.302022) (xy 124.000391 -281.25449)
			(xy 124.023081 -281.209958) (xy 124.052457 -281.169525) (xy 124.087797 -281.134185) (xy 124.12823 -281.104809)
			(xy 124.172762 -281.082119) (xy 124.220294 -281.066675) (xy 124.269657 -281.058856) (xy 124.319635 -281.058856)
			(xy 124.368998 -281.066675) (xy 124.41653 -281.082119) (xy 124.461062 -281.104809) (xy 124.501495 -281.134185)
			(xy 124.536835 -281.169525) (xy 124.566211 -281.209958) (xy 124.588901 -281.25449) (xy 124.604345 -281.302022)
			(xy 124.612164 -281.351385) (xy 124.612654 -281.376374) (xy 124.918465 -281.376374) (xy 124.92256 -281.325646)
			(xy 124.934739 -281.276232) (xy 124.954687 -281.229412) (xy 124.981888 -281.186398) (xy 125.015636 -281.148304)
			(xy 125.055058 -281.116117) (xy 125.099132 -281.090671) (xy 125.146718 -281.072624) (xy 125.196582 -281.062444)
			(xy 125.247434 -281.060395) (xy 125.297955 -281.066529) (xy 125.346839 -281.080689) (xy 125.392818 -281.102506)
			(xy 125.434702 -281.131416) (xy 125.471406 -281.166671) (xy 125.501979 -281.207357) (xy 125.52563 -281.25242)
			(xy 125.541746 -281.300694) (xy 125.54991 -281.350928) (xy 125.550422 -281.376374) (xy 125.54991 -281.40182)
			(xy 125.541746 -281.452054) (xy 125.52563 -281.500328) (xy 125.501979 -281.545391) (xy 125.471406 -281.586077)
			(xy 125.434702 -281.621332) (xy 125.392818 -281.650242) (xy 125.346839 -281.672059) (xy 125.297955 -281.686219)
			(xy 125.247434 -281.692353) (xy 125.196582 -281.690304) (xy 125.146718 -281.680124) (xy 125.099132 -281.662077)
			(xy 125.055058 -281.636631) (xy 125.015636 -281.604444) (xy 124.981888 -281.56635) (xy 124.954687 -281.523336)
			(xy 124.934739 -281.476516) (xy 124.92256 -281.427102) (xy 124.918465 -281.376374) (xy 124.612654 -281.376374)
			(xy 124.612164 -281.401363) (xy 124.604345 -281.450726) (xy 124.588901 -281.498258) (xy 124.566211 -281.54279)
			(xy 124.536835 -281.583223) (xy 124.501495 -281.618563) (xy 124.461062 -281.647939) (xy 124.41653 -281.670629)
			(xy 124.368998 -281.686073) (xy 124.319635 -281.693892) (xy 124.269657 -281.693892) (xy 124.220294 -281.686073)
			(xy 124.172762 -281.670629) (xy 124.12823 -281.647939) (xy 124.087797 -281.618563) (xy 124.052457 -281.583223)
			(xy 124.023081 -281.54279) (xy 124.000391 -281.498258) (xy 123.984947 -281.450726) (xy 123.977128 -281.401363)
			(xy 123.670065 -281.401363) (xy 123.670056 -281.40182) (xy 123.661892 -281.452054) (xy 123.645776 -281.500328)
			(xy 123.622125 -281.545391) (xy 123.591552 -281.586077) (xy 123.554848 -281.621332) (xy 123.512964 -281.650242)
			(xy 123.466985 -281.672059) (xy 123.418101 -281.686219) (xy 123.36758 -281.692353) (xy 123.316728 -281.690304)
			(xy 123.266864 -281.680124) (xy 123.219278 -281.662077) (xy 123.175204 -281.636631) (xy 123.135782 -281.604444)
			(xy 123.102034 -281.56635) (xy 123.074833 -281.523336) (xy 123.054885 -281.476516) (xy 123.042706 -281.427102)
			(xy 123.038611 -281.376374) (xy 122.730514 -281.376374) (xy 122.730002 -281.40182) (xy 122.721838 -281.452054)
			(xy 122.705722 -281.500328) (xy 122.682071 -281.545391) (xy 122.651498 -281.586077) (xy 122.614794 -281.621332)
			(xy 122.57291 -281.650242) (xy 122.526931 -281.672059) (xy 122.478047 -281.686219) (xy 122.427526 -281.692353)
			(xy 122.376674 -281.690304) (xy 122.32681 -281.680124) (xy 122.279224 -281.662077) (xy 122.23515 -281.636631)
			(xy 122.195728 -281.604444) (xy 122.16198 -281.56635) (xy 122.134779 -281.523336) (xy 122.114831 -281.476516)
			(xy 122.102652 -281.427102) (xy 122.098557 -281.376374) (xy 121.792746 -281.376374) (xy 121.792256 -281.401363)
			(xy 121.784437 -281.450726) (xy 121.768993 -281.498258) (xy 121.746303 -281.54279) (xy 121.716927 -281.583223)
			(xy 121.681587 -281.618563) (xy 121.641154 -281.647939) (xy 121.596622 -281.670629) (xy 121.54909 -281.686073)
			(xy 121.499727 -281.693892) (xy 121.449749 -281.693892) (xy 121.400386 -281.686073) (xy 121.352854 -281.670629)
			(xy 121.308322 -281.647939) (xy 121.267889 -281.618563) (xy 121.232549 -281.583223) (xy 121.203173 -281.54279)
			(xy 121.180483 -281.498258) (xy 121.165039 -281.450726) (xy 121.15722 -281.401363) (xy 118.972348 -281.401363)
			(xy 118.964529 -281.450726) (xy 118.949085 -281.498258) (xy 118.926395 -281.54279) (xy 118.897019 -281.583223)
			(xy 118.861679 -281.618563) (xy 118.821246 -281.647939) (xy 118.776714 -281.670629) (xy 118.729182 -281.686073)
			(xy 118.679819 -281.693892) (xy 118.629841 -281.693892) (xy 118.580478 -281.686073) (xy 118.532946 -281.670629)
			(xy 118.488414 -281.647939) (xy 118.447981 -281.618563) (xy 118.412641 -281.583223) (xy 118.383265 -281.54279)
			(xy 118.360575 -281.498258) (xy 118.345131 -281.450726) (xy 118.337312 -281.401363) (xy 116.152186 -281.401363)
			(xy 116.144367 -281.450726) (xy 116.128923 -281.498258) (xy 116.106233 -281.54279) (xy 116.076857 -281.583223)
			(xy 116.041517 -281.618563) (xy 116.001084 -281.647939) (xy 115.956552 -281.670629) (xy 115.90902 -281.686073)
			(xy 115.859657 -281.693892) (xy 115.809679 -281.693892) (xy 115.760316 -281.686073) (xy 115.712784 -281.670629)
			(xy 115.668252 -281.647939) (xy 115.627819 -281.618563) (xy 115.592479 -281.583223) (xy 115.563103 -281.54279)
			(xy 115.540413 -281.498258) (xy 115.524969 -281.450726) (xy 115.51715 -281.401363) (xy 115.212132 -281.401363)
			(xy 115.204313 -281.450726) (xy 115.188869 -281.498258) (xy 115.166179 -281.54279) (xy 115.136803 -281.583223)
			(xy 115.101463 -281.618563) (xy 115.06103 -281.647939) (xy 115.016498 -281.670629) (xy 114.968966 -281.686073)
			(xy 114.919603 -281.693892) (xy 114.869625 -281.693892) (xy 114.820262 -281.686073) (xy 114.77273 -281.670629)
			(xy 114.728198 -281.647939) (xy 114.687765 -281.618563) (xy 114.652425 -281.583223) (xy 114.623049 -281.54279)
			(xy 114.600359 -281.498258) (xy 114.584915 -281.450726) (xy 114.577096 -281.401363) (xy 114.272332 -281.401363)
			(xy 114.264513 -281.450726) (xy 114.249069 -281.498258) (xy 114.226379 -281.54279) (xy 114.197003 -281.583223)
			(xy 114.161663 -281.618563) (xy 114.12123 -281.647939) (xy 114.076698 -281.670629) (xy 114.029166 -281.686073)
			(xy 113.979803 -281.693892) (xy 113.929825 -281.693892) (xy 113.880462 -281.686073) (xy 113.83293 -281.670629)
			(xy 113.788398 -281.647939) (xy 113.747965 -281.618563) (xy 113.712625 -281.583223) (xy 113.683249 -281.54279)
			(xy 113.660559 -281.498258) (xy 113.645115 -281.450726) (xy 113.637296 -281.401363) (xy 110.518466 -281.401363)
			(xy 110.510647 -281.450726) (xy 110.495203 -281.498258) (xy 110.472513 -281.54279) (xy 110.443137 -281.583223)
			(xy 110.407797 -281.618563) (xy 110.367364 -281.647939) (xy 110.322832 -281.670629) (xy 110.2753 -281.686073)
			(xy 110.225937 -281.693892) (xy 110.175959 -281.693892) (xy 110.126596 -281.686073) (xy 110.079064 -281.670629)
			(xy 110.034532 -281.647939) (xy 109.994099 -281.618563) (xy 109.958759 -281.583223) (xy 109.929383 -281.54279)
			(xy 109.906693 -281.498258) (xy 109.891249 -281.450726) (xy 109.88343 -281.401363) (xy 109.578666 -281.401363)
			(xy 109.570847 -281.450726) (xy 109.555403 -281.498258) (xy 109.532713 -281.54279) (xy 109.503337 -281.583223)
			(xy 109.467997 -281.618563) (xy 109.427564 -281.647939) (xy 109.383032 -281.670629) (xy 109.3355 -281.686073)
			(xy 109.286137 -281.693892) (xy 109.236159 -281.693892) (xy 109.186796 -281.686073) (xy 109.139264 -281.670629)
			(xy 109.094732 -281.647939) (xy 109.054299 -281.618563) (xy 109.018959 -281.583223) (xy 108.989583 -281.54279)
			(xy 108.966893 -281.498258) (xy 108.951449 -281.450726) (xy 108.94363 -281.401363) (xy 108.638612 -281.401363)
			(xy 108.630793 -281.450726) (xy 108.615349 -281.498258) (xy 108.592659 -281.54279) (xy 108.563283 -281.583223)
			(xy 108.527943 -281.618563) (xy 108.48751 -281.647939) (xy 108.442978 -281.670629) (xy 108.395446 -281.686073)
			(xy 108.346083 -281.693892) (xy 108.296105 -281.693892) (xy 108.246742 -281.686073) (xy 108.19921 -281.670629)
			(xy 108.154678 -281.647939) (xy 108.114245 -281.618563) (xy 108.078905 -281.583223) (xy 108.049529 -281.54279)
			(xy 108.026839 -281.498258) (xy 108.011395 -281.450726) (xy 108.003576 -281.401363) (xy 105.81845 -281.401363)
			(xy 105.810631 -281.450726) (xy 105.795187 -281.498258) (xy 105.772497 -281.54279) (xy 105.743121 -281.583223)
			(xy 105.707781 -281.618563) (xy 105.667348 -281.647939) (xy 105.622816 -281.670629) (xy 105.575284 -281.686073)
			(xy 105.525921 -281.693892) (xy 105.475943 -281.693892) (xy 105.42658 -281.686073) (xy 105.379048 -281.670629)
			(xy 105.334516 -281.647939) (xy 105.294083 -281.618563) (xy 105.258743 -281.583223) (xy 105.229367 -281.54279)
			(xy 105.206677 -281.498258) (xy 105.191233 -281.450726) (xy 105.183414 -281.401363) (xy 102.998542 -281.401363)
			(xy 102.990723 -281.450726) (xy 102.975279 -281.498258) (xy 102.952589 -281.54279) (xy 102.923213 -281.583223)
			(xy 102.887873 -281.618563) (xy 102.84744 -281.647939) (xy 102.802908 -281.670629) (xy 102.755376 -281.686073)
			(xy 102.706013 -281.693892) (xy 102.656035 -281.693892) (xy 102.606672 -281.686073) (xy 102.55914 -281.670629)
			(xy 102.514608 -281.647939) (xy 102.474175 -281.618563) (xy 102.438835 -281.583223) (xy 102.409459 -281.54279)
			(xy 102.386769 -281.498258) (xy 102.371325 -281.450726) (xy 102.363506 -281.401363) (xy 102.056189 -281.401363)
			(xy 102.05618 -281.40182) (xy 102.048016 -281.452054) (xy 102.0319 -281.500328) (xy 102.008249 -281.545391)
			(xy 101.977676 -281.586077) (xy 101.940972 -281.621332) (xy 101.899088 -281.650242) (xy 101.853109 -281.672059)
			(xy 101.804225 -281.686219) (xy 101.753704 -281.692353) (xy 101.702852 -281.690304) (xy 101.652988 -281.680124)
			(xy 101.605402 -281.662077) (xy 101.561328 -281.636631) (xy 101.521906 -281.604444) (xy 101.488158 -281.56635)
			(xy 101.460957 -281.523336) (xy 101.441009 -281.476516) (xy 101.42883 -281.427102) (xy 101.424735 -281.376374)
			(xy 101.116892 -281.376374) (xy 101.11638 -281.40182) (xy 101.108216 -281.452054) (xy 101.0921 -281.500328)
			(xy 101.068449 -281.545391) (xy 101.037876 -281.586077) (xy 101.001172 -281.621332) (xy 100.959288 -281.650242)
			(xy 100.913309 -281.672059) (xy 100.864425 -281.686219) (xy 100.813904 -281.692353) (xy 100.763052 -281.690304)
			(xy 100.713188 -281.680124) (xy 100.665602 -281.662077) (xy 100.621528 -281.636631) (xy 100.582106 -281.604444)
			(xy 100.548358 -281.56635) (xy 100.521157 -281.523336) (xy 100.501209 -281.476516) (xy 100.48903 -281.427102)
			(xy 100.484935 -281.376374) (xy 100.179124 -281.376374) (xy 100.178634 -281.401363) (xy 100.170815 -281.450726)
			(xy 100.155371 -281.498258) (xy 100.132681 -281.54279) (xy 100.103305 -281.583223) (xy 100.067965 -281.618563)
			(xy 100.027532 -281.647939) (xy 99.983 -281.670629) (xy 99.935468 -281.686073) (xy 99.886105 -281.693892)
			(xy 99.836127 -281.693892) (xy 99.786764 -281.686073) (xy 99.739232 -281.670629) (xy 99.6947 -281.647939)
			(xy 99.654267 -281.618563) (xy 99.618927 -281.583223) (xy 99.589551 -281.54279) (xy 99.566861 -281.498258)
			(xy 99.551417 -281.450726) (xy 99.543598 -281.401363) (xy 99.236281 -281.401363) (xy 99.236272 -281.40182)
			(xy 99.228108 -281.452054) (xy 99.211992 -281.500328) (xy 99.188341 -281.545391) (xy 99.157768 -281.586077)
			(xy 99.121064 -281.621332) (xy 99.07918 -281.650242) (xy 99.033201 -281.672059) (xy 98.984317 -281.686219)
			(xy 98.933796 -281.692353) (xy 98.882944 -281.690304) (xy 98.83308 -281.680124) (xy 98.785494 -281.662077)
			(xy 98.74142 -281.636631) (xy 98.701998 -281.604444) (xy 98.66825 -281.56635) (xy 98.641049 -281.523336)
			(xy 98.621101 -281.476516) (xy 98.608922 -281.427102) (xy 98.604827 -281.376374) (xy 98.29673 -281.376374)
			(xy 98.296218 -281.40182) (xy 98.288054 -281.452054) (xy 98.271938 -281.500328) (xy 98.248287 -281.545391)
			(xy 98.217714 -281.586077) (xy 98.18101 -281.621332) (xy 98.139126 -281.650242) (xy 98.093147 -281.672059)
			(xy 98.044263 -281.686219) (xy 97.993742 -281.692353) (xy 97.94289 -281.690304) (xy 97.893026 -281.680124)
			(xy 97.84544 -281.662077) (xy 97.801366 -281.636631) (xy 97.761944 -281.604444) (xy 97.728196 -281.56635)
			(xy 97.700995 -281.523336) (xy 97.681047 -281.476516) (xy 97.668868 -281.427102) (xy 97.664773 -281.376374)
			(xy 97.358962 -281.376374) (xy 97.358472 -281.401363) (xy 97.350653 -281.450726) (xy 97.335209 -281.498258)
			(xy 97.312519 -281.54279) (xy 97.283143 -281.583223) (xy 97.247803 -281.618563) (xy 97.20737 -281.647939)
			(xy 97.162838 -281.670629) (xy 97.115306 -281.686073) (xy 97.065943 -281.693892) (xy 97.015965 -281.693892)
			(xy 96.966602 -281.686073) (xy 96.91907 -281.670629) (xy 96.874538 -281.647939) (xy 96.834105 -281.618563)
			(xy 96.798765 -281.583223) (xy 96.769389 -281.54279) (xy 96.746699 -281.498258) (xy 96.731255 -281.450726)
			(xy 96.723436 -281.401363) (xy 96.416373 -281.401363) (xy 96.416364 -281.40182) (xy 96.4082 -281.452054)
			(xy 96.392084 -281.500328) (xy 96.368433 -281.545391) (xy 96.33786 -281.586077) (xy 96.301156 -281.621332)
			(xy 96.259272 -281.650242) (xy 96.213293 -281.672059) (xy 96.164409 -281.686219) (xy 96.113888 -281.692353)
			(xy 96.063036 -281.690304) (xy 96.013172 -281.680124) (xy 95.965586 -281.662077) (xy 95.921512 -281.636631)
			(xy 95.88209 -281.604444) (xy 95.848342 -281.56635) (xy 95.821141 -281.523336) (xy 95.801193 -281.476516)
			(xy 95.789014 -281.427102) (xy 95.784919 -281.376374) (xy 95.479108 -281.376374) (xy 95.478618 -281.401363)
			(xy 95.470799 -281.450726) (xy 95.455355 -281.498258) (xy 95.432665 -281.54279) (xy 95.403289 -281.583223)
			(xy 95.367949 -281.618563) (xy 95.327516 -281.647939) (xy 95.282984 -281.670629) (xy 95.235452 -281.686073)
			(xy 95.186089 -281.693892) (xy 95.136111 -281.693892) (xy 95.086748 -281.686073) (xy 95.039216 -281.670629)
			(xy 94.994684 -281.647939) (xy 94.954251 -281.618563) (xy 94.918911 -281.583223) (xy 94.889535 -281.54279)
			(xy 94.866845 -281.498258) (xy 94.851401 -281.450726) (xy 94.843582 -281.401363) (xy 94.536265 -281.401363)
			(xy 94.536256 -281.40182) (xy 94.528092 -281.452054) (xy 94.511976 -281.500328) (xy 94.488325 -281.545391)
			(xy 94.457752 -281.586077) (xy 94.421048 -281.621332) (xy 94.379164 -281.650242) (xy 94.333185 -281.672059)
			(xy 94.284301 -281.686219) (xy 94.23378 -281.692353) (xy 94.182928 -281.690304) (xy 94.133064 -281.680124)
			(xy 94.085478 -281.662077) (xy 94.041404 -281.636631) (xy 94.001982 -281.604444) (xy 93.968234 -281.56635)
			(xy 93.941033 -281.523336) (xy 93.921085 -281.476516) (xy 93.908906 -281.427102) (xy 93.904811 -281.376374)
			(xy 93.599511 -281.376374) (xy 93.599525 -281.376558) (xy 93.595583 -281.426354) (xy 93.583905 -281.474923)
			(xy 93.564777 -281.521068) (xy 93.53867 -281.563655) (xy 93.506225 -281.601637) (xy 93.468242 -281.634079)
			(xy 93.425653 -281.660184) (xy 93.379507 -281.67931) (xy 93.330938 -281.690986) (xy 93.281141 -281.694925)
			(xy 93.231341 -281.69103) (xy 93.182761 -281.679397) (xy 93.136598 -281.660312) (xy 93.093987 -281.634245)
			(xy 93.055974 -281.601836) (xy 93.023496 -281.563883) (xy 92.997352 -281.521319) (xy 92.978183 -281.475191)
			(xy 92.966461 -281.426633) (xy 92.964 -281.401774) (xy 92.96273 -281.386788) (xy 92.945204 -281.36342)
			(xy 92.894658 -281.34437) (xy 92.89415 -281.34437) (xy 92.846398 -281.326844) (xy 92.837201 -281.323912)
			(xy 92.81792 -281.324425) (xy 92.800194 -281.332027) (xy 92.793058 -281.338528) (xy 92.635832 -281.495754)
			(xy 92.632022 -281.50439) (xy 92.622125 -281.525832) (xy 92.596935 -281.565776) (xy 92.566116 -281.601556)
			(xy 92.530344 -281.632385) (xy 92.490406 -281.657585) (xy 92.468954 -281.667458) (xy 92.460318 -281.671268)
			(xy 92.158566 -281.97302) (xy 92.146374 -281.984958) (xy 92.141548 -282.018486) (xy 92.14993 -282.033472)
			(xy 92.161113 -282.054734) (xy 92.177645 -282.099837) (xy 92.187194 -282.146916) (xy 92.188792 -282.170886)
			(xy 92.188792 -282.17368) (xy 92.189023 -282.18638) (xy 92.494857 -282.18638) (xy 92.498952 -282.135652)
			(xy 92.511131 -282.086238) (xy 92.531079 -282.039418) (xy 92.55828 -281.996404) (xy 92.592028 -281.95831)
			(xy 92.63145 -281.926123) (xy 92.675524 -281.900677) (xy 92.72311 -281.88263) (xy 92.772974 -281.87245)
			(xy 92.823826 -281.870401) (xy 92.874347 -281.876535) (xy 92.923231 -281.890695) (xy 92.96921 -281.912512)
			(xy 93.011094 -281.941422) (xy 93.047798 -281.976677) (xy 93.078371 -282.017363) (xy 93.102022 -282.062426)
			(xy 93.118138 -282.1107) (xy 93.126302 -282.160934) (xy 93.126814 -282.18638) (xy 93.126311 -282.211369)
			(xy 93.433628 -282.211369) (xy 93.433628 -282.161391) (xy 93.441447 -282.112028) (xy 93.456891 -282.064496)
			(xy 93.479581 -282.019964) (xy 93.508957 -281.979531) (xy 93.544297 -281.944191) (xy 93.58473 -281.914815)
			(xy 93.629262 -281.892125) (xy 93.676794 -281.876681) (xy 93.726157 -281.868862) (xy 93.776135 -281.868862)
			(xy 93.825498 -281.876681) (xy 93.87303 -281.892125) (xy 93.917562 -281.914815) (xy 93.957995 -281.944191)
			(xy 93.993335 -281.979531) (xy 94.022711 -282.019964) (xy 94.045401 -282.064496) (xy 94.060845 -282.112028)
			(xy 94.068664 -282.161391) (xy 94.069154 -282.18638) (xy 94.374711 -282.18638) (xy 94.378806 -282.135652)
			(xy 94.390985 -282.086238) (xy 94.410933 -282.039418) (xy 94.438134 -281.996404) (xy 94.471882 -281.95831)
			(xy 94.511304 -281.926123) (xy 94.555378 -281.900677) (xy 94.602964 -281.88263) (xy 94.652828 -281.87245)
			(xy 94.70368 -281.870401) (xy 94.754201 -281.876535) (xy 94.803085 -281.890695) (xy 94.849064 -281.912512)
			(xy 94.890948 -281.941422) (xy 94.927652 -281.976677) (xy 94.958225 -282.017363) (xy 94.981876 -282.062426)
			(xy 94.997992 -282.1107) (xy 95.006156 -282.160934) (xy 95.006668 -282.18638) (xy 95.314765 -282.18638)
			(xy 95.31886 -282.135652) (xy 95.331039 -282.086238) (xy 95.350987 -282.039418) (xy 95.378188 -281.996404)
			(xy 95.411936 -281.95831) (xy 95.451358 -281.926123) (xy 95.495432 -281.900677) (xy 95.543018 -281.88263)
			(xy 95.592882 -281.87245) (xy 95.643734 -281.870401) (xy 95.694255 -281.876535) (xy 95.743139 -281.890695)
			(xy 95.789118 -281.912512) (xy 95.831002 -281.941422) (xy 95.867706 -281.976677) (xy 95.898279 -282.017363)
			(xy 95.92193 -282.062426) (xy 95.938046 -282.1107) (xy 95.94621 -282.160934) (xy 95.946722 -282.18638)
			(xy 95.946219 -282.211369) (xy 96.253536 -282.211369) (xy 96.253536 -282.161391) (xy 96.261355 -282.112028)
			(xy 96.276799 -282.064496) (xy 96.299489 -282.019964) (xy 96.328865 -281.979531) (xy 96.364205 -281.944191)
			(xy 96.404638 -281.914815) (xy 96.44917 -281.892125) (xy 96.496702 -281.876681) (xy 96.546065 -281.868862)
			(xy 96.596043 -281.868862) (xy 96.645406 -281.876681) (xy 96.692938 -281.892125) (xy 96.73747 -281.914815)
			(xy 96.777903 -281.944191) (xy 96.813243 -281.979531) (xy 96.842619 -282.019964) (xy 96.865309 -282.064496)
			(xy 96.880753 -282.112028) (xy 96.888572 -282.161391) (xy 96.889062 -282.18638) (xy 96.888572 -282.211369)
			(xy 97.19359 -282.211369) (xy 97.19359 -282.161391) (xy 97.201409 -282.112028) (xy 97.216853 -282.064496)
			(xy 97.239543 -282.019964) (xy 97.268919 -281.979531) (xy 97.304259 -281.944191) (xy 97.344692 -281.914815)
			(xy 97.389224 -281.892125) (xy 97.436756 -281.876681) (xy 97.486119 -281.868862) (xy 97.536097 -281.868862)
			(xy 97.58546 -281.876681) (xy 97.632992 -281.892125) (xy 97.677524 -281.914815) (xy 97.717957 -281.944191)
			(xy 97.753297 -281.979531) (xy 97.782673 -282.019964) (xy 97.805363 -282.064496) (xy 97.820807 -282.112028)
			(xy 97.828626 -282.161391) (xy 97.829116 -282.18638) (xy 97.828626 -282.211369) (xy 98.133644 -282.211369)
			(xy 98.133644 -282.161391) (xy 98.141463 -282.112028) (xy 98.156907 -282.064496) (xy 98.179597 -282.019964)
			(xy 98.208973 -281.979531) (xy 98.244313 -281.944191) (xy 98.284746 -281.914815) (xy 98.329278 -281.892125)
			(xy 98.37681 -281.876681) (xy 98.426173 -281.868862) (xy 98.476151 -281.868862) (xy 98.525514 -281.876681)
			(xy 98.573046 -281.892125) (xy 98.617578 -281.914815) (xy 98.658011 -281.944191) (xy 98.693351 -281.979531)
			(xy 98.722727 -282.019964) (xy 98.745417 -282.064496) (xy 98.760861 -282.112028) (xy 98.76868 -282.161391)
			(xy 98.76917 -282.18638) (xy 98.76868 -282.211369) (xy 99.073444 -282.211369) (xy 99.073444 -282.161391)
			(xy 99.081263 -282.112028) (xy 99.096707 -282.064496) (xy 99.119397 -282.019964) (xy 99.148773 -281.979531)
			(xy 99.184113 -281.944191) (xy 99.224546 -281.914815) (xy 99.269078 -281.892125) (xy 99.31661 -281.876681)
			(xy 99.365973 -281.868862) (xy 99.415951 -281.868862) (xy 99.465314 -281.876681) (xy 99.512846 -281.892125)
			(xy 99.557378 -281.914815) (xy 99.597811 -281.944191) (xy 99.633151 -281.979531) (xy 99.662527 -282.019964)
			(xy 99.685217 -282.064496) (xy 99.700661 -282.112028) (xy 99.70848 -282.161391) (xy 99.70897 -282.18638)
			(xy 99.70848 -282.211369) (xy 100.013498 -282.211369) (xy 100.013498 -282.161391) (xy 100.021317 -282.112028)
			(xy 100.036761 -282.064496) (xy 100.059451 -282.019964) (xy 100.088827 -281.979531) (xy 100.124167 -281.944191)
			(xy 100.1646 -281.914815) (xy 100.209132 -281.892125) (xy 100.256664 -281.876681) (xy 100.306027 -281.868862)
			(xy 100.356005 -281.868862) (xy 100.405368 -281.876681) (xy 100.4529 -281.892125) (xy 100.497432 -281.914815)
			(xy 100.537865 -281.944191) (xy 100.573205 -281.979531) (xy 100.602581 -282.019964) (xy 100.625271 -282.064496)
			(xy 100.640715 -282.112028) (xy 100.648534 -282.161391) (xy 100.649024 -282.18638) (xy 100.648534 -282.211369)
			(xy 100.953552 -282.211369) (xy 100.953552 -282.161391) (xy 100.961371 -282.112028) (xy 100.976815 -282.064496)
			(xy 100.999505 -282.019964) (xy 101.028881 -281.979531) (xy 101.064221 -281.944191) (xy 101.104654 -281.914815)
			(xy 101.149186 -281.892125) (xy 101.196718 -281.876681) (xy 101.246081 -281.868862) (xy 101.296059 -281.868862)
			(xy 101.345422 -281.876681) (xy 101.392954 -281.892125) (xy 101.437486 -281.914815) (xy 101.477919 -281.944191)
			(xy 101.513259 -281.979531) (xy 101.542635 -282.019964) (xy 101.565325 -282.064496) (xy 101.580769 -282.112028)
			(xy 101.588588 -282.161391) (xy 101.589078 -282.18638) (xy 101.588588 -282.211369) (xy 101.893606 -282.211369)
			(xy 101.893606 -282.161391) (xy 101.901425 -282.112028) (xy 101.916869 -282.064496) (xy 101.939559 -282.019964)
			(xy 101.968935 -281.979531) (xy 102.004275 -281.944191) (xy 102.044708 -281.914815) (xy 102.08924 -281.892125)
			(xy 102.136772 -281.876681) (xy 102.186135 -281.868862) (xy 102.236113 -281.868862) (xy 102.285476 -281.876681)
			(xy 102.333008 -281.892125) (xy 102.37754 -281.914815) (xy 102.417973 -281.944191) (xy 102.453313 -281.979531)
			(xy 102.482689 -282.019964) (xy 102.505379 -282.064496) (xy 102.520823 -282.112028) (xy 102.528642 -282.161391)
			(xy 102.529132 -282.18638) (xy 102.528642 -282.211369) (xy 102.83366 -282.211369) (xy 102.83366 -282.161391)
			(xy 102.841479 -282.112028) (xy 102.856923 -282.064496) (xy 102.879613 -282.019964) (xy 102.908989 -281.979531)
			(xy 102.944329 -281.944191) (xy 102.984762 -281.914815) (xy 103.029294 -281.892125) (xy 103.076826 -281.876681)
			(xy 103.126189 -281.868862) (xy 103.176167 -281.868862) (xy 103.22553 -281.876681) (xy 103.273062 -281.892125)
			(xy 103.317594 -281.914815) (xy 103.358027 -281.944191) (xy 103.393367 -281.979531) (xy 103.422743 -282.019964)
			(xy 103.445433 -282.064496) (xy 103.460877 -282.112028) (xy 103.468696 -282.161391) (xy 103.469186 -282.18638)
			(xy 103.468696 -282.211369) (xy 103.77346 -282.211369) (xy 103.77346 -282.161391) (xy 103.781279 -282.112028)
			(xy 103.796723 -282.064496) (xy 103.819413 -282.019964) (xy 103.848789 -281.979531) (xy 103.884129 -281.944191)
			(xy 103.924562 -281.914815) (xy 103.969094 -281.892125) (xy 104.016626 -281.876681) (xy 104.065989 -281.868862)
			(xy 104.115967 -281.868862) (xy 104.16533 -281.876681) (xy 104.212862 -281.892125) (xy 104.257394 -281.914815)
			(xy 104.297827 -281.944191) (xy 104.333167 -281.979531) (xy 104.362543 -282.019964) (xy 104.385233 -282.064496)
			(xy 104.400677 -282.112028) (xy 104.408496 -282.161391) (xy 104.408986 -282.18638) (xy 104.408496 -282.211369)
			(xy 104.713514 -282.211369) (xy 104.713514 -282.161391) (xy 104.721333 -282.112028) (xy 104.736777 -282.064496)
			(xy 104.759467 -282.019964) (xy 104.788843 -281.979531) (xy 104.824183 -281.944191) (xy 104.864616 -281.914815)
			(xy 104.909148 -281.892125) (xy 104.95668 -281.876681) (xy 105.006043 -281.868862) (xy 105.056021 -281.868862)
			(xy 105.105384 -281.876681) (xy 105.152916 -281.892125) (xy 105.197448 -281.914815) (xy 105.237881 -281.944191)
			(xy 105.273221 -281.979531) (xy 105.302597 -282.019964) (xy 105.325287 -282.064496) (xy 105.340731 -282.112028)
			(xy 105.34855 -282.161391) (xy 105.34904 -282.18638) (xy 105.34855 -282.211369) (xy 105.653568 -282.211369)
			(xy 105.653568 -282.161391) (xy 105.661387 -282.112028) (xy 105.676831 -282.064496) (xy 105.699521 -282.019964)
			(xy 105.728897 -281.979531) (xy 105.764237 -281.944191) (xy 105.80467 -281.914815) (xy 105.849202 -281.892125)
			(xy 105.896734 -281.876681) (xy 105.946097 -281.868862) (xy 105.996075 -281.868862) (xy 106.045438 -281.876681)
			(xy 106.09297 -281.892125) (xy 106.137502 -281.914815) (xy 106.177935 -281.944191) (xy 106.213275 -281.979531)
			(xy 106.242651 -282.019964) (xy 106.265341 -282.064496) (xy 106.280785 -282.112028) (xy 106.288604 -282.161391)
			(xy 106.289094 -282.18638) (xy 106.288604 -282.211369) (xy 106.593622 -282.211369) (xy 106.593622 -282.161391)
			(xy 106.601441 -282.112028) (xy 106.616885 -282.064496) (xy 106.639575 -282.019964) (xy 106.668951 -281.979531)
			(xy 106.704291 -281.944191) (xy 106.744724 -281.914815) (xy 106.789256 -281.892125) (xy 106.836788 -281.876681)
			(xy 106.886151 -281.868862) (xy 106.936129 -281.868862) (xy 106.985492 -281.876681) (xy 107.033024 -281.892125)
			(xy 107.077556 -281.914815) (xy 107.117989 -281.944191) (xy 107.153329 -281.979531) (xy 107.182705 -282.019964)
			(xy 107.205395 -282.064496) (xy 107.220839 -282.112028) (xy 107.228658 -282.161391) (xy 107.229148 -282.18638)
			(xy 107.228658 -282.211369) (xy 107.533422 -282.211369) (xy 107.533422 -282.161391) (xy 107.541241 -282.112028)
			(xy 107.556685 -282.064496) (xy 107.579375 -282.019964) (xy 107.608751 -281.979531) (xy 107.644091 -281.944191)
			(xy 107.684524 -281.914815) (xy 107.729056 -281.892125) (xy 107.776588 -281.876681) (xy 107.825951 -281.868862)
			(xy 107.875929 -281.868862) (xy 107.925292 -281.876681) (xy 107.972824 -281.892125) (xy 108.017356 -281.914815)
			(xy 108.057789 -281.944191) (xy 108.093129 -281.979531) (xy 108.122505 -282.019964) (xy 108.145195 -282.064496)
			(xy 108.160639 -282.112028) (xy 108.168458 -282.161391) (xy 108.168948 -282.18638) (xy 108.474759 -282.18638)
			(xy 108.478854 -282.135652) (xy 108.491033 -282.086238) (xy 108.510981 -282.039418) (xy 108.538182 -281.996404)
			(xy 108.57193 -281.95831) (xy 108.611352 -281.926123) (xy 108.655426 -281.900677) (xy 108.703012 -281.88263)
			(xy 108.752876 -281.87245) (xy 108.803728 -281.870401) (xy 108.854249 -281.876535) (xy 108.903133 -281.890695)
			(xy 108.949112 -281.912512) (xy 108.990996 -281.941422) (xy 109.0277 -281.976677) (xy 109.058273 -282.017363)
			(xy 109.081924 -282.062426) (xy 109.09804 -282.1107) (xy 109.106204 -282.160934) (xy 109.106716 -282.18638)
			(xy 109.414813 -282.18638) (xy 109.418908 -282.135652) (xy 109.431087 -282.086238) (xy 109.451035 -282.039418)
			(xy 109.478236 -281.996404) (xy 109.511984 -281.95831) (xy 109.551406 -281.926123) (xy 109.59548 -281.900677)
			(xy 109.643066 -281.88263) (xy 109.69293 -281.87245) (xy 109.743782 -281.870401) (xy 109.794303 -281.876535)
			(xy 109.843187 -281.890695) (xy 109.889166 -281.912512) (xy 109.93105 -281.941422) (xy 109.967754 -281.976677)
			(xy 109.998327 -282.017363) (xy 110.021978 -282.062426) (xy 110.038094 -282.1107) (xy 110.046258 -282.160934)
			(xy 110.04677 -282.18638) (xy 110.046267 -282.211369) (xy 110.353584 -282.211369) (xy 110.353584 -282.161391)
			(xy 110.361403 -282.112028) (xy 110.376847 -282.064496) (xy 110.399537 -282.019964) (xy 110.428913 -281.979531)
			(xy 110.464253 -281.944191) (xy 110.504686 -281.914815) (xy 110.549218 -281.892125) (xy 110.59675 -281.876681)
			(xy 110.646113 -281.868862) (xy 110.696091 -281.868862) (xy 110.745454 -281.876681) (xy 110.792986 -281.892125)
			(xy 110.837518 -281.914815) (xy 110.877951 -281.944191) (xy 110.913291 -281.979531) (xy 110.942667 -282.019964)
			(xy 110.965357 -282.064496) (xy 110.980801 -282.112028) (xy 110.98862 -282.161391) (xy 110.98911 -282.18638)
			(xy 110.98862 -282.211369) (xy 113.167142 -282.211369) (xy 113.167142 -282.161391) (xy 113.174961 -282.112028)
			(xy 113.190405 -282.064496) (xy 113.213095 -282.019964) (xy 113.242471 -281.979531) (xy 113.277811 -281.944191)
			(xy 113.318244 -281.914815) (xy 113.362776 -281.892125) (xy 113.410308 -281.876681) (xy 113.459671 -281.868862)
			(xy 113.509649 -281.868862) (xy 113.559012 -281.876681) (xy 113.606544 -281.892125) (xy 113.651076 -281.914815)
			(xy 113.691509 -281.944191) (xy 113.726849 -281.979531) (xy 113.756225 -282.019964) (xy 113.778915 -282.064496)
			(xy 113.794359 -282.112028) (xy 113.802178 -282.161391) (xy 113.802668 -282.18638) (xy 114.108479 -282.18638)
			(xy 114.112574 -282.135652) (xy 114.124753 -282.086238) (xy 114.144701 -282.039418) (xy 114.171902 -281.996404)
			(xy 114.20565 -281.95831) (xy 114.245072 -281.926123) (xy 114.289146 -281.900677) (xy 114.336732 -281.88263)
			(xy 114.386596 -281.87245) (xy 114.437448 -281.870401) (xy 114.487969 -281.876535) (xy 114.536853 -281.890695)
			(xy 114.582832 -281.912512) (xy 114.624716 -281.941422) (xy 114.66142 -281.976677) (xy 114.691993 -282.017363)
			(xy 114.715644 -282.062426) (xy 114.73176 -282.1107) (xy 114.739924 -282.160934) (xy 114.740436 -282.18638)
			(xy 115.048533 -282.18638) (xy 115.052628 -282.135652) (xy 115.064807 -282.086238) (xy 115.084755 -282.039418)
			(xy 115.111956 -281.996404) (xy 115.145704 -281.95831) (xy 115.185126 -281.926123) (xy 115.2292 -281.900677)
			(xy 115.276786 -281.88263) (xy 115.32665 -281.87245) (xy 115.377502 -281.870401) (xy 115.428023 -281.876535)
			(xy 115.476907 -281.890695) (xy 115.522886 -281.912512) (xy 115.56477 -281.941422) (xy 115.601474 -281.976677)
			(xy 115.632047 -282.017363) (xy 115.655698 -282.062426) (xy 115.671814 -282.1107) (xy 115.679978 -282.160934)
			(xy 115.68049 -282.18638) (xy 115.679987 -282.211369) (xy 115.987304 -282.211369) (xy 115.987304 -282.161391)
			(xy 115.995123 -282.112028) (xy 116.010567 -282.064496) (xy 116.033257 -282.019964) (xy 116.062633 -281.979531)
			(xy 116.097973 -281.944191) (xy 116.138406 -281.914815) (xy 116.182938 -281.892125) (xy 116.23047 -281.876681)
			(xy 116.279833 -281.868862) (xy 116.329811 -281.868862) (xy 116.379174 -281.876681) (xy 116.426706 -281.892125)
			(xy 116.471238 -281.914815) (xy 116.511671 -281.944191) (xy 116.547011 -281.979531) (xy 116.576387 -282.019964)
			(xy 116.599077 -282.064496) (xy 116.614521 -282.112028) (xy 116.62234 -282.161391) (xy 116.62283 -282.18638)
			(xy 116.62234 -282.211369) (xy 116.927104 -282.211369) (xy 116.927104 -282.161391) (xy 116.934923 -282.112028)
			(xy 116.950367 -282.064496) (xy 116.973057 -282.019964) (xy 117.002433 -281.979531) (xy 117.037773 -281.944191)
			(xy 117.078206 -281.914815) (xy 117.122738 -281.892125) (xy 117.17027 -281.876681) (xy 117.219633 -281.868862)
			(xy 117.269611 -281.868862) (xy 117.318974 -281.876681) (xy 117.366506 -281.892125) (xy 117.411038 -281.914815)
			(xy 117.451471 -281.944191) (xy 117.486811 -281.979531) (xy 117.516187 -282.019964) (xy 117.538877 -282.064496)
			(xy 117.554321 -282.112028) (xy 117.56214 -282.161391) (xy 117.56263 -282.18638) (xy 117.56214 -282.211369)
			(xy 117.867158 -282.211369) (xy 117.867158 -282.161391) (xy 117.874977 -282.112028) (xy 117.890421 -282.064496)
			(xy 117.913111 -282.019964) (xy 117.942487 -281.979531) (xy 117.977827 -281.944191) (xy 118.01826 -281.914815)
			(xy 118.062792 -281.892125) (xy 118.110324 -281.876681) (xy 118.159687 -281.868862) (xy 118.209665 -281.868862)
			(xy 118.259028 -281.876681) (xy 118.30656 -281.892125) (xy 118.351092 -281.914815) (xy 118.391525 -281.944191)
			(xy 118.426865 -281.979531) (xy 118.456241 -282.019964) (xy 118.478931 -282.064496) (xy 118.494375 -282.112028)
			(xy 118.502194 -282.161391) (xy 118.502684 -282.18638) (xy 118.502194 -282.211369) (xy 118.807212 -282.211369)
			(xy 118.807212 -282.161391) (xy 118.815031 -282.112028) (xy 118.830475 -282.064496) (xy 118.853165 -282.019964)
			(xy 118.882541 -281.979531) (xy 118.917881 -281.944191) (xy 118.958314 -281.914815) (xy 119.002846 -281.892125)
			(xy 119.050378 -281.876681) (xy 119.099741 -281.868862) (xy 119.149719 -281.868862) (xy 119.199082 -281.876681)
			(xy 119.246614 -281.892125) (xy 119.291146 -281.914815) (xy 119.331579 -281.944191) (xy 119.366919 -281.979531)
			(xy 119.396295 -282.019964) (xy 119.418985 -282.064496) (xy 119.434429 -282.112028) (xy 119.442248 -282.161391)
			(xy 119.442738 -282.18638) (xy 119.442248 -282.211369) (xy 119.747266 -282.211369) (xy 119.747266 -282.161391)
			(xy 119.755085 -282.112028) (xy 119.770529 -282.064496) (xy 119.793219 -282.019964) (xy 119.822595 -281.979531)
			(xy 119.857935 -281.944191) (xy 119.898368 -281.914815) (xy 119.9429 -281.892125) (xy 119.990432 -281.876681)
			(xy 120.039795 -281.868862) (xy 120.089773 -281.868862) (xy 120.139136 -281.876681) (xy 120.186668 -281.892125)
			(xy 120.2312 -281.914815) (xy 120.271633 -281.944191) (xy 120.306973 -281.979531) (xy 120.336349 -282.019964)
			(xy 120.359039 -282.064496) (xy 120.374483 -282.112028) (xy 120.382302 -282.161391) (xy 120.382792 -282.18638)
			(xy 120.382302 -282.211369) (xy 120.68732 -282.211369) (xy 120.68732 -282.161391) (xy 120.695139 -282.112028)
			(xy 120.710583 -282.064496) (xy 120.733273 -282.019964) (xy 120.762649 -281.979531) (xy 120.797989 -281.944191)
			(xy 120.838422 -281.914815) (xy 120.882954 -281.892125) (xy 120.930486 -281.876681) (xy 120.979849 -281.868862)
			(xy 121.029827 -281.868862) (xy 121.07919 -281.876681) (xy 121.126722 -281.892125) (xy 121.171254 -281.914815)
			(xy 121.211687 -281.944191) (xy 121.247027 -281.979531) (xy 121.276403 -282.019964) (xy 121.299093 -282.064496)
			(xy 121.314537 -282.112028) (xy 121.322356 -282.161391) (xy 121.322846 -282.18638) (xy 121.322356 -282.211369)
			(xy 121.62712 -282.211369) (xy 121.62712 -282.161391) (xy 121.634939 -282.112028) (xy 121.650383 -282.064496)
			(xy 121.673073 -282.019964) (xy 121.702449 -281.979531) (xy 121.737789 -281.944191) (xy 121.778222 -281.914815)
			(xy 121.822754 -281.892125) (xy 121.870286 -281.876681) (xy 121.919649 -281.868862) (xy 121.969627 -281.868862)
			(xy 122.01899 -281.876681) (xy 122.066522 -281.892125) (xy 122.111054 -281.914815) (xy 122.151487 -281.944191)
			(xy 122.186827 -281.979531) (xy 122.216203 -282.019964) (xy 122.238893 -282.064496) (xy 122.254337 -282.112028)
			(xy 122.262156 -282.161391) (xy 122.262646 -282.18638) (xy 122.262156 -282.211369) (xy 122.567174 -282.211369)
			(xy 122.567174 -282.161391) (xy 122.574993 -282.112028) (xy 122.590437 -282.064496) (xy 122.613127 -282.019964)
			(xy 122.642503 -281.979531) (xy 122.677843 -281.944191) (xy 122.718276 -281.914815) (xy 122.762808 -281.892125)
			(xy 122.81034 -281.876681) (xy 122.859703 -281.868862) (xy 122.909681 -281.868862) (xy 122.959044 -281.876681)
			(xy 123.006576 -281.892125) (xy 123.051108 -281.914815) (xy 123.091541 -281.944191) (xy 123.126881 -281.979531)
			(xy 123.156257 -282.019964) (xy 123.178947 -282.064496) (xy 123.194391 -282.112028) (xy 123.20221 -282.161391)
			(xy 123.2027 -282.18638) (xy 123.20221 -282.211369) (xy 123.507228 -282.211369) (xy 123.507228 -282.161391)
			(xy 123.515047 -282.112028) (xy 123.530491 -282.064496) (xy 123.553181 -282.019964) (xy 123.582557 -281.979531)
			(xy 123.617897 -281.944191) (xy 123.65833 -281.914815) (xy 123.702862 -281.892125) (xy 123.750394 -281.876681)
			(xy 123.799757 -281.868862) (xy 123.849735 -281.868862) (xy 123.899098 -281.876681) (xy 123.94663 -281.892125)
			(xy 123.991162 -281.914815) (xy 124.031595 -281.944191) (xy 124.066935 -281.979531) (xy 124.096311 -282.019964)
			(xy 124.119001 -282.064496) (xy 124.134445 -282.112028) (xy 124.142264 -282.161391) (xy 124.142754 -282.18638)
			(xy 124.142264 -282.211369) (xy 124.447282 -282.211369) (xy 124.447282 -282.161391) (xy 124.455101 -282.112028)
			(xy 124.470545 -282.064496) (xy 124.493235 -282.019964) (xy 124.522611 -281.979531) (xy 124.557951 -281.944191)
			(xy 124.598384 -281.914815) (xy 124.642916 -281.892125) (xy 124.690448 -281.876681) (xy 124.739811 -281.868862)
			(xy 124.789789 -281.868862) (xy 124.839152 -281.876681) (xy 124.886684 -281.892125) (xy 124.931216 -281.914815)
			(xy 124.971649 -281.944191) (xy 125.006989 -281.979531) (xy 125.036365 -282.019964) (xy 125.059055 -282.064496)
			(xy 125.074499 -282.112028) (xy 125.082318 -282.161391) (xy 125.082808 -282.18638) (xy 125.082318 -282.211369)
			(xy 125.387336 -282.211369) (xy 125.387336 -282.161391) (xy 125.395155 -282.112028) (xy 125.410599 -282.064496)
			(xy 125.433289 -282.019964) (xy 125.462665 -281.979531) (xy 125.498005 -281.944191) (xy 125.538438 -281.914815)
			(xy 125.58297 -281.892125) (xy 125.630502 -281.876681) (xy 125.679865 -281.868862) (xy 125.729843 -281.868862)
			(xy 125.779206 -281.876681) (xy 125.826738 -281.892125) (xy 125.87127 -281.914815) (xy 125.911703 -281.944191)
			(xy 125.947043 -281.979531) (xy 125.976419 -282.019964) (xy 125.999109 -282.064496) (xy 126.014553 -282.112028)
			(xy 126.022372 -282.161391) (xy 126.022862 -282.18638) (xy 126.022372 -282.211369) (xy 126.014553 -282.260732)
			(xy 125.999109 -282.308264) (xy 125.976419 -282.352796) (xy 125.947043 -282.393229) (xy 125.911703 -282.428569)
			(xy 125.87127 -282.457945) (xy 125.826738 -282.480635) (xy 125.779206 -282.496079) (xy 125.729843 -282.503898)
			(xy 125.679865 -282.503898) (xy 125.630502 -282.496079) (xy 125.58297 -282.480635) (xy 125.538438 -282.457945)
			(xy 125.498005 -282.428569) (xy 125.462665 -282.393229) (xy 125.433289 -282.352796) (xy 125.410599 -282.308264)
			(xy 125.395155 -282.260732) (xy 125.387336 -282.211369) (xy 125.082318 -282.211369) (xy 125.074499 -282.260732)
			(xy 125.059055 -282.308264) (xy 125.036365 -282.352796) (xy 125.006989 -282.393229) (xy 124.971649 -282.428569)
			(xy 124.931216 -282.457945) (xy 124.886684 -282.480635) (xy 124.839152 -282.496079) (xy 124.789789 -282.503898)
			(xy 124.739811 -282.503898) (xy 124.690448 -282.496079) (xy 124.642916 -282.480635) (xy 124.598384 -282.457945)
			(xy 124.557951 -282.428569) (xy 124.522611 -282.393229) (xy 124.493235 -282.352796) (xy 124.470545 -282.308264)
			(xy 124.455101 -282.260732) (xy 124.447282 -282.211369) (xy 124.142264 -282.211369) (xy 124.134445 -282.260732)
			(xy 124.119001 -282.308264) (xy 124.096311 -282.352796) (xy 124.066935 -282.393229) (xy 124.031595 -282.428569)
			(xy 123.991162 -282.457945) (xy 123.94663 -282.480635) (xy 123.899098 -282.496079) (xy 123.849735 -282.503898)
			(xy 123.799757 -282.503898) (xy 123.750394 -282.496079) (xy 123.702862 -282.480635) (xy 123.65833 -282.457945)
			(xy 123.617897 -282.428569) (xy 123.582557 -282.393229) (xy 123.553181 -282.352796) (xy 123.530491 -282.308264)
			(xy 123.515047 -282.260732) (xy 123.507228 -282.211369) (xy 123.20221 -282.211369) (xy 123.194391 -282.260732)
			(xy 123.178947 -282.308264) (xy 123.156257 -282.352796) (xy 123.126881 -282.393229) (xy 123.091541 -282.428569)
			(xy 123.051108 -282.457945) (xy 123.006576 -282.480635) (xy 122.959044 -282.496079) (xy 122.909681 -282.503898)
			(xy 122.859703 -282.503898) (xy 122.81034 -282.496079) (xy 122.762808 -282.480635) (xy 122.718276 -282.457945)
			(xy 122.677843 -282.428569) (xy 122.642503 -282.393229) (xy 122.613127 -282.352796) (xy 122.590437 -282.308264)
			(xy 122.574993 -282.260732) (xy 122.567174 -282.211369) (xy 122.262156 -282.211369) (xy 122.254337 -282.260732)
			(xy 122.238893 -282.308264) (xy 122.216203 -282.352796) (xy 122.186827 -282.393229) (xy 122.151487 -282.428569)
			(xy 122.111054 -282.457945) (xy 122.066522 -282.480635) (xy 122.01899 -282.496079) (xy 121.969627 -282.503898)
			(xy 121.919649 -282.503898) (xy 121.870286 -282.496079) (xy 121.822754 -282.480635) (xy 121.778222 -282.457945)
			(xy 121.737789 -282.428569) (xy 121.702449 -282.393229) (xy 121.673073 -282.352796) (xy 121.650383 -282.308264)
			(xy 121.634939 -282.260732) (xy 121.62712 -282.211369) (xy 121.322356 -282.211369) (xy 121.314537 -282.260732)
			(xy 121.299093 -282.308264) (xy 121.276403 -282.352796) (xy 121.247027 -282.393229) (xy 121.211687 -282.428569)
			(xy 121.171254 -282.457945) (xy 121.126722 -282.480635) (xy 121.07919 -282.496079) (xy 121.029827 -282.503898)
			(xy 120.979849 -282.503898) (xy 120.930486 -282.496079) (xy 120.882954 -282.480635) (xy 120.838422 -282.457945)
			(xy 120.797989 -282.428569) (xy 120.762649 -282.393229) (xy 120.733273 -282.352796) (xy 120.710583 -282.308264)
			(xy 120.695139 -282.260732) (xy 120.68732 -282.211369) (xy 120.382302 -282.211369) (xy 120.374483 -282.260732)
			(xy 120.359039 -282.308264) (xy 120.336349 -282.352796) (xy 120.306973 -282.393229) (xy 120.271633 -282.428569)
			(xy 120.2312 -282.457945) (xy 120.186668 -282.480635) (xy 120.139136 -282.496079) (xy 120.089773 -282.503898)
			(xy 120.039795 -282.503898) (xy 119.990432 -282.496079) (xy 119.9429 -282.480635) (xy 119.898368 -282.457945)
			(xy 119.857935 -282.428569) (xy 119.822595 -282.393229) (xy 119.793219 -282.352796) (xy 119.770529 -282.308264)
			(xy 119.755085 -282.260732) (xy 119.747266 -282.211369) (xy 119.442248 -282.211369) (xy 119.434429 -282.260732)
			(xy 119.418985 -282.308264) (xy 119.396295 -282.352796) (xy 119.366919 -282.393229) (xy 119.331579 -282.428569)
			(xy 119.291146 -282.457945) (xy 119.246614 -282.480635) (xy 119.199082 -282.496079) (xy 119.149719 -282.503898)
			(xy 119.099741 -282.503898) (xy 119.050378 -282.496079) (xy 119.002846 -282.480635) (xy 118.958314 -282.457945)
			(xy 118.917881 -282.428569) (xy 118.882541 -282.393229) (xy 118.853165 -282.352796) (xy 118.830475 -282.308264)
			(xy 118.815031 -282.260732) (xy 118.807212 -282.211369) (xy 118.502194 -282.211369) (xy 118.494375 -282.260732)
			(xy 118.478931 -282.308264) (xy 118.456241 -282.352796) (xy 118.426865 -282.393229) (xy 118.391525 -282.428569)
			(xy 118.351092 -282.457945) (xy 118.30656 -282.480635) (xy 118.259028 -282.496079) (xy 118.209665 -282.503898)
			(xy 118.159687 -282.503898) (xy 118.110324 -282.496079) (xy 118.062792 -282.480635) (xy 118.01826 -282.457945)
			(xy 117.977827 -282.428569) (xy 117.942487 -282.393229) (xy 117.913111 -282.352796) (xy 117.890421 -282.308264)
			(xy 117.874977 -282.260732) (xy 117.867158 -282.211369) (xy 117.56214 -282.211369) (xy 117.554321 -282.260732)
			(xy 117.538877 -282.308264) (xy 117.516187 -282.352796) (xy 117.486811 -282.393229) (xy 117.451471 -282.428569)
			(xy 117.411038 -282.457945) (xy 117.366506 -282.480635) (xy 117.318974 -282.496079) (xy 117.269611 -282.503898)
			(xy 117.219633 -282.503898) (xy 117.17027 -282.496079) (xy 117.122738 -282.480635) (xy 117.078206 -282.457945)
			(xy 117.037773 -282.428569) (xy 117.002433 -282.393229) (xy 116.973057 -282.352796) (xy 116.950367 -282.308264)
			(xy 116.934923 -282.260732) (xy 116.927104 -282.211369) (xy 116.62234 -282.211369) (xy 116.614521 -282.260732)
			(xy 116.599077 -282.308264) (xy 116.576387 -282.352796) (xy 116.547011 -282.393229) (xy 116.511671 -282.428569)
			(xy 116.471238 -282.457945) (xy 116.426706 -282.480635) (xy 116.379174 -282.496079) (xy 116.329811 -282.503898)
			(xy 116.279833 -282.503898) (xy 116.23047 -282.496079) (xy 116.182938 -282.480635) (xy 116.138406 -282.457945)
			(xy 116.097973 -282.428569) (xy 116.062633 -282.393229) (xy 116.033257 -282.352796) (xy 116.010567 -282.308264)
			(xy 115.995123 -282.260732) (xy 115.987304 -282.211369) (xy 115.679987 -282.211369) (xy 115.679978 -282.211826)
			(xy 115.671814 -282.26206) (xy 115.655698 -282.310334) (xy 115.632047 -282.355397) (xy 115.601474 -282.396083)
			(xy 115.56477 -282.431338) (xy 115.522886 -282.460248) (xy 115.476907 -282.482065) (xy 115.428023 -282.496225)
			(xy 115.377502 -282.502359) (xy 115.32665 -282.50031) (xy 115.276786 -282.49013) (xy 115.2292 -282.472083)
			(xy 115.185126 -282.446637) (xy 115.145704 -282.41445) (xy 115.111956 -282.376356) (xy 115.084755 -282.333342)
			(xy 115.064807 -282.286522) (xy 115.052628 -282.237108) (xy 115.048533 -282.18638) (xy 114.740436 -282.18638)
			(xy 114.739924 -282.211826) (xy 114.73176 -282.26206) (xy 114.715644 -282.310334) (xy 114.691993 -282.355397)
			(xy 114.66142 -282.396083) (xy 114.624716 -282.431338) (xy 114.582832 -282.460248) (xy 114.536853 -282.482065)
			(xy 114.487969 -282.496225) (xy 114.437448 -282.502359) (xy 114.386596 -282.50031) (xy 114.336732 -282.49013)
			(xy 114.289146 -282.472083) (xy 114.245072 -282.446637) (xy 114.20565 -282.41445) (xy 114.171902 -282.376356)
			(xy 114.144701 -282.333342) (xy 114.124753 -282.286522) (xy 114.112574 -282.237108) (xy 114.108479 -282.18638)
			(xy 113.802668 -282.18638) (xy 113.802178 -282.211369) (xy 113.794359 -282.260732) (xy 113.778915 -282.308264)
			(xy 113.756225 -282.352796) (xy 113.726849 -282.393229) (xy 113.691509 -282.428569) (xy 113.651076 -282.457945)
			(xy 113.606544 -282.480635) (xy 113.559012 -282.496079) (xy 113.509649 -282.503898) (xy 113.459671 -282.503898)
			(xy 113.410308 -282.496079) (xy 113.362776 -282.480635) (xy 113.318244 -282.457945) (xy 113.277811 -282.428569)
			(xy 113.242471 -282.393229) (xy 113.213095 -282.352796) (xy 113.190405 -282.308264) (xy 113.174961 -282.260732)
			(xy 113.167142 -282.211369) (xy 110.98862 -282.211369) (xy 110.980801 -282.260732) (xy 110.965357 -282.308264)
			(xy 110.942667 -282.352796) (xy 110.913291 -282.393229) (xy 110.877951 -282.428569) (xy 110.837518 -282.457945)
			(xy 110.792986 -282.480635) (xy 110.745454 -282.496079) (xy 110.696091 -282.503898) (xy 110.646113 -282.503898)
			(xy 110.59675 -282.496079) (xy 110.549218 -282.480635) (xy 110.504686 -282.457945) (xy 110.464253 -282.428569)
			(xy 110.428913 -282.393229) (xy 110.399537 -282.352796) (xy 110.376847 -282.308264) (xy 110.361403 -282.260732)
			(xy 110.353584 -282.211369) (xy 110.046267 -282.211369) (xy 110.046258 -282.211826) (xy 110.038094 -282.26206)
			(xy 110.021978 -282.310334) (xy 109.998327 -282.355397) (xy 109.967754 -282.396083) (xy 109.93105 -282.431338)
			(xy 109.889166 -282.460248) (xy 109.843187 -282.482065) (xy 109.794303 -282.496225) (xy 109.743782 -282.502359)
			(xy 109.69293 -282.50031) (xy 109.643066 -282.49013) (xy 109.59548 -282.472083) (xy 109.551406 -282.446637)
			(xy 109.511984 -282.41445) (xy 109.478236 -282.376356) (xy 109.451035 -282.333342) (xy 109.431087 -282.286522)
			(xy 109.418908 -282.237108) (xy 109.414813 -282.18638) (xy 109.106716 -282.18638) (xy 109.106204 -282.211826)
			(xy 109.09804 -282.26206) (xy 109.081924 -282.310334) (xy 109.058273 -282.355397) (xy 109.0277 -282.396083)
			(xy 108.990996 -282.431338) (xy 108.949112 -282.460248) (xy 108.903133 -282.482065) (xy 108.854249 -282.496225)
			(xy 108.803728 -282.502359) (xy 108.752876 -282.50031) (xy 108.703012 -282.49013) (xy 108.655426 -282.472083)
			(xy 108.611352 -282.446637) (xy 108.57193 -282.41445) (xy 108.538182 -282.376356) (xy 108.510981 -282.333342)
			(xy 108.491033 -282.286522) (xy 108.478854 -282.237108) (xy 108.474759 -282.18638) (xy 108.168948 -282.18638)
			(xy 108.168458 -282.211369) (xy 108.160639 -282.260732) (xy 108.145195 -282.308264) (xy 108.122505 -282.352796)
			(xy 108.093129 -282.393229) (xy 108.057789 -282.428569) (xy 108.017356 -282.457945) (xy 107.972824 -282.480635)
			(xy 107.925292 -282.496079) (xy 107.875929 -282.503898) (xy 107.825951 -282.503898) (xy 107.776588 -282.496079)
			(xy 107.729056 -282.480635) (xy 107.684524 -282.457945) (xy 107.644091 -282.428569) (xy 107.608751 -282.393229)
			(xy 107.579375 -282.352796) (xy 107.556685 -282.308264) (xy 107.541241 -282.260732) (xy 107.533422 -282.211369)
			(xy 107.228658 -282.211369) (xy 107.220839 -282.260732) (xy 107.205395 -282.308264) (xy 107.182705 -282.352796)
			(xy 107.153329 -282.393229) (xy 107.117989 -282.428569) (xy 107.077556 -282.457945) (xy 107.033024 -282.480635)
			(xy 106.985492 -282.496079) (xy 106.936129 -282.503898) (xy 106.886151 -282.503898) (xy 106.836788 -282.496079)
			(xy 106.789256 -282.480635) (xy 106.744724 -282.457945) (xy 106.704291 -282.428569) (xy 106.668951 -282.393229)
			(xy 106.639575 -282.352796) (xy 106.616885 -282.308264) (xy 106.601441 -282.260732) (xy 106.593622 -282.211369)
			(xy 106.288604 -282.211369) (xy 106.280785 -282.260732) (xy 106.265341 -282.308264) (xy 106.242651 -282.352796)
			(xy 106.213275 -282.393229) (xy 106.177935 -282.428569) (xy 106.137502 -282.457945) (xy 106.09297 -282.480635)
			(xy 106.045438 -282.496079) (xy 105.996075 -282.503898) (xy 105.946097 -282.503898) (xy 105.896734 -282.496079)
			(xy 105.849202 -282.480635) (xy 105.80467 -282.457945) (xy 105.764237 -282.428569) (xy 105.728897 -282.393229)
			(xy 105.699521 -282.352796) (xy 105.676831 -282.308264) (xy 105.661387 -282.260732) (xy 105.653568 -282.211369)
			(xy 105.34855 -282.211369) (xy 105.340731 -282.260732) (xy 105.325287 -282.308264) (xy 105.302597 -282.352796)
			(xy 105.273221 -282.393229) (xy 105.237881 -282.428569) (xy 105.197448 -282.457945) (xy 105.152916 -282.480635)
			(xy 105.105384 -282.496079) (xy 105.056021 -282.503898) (xy 105.006043 -282.503898) (xy 104.95668 -282.496079)
			(xy 104.909148 -282.480635) (xy 104.864616 -282.457945) (xy 104.824183 -282.428569) (xy 104.788843 -282.393229)
			(xy 104.759467 -282.352796) (xy 104.736777 -282.308264) (xy 104.721333 -282.260732) (xy 104.713514 -282.211369)
			(xy 104.408496 -282.211369) (xy 104.400677 -282.260732) (xy 104.385233 -282.308264) (xy 104.362543 -282.352796)
			(xy 104.333167 -282.393229) (xy 104.297827 -282.428569) (xy 104.257394 -282.457945) (xy 104.212862 -282.480635)
			(xy 104.16533 -282.496079) (xy 104.115967 -282.503898) (xy 104.065989 -282.503898) (xy 104.016626 -282.496079)
			(xy 103.969094 -282.480635) (xy 103.924562 -282.457945) (xy 103.884129 -282.428569) (xy 103.848789 -282.393229)
			(xy 103.819413 -282.352796) (xy 103.796723 -282.308264) (xy 103.781279 -282.260732) (xy 103.77346 -282.211369)
			(xy 103.468696 -282.211369) (xy 103.460877 -282.260732) (xy 103.445433 -282.308264) (xy 103.422743 -282.352796)
			(xy 103.393367 -282.393229) (xy 103.358027 -282.428569) (xy 103.317594 -282.457945) (xy 103.273062 -282.480635)
			(xy 103.22553 -282.496079) (xy 103.176167 -282.503898) (xy 103.126189 -282.503898) (xy 103.076826 -282.496079)
			(xy 103.029294 -282.480635) (xy 102.984762 -282.457945) (xy 102.944329 -282.428569) (xy 102.908989 -282.393229)
			(xy 102.879613 -282.352796) (xy 102.856923 -282.308264) (xy 102.841479 -282.260732) (xy 102.83366 -282.211369)
			(xy 102.528642 -282.211369) (xy 102.520823 -282.260732) (xy 102.505379 -282.308264) (xy 102.482689 -282.352796)
			(xy 102.453313 -282.393229) (xy 102.417973 -282.428569) (xy 102.37754 -282.457945) (xy 102.333008 -282.480635)
			(xy 102.285476 -282.496079) (xy 102.236113 -282.503898) (xy 102.186135 -282.503898) (xy 102.136772 -282.496079)
			(xy 102.08924 -282.480635) (xy 102.044708 -282.457945) (xy 102.004275 -282.428569) (xy 101.968935 -282.393229)
			(xy 101.939559 -282.352796) (xy 101.916869 -282.308264) (xy 101.901425 -282.260732) (xy 101.893606 -282.211369)
			(xy 101.588588 -282.211369) (xy 101.580769 -282.260732) (xy 101.565325 -282.308264) (xy 101.542635 -282.352796)
			(xy 101.513259 -282.393229) (xy 101.477919 -282.428569) (xy 101.437486 -282.457945) (xy 101.392954 -282.480635)
			(xy 101.345422 -282.496079) (xy 101.296059 -282.503898) (xy 101.246081 -282.503898) (xy 101.196718 -282.496079)
			(xy 101.149186 -282.480635) (xy 101.104654 -282.457945) (xy 101.064221 -282.428569) (xy 101.028881 -282.393229)
			(xy 100.999505 -282.352796) (xy 100.976815 -282.308264) (xy 100.961371 -282.260732) (xy 100.953552 -282.211369)
			(xy 100.648534 -282.211369) (xy 100.640715 -282.260732) (xy 100.625271 -282.308264) (xy 100.602581 -282.352796)
			(xy 100.573205 -282.393229) (xy 100.537865 -282.428569) (xy 100.497432 -282.457945) (xy 100.4529 -282.480635)
			(xy 100.405368 -282.496079) (xy 100.356005 -282.503898) (xy 100.306027 -282.503898) (xy 100.256664 -282.496079)
			(xy 100.209132 -282.480635) (xy 100.1646 -282.457945) (xy 100.124167 -282.428569) (xy 100.088827 -282.393229)
			(xy 100.059451 -282.352796) (xy 100.036761 -282.308264) (xy 100.021317 -282.260732) (xy 100.013498 -282.211369)
			(xy 99.70848 -282.211369) (xy 99.700661 -282.260732) (xy 99.685217 -282.308264) (xy 99.662527 -282.352796)
			(xy 99.633151 -282.393229) (xy 99.597811 -282.428569) (xy 99.557378 -282.457945) (xy 99.512846 -282.480635)
			(xy 99.465314 -282.496079) (xy 99.415951 -282.503898) (xy 99.365973 -282.503898) (xy 99.31661 -282.496079)
			(xy 99.269078 -282.480635) (xy 99.224546 -282.457945) (xy 99.184113 -282.428569) (xy 99.148773 -282.393229)
			(xy 99.119397 -282.352796) (xy 99.096707 -282.308264) (xy 99.081263 -282.260732) (xy 99.073444 -282.211369)
			(xy 98.76868 -282.211369) (xy 98.760861 -282.260732) (xy 98.745417 -282.308264) (xy 98.722727 -282.352796)
			(xy 98.693351 -282.393229) (xy 98.658011 -282.428569) (xy 98.617578 -282.457945) (xy 98.573046 -282.480635)
			(xy 98.525514 -282.496079) (xy 98.476151 -282.503898) (xy 98.426173 -282.503898) (xy 98.37681 -282.496079)
			(xy 98.329278 -282.480635) (xy 98.284746 -282.457945) (xy 98.244313 -282.428569) (xy 98.208973 -282.393229)
			(xy 98.179597 -282.352796) (xy 98.156907 -282.308264) (xy 98.141463 -282.260732) (xy 98.133644 -282.211369)
			(xy 97.828626 -282.211369) (xy 97.820807 -282.260732) (xy 97.805363 -282.308264) (xy 97.782673 -282.352796)
			(xy 97.753297 -282.393229) (xy 97.717957 -282.428569) (xy 97.677524 -282.457945) (xy 97.632992 -282.480635)
			(xy 97.58546 -282.496079) (xy 97.536097 -282.503898) (xy 97.486119 -282.503898) (xy 97.436756 -282.496079)
			(xy 97.389224 -282.480635) (xy 97.344692 -282.457945) (xy 97.304259 -282.428569) (xy 97.268919 -282.393229)
			(xy 97.239543 -282.352796) (xy 97.216853 -282.308264) (xy 97.201409 -282.260732) (xy 97.19359 -282.211369)
			(xy 96.888572 -282.211369) (xy 96.880753 -282.260732) (xy 96.865309 -282.308264) (xy 96.842619 -282.352796)
			(xy 96.813243 -282.393229) (xy 96.777903 -282.428569) (xy 96.73747 -282.457945) (xy 96.692938 -282.480635)
			(xy 96.645406 -282.496079) (xy 96.596043 -282.503898) (xy 96.546065 -282.503898) (xy 96.496702 -282.496079)
			(xy 96.44917 -282.480635) (xy 96.404638 -282.457945) (xy 96.364205 -282.428569) (xy 96.328865 -282.393229)
			(xy 96.299489 -282.352796) (xy 96.276799 -282.308264) (xy 96.261355 -282.260732) (xy 96.253536 -282.211369)
			(xy 95.946219 -282.211369) (xy 95.94621 -282.211826) (xy 95.938046 -282.26206) (xy 95.92193 -282.310334)
			(xy 95.898279 -282.355397) (xy 95.867706 -282.396083) (xy 95.831002 -282.431338) (xy 95.789118 -282.460248)
			(xy 95.743139 -282.482065) (xy 95.694255 -282.496225) (xy 95.643734 -282.502359) (xy 95.592882 -282.50031)
			(xy 95.543018 -282.49013) (xy 95.495432 -282.472083) (xy 95.451358 -282.446637) (xy 95.411936 -282.41445)
			(xy 95.378188 -282.376356) (xy 95.350987 -282.333342) (xy 95.331039 -282.286522) (xy 95.31886 -282.237108)
			(xy 95.314765 -282.18638) (xy 95.006668 -282.18638) (xy 95.006156 -282.211826) (xy 94.997992 -282.26206)
			(xy 94.981876 -282.310334) (xy 94.958225 -282.355397) (xy 94.927652 -282.396083) (xy 94.890948 -282.431338)
			(xy 94.849064 -282.460248) (xy 94.803085 -282.482065) (xy 94.754201 -282.496225) (xy 94.70368 -282.502359)
			(xy 94.652828 -282.50031) (xy 94.602964 -282.49013) (xy 94.555378 -282.472083) (xy 94.511304 -282.446637)
			(xy 94.471882 -282.41445) (xy 94.438134 -282.376356) (xy 94.410933 -282.333342) (xy 94.390985 -282.286522)
			(xy 94.378806 -282.237108) (xy 94.374711 -282.18638) (xy 94.069154 -282.18638) (xy 94.068664 -282.211369)
			(xy 94.060845 -282.260732) (xy 94.045401 -282.308264) (xy 94.022711 -282.352796) (xy 93.993335 -282.393229)
			(xy 93.957995 -282.428569) (xy 93.917562 -282.457945) (xy 93.87303 -282.480635) (xy 93.825498 -282.496079)
			(xy 93.776135 -282.503898) (xy 93.726157 -282.503898) (xy 93.676794 -282.496079) (xy 93.629262 -282.480635)
			(xy 93.58473 -282.457945) (xy 93.544297 -282.428569) (xy 93.508957 -282.393229) (xy 93.479581 -282.352796)
			(xy 93.456891 -282.308264) (xy 93.441447 -282.260732) (xy 93.433628 -282.211369) (xy 93.126311 -282.211369)
			(xy 93.126302 -282.211826) (xy 93.118138 -282.26206) (xy 93.102022 -282.310334) (xy 93.078371 -282.355397)
			(xy 93.047798 -282.396083) (xy 93.011094 -282.431338) (xy 92.96921 -282.460248) (xy 92.923231 -282.482065)
			(xy 92.874347 -282.496225) (xy 92.823826 -282.502359) (xy 92.772974 -282.50031) (xy 92.72311 -282.49013)
			(xy 92.675524 -282.472083) (xy 92.63145 -282.446637) (xy 92.592028 -282.41445) (xy 92.55828 -282.376356)
			(xy 92.531079 -282.333342) (xy 92.511131 -282.286522) (xy 92.498952 -282.237108) (xy 92.494857 -282.18638)
			(xy 92.189023 -282.18638) (xy 92.189046 -282.18765) (xy 92.189046 -282.192222) (xy 92.188085 -282.217676)
			(xy 92.17906 -282.267804) (xy 92.162157 -282.315852) (xy 92.13781 -282.360589) (xy 92.10664 -282.400873)
			(xy 92.069447 -282.435671) (xy 92.02718 -282.464093) (xy 91.980923 -282.485413) (xy 91.931858 -282.499083)
			(xy 91.906598 -282.502356) (xy 91.88704 -282.504642) (xy 91.861386 -282.533344) (xy 91.861386 -282.996386)
			(xy 92.024703 -282.996386) (xy 92.028798 -282.945658) (xy 92.040977 -282.896244) (xy 92.060925 -282.849424)
			(xy 92.088126 -282.80641) (xy 92.121874 -282.768316) (xy 92.161296 -282.736129) (xy 92.20537 -282.710683)
			(xy 92.252956 -282.692636) (xy 92.30282 -282.682456) (xy 92.353672 -282.680407) (xy 92.404193 -282.686541)
			(xy 92.453077 -282.700701) (xy 92.499056 -282.722518) (xy 92.54094 -282.751428) (xy 92.577644 -282.786683)
			(xy 92.608217 -282.827369) (xy 92.631868 -282.872432) (xy 92.647984 -282.920706) (xy 92.656148 -282.97094)
			(xy 92.65666 -282.996386) (xy 92.656157 -283.021375) (xy 92.963474 -283.021375) (xy 92.963474 -282.971397)
			(xy 92.971293 -282.922034) (xy 92.986737 -282.874502) (xy 93.009427 -282.82997) (xy 93.038803 -282.789537)
			(xy 93.074143 -282.754197) (xy 93.114576 -282.724821) (xy 93.159108 -282.702131) (xy 93.20664 -282.686687)
			(xy 93.256003 -282.678868) (xy 93.305981 -282.678868) (xy 93.355344 -282.686687) (xy 93.402876 -282.702131)
			(xy 93.447408 -282.724821) (xy 93.487841 -282.754197) (xy 93.523181 -282.789537) (xy 93.552557 -282.82997)
			(xy 93.575247 -282.874502) (xy 93.590691 -282.922034) (xy 93.59851 -282.971397) (xy 93.599 -282.996386)
			(xy 93.904811 -282.996386) (xy 93.908906 -282.945658) (xy 93.921085 -282.896244) (xy 93.941033 -282.849424)
			(xy 93.968234 -282.80641) (xy 94.001982 -282.768316) (xy 94.041404 -282.736129) (xy 94.085478 -282.710683)
			(xy 94.133064 -282.692636) (xy 94.182928 -282.682456) (xy 94.23378 -282.680407) (xy 94.284301 -282.686541)
			(xy 94.333185 -282.700701) (xy 94.379164 -282.722518) (xy 94.421048 -282.751428) (xy 94.457752 -282.786683)
			(xy 94.488325 -282.827369) (xy 94.511976 -282.872432) (xy 94.528092 -282.920706) (xy 94.536256 -282.97094)
			(xy 94.536768 -282.996386) (xy 94.536265 -283.021375) (xy 94.843582 -283.021375) (xy 94.843582 -282.971397)
			(xy 94.851401 -282.922034) (xy 94.866845 -282.874502) (xy 94.889535 -282.82997) (xy 94.918911 -282.789537)
			(xy 94.954251 -282.754197) (xy 94.994684 -282.724821) (xy 95.039216 -282.702131) (xy 95.086748 -282.686687)
			(xy 95.136111 -282.678868) (xy 95.186089 -282.678868) (xy 95.235452 -282.686687) (xy 95.282984 -282.702131)
			(xy 95.327516 -282.724821) (xy 95.367949 -282.754197) (xy 95.403289 -282.789537) (xy 95.432665 -282.82997)
			(xy 95.455355 -282.874502) (xy 95.470799 -282.922034) (xy 95.478618 -282.971397) (xy 95.479108 -282.996386)
			(xy 95.784919 -282.996386) (xy 95.789014 -282.945658) (xy 95.801193 -282.896244) (xy 95.821141 -282.849424)
			(xy 95.848342 -282.80641) (xy 95.88209 -282.768316) (xy 95.921512 -282.736129) (xy 95.965586 -282.710683)
			(xy 96.013172 -282.692636) (xy 96.063036 -282.682456) (xy 96.113888 -282.680407) (xy 96.164409 -282.686541)
			(xy 96.213293 -282.700701) (xy 96.259272 -282.722518) (xy 96.301156 -282.751428) (xy 96.33786 -282.786683)
			(xy 96.368433 -282.827369) (xy 96.392084 -282.872432) (xy 96.4082 -282.920706) (xy 96.416364 -282.97094)
			(xy 96.416876 -282.996386) (xy 96.416373 -283.021375) (xy 96.723436 -283.021375) (xy 96.723436 -282.971397)
			(xy 96.731255 -282.922034) (xy 96.746699 -282.874502) (xy 96.769389 -282.82997) (xy 96.798765 -282.789537)
			(xy 96.834105 -282.754197) (xy 96.874538 -282.724821) (xy 96.91907 -282.702131) (xy 96.966602 -282.686687)
			(xy 97.015965 -282.678868) (xy 97.065943 -282.678868) (xy 97.115306 -282.686687) (xy 97.162838 -282.702131)
			(xy 97.20737 -282.724821) (xy 97.247803 -282.754197) (xy 97.283143 -282.789537) (xy 97.312519 -282.82997)
			(xy 97.335209 -282.874502) (xy 97.350653 -282.922034) (xy 97.358472 -282.971397) (xy 97.358962 -282.996386)
			(xy 97.664773 -282.996386) (xy 97.668868 -282.945658) (xy 97.681047 -282.896244) (xy 97.700995 -282.849424)
			(xy 97.728196 -282.80641) (xy 97.761944 -282.768316) (xy 97.801366 -282.736129) (xy 97.84544 -282.710683)
			(xy 97.893026 -282.692636) (xy 97.94289 -282.682456) (xy 97.993742 -282.680407) (xy 98.044263 -282.686541)
			(xy 98.093147 -282.700701) (xy 98.139126 -282.722518) (xy 98.18101 -282.751428) (xy 98.217714 -282.786683)
			(xy 98.248287 -282.827369) (xy 98.271938 -282.872432) (xy 98.288054 -282.920706) (xy 98.296218 -282.97094)
			(xy 98.29673 -282.996386) (xy 98.604827 -282.996386) (xy 98.608922 -282.945658) (xy 98.621101 -282.896244)
			(xy 98.641049 -282.849424) (xy 98.66825 -282.80641) (xy 98.701998 -282.768316) (xy 98.74142 -282.736129)
			(xy 98.785494 -282.710683) (xy 98.83308 -282.692636) (xy 98.882944 -282.682456) (xy 98.933796 -282.680407)
			(xy 98.984317 -282.686541) (xy 99.033201 -282.700701) (xy 99.07918 -282.722518) (xy 99.121064 -282.751428)
			(xy 99.157768 -282.786683) (xy 99.188341 -282.827369) (xy 99.211992 -282.872432) (xy 99.228108 -282.920706)
			(xy 99.236272 -282.97094) (xy 99.236784 -282.996386) (xy 99.236281 -283.021375) (xy 99.543598 -283.021375)
			(xy 99.543598 -282.971397) (xy 99.551417 -282.922034) (xy 99.566861 -282.874502) (xy 99.589551 -282.82997)
			(xy 99.618927 -282.789537) (xy 99.654267 -282.754197) (xy 99.6947 -282.724821) (xy 99.739232 -282.702131)
			(xy 99.786764 -282.686687) (xy 99.836127 -282.678868) (xy 99.886105 -282.678868) (xy 99.935468 -282.686687)
			(xy 99.983 -282.702131) (xy 100.027532 -282.724821) (xy 100.067965 -282.754197) (xy 100.103305 -282.789537)
			(xy 100.132681 -282.82997) (xy 100.155371 -282.874502) (xy 100.170815 -282.922034) (xy 100.178634 -282.971397)
			(xy 100.179124 -282.996386) (xy 100.484935 -282.996386) (xy 100.48903 -282.945658) (xy 100.501209 -282.896244)
			(xy 100.521157 -282.849424) (xy 100.548358 -282.80641) (xy 100.582106 -282.768316) (xy 100.621528 -282.736129)
			(xy 100.665602 -282.710683) (xy 100.713188 -282.692636) (xy 100.763052 -282.682456) (xy 100.813904 -282.680407)
			(xy 100.864425 -282.686541) (xy 100.913309 -282.700701) (xy 100.959288 -282.722518) (xy 101.001172 -282.751428)
			(xy 101.037876 -282.786683) (xy 101.068449 -282.827369) (xy 101.0921 -282.872432) (xy 101.108216 -282.920706)
			(xy 101.11638 -282.97094) (xy 101.116892 -282.996386) (xy 101.424735 -282.996386) (xy 101.42883 -282.945658)
			(xy 101.441009 -282.896244) (xy 101.460957 -282.849424) (xy 101.488158 -282.80641) (xy 101.521906 -282.768316)
			(xy 101.561328 -282.736129) (xy 101.605402 -282.710683) (xy 101.652988 -282.692636) (xy 101.702852 -282.682456)
			(xy 101.753704 -282.680407) (xy 101.804225 -282.686541) (xy 101.853109 -282.700701) (xy 101.899088 -282.722518)
			(xy 101.940972 -282.751428) (xy 101.977676 -282.786683) (xy 102.008249 -282.827369) (xy 102.0319 -282.872432)
			(xy 102.048016 -282.920706) (xy 102.05618 -282.97094) (xy 102.056692 -282.996386) (xy 102.056189 -283.021375)
			(xy 102.363506 -283.021375) (xy 102.363506 -282.971397) (xy 102.371325 -282.922034) (xy 102.386769 -282.874502)
			(xy 102.409459 -282.82997) (xy 102.438835 -282.789537) (xy 102.474175 -282.754197) (xy 102.514608 -282.724821)
			(xy 102.55914 -282.702131) (xy 102.606672 -282.686687) (xy 102.656035 -282.678868) (xy 102.706013 -282.678868)
			(xy 102.755376 -282.686687) (xy 102.802908 -282.702131) (xy 102.84744 -282.724821) (xy 102.887873 -282.754197)
			(xy 102.923213 -282.789537) (xy 102.952589 -282.82997) (xy 102.975279 -282.874502) (xy 102.990723 -282.922034)
			(xy 102.998542 -282.971397) (xy 102.999032 -282.996386) (xy 103.304843 -282.996386) (xy 103.308938 -282.945658)
			(xy 103.321117 -282.896244) (xy 103.341065 -282.849424) (xy 103.368266 -282.80641) (xy 103.402014 -282.768316)
			(xy 103.441436 -282.736129) (xy 103.48551 -282.710683) (xy 103.533096 -282.692636) (xy 103.58296 -282.682456)
			(xy 103.633812 -282.680407) (xy 103.684333 -282.686541) (xy 103.733217 -282.700701) (xy 103.779196 -282.722518)
			(xy 103.82108 -282.751428) (xy 103.857784 -282.786683) (xy 103.888357 -282.827369) (xy 103.912008 -282.872432)
			(xy 103.928124 -282.920706) (xy 103.936288 -282.97094) (xy 103.9368 -282.996386) (xy 104.244897 -282.996386)
			(xy 104.248992 -282.945658) (xy 104.261171 -282.896244) (xy 104.281119 -282.849424) (xy 104.30832 -282.80641)
			(xy 104.342068 -282.768316) (xy 104.38149 -282.736129) (xy 104.425564 -282.710683) (xy 104.47315 -282.692636)
			(xy 104.523014 -282.682456) (xy 104.573866 -282.680407) (xy 104.624387 -282.686541) (xy 104.673271 -282.700701)
			(xy 104.71925 -282.722518) (xy 104.761134 -282.751428) (xy 104.797838 -282.786683) (xy 104.828411 -282.827369)
			(xy 104.852062 -282.872432) (xy 104.868178 -282.920706) (xy 104.876342 -282.97094) (xy 104.876854 -282.996386)
			(xy 104.876351 -283.021375) (xy 105.183414 -283.021375) (xy 105.183414 -282.971397) (xy 105.191233 -282.922034)
			(xy 105.206677 -282.874502) (xy 105.229367 -282.82997) (xy 105.258743 -282.789537) (xy 105.294083 -282.754197)
			(xy 105.334516 -282.724821) (xy 105.379048 -282.702131) (xy 105.42658 -282.686687) (xy 105.475943 -282.678868)
			(xy 105.525921 -282.678868) (xy 105.575284 -282.686687) (xy 105.622816 -282.702131) (xy 105.667348 -282.724821)
			(xy 105.707781 -282.754197) (xy 105.743121 -282.789537) (xy 105.772497 -282.82997) (xy 105.795187 -282.874502)
			(xy 105.810631 -282.922034) (xy 105.81845 -282.971397) (xy 105.81894 -282.996386) (xy 106.124751 -282.996386)
			(xy 106.128846 -282.945658) (xy 106.141025 -282.896244) (xy 106.160973 -282.849424) (xy 106.188174 -282.80641)
			(xy 106.221922 -282.768316) (xy 106.261344 -282.736129) (xy 106.305418 -282.710683) (xy 106.353004 -282.692636)
			(xy 106.402868 -282.682456) (xy 106.45372 -282.680407) (xy 106.504241 -282.686541) (xy 106.553125 -282.700701)
			(xy 106.599104 -282.722518) (xy 106.640988 -282.751428) (xy 106.677692 -282.786683) (xy 106.708265 -282.827369)
			(xy 106.731916 -282.872432) (xy 106.748032 -282.920706) (xy 106.756196 -282.97094) (xy 106.756708 -282.996386)
			(xy 107.064805 -282.996386) (xy 107.0689 -282.945658) (xy 107.081079 -282.896244) (xy 107.101027 -282.849424)
			(xy 107.128228 -282.80641) (xy 107.161976 -282.768316) (xy 107.201398 -282.736129) (xy 107.245472 -282.710683)
			(xy 107.293058 -282.692636) (xy 107.342922 -282.682456) (xy 107.393774 -282.680407) (xy 107.444295 -282.686541)
			(xy 107.493179 -282.700701) (xy 107.539158 -282.722518) (xy 107.581042 -282.751428) (xy 107.617746 -282.786683)
			(xy 107.648319 -282.827369) (xy 107.67197 -282.872432) (xy 107.688086 -282.920706) (xy 107.69625 -282.97094)
			(xy 107.696762 -282.996386) (xy 107.696259 -283.021375) (xy 108.003576 -283.021375) (xy 108.003576 -282.971397)
			(xy 108.011395 -282.922034) (xy 108.026839 -282.874502) (xy 108.049529 -282.82997) (xy 108.078905 -282.789537)
			(xy 108.114245 -282.754197) (xy 108.154678 -282.724821) (xy 108.19921 -282.702131) (xy 108.246742 -282.686687)
			(xy 108.296105 -282.678868) (xy 108.346083 -282.678868) (xy 108.395446 -282.686687) (xy 108.442978 -282.702131)
			(xy 108.48751 -282.724821) (xy 108.527943 -282.754197) (xy 108.563283 -282.789537) (xy 108.592659 -282.82997)
			(xy 108.615349 -282.874502) (xy 108.630793 -282.922034) (xy 108.638612 -282.971397) (xy 108.639102 -282.996386)
			(xy 108.638612 -283.021375) (xy 115.51715 -283.021375) (xy 115.51715 -282.971397) (xy 115.524969 -282.922034)
			(xy 115.540413 -282.874502) (xy 115.563103 -282.82997) (xy 115.592479 -282.789537) (xy 115.627819 -282.754197)
			(xy 115.668252 -282.724821) (xy 115.712784 -282.702131) (xy 115.760316 -282.686687) (xy 115.809679 -282.678868)
			(xy 115.859657 -282.678868) (xy 115.90902 -282.686687) (xy 115.956552 -282.702131) (xy 116.001084 -282.724821)
			(xy 116.041517 -282.754197) (xy 116.076857 -282.789537) (xy 116.106233 -282.82997) (xy 116.128923 -282.874502)
			(xy 116.144367 -282.922034) (xy 116.152186 -282.971397) (xy 116.152676 -282.996386) (xy 116.458487 -282.996386)
			(xy 116.462582 -282.945658) (xy 116.474761 -282.896244) (xy 116.494709 -282.849424) (xy 116.52191 -282.80641)
			(xy 116.555658 -282.768316) (xy 116.59508 -282.736129) (xy 116.639154 -282.710683) (xy 116.68674 -282.692636)
			(xy 116.736604 -282.682456) (xy 116.787456 -282.680407) (xy 116.837977 -282.686541) (xy 116.886861 -282.700701)
			(xy 116.93284 -282.722518) (xy 116.974724 -282.751428) (xy 117.011428 -282.786683) (xy 117.042001 -282.827369)
			(xy 117.065652 -282.872432) (xy 117.081768 -282.920706) (xy 117.089932 -282.97094) (xy 117.090444 -282.996386)
			(xy 117.398541 -282.996386) (xy 117.402636 -282.945658) (xy 117.414815 -282.896244) (xy 117.434763 -282.849424)
			(xy 117.461964 -282.80641) (xy 117.495712 -282.768316) (xy 117.535134 -282.736129) (xy 117.579208 -282.710683)
			(xy 117.626794 -282.692636) (xy 117.676658 -282.682456) (xy 117.72751 -282.680407) (xy 117.778031 -282.686541)
			(xy 117.826915 -282.700701) (xy 117.872894 -282.722518) (xy 117.914778 -282.751428) (xy 117.951482 -282.786683)
			(xy 117.982055 -282.827369) (xy 118.005706 -282.872432) (xy 118.021822 -282.920706) (xy 118.029986 -282.97094)
			(xy 118.030498 -282.996386) (xy 118.029995 -283.021375) (xy 118.337312 -283.021375) (xy 118.337312 -282.971397)
			(xy 118.345131 -282.922034) (xy 118.360575 -282.874502) (xy 118.383265 -282.82997) (xy 118.412641 -282.789537)
			(xy 118.447981 -282.754197) (xy 118.488414 -282.724821) (xy 118.532946 -282.702131) (xy 118.580478 -282.686687)
			(xy 118.629841 -282.678868) (xy 118.679819 -282.678868) (xy 118.729182 -282.686687) (xy 118.776714 -282.702131)
			(xy 118.821246 -282.724821) (xy 118.861679 -282.754197) (xy 118.897019 -282.789537) (xy 118.926395 -282.82997)
			(xy 118.949085 -282.874502) (xy 118.964529 -282.922034) (xy 118.972348 -282.971397) (xy 118.972838 -282.996386)
			(xy 119.278395 -282.996386) (xy 119.28249 -282.945658) (xy 119.294669 -282.896244) (xy 119.314617 -282.849424)
			(xy 119.341818 -282.80641) (xy 119.375566 -282.768316) (xy 119.414988 -282.736129) (xy 119.459062 -282.710683)
			(xy 119.506648 -282.692636) (xy 119.556512 -282.682456) (xy 119.607364 -282.680407) (xy 119.657885 -282.686541)
			(xy 119.706769 -282.700701) (xy 119.752748 -282.722518) (xy 119.794632 -282.751428) (xy 119.831336 -282.786683)
			(xy 119.861909 -282.827369) (xy 119.88556 -282.872432) (xy 119.901676 -282.920706) (xy 119.90984 -282.97094)
			(xy 119.910352 -282.996386) (xy 120.218449 -282.996386) (xy 120.222544 -282.945658) (xy 120.234723 -282.896244)
			(xy 120.254671 -282.849424) (xy 120.281872 -282.80641) (xy 120.31562 -282.768316) (xy 120.355042 -282.736129)
			(xy 120.399116 -282.710683) (xy 120.446702 -282.692636) (xy 120.496566 -282.682456) (xy 120.547418 -282.680407)
			(xy 120.597939 -282.686541) (xy 120.646823 -282.700701) (xy 120.692802 -282.722518) (xy 120.734686 -282.751428)
			(xy 120.77139 -282.786683) (xy 120.801963 -282.827369) (xy 120.825614 -282.872432) (xy 120.84173 -282.920706)
			(xy 120.849894 -282.97094) (xy 120.850406 -282.996386) (xy 120.849903 -283.021375) (xy 121.15722 -283.021375)
			(xy 121.15722 -282.971397) (xy 121.165039 -282.922034) (xy 121.180483 -282.874502) (xy 121.203173 -282.82997)
			(xy 121.232549 -282.789537) (xy 121.267889 -282.754197) (xy 121.308322 -282.724821) (xy 121.352854 -282.702131)
			(xy 121.400386 -282.686687) (xy 121.449749 -282.678868) (xy 121.499727 -282.678868) (xy 121.54909 -282.686687)
			(xy 121.596622 -282.702131) (xy 121.641154 -282.724821) (xy 121.681587 -282.754197) (xy 121.716927 -282.789537)
			(xy 121.746303 -282.82997) (xy 121.768993 -282.874502) (xy 121.784437 -282.922034) (xy 121.792256 -282.971397)
			(xy 121.792746 -282.996386) (xy 122.098557 -282.996386) (xy 122.102652 -282.945658) (xy 122.114831 -282.896244)
			(xy 122.134779 -282.849424) (xy 122.16198 -282.80641) (xy 122.195728 -282.768316) (xy 122.23515 -282.736129)
			(xy 122.279224 -282.710683) (xy 122.32681 -282.692636) (xy 122.376674 -282.682456) (xy 122.427526 -282.680407)
			(xy 122.478047 -282.686541) (xy 122.526931 -282.700701) (xy 122.57291 -282.722518) (xy 122.614794 -282.751428)
			(xy 122.651498 -282.786683) (xy 122.682071 -282.827369) (xy 122.705722 -282.872432) (xy 122.721838 -282.920706)
			(xy 122.730002 -282.97094) (xy 122.730514 -282.996386) (xy 123.038611 -282.996386) (xy 123.042706 -282.945658)
			(xy 123.054885 -282.896244) (xy 123.074833 -282.849424) (xy 123.102034 -282.80641) (xy 123.135782 -282.768316)
			(xy 123.175204 -282.736129) (xy 123.219278 -282.710683) (xy 123.266864 -282.692636) (xy 123.316728 -282.682456)
			(xy 123.36758 -282.680407) (xy 123.418101 -282.686541) (xy 123.466985 -282.700701) (xy 123.512964 -282.722518)
			(xy 123.554848 -282.751428) (xy 123.591552 -282.786683) (xy 123.622125 -282.827369) (xy 123.645776 -282.872432)
			(xy 123.661892 -282.920706) (xy 123.670056 -282.97094) (xy 123.670568 -282.996386) (xy 123.670065 -283.021375)
			(xy 123.977128 -283.021375) (xy 123.977128 -282.971397) (xy 123.984947 -282.922034) (xy 124.000391 -282.874502)
			(xy 124.023081 -282.82997) (xy 124.052457 -282.789537) (xy 124.087797 -282.754197) (xy 124.12823 -282.724821)
			(xy 124.172762 -282.702131) (xy 124.220294 -282.686687) (xy 124.269657 -282.678868) (xy 124.319635 -282.678868)
			(xy 124.368998 -282.686687) (xy 124.41653 -282.702131) (xy 124.461062 -282.724821) (xy 124.501495 -282.754197)
			(xy 124.536835 -282.789537) (xy 124.566211 -282.82997) (xy 124.588901 -282.874502) (xy 124.604345 -282.922034)
			(xy 124.612164 -282.971397) (xy 124.612654 -282.996386) (xy 124.918465 -282.996386) (xy 124.92256 -282.945658)
			(xy 124.934739 -282.896244) (xy 124.954687 -282.849424) (xy 124.981888 -282.80641) (xy 125.015636 -282.768316)
			(xy 125.055058 -282.736129) (xy 125.099132 -282.710683) (xy 125.146718 -282.692636) (xy 125.196582 -282.682456)
			(xy 125.247434 -282.680407) (xy 125.297955 -282.686541) (xy 125.346839 -282.700701) (xy 125.392818 -282.722518)
			(xy 125.434702 -282.751428) (xy 125.471406 -282.786683) (xy 125.501979 -282.827369) (xy 125.52563 -282.872432)
			(xy 125.541746 -282.920706) (xy 125.54991 -282.97094) (xy 125.550422 -282.996386) (xy 125.54991 -283.021832)
			(xy 125.541746 -283.072066) (xy 125.52563 -283.12034) (xy 125.501979 -283.165403) (xy 125.471406 -283.206089)
			(xy 125.434702 -283.241344) (xy 125.392818 -283.270254) (xy 125.346839 -283.292071) (xy 125.297955 -283.306231)
			(xy 125.247434 -283.312365) (xy 125.196582 -283.310316) (xy 125.146718 -283.300136) (xy 125.099132 -283.282089)
			(xy 125.055058 -283.256643) (xy 125.015636 -283.224456) (xy 124.981888 -283.186362) (xy 124.954687 -283.143348)
			(xy 124.934739 -283.096528) (xy 124.92256 -283.047114) (xy 124.918465 -282.996386) (xy 124.612654 -282.996386)
			(xy 124.612164 -283.021375) (xy 124.604345 -283.070738) (xy 124.588901 -283.11827) (xy 124.566211 -283.162802)
			(xy 124.536835 -283.203235) (xy 124.501495 -283.238575) (xy 124.461062 -283.267951) (xy 124.41653 -283.290641)
			(xy 124.368998 -283.306085) (xy 124.319635 -283.313904) (xy 124.269657 -283.313904) (xy 124.220294 -283.306085)
			(xy 124.172762 -283.290641) (xy 124.12823 -283.267951) (xy 124.087797 -283.238575) (xy 124.052457 -283.203235)
			(xy 124.023081 -283.162802) (xy 124.000391 -283.11827) (xy 123.984947 -283.070738) (xy 123.977128 -283.021375)
			(xy 123.670065 -283.021375) (xy 123.670056 -283.021832) (xy 123.661892 -283.072066) (xy 123.645776 -283.12034)
			(xy 123.622125 -283.165403) (xy 123.591552 -283.206089) (xy 123.554848 -283.241344) (xy 123.512964 -283.270254)
			(xy 123.466985 -283.292071) (xy 123.418101 -283.306231) (xy 123.36758 -283.312365) (xy 123.316728 -283.310316)
			(xy 123.266864 -283.300136) (xy 123.219278 -283.282089) (xy 123.175204 -283.256643) (xy 123.135782 -283.224456)
			(xy 123.102034 -283.186362) (xy 123.074833 -283.143348) (xy 123.054885 -283.096528) (xy 123.042706 -283.047114)
			(xy 123.038611 -282.996386) (xy 122.730514 -282.996386) (xy 122.730002 -283.021832) (xy 122.721838 -283.072066)
			(xy 122.705722 -283.12034) (xy 122.682071 -283.165403) (xy 122.651498 -283.206089) (xy 122.614794 -283.241344)
			(xy 122.57291 -283.270254) (xy 122.526931 -283.292071) (xy 122.478047 -283.306231) (xy 122.427526 -283.312365)
			(xy 122.376674 -283.310316) (xy 122.32681 -283.300136) (xy 122.279224 -283.282089) (xy 122.23515 -283.256643)
			(xy 122.195728 -283.224456) (xy 122.16198 -283.186362) (xy 122.134779 -283.143348) (xy 122.114831 -283.096528)
			(xy 122.102652 -283.047114) (xy 122.098557 -282.996386) (xy 121.792746 -282.996386) (xy 121.792256 -283.021375)
			(xy 121.784437 -283.070738) (xy 121.768993 -283.11827) (xy 121.746303 -283.162802) (xy 121.716927 -283.203235)
			(xy 121.681587 -283.238575) (xy 121.641154 -283.267951) (xy 121.596622 -283.290641) (xy 121.54909 -283.306085)
			(xy 121.499727 -283.313904) (xy 121.449749 -283.313904) (xy 121.400386 -283.306085) (xy 121.352854 -283.290641)
			(xy 121.308322 -283.267951) (xy 121.267889 -283.238575) (xy 121.232549 -283.203235) (xy 121.203173 -283.162802)
			(xy 121.180483 -283.11827) (xy 121.165039 -283.070738) (xy 121.15722 -283.021375) (xy 120.849903 -283.021375)
			(xy 120.849894 -283.021832) (xy 120.84173 -283.072066) (xy 120.825614 -283.12034) (xy 120.801963 -283.165403)
			(xy 120.77139 -283.206089) (xy 120.734686 -283.241344) (xy 120.692802 -283.270254) (xy 120.646823 -283.292071)
			(xy 120.597939 -283.306231) (xy 120.547418 -283.312365) (xy 120.496566 -283.310316) (xy 120.446702 -283.300136)
			(xy 120.399116 -283.282089) (xy 120.355042 -283.256643) (xy 120.31562 -283.224456) (xy 120.281872 -283.186362)
			(xy 120.254671 -283.143348) (xy 120.234723 -283.096528) (xy 120.222544 -283.047114) (xy 120.218449 -282.996386)
			(xy 119.910352 -282.996386) (xy 119.90984 -283.021832) (xy 119.901676 -283.072066) (xy 119.88556 -283.12034)
			(xy 119.861909 -283.165403) (xy 119.831336 -283.206089) (xy 119.794632 -283.241344) (xy 119.752748 -283.270254)
			(xy 119.706769 -283.292071) (xy 119.657885 -283.306231) (xy 119.607364 -283.312365) (xy 119.556512 -283.310316)
			(xy 119.506648 -283.300136) (xy 119.459062 -283.282089) (xy 119.414988 -283.256643) (xy 119.375566 -283.224456)
			(xy 119.341818 -283.186362) (xy 119.314617 -283.143348) (xy 119.294669 -283.096528) (xy 119.28249 -283.047114)
			(xy 119.278395 -282.996386) (xy 118.972838 -282.996386) (xy 118.972348 -283.021375) (xy 118.964529 -283.070738)
			(xy 118.949085 -283.11827) (xy 118.926395 -283.162802) (xy 118.897019 -283.203235) (xy 118.861679 -283.238575)
			(xy 118.821246 -283.267951) (xy 118.776714 -283.290641) (xy 118.729182 -283.306085) (xy 118.679819 -283.313904)
			(xy 118.629841 -283.313904) (xy 118.580478 -283.306085) (xy 118.532946 -283.290641) (xy 118.488414 -283.267951)
			(xy 118.447981 -283.238575) (xy 118.412641 -283.203235) (xy 118.383265 -283.162802) (xy 118.360575 -283.11827)
			(xy 118.345131 -283.070738) (xy 118.337312 -283.021375) (xy 118.029995 -283.021375) (xy 118.029986 -283.021832)
			(xy 118.021822 -283.072066) (xy 118.005706 -283.12034) (xy 117.982055 -283.165403) (xy 117.951482 -283.206089)
			(xy 117.914778 -283.241344) (xy 117.872894 -283.270254) (xy 117.826915 -283.292071) (xy 117.778031 -283.306231)
			(xy 117.72751 -283.312365) (xy 117.676658 -283.310316) (xy 117.626794 -283.300136) (xy 117.579208 -283.282089)
			(xy 117.535134 -283.256643) (xy 117.495712 -283.224456) (xy 117.461964 -283.186362) (xy 117.434763 -283.143348)
			(xy 117.414815 -283.096528) (xy 117.402636 -283.047114) (xy 117.398541 -282.996386) (xy 117.090444 -282.996386)
			(xy 117.089932 -283.021832) (xy 117.081768 -283.072066) (xy 117.065652 -283.12034) (xy 117.042001 -283.165403)
			(xy 117.011428 -283.206089) (xy 116.974724 -283.241344) (xy 116.93284 -283.270254) (xy 116.886861 -283.292071)
			(xy 116.837977 -283.306231) (xy 116.787456 -283.312365) (xy 116.736604 -283.310316) (xy 116.68674 -283.300136)
			(xy 116.639154 -283.282089) (xy 116.59508 -283.256643) (xy 116.555658 -283.224456) (xy 116.52191 -283.186362)
			(xy 116.494709 -283.143348) (xy 116.474761 -283.096528) (xy 116.462582 -283.047114) (xy 116.458487 -282.996386)
			(xy 116.152676 -282.996386) (xy 116.152186 -283.021375) (xy 116.144367 -283.070738) (xy 116.128923 -283.11827)
			(xy 116.106233 -283.162802) (xy 116.076857 -283.203235) (xy 116.041517 -283.238575) (xy 116.001084 -283.267951)
			(xy 115.956552 -283.290641) (xy 115.90902 -283.306085) (xy 115.859657 -283.313904) (xy 115.809679 -283.313904)
			(xy 115.760316 -283.306085) (xy 115.712784 -283.290641) (xy 115.668252 -283.267951) (xy 115.627819 -283.238575)
			(xy 115.592479 -283.203235) (xy 115.563103 -283.162802) (xy 115.540413 -283.11827) (xy 115.524969 -283.070738)
			(xy 115.51715 -283.021375) (xy 108.638612 -283.021375) (xy 108.630793 -283.070738) (xy 108.615349 -283.11827)
			(xy 108.592659 -283.162802) (xy 108.563283 -283.203235) (xy 108.527943 -283.238575) (xy 108.48751 -283.267951)
			(xy 108.442978 -283.290641) (xy 108.395446 -283.306085) (xy 108.346083 -283.313904) (xy 108.296105 -283.313904)
			(xy 108.246742 -283.306085) (xy 108.19921 -283.290641) (xy 108.154678 -283.267951) (xy 108.114245 -283.238575)
			(xy 108.078905 -283.203235) (xy 108.049529 -283.162802) (xy 108.026839 -283.11827) (xy 108.011395 -283.070738)
			(xy 108.003576 -283.021375) (xy 107.696259 -283.021375) (xy 107.69625 -283.021832) (xy 107.688086 -283.072066)
			(xy 107.67197 -283.12034) (xy 107.648319 -283.165403) (xy 107.617746 -283.206089) (xy 107.581042 -283.241344)
			(xy 107.539158 -283.270254) (xy 107.493179 -283.292071) (xy 107.444295 -283.306231) (xy 107.393774 -283.312365)
			(xy 107.342922 -283.310316) (xy 107.293058 -283.300136) (xy 107.245472 -283.282089) (xy 107.201398 -283.256643)
			(xy 107.161976 -283.224456) (xy 107.128228 -283.186362) (xy 107.101027 -283.143348) (xy 107.081079 -283.096528)
			(xy 107.0689 -283.047114) (xy 107.064805 -282.996386) (xy 106.756708 -282.996386) (xy 106.756196 -283.021832)
			(xy 106.748032 -283.072066) (xy 106.731916 -283.12034) (xy 106.708265 -283.165403) (xy 106.677692 -283.206089)
			(xy 106.640988 -283.241344) (xy 106.599104 -283.270254) (xy 106.553125 -283.292071) (xy 106.504241 -283.306231)
			(xy 106.45372 -283.312365) (xy 106.402868 -283.310316) (xy 106.353004 -283.300136) (xy 106.305418 -283.282089)
			(xy 106.261344 -283.256643) (xy 106.221922 -283.224456) (xy 106.188174 -283.186362) (xy 106.160973 -283.143348)
			(xy 106.141025 -283.096528) (xy 106.128846 -283.047114) (xy 106.124751 -282.996386) (xy 105.81894 -282.996386)
			(xy 105.81845 -283.021375) (xy 105.810631 -283.070738) (xy 105.795187 -283.11827) (xy 105.772497 -283.162802)
			(xy 105.743121 -283.203235) (xy 105.707781 -283.238575) (xy 105.667348 -283.267951) (xy 105.622816 -283.290641)
			(xy 105.575284 -283.306085) (xy 105.525921 -283.313904) (xy 105.475943 -283.313904) (xy 105.42658 -283.306085)
			(xy 105.379048 -283.290641) (xy 105.334516 -283.267951) (xy 105.294083 -283.238575) (xy 105.258743 -283.203235)
			(xy 105.229367 -283.162802) (xy 105.206677 -283.11827) (xy 105.191233 -283.070738) (xy 105.183414 -283.021375)
			(xy 104.876351 -283.021375) (xy 104.876342 -283.021832) (xy 104.868178 -283.072066) (xy 104.852062 -283.12034)
			(xy 104.828411 -283.165403) (xy 104.797838 -283.206089) (xy 104.761134 -283.241344) (xy 104.71925 -283.270254)
			(xy 104.673271 -283.292071) (xy 104.624387 -283.306231) (xy 104.573866 -283.312365) (xy 104.523014 -283.310316)
			(xy 104.47315 -283.300136) (xy 104.425564 -283.282089) (xy 104.38149 -283.256643) (xy 104.342068 -283.224456)
			(xy 104.30832 -283.186362) (xy 104.281119 -283.143348) (xy 104.261171 -283.096528) (xy 104.248992 -283.047114)
			(xy 104.244897 -282.996386) (xy 103.9368 -282.996386) (xy 103.936288 -283.021832) (xy 103.928124 -283.072066)
			(xy 103.912008 -283.12034) (xy 103.888357 -283.165403) (xy 103.857784 -283.206089) (xy 103.82108 -283.241344)
			(xy 103.779196 -283.270254) (xy 103.733217 -283.292071) (xy 103.684333 -283.306231) (xy 103.633812 -283.312365)
			(xy 103.58296 -283.310316) (xy 103.533096 -283.300136) (xy 103.48551 -283.282089) (xy 103.441436 -283.256643)
			(xy 103.402014 -283.224456) (xy 103.368266 -283.186362) (xy 103.341065 -283.143348) (xy 103.321117 -283.096528)
			(xy 103.308938 -283.047114) (xy 103.304843 -282.996386) (xy 102.999032 -282.996386) (xy 102.998542 -283.021375)
			(xy 102.990723 -283.070738) (xy 102.975279 -283.11827) (xy 102.952589 -283.162802) (xy 102.923213 -283.203235)
			(xy 102.887873 -283.238575) (xy 102.84744 -283.267951) (xy 102.802908 -283.290641) (xy 102.755376 -283.306085)
			(xy 102.706013 -283.313904) (xy 102.656035 -283.313904) (xy 102.606672 -283.306085) (xy 102.55914 -283.290641)
			(xy 102.514608 -283.267951) (xy 102.474175 -283.238575) (xy 102.438835 -283.203235) (xy 102.409459 -283.162802)
			(xy 102.386769 -283.11827) (xy 102.371325 -283.070738) (xy 102.363506 -283.021375) (xy 102.056189 -283.021375)
			(xy 102.05618 -283.021832) (xy 102.048016 -283.072066) (xy 102.0319 -283.12034) (xy 102.008249 -283.165403)
			(xy 101.977676 -283.206089) (xy 101.940972 -283.241344) (xy 101.899088 -283.270254) (xy 101.853109 -283.292071)
			(xy 101.804225 -283.306231) (xy 101.753704 -283.312365) (xy 101.702852 -283.310316) (xy 101.652988 -283.300136)
			(xy 101.605402 -283.282089) (xy 101.561328 -283.256643) (xy 101.521906 -283.224456) (xy 101.488158 -283.186362)
			(xy 101.460957 -283.143348) (xy 101.441009 -283.096528) (xy 101.42883 -283.047114) (xy 101.424735 -282.996386)
			(xy 101.116892 -282.996386) (xy 101.11638 -283.021832) (xy 101.108216 -283.072066) (xy 101.0921 -283.12034)
			(xy 101.068449 -283.165403) (xy 101.037876 -283.206089) (xy 101.001172 -283.241344) (xy 100.959288 -283.270254)
			(xy 100.913309 -283.292071) (xy 100.864425 -283.306231) (xy 100.813904 -283.312365) (xy 100.763052 -283.310316)
			(xy 100.713188 -283.300136) (xy 100.665602 -283.282089) (xy 100.621528 -283.256643) (xy 100.582106 -283.224456)
			(xy 100.548358 -283.186362) (xy 100.521157 -283.143348) (xy 100.501209 -283.096528) (xy 100.48903 -283.047114)
			(xy 100.484935 -282.996386) (xy 100.179124 -282.996386) (xy 100.178634 -283.021375) (xy 100.170815 -283.070738)
			(xy 100.155371 -283.11827) (xy 100.132681 -283.162802) (xy 100.103305 -283.203235) (xy 100.067965 -283.238575)
			(xy 100.027532 -283.267951) (xy 99.983 -283.290641) (xy 99.935468 -283.306085) (xy 99.886105 -283.313904)
			(xy 99.836127 -283.313904) (xy 99.786764 -283.306085) (xy 99.739232 -283.290641) (xy 99.6947 -283.267951)
			(xy 99.654267 -283.238575) (xy 99.618927 -283.203235) (xy 99.589551 -283.162802) (xy 99.566861 -283.11827)
			(xy 99.551417 -283.070738) (xy 99.543598 -283.021375) (xy 99.236281 -283.021375) (xy 99.236272 -283.021832)
			(xy 99.228108 -283.072066) (xy 99.211992 -283.12034) (xy 99.188341 -283.165403) (xy 99.157768 -283.206089)
			(xy 99.121064 -283.241344) (xy 99.07918 -283.270254) (xy 99.033201 -283.292071) (xy 98.984317 -283.306231)
			(xy 98.933796 -283.312365) (xy 98.882944 -283.310316) (xy 98.83308 -283.300136) (xy 98.785494 -283.282089)
			(xy 98.74142 -283.256643) (xy 98.701998 -283.224456) (xy 98.66825 -283.186362) (xy 98.641049 -283.143348)
			(xy 98.621101 -283.096528) (xy 98.608922 -283.047114) (xy 98.604827 -282.996386) (xy 98.29673 -282.996386)
			(xy 98.296218 -283.021832) (xy 98.288054 -283.072066) (xy 98.271938 -283.12034) (xy 98.248287 -283.165403)
			(xy 98.217714 -283.206089) (xy 98.18101 -283.241344) (xy 98.139126 -283.270254) (xy 98.093147 -283.292071)
			(xy 98.044263 -283.306231) (xy 97.993742 -283.312365) (xy 97.94289 -283.310316) (xy 97.893026 -283.300136)
			(xy 97.84544 -283.282089) (xy 97.801366 -283.256643) (xy 97.761944 -283.224456) (xy 97.728196 -283.186362)
			(xy 97.700995 -283.143348) (xy 97.681047 -283.096528) (xy 97.668868 -283.047114) (xy 97.664773 -282.996386)
			(xy 97.358962 -282.996386) (xy 97.358472 -283.021375) (xy 97.350653 -283.070738) (xy 97.335209 -283.11827)
			(xy 97.312519 -283.162802) (xy 97.283143 -283.203235) (xy 97.247803 -283.238575) (xy 97.20737 -283.267951)
			(xy 97.162838 -283.290641) (xy 97.115306 -283.306085) (xy 97.065943 -283.313904) (xy 97.015965 -283.313904)
			(xy 96.966602 -283.306085) (xy 96.91907 -283.290641) (xy 96.874538 -283.267951) (xy 96.834105 -283.238575)
			(xy 96.798765 -283.203235) (xy 96.769389 -283.162802) (xy 96.746699 -283.11827) (xy 96.731255 -283.070738)
			(xy 96.723436 -283.021375) (xy 96.416373 -283.021375) (xy 96.416364 -283.021832) (xy 96.4082 -283.072066)
			(xy 96.392084 -283.12034) (xy 96.368433 -283.165403) (xy 96.33786 -283.206089) (xy 96.301156 -283.241344)
			(xy 96.259272 -283.270254) (xy 96.213293 -283.292071) (xy 96.164409 -283.306231) (xy 96.113888 -283.312365)
			(xy 96.063036 -283.310316) (xy 96.013172 -283.300136) (xy 95.965586 -283.282089) (xy 95.921512 -283.256643)
			(xy 95.88209 -283.224456) (xy 95.848342 -283.186362) (xy 95.821141 -283.143348) (xy 95.801193 -283.096528)
			(xy 95.789014 -283.047114) (xy 95.784919 -282.996386) (xy 95.479108 -282.996386) (xy 95.478618 -283.021375)
			(xy 95.470799 -283.070738) (xy 95.455355 -283.11827) (xy 95.432665 -283.162802) (xy 95.403289 -283.203235)
			(xy 95.367949 -283.238575) (xy 95.327516 -283.267951) (xy 95.282984 -283.290641) (xy 95.235452 -283.306085)
			(xy 95.186089 -283.313904) (xy 95.136111 -283.313904) (xy 95.086748 -283.306085) (xy 95.039216 -283.290641)
			(xy 94.994684 -283.267951) (xy 94.954251 -283.238575) (xy 94.918911 -283.203235) (xy 94.889535 -283.162802)
			(xy 94.866845 -283.11827) (xy 94.851401 -283.070738) (xy 94.843582 -283.021375) (xy 94.536265 -283.021375)
			(xy 94.536256 -283.021832) (xy 94.528092 -283.072066) (xy 94.511976 -283.12034) (xy 94.488325 -283.165403)
			(xy 94.457752 -283.206089) (xy 94.421048 -283.241344) (xy 94.379164 -283.270254) (xy 94.333185 -283.292071)
			(xy 94.284301 -283.306231) (xy 94.23378 -283.312365) (xy 94.182928 -283.310316) (xy 94.133064 -283.300136)
			(xy 94.085478 -283.282089) (xy 94.041404 -283.256643) (xy 94.001982 -283.224456) (xy 93.968234 -283.186362)
			(xy 93.941033 -283.143348) (xy 93.921085 -283.096528) (xy 93.908906 -283.047114) (xy 93.904811 -282.996386)
			(xy 93.599 -282.996386) (xy 93.59851 -283.021375) (xy 93.590691 -283.070738) (xy 93.575247 -283.11827)
			(xy 93.552557 -283.162802) (xy 93.523181 -283.203235) (xy 93.487841 -283.238575) (xy 93.447408 -283.267951)
			(xy 93.402876 -283.290641) (xy 93.355344 -283.306085) (xy 93.305981 -283.313904) (xy 93.256003 -283.313904)
			(xy 93.20664 -283.306085) (xy 93.159108 -283.290641) (xy 93.114576 -283.267951) (xy 93.074143 -283.238575)
			(xy 93.038803 -283.203235) (xy 93.009427 -283.162802) (xy 92.986737 -283.11827) (xy 92.971293 -283.070738)
			(xy 92.963474 -283.021375) (xy 92.656157 -283.021375) (xy 92.656148 -283.021832) (xy 92.647984 -283.072066)
			(xy 92.631868 -283.12034) (xy 92.608217 -283.165403) (xy 92.577644 -283.206089) (xy 92.54094 -283.241344)
			(xy 92.499056 -283.270254) (xy 92.453077 -283.292071) (xy 92.404193 -283.306231) (xy 92.353672 -283.312365)
			(xy 92.30282 -283.310316) (xy 92.252956 -283.300136) (xy 92.20537 -283.282089) (xy 92.161296 -283.256643)
			(xy 92.121874 -283.224456) (xy 92.088126 -283.186362) (xy 92.060925 -283.143348) (xy 92.040977 -283.096528)
			(xy 92.028798 -283.047114) (xy 92.024703 -282.996386) (xy 91.861386 -282.996386) (xy 91.861386 -283.459428)
			(xy 91.88704 -283.48813) (xy 91.906598 -283.490416) (xy 91.932163 -283.4938) (xy 91.981803 -283.507765)
			(xy 92.028538 -283.529558) (xy 92.071145 -283.558606) (xy 92.108506 -283.594148) (xy 92.139642 -283.635253)
			(xy 92.163738 -283.680844) (xy 92.180162 -283.729725) (xy 92.188483 -283.780616) (xy 92.188483 -283.806392)
			(xy 92.494857 -283.806392) (xy 92.498952 -283.755664) (xy 92.511131 -283.70625) (xy 92.531079 -283.65943)
			(xy 92.55828 -283.616416) (xy 92.592028 -283.578322) (xy 92.63145 -283.546135) (xy 92.675524 -283.520689)
			(xy 92.72311 -283.502642) (xy 92.772974 -283.492462) (xy 92.823826 -283.490413) (xy 92.874347 -283.496547)
			(xy 92.923231 -283.510707) (xy 92.96921 -283.532524) (xy 93.011094 -283.561434) (xy 93.047798 -283.596689)
			(xy 93.078371 -283.637375) (xy 93.102022 -283.682438) (xy 93.118138 -283.730712) (xy 93.126302 -283.780946)
			(xy 93.126814 -283.806392) (xy 93.126311 -283.831381) (xy 93.433628 -283.831381) (xy 93.433628 -283.781403)
			(xy 93.441447 -283.73204) (xy 93.456891 -283.684508) (xy 93.479581 -283.639976) (xy 93.508957 -283.599543)
			(xy 93.544297 -283.564203) (xy 93.58473 -283.534827) (xy 93.629262 -283.512137) (xy 93.676794 -283.496693)
			(xy 93.726157 -283.488874) (xy 93.776135 -283.488874) (xy 93.825498 -283.496693) (xy 93.87303 -283.512137)
			(xy 93.917562 -283.534827) (xy 93.957995 -283.564203) (xy 93.993335 -283.599543) (xy 94.022711 -283.639976)
			(xy 94.045401 -283.684508) (xy 94.060845 -283.73204) (xy 94.068664 -283.781403) (xy 94.069154 -283.806392)
			(xy 94.374711 -283.806392) (xy 94.378806 -283.755664) (xy 94.390985 -283.70625) (xy 94.410933 -283.65943)
			(xy 94.438134 -283.616416) (xy 94.471882 -283.578322) (xy 94.511304 -283.546135) (xy 94.555378 -283.520689)
			(xy 94.602964 -283.502642) (xy 94.652828 -283.492462) (xy 94.70368 -283.490413) (xy 94.754201 -283.496547)
			(xy 94.803085 -283.510707) (xy 94.849064 -283.532524) (xy 94.890948 -283.561434) (xy 94.927652 -283.596689)
			(xy 94.958225 -283.637375) (xy 94.981876 -283.682438) (xy 94.997992 -283.730712) (xy 95.006156 -283.780946)
			(xy 95.006668 -283.806392) (xy 95.314765 -283.806392) (xy 95.31886 -283.755664) (xy 95.331039 -283.70625)
			(xy 95.350987 -283.65943) (xy 95.378188 -283.616416) (xy 95.411936 -283.578322) (xy 95.451358 -283.546135)
			(xy 95.495432 -283.520689) (xy 95.543018 -283.502642) (xy 95.592882 -283.492462) (xy 95.643734 -283.490413)
			(xy 95.694255 -283.496547) (xy 95.743139 -283.510707) (xy 95.789118 -283.532524) (xy 95.831002 -283.561434)
			(xy 95.867706 -283.596689) (xy 95.898279 -283.637375) (xy 95.92193 -283.682438) (xy 95.938046 -283.730712)
			(xy 95.94621 -283.780946) (xy 95.946722 -283.806392) (xy 95.946219 -283.831381) (xy 96.253536 -283.831381)
			(xy 96.253536 -283.781403) (xy 96.261355 -283.73204) (xy 96.276799 -283.684508) (xy 96.299489 -283.639976)
			(xy 96.328865 -283.599543) (xy 96.364205 -283.564203) (xy 96.404638 -283.534827) (xy 96.44917 -283.512137)
			(xy 96.496702 -283.496693) (xy 96.546065 -283.488874) (xy 96.596043 -283.488874) (xy 96.645406 -283.496693)
			(xy 96.692938 -283.512137) (xy 96.73747 -283.534827) (xy 96.777903 -283.564203) (xy 96.813243 -283.599543)
			(xy 96.842619 -283.639976) (xy 96.865309 -283.684508) (xy 96.880753 -283.73204) (xy 96.888572 -283.781403)
			(xy 96.889062 -283.806392) (xy 96.888572 -283.831381) (xy 99.073444 -283.831381) (xy 99.073444 -283.781403)
			(xy 99.081263 -283.73204) (xy 99.096707 -283.684508) (xy 99.119397 -283.639976) (xy 99.148773 -283.599543)
			(xy 99.184113 -283.564203) (xy 99.224546 -283.534827) (xy 99.269078 -283.512137) (xy 99.31661 -283.496693)
			(xy 99.365973 -283.488874) (xy 99.415951 -283.488874) (xy 99.465314 -283.496693) (xy 99.512846 -283.512137)
			(xy 99.557378 -283.534827) (xy 99.597811 -283.564203) (xy 99.633151 -283.599543) (xy 99.662527 -283.639976)
			(xy 99.685217 -283.684508) (xy 99.700661 -283.73204) (xy 99.70848 -283.781403) (xy 99.70897 -283.806392)
			(xy 99.70848 -283.831381) (xy 101.893606 -283.831381) (xy 101.893606 -283.781403) (xy 101.901425 -283.73204)
			(xy 101.916869 -283.684508) (xy 101.939559 -283.639976) (xy 101.968935 -283.599543) (xy 102.004275 -283.564203)
			(xy 102.044708 -283.534827) (xy 102.08924 -283.512137) (xy 102.136772 -283.496693) (xy 102.186135 -283.488874)
			(xy 102.236113 -283.488874) (xy 102.285476 -283.496693) (xy 102.333008 -283.512137) (xy 102.37754 -283.534827)
			(xy 102.417973 -283.564203) (xy 102.453313 -283.599543) (xy 102.482689 -283.639976) (xy 102.505379 -283.684508)
			(xy 102.520823 -283.73204) (xy 102.528642 -283.781403) (xy 102.529132 -283.806392) (xy 102.528642 -283.831381)
			(xy 104.713514 -283.831381) (xy 104.713514 -283.781403) (xy 104.721333 -283.73204) (xy 104.736777 -283.684508)
			(xy 104.759467 -283.639976) (xy 104.788843 -283.599543) (xy 104.824183 -283.564203) (xy 104.864616 -283.534827)
			(xy 104.909148 -283.512137) (xy 104.95668 -283.496693) (xy 105.006043 -283.488874) (xy 105.056021 -283.488874)
			(xy 105.105384 -283.496693) (xy 105.152916 -283.512137) (xy 105.197448 -283.534827) (xy 105.237881 -283.564203)
			(xy 105.273221 -283.599543) (xy 105.302597 -283.639976) (xy 105.325287 -283.684508) (xy 105.340731 -283.73204)
			(xy 105.34855 -283.781403) (xy 105.34904 -283.806392) (xy 105.34855 -283.831381) (xy 107.533422 -283.831381)
			(xy 107.533422 -283.781403) (xy 107.541241 -283.73204) (xy 107.556685 -283.684508) (xy 107.579375 -283.639976)
			(xy 107.608751 -283.599543) (xy 107.644091 -283.564203) (xy 107.684524 -283.534827) (xy 107.729056 -283.512137)
			(xy 107.776588 -283.496693) (xy 107.825951 -283.488874) (xy 107.875929 -283.488874) (xy 107.925292 -283.496693)
			(xy 107.972824 -283.512137) (xy 108.017356 -283.534827) (xy 108.057789 -283.564203) (xy 108.093129 -283.599543)
			(xy 108.122505 -283.639976) (xy 108.145195 -283.684508) (xy 108.160639 -283.73204) (xy 108.168458 -283.781403)
			(xy 108.168948 -283.806392) (xy 108.474759 -283.806392) (xy 108.478854 -283.755664) (xy 108.491033 -283.70625)
			(xy 108.510981 -283.65943) (xy 108.538182 -283.616416) (xy 108.57193 -283.578322) (xy 108.611352 -283.546135)
			(xy 108.655426 -283.520689) (xy 108.703012 -283.502642) (xy 108.752876 -283.492462) (xy 108.803728 -283.490413)
			(xy 108.854249 -283.496547) (xy 108.903133 -283.510707) (xy 108.949112 -283.532524) (xy 108.990996 -283.561434)
			(xy 109.0277 -283.596689) (xy 109.058273 -283.637375) (xy 109.081924 -283.682438) (xy 109.09804 -283.730712)
			(xy 109.106204 -283.780946) (xy 109.106716 -283.806392) (xy 109.414813 -283.806392) (xy 109.418908 -283.755664)
			(xy 109.431087 -283.70625) (xy 109.451035 -283.65943) (xy 109.478236 -283.616416) (xy 109.511984 -283.578322)
			(xy 109.551406 -283.546135) (xy 109.59548 -283.520689) (xy 109.643066 -283.502642) (xy 109.69293 -283.492462)
			(xy 109.743782 -283.490413) (xy 109.794303 -283.496547) (xy 109.843187 -283.510707) (xy 109.889166 -283.532524)
			(xy 109.93105 -283.561434) (xy 109.967754 -283.596689) (xy 109.998327 -283.637375) (xy 110.021978 -283.682438)
			(xy 110.038094 -283.730712) (xy 110.046258 -283.780946) (xy 110.04677 -283.806392) (xy 110.046267 -283.831381)
			(xy 110.353584 -283.831381) (xy 110.353584 -283.781403) (xy 110.361403 -283.73204) (xy 110.376847 -283.684508)
			(xy 110.399537 -283.639976) (xy 110.428913 -283.599543) (xy 110.464253 -283.564203) (xy 110.504686 -283.534827)
			(xy 110.549218 -283.512137) (xy 110.59675 -283.496693) (xy 110.646113 -283.488874) (xy 110.696091 -283.488874)
			(xy 110.745454 -283.496693) (xy 110.792986 -283.512137) (xy 110.837518 -283.534827) (xy 110.877951 -283.564203)
			(xy 110.913291 -283.599543) (xy 110.942667 -283.639976) (xy 110.965357 -283.684508) (xy 110.980801 -283.73204)
			(xy 110.98862 -283.781403) (xy 110.98911 -283.806392) (xy 110.98862 -283.831381) (xy 113.167142 -283.831381)
			(xy 113.167142 -283.781403) (xy 113.174961 -283.73204) (xy 113.190405 -283.684508) (xy 113.213095 -283.639976)
			(xy 113.242471 -283.599543) (xy 113.277811 -283.564203) (xy 113.318244 -283.534827) (xy 113.362776 -283.512137)
			(xy 113.410308 -283.496693) (xy 113.459671 -283.488874) (xy 113.509649 -283.488874) (xy 113.559012 -283.496693)
			(xy 113.606544 -283.512137) (xy 113.651076 -283.534827) (xy 113.691509 -283.564203) (xy 113.726849 -283.599543)
			(xy 113.756225 -283.639976) (xy 113.778915 -283.684508) (xy 113.794359 -283.73204) (xy 113.802178 -283.781403)
			(xy 113.802668 -283.806392) (xy 114.108479 -283.806392) (xy 114.112574 -283.755664) (xy 114.124753 -283.70625)
			(xy 114.144701 -283.65943) (xy 114.171902 -283.616416) (xy 114.20565 -283.578322) (xy 114.245072 -283.546135)
			(xy 114.289146 -283.520689) (xy 114.336732 -283.502642) (xy 114.386596 -283.492462) (xy 114.437448 -283.490413)
			(xy 114.487969 -283.496547) (xy 114.536853 -283.510707) (xy 114.582832 -283.532524) (xy 114.624716 -283.561434)
			(xy 114.66142 -283.596689) (xy 114.691993 -283.637375) (xy 114.715644 -283.682438) (xy 114.73176 -283.730712)
			(xy 114.739924 -283.780946) (xy 114.740436 -283.806392) (xy 115.048533 -283.806392) (xy 115.052628 -283.755664)
			(xy 115.064807 -283.70625) (xy 115.084755 -283.65943) (xy 115.111956 -283.616416) (xy 115.145704 -283.578322)
			(xy 115.185126 -283.546135) (xy 115.2292 -283.520689) (xy 115.276786 -283.502642) (xy 115.32665 -283.492462)
			(xy 115.377502 -283.490413) (xy 115.428023 -283.496547) (xy 115.476907 -283.510707) (xy 115.522886 -283.532524)
			(xy 115.56477 -283.561434) (xy 115.601474 -283.596689) (xy 115.632047 -283.637375) (xy 115.655698 -283.682438)
			(xy 115.671814 -283.730712) (xy 115.679978 -283.780946) (xy 115.68049 -283.806392) (xy 115.679987 -283.831381)
			(xy 115.987304 -283.831381) (xy 115.987304 -283.781403) (xy 115.995123 -283.73204) (xy 116.010567 -283.684508)
			(xy 116.033257 -283.639976) (xy 116.062633 -283.599543) (xy 116.097973 -283.564203) (xy 116.138406 -283.534827)
			(xy 116.182938 -283.512137) (xy 116.23047 -283.496693) (xy 116.279833 -283.488874) (xy 116.329811 -283.488874)
			(xy 116.379174 -283.496693) (xy 116.426706 -283.512137) (xy 116.471238 -283.534827) (xy 116.511671 -283.564203)
			(xy 116.547011 -283.599543) (xy 116.576387 -283.639976) (xy 116.599077 -283.684508) (xy 116.614521 -283.73204)
			(xy 116.62234 -283.781403) (xy 116.62283 -283.806392) (xy 116.62234 -283.831381) (xy 118.807212 -283.831381)
			(xy 118.807212 -283.781403) (xy 118.815031 -283.73204) (xy 118.830475 -283.684508) (xy 118.853165 -283.639976)
			(xy 118.882541 -283.599543) (xy 118.917881 -283.564203) (xy 118.958314 -283.534827) (xy 119.002846 -283.512137)
			(xy 119.050378 -283.496693) (xy 119.099741 -283.488874) (xy 119.149719 -283.488874) (xy 119.199082 -283.496693)
			(xy 119.246614 -283.512137) (xy 119.291146 -283.534827) (xy 119.331579 -283.564203) (xy 119.366919 -283.599543)
			(xy 119.396295 -283.639976) (xy 119.418985 -283.684508) (xy 119.434429 -283.73204) (xy 119.442248 -283.781403)
			(xy 119.442738 -283.806392) (xy 119.442248 -283.831381) (xy 121.62712 -283.831381) (xy 121.62712 -283.781403)
			(xy 121.634939 -283.73204) (xy 121.650383 -283.684508) (xy 121.673073 -283.639976) (xy 121.702449 -283.599543)
			(xy 121.737789 -283.564203) (xy 121.778222 -283.534827) (xy 121.822754 -283.512137) (xy 121.870286 -283.496693)
			(xy 121.919649 -283.488874) (xy 121.969627 -283.488874) (xy 122.01899 -283.496693) (xy 122.066522 -283.512137)
			(xy 122.111054 -283.534827) (xy 122.151487 -283.564203) (xy 122.186827 -283.599543) (xy 122.216203 -283.639976)
			(xy 122.238893 -283.684508) (xy 122.254337 -283.73204) (xy 122.262156 -283.781403) (xy 122.262646 -283.806392)
			(xy 122.262156 -283.831381) (xy 124.447282 -283.831381) (xy 124.447282 -283.781403) (xy 124.455101 -283.73204)
			(xy 124.470545 -283.684508) (xy 124.493235 -283.639976) (xy 124.522611 -283.599543) (xy 124.557951 -283.564203)
			(xy 124.598384 -283.534827) (xy 124.642916 -283.512137) (xy 124.690448 -283.496693) (xy 124.739811 -283.488874)
			(xy 124.789789 -283.488874) (xy 124.839152 -283.496693) (xy 124.886684 -283.512137) (xy 124.931216 -283.534827)
			(xy 124.971649 -283.564203) (xy 125.006989 -283.599543) (xy 125.036365 -283.639976) (xy 125.059055 -283.684508)
			(xy 125.074499 -283.73204) (xy 125.082318 -283.781403) (xy 125.082808 -283.806392) (xy 125.082318 -283.831381)
			(xy 125.074499 -283.880744) (xy 125.059055 -283.928276) (xy 125.036365 -283.972808) (xy 125.006989 -284.013241)
			(xy 124.971649 -284.048581) (xy 124.931216 -284.077957) (xy 124.886684 -284.100647) (xy 124.839152 -284.116091)
			(xy 124.789789 -284.12391) (xy 124.739811 -284.12391) (xy 124.690448 -284.116091) (xy 124.642916 -284.100647)
			(xy 124.598384 -284.077957) (xy 124.557951 -284.048581) (xy 124.522611 -284.013241) (xy 124.493235 -283.972808)
			(xy 124.470545 -283.928276) (xy 124.455101 -283.880744) (xy 124.447282 -283.831381) (xy 122.262156 -283.831381)
			(xy 122.254337 -283.880744) (xy 122.238893 -283.928276) (xy 122.216203 -283.972808) (xy 122.186827 -284.013241)
			(xy 122.151487 -284.048581) (xy 122.111054 -284.077957) (xy 122.066522 -284.100647) (xy 122.01899 -284.116091)
			(xy 121.969627 -284.12391) (xy 121.919649 -284.12391) (xy 121.870286 -284.116091) (xy 121.822754 -284.100647)
			(xy 121.778222 -284.077957) (xy 121.737789 -284.048581) (xy 121.702449 -284.013241) (xy 121.673073 -283.972808)
			(xy 121.650383 -283.928276) (xy 121.634939 -283.880744) (xy 121.62712 -283.831381) (xy 119.442248 -283.831381)
			(xy 119.434429 -283.880744) (xy 119.418985 -283.928276) (xy 119.396295 -283.972808) (xy 119.366919 -284.013241)
			(xy 119.331579 -284.048581) (xy 119.291146 -284.077957) (xy 119.246614 -284.100647) (xy 119.199082 -284.116091)
			(xy 119.149719 -284.12391) (xy 119.099741 -284.12391) (xy 119.050378 -284.116091) (xy 119.002846 -284.100647)
			(xy 118.958314 -284.077957) (xy 118.917881 -284.048581) (xy 118.882541 -284.013241) (xy 118.853165 -283.972808)
			(xy 118.830475 -283.928276) (xy 118.815031 -283.880744) (xy 118.807212 -283.831381) (xy 116.62234 -283.831381)
			(xy 116.614521 -283.880744) (xy 116.599077 -283.928276) (xy 116.576387 -283.972808) (xy 116.547011 -284.013241)
			(xy 116.511671 -284.048581) (xy 116.471238 -284.077957) (xy 116.426706 -284.100647) (xy 116.379174 -284.116091)
			(xy 116.329811 -284.12391) (xy 116.279833 -284.12391) (xy 116.23047 -284.116091) (xy 116.182938 -284.100647)
			(xy 116.138406 -284.077957) (xy 116.097973 -284.048581) (xy 116.062633 -284.013241) (xy 116.033257 -283.972808)
			(xy 116.010567 -283.928276) (xy 115.995123 -283.880744) (xy 115.987304 -283.831381) (xy 115.679987 -283.831381)
			(xy 115.679978 -283.831838) (xy 115.671814 -283.882072) (xy 115.655698 -283.930346) (xy 115.632047 -283.975409)
			(xy 115.601474 -284.016095) (xy 115.56477 -284.05135) (xy 115.522886 -284.08026) (xy 115.476907 -284.102077)
			(xy 115.428023 -284.116237) (xy 115.377502 -284.122371) (xy 115.32665 -284.120322) (xy 115.276786 -284.110142)
			(xy 115.2292 -284.092095) (xy 115.185126 -284.066649) (xy 115.145704 -284.034462) (xy 115.111956 -283.996368)
			(xy 115.084755 -283.953354) (xy 115.064807 -283.906534) (xy 115.052628 -283.85712) (xy 115.048533 -283.806392)
			(xy 114.740436 -283.806392) (xy 114.739924 -283.831838) (xy 114.73176 -283.882072) (xy 114.715644 -283.930346)
			(xy 114.691993 -283.975409) (xy 114.66142 -284.016095) (xy 114.624716 -284.05135) (xy 114.582832 -284.08026)
			(xy 114.536853 -284.102077) (xy 114.487969 -284.116237) (xy 114.437448 -284.122371) (xy 114.386596 -284.120322)
			(xy 114.336732 -284.110142) (xy 114.289146 -284.092095) (xy 114.245072 -284.066649) (xy 114.20565 -284.034462)
			(xy 114.171902 -283.996368) (xy 114.144701 -283.953354) (xy 114.124753 -283.906534) (xy 114.112574 -283.85712)
			(xy 114.108479 -283.806392) (xy 113.802668 -283.806392) (xy 113.802178 -283.831381) (xy 113.794359 -283.880744)
			(xy 113.778915 -283.928276) (xy 113.756225 -283.972808) (xy 113.726849 -284.013241) (xy 113.691509 -284.048581)
			(xy 113.651076 -284.077957) (xy 113.606544 -284.100647) (xy 113.559012 -284.116091) (xy 113.509649 -284.12391)
			(xy 113.459671 -284.12391) (xy 113.410308 -284.116091) (xy 113.362776 -284.100647) (xy 113.318244 -284.077957)
			(xy 113.277811 -284.048581) (xy 113.242471 -284.013241) (xy 113.213095 -283.972808) (xy 113.190405 -283.928276)
			(xy 113.174961 -283.880744) (xy 113.167142 -283.831381) (xy 110.98862 -283.831381) (xy 110.980801 -283.880744)
			(xy 110.965357 -283.928276) (xy 110.942667 -283.972808) (xy 110.913291 -284.013241) (xy 110.877951 -284.048581)
			(xy 110.837518 -284.077957) (xy 110.792986 -284.100647) (xy 110.745454 -284.116091) (xy 110.696091 -284.12391)
			(xy 110.646113 -284.12391) (xy 110.59675 -284.116091) (xy 110.549218 -284.100647) (xy 110.504686 -284.077957)
			(xy 110.464253 -284.048581) (xy 110.428913 -284.013241) (xy 110.399537 -283.972808) (xy 110.376847 -283.928276)
			(xy 110.361403 -283.880744) (xy 110.353584 -283.831381) (xy 110.046267 -283.831381) (xy 110.046258 -283.831838)
			(xy 110.038094 -283.882072) (xy 110.021978 -283.930346) (xy 109.998327 -283.975409) (xy 109.967754 -284.016095)
			(xy 109.93105 -284.05135) (xy 109.889166 -284.08026) (xy 109.843187 -284.102077) (xy 109.794303 -284.116237)
			(xy 109.743782 -284.122371) (xy 109.69293 -284.120322) (xy 109.643066 -284.110142) (xy 109.59548 -284.092095)
			(xy 109.551406 -284.066649) (xy 109.511984 -284.034462) (xy 109.478236 -283.996368) (xy 109.451035 -283.953354)
			(xy 109.431087 -283.906534) (xy 109.418908 -283.85712) (xy 109.414813 -283.806392) (xy 109.106716 -283.806392)
			(xy 109.106204 -283.831838) (xy 109.09804 -283.882072) (xy 109.081924 -283.930346) (xy 109.058273 -283.975409)
			(xy 109.0277 -284.016095) (xy 108.990996 -284.05135) (xy 108.949112 -284.08026) (xy 108.903133 -284.102077)
			(xy 108.854249 -284.116237) (xy 108.803728 -284.122371) (xy 108.752876 -284.120322) (xy 108.703012 -284.110142)
			(xy 108.655426 -284.092095) (xy 108.611352 -284.066649) (xy 108.57193 -284.034462) (xy 108.538182 -283.996368)
			(xy 108.510981 -283.953354) (xy 108.491033 -283.906534) (xy 108.478854 -283.85712) (xy 108.474759 -283.806392)
			(xy 108.168948 -283.806392) (xy 108.168458 -283.831381) (xy 108.160639 -283.880744) (xy 108.145195 -283.928276)
			(xy 108.122505 -283.972808) (xy 108.093129 -284.013241) (xy 108.057789 -284.048581) (xy 108.017356 -284.077957)
			(xy 107.972824 -284.100647) (xy 107.925292 -284.116091) (xy 107.875929 -284.12391) (xy 107.825951 -284.12391)
			(xy 107.776588 -284.116091) (xy 107.729056 -284.100647) (xy 107.684524 -284.077957) (xy 107.644091 -284.048581)
			(xy 107.608751 -284.013241) (xy 107.579375 -283.972808) (xy 107.556685 -283.928276) (xy 107.541241 -283.880744)
			(xy 107.533422 -283.831381) (xy 105.34855 -283.831381) (xy 105.340731 -283.880744) (xy 105.325287 -283.928276)
			(xy 105.302597 -283.972808) (xy 105.273221 -284.013241) (xy 105.237881 -284.048581) (xy 105.197448 -284.077957)
			(xy 105.152916 -284.100647) (xy 105.105384 -284.116091) (xy 105.056021 -284.12391) (xy 105.006043 -284.12391)
			(xy 104.95668 -284.116091) (xy 104.909148 -284.100647) (xy 104.864616 -284.077957) (xy 104.824183 -284.048581)
			(xy 104.788843 -284.013241) (xy 104.759467 -283.972808) (xy 104.736777 -283.928276) (xy 104.721333 -283.880744)
			(xy 104.713514 -283.831381) (xy 102.528642 -283.831381) (xy 102.520823 -283.880744) (xy 102.505379 -283.928276)
			(xy 102.482689 -283.972808) (xy 102.453313 -284.013241) (xy 102.417973 -284.048581) (xy 102.37754 -284.077957)
			(xy 102.333008 -284.100647) (xy 102.285476 -284.116091) (xy 102.236113 -284.12391) (xy 102.186135 -284.12391)
			(xy 102.136772 -284.116091) (xy 102.08924 -284.100647) (xy 102.044708 -284.077957) (xy 102.004275 -284.048581)
			(xy 101.968935 -284.013241) (xy 101.939559 -283.972808) (xy 101.916869 -283.928276) (xy 101.901425 -283.880744)
			(xy 101.893606 -283.831381) (xy 99.70848 -283.831381) (xy 99.700661 -283.880744) (xy 99.685217 -283.928276)
			(xy 99.662527 -283.972808) (xy 99.633151 -284.013241) (xy 99.597811 -284.048581) (xy 99.557378 -284.077957)
			(xy 99.512846 -284.100647) (xy 99.465314 -284.116091) (xy 99.415951 -284.12391) (xy 99.365973 -284.12391)
			(xy 99.31661 -284.116091) (xy 99.269078 -284.100647) (xy 99.224546 -284.077957) (xy 99.184113 -284.048581)
			(xy 99.148773 -284.013241) (xy 99.119397 -283.972808) (xy 99.096707 -283.928276) (xy 99.081263 -283.880744)
			(xy 99.073444 -283.831381) (xy 96.888572 -283.831381) (xy 96.880753 -283.880744) (xy 96.865309 -283.928276)
			(xy 96.842619 -283.972808) (xy 96.813243 -284.013241) (xy 96.777903 -284.048581) (xy 96.73747 -284.077957)
			(xy 96.692938 -284.100647) (xy 96.645406 -284.116091) (xy 96.596043 -284.12391) (xy 96.546065 -284.12391)
			(xy 96.496702 -284.116091) (xy 96.44917 -284.100647) (xy 96.404638 -284.077957) (xy 96.364205 -284.048581)
			(xy 96.328865 -284.013241) (xy 96.299489 -283.972808) (xy 96.276799 -283.928276) (xy 96.261355 -283.880744)
			(xy 96.253536 -283.831381) (xy 95.946219 -283.831381) (xy 95.94621 -283.831838) (xy 95.938046 -283.882072)
			(xy 95.92193 -283.930346) (xy 95.898279 -283.975409) (xy 95.867706 -284.016095) (xy 95.831002 -284.05135)
			(xy 95.789118 -284.08026) (xy 95.743139 -284.102077) (xy 95.694255 -284.116237) (xy 95.643734 -284.122371)
			(xy 95.592882 -284.120322) (xy 95.543018 -284.110142) (xy 95.495432 -284.092095) (xy 95.451358 -284.066649)
			(xy 95.411936 -284.034462) (xy 95.378188 -283.996368) (xy 95.350987 -283.953354) (xy 95.331039 -283.906534)
			(xy 95.31886 -283.85712) (xy 95.314765 -283.806392) (xy 95.006668 -283.806392) (xy 95.006156 -283.831838)
			(xy 94.997992 -283.882072) (xy 94.981876 -283.930346) (xy 94.958225 -283.975409) (xy 94.927652 -284.016095)
			(xy 94.890948 -284.05135) (xy 94.849064 -284.08026) (xy 94.803085 -284.102077) (xy 94.754201 -284.116237)
			(xy 94.70368 -284.122371) (xy 94.652828 -284.120322) (xy 94.602964 -284.110142) (xy 94.555378 -284.092095)
			(xy 94.511304 -284.066649) (xy 94.471882 -284.034462) (xy 94.438134 -283.996368) (xy 94.410933 -283.953354)
			(xy 94.390985 -283.906534) (xy 94.378806 -283.85712) (xy 94.374711 -283.806392) (xy 94.069154 -283.806392)
			(xy 94.068664 -283.831381) (xy 94.060845 -283.880744) (xy 94.045401 -283.928276) (xy 94.022711 -283.972808)
			(xy 93.993335 -284.013241) (xy 93.957995 -284.048581) (xy 93.917562 -284.077957) (xy 93.87303 -284.100647)
			(xy 93.825498 -284.116091) (xy 93.776135 -284.12391) (xy 93.726157 -284.12391) (xy 93.676794 -284.116091)
			(xy 93.629262 -284.100647) (xy 93.58473 -284.077957) (xy 93.544297 -284.048581) (xy 93.508957 -284.013241)
			(xy 93.479581 -283.972808) (xy 93.456891 -283.928276) (xy 93.441447 -283.880744) (xy 93.433628 -283.831381)
			(xy 93.126311 -283.831381) (xy 93.126302 -283.831838) (xy 93.118138 -283.882072) (xy 93.102022 -283.930346)
			(xy 93.078371 -283.975409) (xy 93.047798 -284.016095) (xy 93.011094 -284.05135) (xy 92.96921 -284.08026)
			(xy 92.923231 -284.102077) (xy 92.874347 -284.116237) (xy 92.823826 -284.122371) (xy 92.772974 -284.120322)
			(xy 92.72311 -284.110142) (xy 92.675524 -284.092095) (xy 92.63145 -284.066649) (xy 92.592028 -284.034462)
			(xy 92.55828 -283.996368) (xy 92.531079 -283.953354) (xy 92.511131 -283.906534) (xy 92.498952 -283.85712)
			(xy 92.494857 -283.806392) (xy 92.188483 -283.806392) (xy 92.188483 -283.832182) (xy 92.180162 -283.883073)
			(xy 92.163739 -283.931955) (xy 92.139643 -283.977545) (xy 92.108507 -284.018651) (xy 92.071146 -284.054193)
			(xy 92.02854 -284.083242) (xy 91.981804 -284.105034) (xy 91.932165 -284.119) (xy 91.906598 -284.122368)
			(xy 91.88704 -284.124654) (xy 91.861386 -284.153356) (xy 91.861386 -284.616398) (xy 92.024703 -284.616398)
			(xy 92.028798 -284.56567) (xy 92.040977 -284.516256) (xy 92.060925 -284.469436) (xy 92.088126 -284.426422)
			(xy 92.121874 -284.388328) (xy 92.161296 -284.356141) (xy 92.20537 -284.330695) (xy 92.252956 -284.312648)
			(xy 92.30282 -284.302468) (xy 92.353672 -284.300419) (xy 92.404193 -284.306553) (xy 92.453077 -284.320713)
			(xy 92.499056 -284.34253) (xy 92.54094 -284.37144) (xy 92.577644 -284.406695) (xy 92.608217 -284.447381)
			(xy 92.631868 -284.492444) (xy 92.647984 -284.540718) (xy 92.656148 -284.590952) (xy 92.65666 -284.616398)
			(xy 92.656157 -284.641387) (xy 92.963474 -284.641387) (xy 92.963474 -284.591409) (xy 92.971293 -284.542046)
			(xy 92.986737 -284.494514) (xy 93.009427 -284.449982) (xy 93.038803 -284.409549) (xy 93.074143 -284.374209)
			(xy 93.114576 -284.344833) (xy 93.159108 -284.322143) (xy 93.20664 -284.306699) (xy 93.256003 -284.29888)
			(xy 93.305981 -284.29888) (xy 93.355344 -284.306699) (xy 93.402876 -284.322143) (xy 93.447408 -284.344833)
			(xy 93.487841 -284.374209) (xy 93.523181 -284.409549) (xy 93.552557 -284.449982) (xy 93.575247 -284.494514)
			(xy 93.590691 -284.542046) (xy 93.59851 -284.591409) (xy 93.599 -284.616398) (xy 93.904811 -284.616398)
			(xy 93.908906 -284.56567) (xy 93.921085 -284.516256) (xy 93.941033 -284.469436) (xy 93.968234 -284.426422)
			(xy 94.001982 -284.388328) (xy 94.041404 -284.356141) (xy 94.085478 -284.330695) (xy 94.133064 -284.312648)
			(xy 94.182928 -284.302468) (xy 94.23378 -284.300419) (xy 94.284301 -284.306553) (xy 94.333185 -284.320713)
			(xy 94.379164 -284.34253) (xy 94.421048 -284.37144) (xy 94.457752 -284.406695) (xy 94.488325 -284.447381)
			(xy 94.511976 -284.492444) (xy 94.528092 -284.540718) (xy 94.536256 -284.590952) (xy 94.536768 -284.616398)
			(xy 94.536265 -284.641387) (xy 94.843582 -284.641387) (xy 94.843582 -284.591409) (xy 94.851401 -284.542046)
			(xy 94.866845 -284.494514) (xy 94.889535 -284.449982) (xy 94.918911 -284.409549) (xy 94.954251 -284.374209)
			(xy 94.994684 -284.344833) (xy 95.039216 -284.322143) (xy 95.086748 -284.306699) (xy 95.136111 -284.29888)
			(xy 95.186089 -284.29888) (xy 95.235452 -284.306699) (xy 95.282984 -284.322143) (xy 95.327516 -284.344833)
			(xy 95.367949 -284.374209) (xy 95.403289 -284.409549) (xy 95.432665 -284.449982) (xy 95.455355 -284.494514)
			(xy 95.470799 -284.542046) (xy 95.478618 -284.591409) (xy 95.479108 -284.616398) (xy 95.784919 -284.616398)
			(xy 95.789014 -284.56567) (xy 95.801193 -284.516256) (xy 95.821141 -284.469436) (xy 95.848342 -284.426422)
			(xy 95.88209 -284.388328) (xy 95.921512 -284.356141) (xy 95.965586 -284.330695) (xy 96.013172 -284.312648)
			(xy 96.063036 -284.302468) (xy 96.113888 -284.300419) (xy 96.164409 -284.306553) (xy 96.213293 -284.320713)
			(xy 96.259272 -284.34253) (xy 96.301156 -284.37144) (xy 96.33786 -284.406695) (xy 96.368433 -284.447381)
			(xy 96.392084 -284.492444) (xy 96.4082 -284.540718) (xy 96.416364 -284.590952) (xy 96.416876 -284.616398)
			(xy 96.416373 -284.641387) (xy 96.723436 -284.641387) (xy 96.723436 -284.591409) (xy 96.731255 -284.542046)
			(xy 96.746699 -284.494514) (xy 96.769389 -284.449982) (xy 96.798765 -284.409549) (xy 96.834105 -284.374209)
			(xy 96.874538 -284.344833) (xy 96.91907 -284.322143) (xy 96.966602 -284.306699) (xy 97.015965 -284.29888)
			(xy 97.065943 -284.29888) (xy 97.115306 -284.306699) (xy 97.162838 -284.322143) (xy 97.20737 -284.344833)
			(xy 97.247803 -284.374209) (xy 97.283143 -284.409549) (xy 97.312519 -284.449982) (xy 97.335209 -284.494514)
			(xy 97.350653 -284.542046) (xy 97.358472 -284.591409) (xy 97.358962 -284.616398) (xy 97.664773 -284.616398)
			(xy 97.668868 -284.56567) (xy 97.681047 -284.516256) (xy 97.700995 -284.469436) (xy 97.728196 -284.426422)
			(xy 97.761944 -284.388328) (xy 97.801366 -284.356141) (xy 97.84544 -284.330695) (xy 97.893026 -284.312648)
			(xy 97.94289 -284.302468) (xy 97.993742 -284.300419) (xy 98.044263 -284.306553) (xy 98.093147 -284.320713)
			(xy 98.139126 -284.34253) (xy 98.18101 -284.37144) (xy 98.217714 -284.406695) (xy 98.248287 -284.447381)
			(xy 98.271938 -284.492444) (xy 98.288054 -284.540718) (xy 98.296218 -284.590952) (xy 98.29673 -284.616398)
			(xy 98.604827 -284.616398) (xy 98.608922 -284.56567) (xy 98.621101 -284.516256) (xy 98.641049 -284.469436)
			(xy 98.66825 -284.426422) (xy 98.701998 -284.388328) (xy 98.74142 -284.356141) (xy 98.785494 -284.330695)
			(xy 98.83308 -284.312648) (xy 98.882944 -284.302468) (xy 98.933796 -284.300419) (xy 98.984317 -284.306553)
			(xy 99.033201 -284.320713) (xy 99.07918 -284.34253) (xy 99.121064 -284.37144) (xy 99.157768 -284.406695)
			(xy 99.188341 -284.447381) (xy 99.211992 -284.492444) (xy 99.228108 -284.540718) (xy 99.236272 -284.590952)
			(xy 99.236784 -284.616398) (xy 99.236281 -284.641387) (xy 99.543598 -284.641387) (xy 99.543598 -284.591409)
			(xy 99.551417 -284.542046) (xy 99.566861 -284.494514) (xy 99.589551 -284.449982) (xy 99.618927 -284.409549)
			(xy 99.654267 -284.374209) (xy 99.6947 -284.344833) (xy 99.739232 -284.322143) (xy 99.786764 -284.306699)
			(xy 99.836127 -284.29888) (xy 99.886105 -284.29888) (xy 99.935468 -284.306699) (xy 99.983 -284.322143)
			(xy 100.027532 -284.344833) (xy 100.067965 -284.374209) (xy 100.103305 -284.409549) (xy 100.132681 -284.449982)
			(xy 100.155371 -284.494514) (xy 100.170815 -284.542046) (xy 100.178634 -284.591409) (xy 100.179124 -284.616398)
			(xy 100.484935 -284.616398) (xy 100.48903 -284.56567) (xy 100.501209 -284.516256) (xy 100.521157 -284.469436)
			(xy 100.548358 -284.426422) (xy 100.582106 -284.388328) (xy 100.621528 -284.356141) (xy 100.665602 -284.330695)
			(xy 100.713188 -284.312648) (xy 100.763052 -284.302468) (xy 100.813904 -284.300419) (xy 100.864425 -284.306553)
			(xy 100.913309 -284.320713) (xy 100.959288 -284.34253) (xy 101.001172 -284.37144) (xy 101.037876 -284.406695)
			(xy 101.068449 -284.447381) (xy 101.0921 -284.492444) (xy 101.108216 -284.540718) (xy 101.11638 -284.590952)
			(xy 101.116892 -284.616398) (xy 101.424735 -284.616398) (xy 101.42883 -284.56567) (xy 101.441009 -284.516256)
			(xy 101.460957 -284.469436) (xy 101.488158 -284.426422) (xy 101.521906 -284.388328) (xy 101.561328 -284.356141)
			(xy 101.605402 -284.330695) (xy 101.652988 -284.312648) (xy 101.702852 -284.302468) (xy 101.753704 -284.300419)
			(xy 101.804225 -284.306553) (xy 101.853109 -284.320713) (xy 101.899088 -284.34253) (xy 101.940972 -284.37144)
			(xy 101.977676 -284.406695) (xy 102.008249 -284.447381) (xy 102.0319 -284.492444) (xy 102.048016 -284.540718)
			(xy 102.05618 -284.590952) (xy 102.056692 -284.616398) (xy 102.056189 -284.641387) (xy 102.363506 -284.641387)
			(xy 102.363506 -284.591409) (xy 102.371325 -284.542046) (xy 102.386769 -284.494514) (xy 102.409459 -284.449982)
			(xy 102.438835 -284.409549) (xy 102.474175 -284.374209) (xy 102.514608 -284.344833) (xy 102.55914 -284.322143)
			(xy 102.606672 -284.306699) (xy 102.656035 -284.29888) (xy 102.706013 -284.29888) (xy 102.755376 -284.306699)
			(xy 102.802908 -284.322143) (xy 102.84744 -284.344833) (xy 102.887873 -284.374209) (xy 102.923213 -284.409549)
			(xy 102.952589 -284.449982) (xy 102.975279 -284.494514) (xy 102.990723 -284.542046) (xy 102.998542 -284.591409)
			(xy 102.999032 -284.616398) (xy 103.304843 -284.616398) (xy 103.308938 -284.56567) (xy 103.321117 -284.516256)
			(xy 103.341065 -284.469436) (xy 103.368266 -284.426422) (xy 103.402014 -284.388328) (xy 103.441436 -284.356141)
			(xy 103.48551 -284.330695) (xy 103.533096 -284.312648) (xy 103.58296 -284.302468) (xy 103.633812 -284.300419)
			(xy 103.684333 -284.306553) (xy 103.733217 -284.320713) (xy 103.779196 -284.34253) (xy 103.82108 -284.37144)
			(xy 103.857784 -284.406695) (xy 103.888357 -284.447381) (xy 103.912008 -284.492444) (xy 103.928124 -284.540718)
			(xy 103.936288 -284.590952) (xy 103.9368 -284.616398) (xy 104.244897 -284.616398) (xy 104.248992 -284.56567)
			(xy 104.261171 -284.516256) (xy 104.281119 -284.469436) (xy 104.30832 -284.426422) (xy 104.342068 -284.388328)
			(xy 104.38149 -284.356141) (xy 104.425564 -284.330695) (xy 104.47315 -284.312648) (xy 104.523014 -284.302468)
			(xy 104.573866 -284.300419) (xy 104.624387 -284.306553) (xy 104.673271 -284.320713) (xy 104.71925 -284.34253)
			(xy 104.761134 -284.37144) (xy 104.797838 -284.406695) (xy 104.828411 -284.447381) (xy 104.852062 -284.492444)
			(xy 104.868178 -284.540718) (xy 104.876342 -284.590952) (xy 104.876854 -284.616398) (xy 104.876351 -284.641387)
			(xy 105.183414 -284.641387) (xy 105.183414 -284.591409) (xy 105.191233 -284.542046) (xy 105.206677 -284.494514)
			(xy 105.229367 -284.449982) (xy 105.258743 -284.409549) (xy 105.294083 -284.374209) (xy 105.334516 -284.344833)
			(xy 105.379048 -284.322143) (xy 105.42658 -284.306699) (xy 105.475943 -284.29888) (xy 105.525921 -284.29888)
			(xy 105.575284 -284.306699) (xy 105.622816 -284.322143) (xy 105.667348 -284.344833) (xy 105.707781 -284.374209)
			(xy 105.743121 -284.409549) (xy 105.772497 -284.449982) (xy 105.795187 -284.494514) (xy 105.810631 -284.542046)
			(xy 105.81845 -284.591409) (xy 105.81894 -284.616398) (xy 106.124751 -284.616398) (xy 106.128846 -284.56567)
			(xy 106.141025 -284.516256) (xy 106.160973 -284.469436) (xy 106.188174 -284.426422) (xy 106.221922 -284.388328)
			(xy 106.261344 -284.356141) (xy 106.305418 -284.330695) (xy 106.353004 -284.312648) (xy 106.402868 -284.302468)
			(xy 106.45372 -284.300419) (xy 106.504241 -284.306553) (xy 106.553125 -284.320713) (xy 106.599104 -284.34253)
			(xy 106.640988 -284.37144) (xy 106.677692 -284.406695) (xy 106.708265 -284.447381) (xy 106.731916 -284.492444)
			(xy 106.748032 -284.540718) (xy 106.756196 -284.590952) (xy 106.756708 -284.616398) (xy 107.064805 -284.616398)
			(xy 107.0689 -284.56567) (xy 107.081079 -284.516256) (xy 107.101027 -284.469436) (xy 107.128228 -284.426422)
			(xy 107.161976 -284.388328) (xy 107.201398 -284.356141) (xy 107.245472 -284.330695) (xy 107.293058 -284.312648)
			(xy 107.342922 -284.302468) (xy 107.393774 -284.300419) (xy 107.444295 -284.306553) (xy 107.493179 -284.320713)
			(xy 107.539158 -284.34253) (xy 107.581042 -284.37144) (xy 107.617746 -284.406695) (xy 107.648319 -284.447381)
			(xy 107.67197 -284.492444) (xy 107.688086 -284.540718) (xy 107.69625 -284.590952) (xy 107.696762 -284.616398)
			(xy 107.696259 -284.641387) (xy 108.003576 -284.641387) (xy 108.003576 -284.591409) (xy 108.011395 -284.542046)
			(xy 108.026839 -284.494514) (xy 108.049529 -284.449982) (xy 108.078905 -284.409549) (xy 108.114245 -284.374209)
			(xy 108.154678 -284.344833) (xy 108.19921 -284.322143) (xy 108.246742 -284.306699) (xy 108.296105 -284.29888)
			(xy 108.346083 -284.29888) (xy 108.395446 -284.306699) (xy 108.442978 -284.322143) (xy 108.48751 -284.344833)
			(xy 108.527943 -284.374209) (xy 108.563283 -284.409549) (xy 108.592659 -284.449982) (xy 108.615349 -284.494514)
			(xy 108.630793 -284.542046) (xy 108.638612 -284.591409) (xy 108.639102 -284.616398) (xy 108.638612 -284.641387)
			(xy 108.94363 -284.641387) (xy 108.94363 -284.591409) (xy 108.951449 -284.542046) (xy 108.966893 -284.494514)
			(xy 108.989583 -284.449982) (xy 109.018959 -284.409549) (xy 109.054299 -284.374209) (xy 109.094732 -284.344833)
			(xy 109.139264 -284.322143) (xy 109.186796 -284.306699) (xy 109.236159 -284.29888) (xy 109.286137 -284.29888)
			(xy 109.3355 -284.306699) (xy 109.383032 -284.322143) (xy 109.427564 -284.344833) (xy 109.467997 -284.374209)
			(xy 109.503337 -284.409549) (xy 109.532713 -284.449982) (xy 109.555403 -284.494514) (xy 109.570847 -284.542046)
			(xy 109.578666 -284.591409) (xy 109.579156 -284.616398) (xy 109.578666 -284.641387) (xy 109.88343 -284.641387)
			(xy 109.88343 -284.591409) (xy 109.891249 -284.542046) (xy 109.906693 -284.494514) (xy 109.929383 -284.449982)
			(xy 109.958759 -284.409549) (xy 109.994099 -284.374209) (xy 110.034532 -284.344833) (xy 110.079064 -284.322143)
			(xy 110.126596 -284.306699) (xy 110.175959 -284.29888) (xy 110.225937 -284.29888) (xy 110.2753 -284.306699)
			(xy 110.322832 -284.322143) (xy 110.367364 -284.344833) (xy 110.407797 -284.374209) (xy 110.443137 -284.409549)
			(xy 110.472513 -284.449982) (xy 110.495203 -284.494514) (xy 110.510647 -284.542046) (xy 110.518466 -284.591409)
			(xy 110.518956 -284.616398) (xy 110.518466 -284.641387) (xy 113.637296 -284.641387) (xy 113.637296 -284.591409)
			(xy 113.645115 -284.542046) (xy 113.660559 -284.494514) (xy 113.683249 -284.449982) (xy 113.712625 -284.409549)
			(xy 113.747965 -284.374209) (xy 113.788398 -284.344833) (xy 113.83293 -284.322143) (xy 113.880462 -284.306699)
			(xy 113.929825 -284.29888) (xy 113.979803 -284.29888) (xy 114.029166 -284.306699) (xy 114.076698 -284.322143)
			(xy 114.12123 -284.344833) (xy 114.161663 -284.374209) (xy 114.197003 -284.409549) (xy 114.226379 -284.449982)
			(xy 114.249069 -284.494514) (xy 114.264513 -284.542046) (xy 114.272332 -284.591409) (xy 114.272822 -284.616398)
			(xy 114.272332 -284.641387) (xy 114.577096 -284.641387) (xy 114.577096 -284.591409) (xy 114.584915 -284.542046)
			(xy 114.600359 -284.494514) (xy 114.623049 -284.449982) (xy 114.652425 -284.409549) (xy 114.687765 -284.374209)
			(xy 114.728198 -284.344833) (xy 114.77273 -284.322143) (xy 114.820262 -284.306699) (xy 114.869625 -284.29888)
			(xy 114.919603 -284.29888) (xy 114.968966 -284.306699) (xy 115.016498 -284.322143) (xy 115.06103 -284.344833)
			(xy 115.101463 -284.374209) (xy 115.136803 -284.409549) (xy 115.166179 -284.449982) (xy 115.188869 -284.494514)
			(xy 115.204313 -284.542046) (xy 115.212132 -284.591409) (xy 115.212622 -284.616398) (xy 115.212132 -284.641387)
			(xy 115.51715 -284.641387) (xy 115.51715 -284.591409) (xy 115.524969 -284.542046) (xy 115.540413 -284.494514)
			(xy 115.563103 -284.449982) (xy 115.592479 -284.409549) (xy 115.627819 -284.374209) (xy 115.668252 -284.344833)
			(xy 115.712784 -284.322143) (xy 115.760316 -284.306699) (xy 115.809679 -284.29888) (xy 115.859657 -284.29888)
			(xy 115.90902 -284.306699) (xy 115.956552 -284.322143) (xy 116.001084 -284.344833) (xy 116.041517 -284.374209)
			(xy 116.076857 -284.409549) (xy 116.106233 -284.449982) (xy 116.128923 -284.494514) (xy 116.144367 -284.542046)
			(xy 116.152186 -284.591409) (xy 116.152676 -284.616398) (xy 116.458487 -284.616398) (xy 116.462582 -284.56567)
			(xy 116.474761 -284.516256) (xy 116.494709 -284.469436) (xy 116.52191 -284.426422) (xy 116.555658 -284.388328)
			(xy 116.59508 -284.356141) (xy 116.639154 -284.330695) (xy 116.68674 -284.312648) (xy 116.736604 -284.302468)
			(xy 116.787456 -284.300419) (xy 116.837977 -284.306553) (xy 116.886861 -284.320713) (xy 116.93284 -284.34253)
			(xy 116.974724 -284.37144) (xy 117.011428 -284.406695) (xy 117.042001 -284.447381) (xy 117.065652 -284.492444)
			(xy 117.081768 -284.540718) (xy 117.089932 -284.590952) (xy 117.090444 -284.616398) (xy 117.398541 -284.616398)
			(xy 117.402636 -284.56567) (xy 117.414815 -284.516256) (xy 117.434763 -284.469436) (xy 117.461964 -284.426422)
			(xy 117.495712 -284.388328) (xy 117.535134 -284.356141) (xy 117.579208 -284.330695) (xy 117.626794 -284.312648)
			(xy 117.676658 -284.302468) (xy 117.72751 -284.300419) (xy 117.778031 -284.306553) (xy 117.826915 -284.320713)
			(xy 117.872894 -284.34253) (xy 117.914778 -284.37144) (xy 117.951482 -284.406695) (xy 117.982055 -284.447381)
			(xy 118.005706 -284.492444) (xy 118.021822 -284.540718) (xy 118.029986 -284.590952) (xy 118.030498 -284.616398)
			(xy 118.029995 -284.641387) (xy 118.337312 -284.641387) (xy 118.337312 -284.591409) (xy 118.345131 -284.542046)
			(xy 118.360575 -284.494514) (xy 118.383265 -284.449982) (xy 118.412641 -284.409549) (xy 118.447981 -284.374209)
			(xy 118.488414 -284.344833) (xy 118.532946 -284.322143) (xy 118.580478 -284.306699) (xy 118.629841 -284.29888)
			(xy 118.679819 -284.29888) (xy 118.729182 -284.306699) (xy 118.776714 -284.322143) (xy 118.821246 -284.344833)
			(xy 118.861679 -284.374209) (xy 118.897019 -284.409549) (xy 118.926395 -284.449982) (xy 118.949085 -284.494514)
			(xy 118.964529 -284.542046) (xy 118.972348 -284.591409) (xy 118.972838 -284.616398) (xy 119.278395 -284.616398)
			(xy 119.28249 -284.56567) (xy 119.294669 -284.516256) (xy 119.314617 -284.469436) (xy 119.341818 -284.426422)
			(xy 119.375566 -284.388328) (xy 119.414988 -284.356141) (xy 119.459062 -284.330695) (xy 119.506648 -284.312648)
			(xy 119.556512 -284.302468) (xy 119.607364 -284.300419) (xy 119.657885 -284.306553) (xy 119.706769 -284.320713)
			(xy 119.752748 -284.34253) (xy 119.794632 -284.37144) (xy 119.831336 -284.406695) (xy 119.861909 -284.447381)
			(xy 119.88556 -284.492444) (xy 119.901676 -284.540718) (xy 119.90984 -284.590952) (xy 119.910352 -284.616398)
			(xy 120.218449 -284.616398) (xy 120.222544 -284.56567) (xy 120.234723 -284.516256) (xy 120.254671 -284.469436)
			(xy 120.281872 -284.426422) (xy 120.31562 -284.388328) (xy 120.355042 -284.356141) (xy 120.399116 -284.330695)
			(xy 120.446702 -284.312648) (xy 120.496566 -284.302468) (xy 120.547418 -284.300419) (xy 120.597939 -284.306553)
			(xy 120.646823 -284.320713) (xy 120.692802 -284.34253) (xy 120.734686 -284.37144) (xy 120.77139 -284.406695)
			(xy 120.801963 -284.447381) (xy 120.825614 -284.492444) (xy 120.84173 -284.540718) (xy 120.849894 -284.590952)
			(xy 120.850406 -284.616398) (xy 120.849903 -284.641387) (xy 121.15722 -284.641387) (xy 121.15722 -284.591409)
			(xy 121.165039 -284.542046) (xy 121.180483 -284.494514) (xy 121.203173 -284.449982) (xy 121.232549 -284.409549)
			(xy 121.267889 -284.374209) (xy 121.308322 -284.344833) (xy 121.352854 -284.322143) (xy 121.400386 -284.306699)
			(xy 121.449749 -284.29888) (xy 121.499727 -284.29888) (xy 121.54909 -284.306699) (xy 121.596622 -284.322143)
			(xy 121.641154 -284.344833) (xy 121.681587 -284.374209) (xy 121.716927 -284.409549) (xy 121.746303 -284.449982)
			(xy 121.768993 -284.494514) (xy 121.784437 -284.542046) (xy 121.792256 -284.591409) (xy 121.792746 -284.616398)
			(xy 122.098557 -284.616398) (xy 122.102652 -284.56567) (xy 122.114831 -284.516256) (xy 122.134779 -284.469436)
			(xy 122.16198 -284.426422) (xy 122.195728 -284.388328) (xy 122.23515 -284.356141) (xy 122.279224 -284.330695)
			(xy 122.32681 -284.312648) (xy 122.376674 -284.302468) (xy 122.427526 -284.300419) (xy 122.478047 -284.306553)
			(xy 122.526931 -284.320713) (xy 122.57291 -284.34253) (xy 122.614794 -284.37144) (xy 122.651498 -284.406695)
			(xy 122.682071 -284.447381) (xy 122.705722 -284.492444) (xy 122.721838 -284.540718) (xy 122.730002 -284.590952)
			(xy 122.730514 -284.616398) (xy 123.038611 -284.616398) (xy 123.042706 -284.56567) (xy 123.054885 -284.516256)
			(xy 123.074833 -284.469436) (xy 123.102034 -284.426422) (xy 123.135782 -284.388328) (xy 123.175204 -284.356141)
			(xy 123.219278 -284.330695) (xy 123.266864 -284.312648) (xy 123.316728 -284.302468) (xy 123.36758 -284.300419)
			(xy 123.418101 -284.306553) (xy 123.466985 -284.320713) (xy 123.512964 -284.34253) (xy 123.554848 -284.37144)
			(xy 123.591552 -284.406695) (xy 123.622125 -284.447381) (xy 123.645776 -284.492444) (xy 123.661892 -284.540718)
			(xy 123.670056 -284.590952) (xy 123.670568 -284.616398) (xy 123.670065 -284.641387) (xy 123.977128 -284.641387)
			(xy 123.977128 -284.591409) (xy 123.984947 -284.542046) (xy 124.000391 -284.494514) (xy 124.023081 -284.449982)
			(xy 124.052457 -284.409549) (xy 124.087797 -284.374209) (xy 124.12823 -284.344833) (xy 124.172762 -284.322143)
			(xy 124.220294 -284.306699) (xy 124.269657 -284.29888) (xy 124.319635 -284.29888) (xy 124.368998 -284.306699)
			(xy 124.41653 -284.322143) (xy 124.461062 -284.344833) (xy 124.501495 -284.374209) (xy 124.536835 -284.409549)
			(xy 124.566211 -284.449982) (xy 124.588901 -284.494514) (xy 124.604345 -284.542046) (xy 124.612164 -284.591409)
			(xy 124.612654 -284.616398) (xy 124.918465 -284.616398) (xy 124.92256 -284.56567) (xy 124.934739 -284.516256)
			(xy 124.954687 -284.469436) (xy 124.981888 -284.426422) (xy 125.015636 -284.388328) (xy 125.055058 -284.356141)
			(xy 125.099132 -284.330695) (xy 125.146718 -284.312648) (xy 125.196582 -284.302468) (xy 125.247434 -284.300419)
			(xy 125.297955 -284.306553) (xy 125.346839 -284.320713) (xy 125.392818 -284.34253) (xy 125.434702 -284.37144)
			(xy 125.471406 -284.406695) (xy 125.501979 -284.447381) (xy 125.52563 -284.492444) (xy 125.541746 -284.540718)
			(xy 125.54991 -284.590952) (xy 125.550422 -284.616398) (xy 125.858519 -284.616398) (xy 125.862614 -284.56567)
			(xy 125.874793 -284.516256) (xy 125.894741 -284.469436) (xy 125.921942 -284.426422) (xy 125.95569 -284.388328)
			(xy 125.995112 -284.356141) (xy 126.039186 -284.330695) (xy 126.086772 -284.312648) (xy 126.136636 -284.302468)
			(xy 126.187488 -284.300419) (xy 126.238009 -284.306553) (xy 126.286893 -284.320713) (xy 126.332872 -284.34253)
			(xy 126.374756 -284.37144) (xy 126.41146 -284.406695) (xy 126.442033 -284.447381) (xy 126.465684 -284.492444)
			(xy 126.4818 -284.540718) (xy 126.489964 -284.590952) (xy 126.490476 -284.616398) (xy 126.489964 -284.641844)
			(xy 126.4818 -284.692078) (xy 126.465684 -284.740352) (xy 126.442033 -284.785415) (xy 126.41146 -284.826101)
			(xy 126.374756 -284.861356) (xy 126.332872 -284.890266) (xy 126.286893 -284.912083) (xy 126.238009 -284.926243)
			(xy 126.187488 -284.932377) (xy 126.136636 -284.930328) (xy 126.086772 -284.920148) (xy 126.039186 -284.902101)
			(xy 125.995112 -284.876655) (xy 125.95569 -284.844468) (xy 125.921942 -284.806374) (xy 125.894741 -284.76336)
			(xy 125.874793 -284.71654) (xy 125.862614 -284.667126) (xy 125.858519 -284.616398) (xy 125.550422 -284.616398)
			(xy 125.54991 -284.641844) (xy 125.541746 -284.692078) (xy 125.52563 -284.740352) (xy 125.501979 -284.785415)
			(xy 125.471406 -284.826101) (xy 125.434702 -284.861356) (xy 125.392818 -284.890266) (xy 125.346839 -284.912083)
			(xy 125.297955 -284.926243) (xy 125.247434 -284.932377) (xy 125.196582 -284.930328) (xy 125.146718 -284.920148)
			(xy 125.099132 -284.902101) (xy 125.055058 -284.876655) (xy 125.015636 -284.844468) (xy 124.981888 -284.806374)
			(xy 124.954687 -284.76336) (xy 124.934739 -284.71654) (xy 124.92256 -284.667126) (xy 124.918465 -284.616398)
			(xy 124.612654 -284.616398) (xy 124.612164 -284.641387) (xy 124.604345 -284.69075) (xy 124.588901 -284.738282)
			(xy 124.566211 -284.782814) (xy 124.536835 -284.823247) (xy 124.501495 -284.858587) (xy 124.461062 -284.887963)
			(xy 124.41653 -284.910653) (xy 124.368998 -284.926097) (xy 124.319635 -284.933916) (xy 124.269657 -284.933916)
			(xy 124.220294 -284.926097) (xy 124.172762 -284.910653) (xy 124.12823 -284.887963) (xy 124.087797 -284.858587)
			(xy 124.052457 -284.823247) (xy 124.023081 -284.782814) (xy 124.000391 -284.738282) (xy 123.984947 -284.69075)
			(xy 123.977128 -284.641387) (xy 123.670065 -284.641387) (xy 123.670056 -284.641844) (xy 123.661892 -284.692078)
			(xy 123.645776 -284.740352) (xy 123.622125 -284.785415) (xy 123.591552 -284.826101) (xy 123.554848 -284.861356)
			(xy 123.512964 -284.890266) (xy 123.466985 -284.912083) (xy 123.418101 -284.926243) (xy 123.36758 -284.932377)
			(xy 123.316728 -284.930328) (xy 123.266864 -284.920148) (xy 123.219278 -284.902101) (xy 123.175204 -284.876655)
			(xy 123.135782 -284.844468) (xy 123.102034 -284.806374) (xy 123.074833 -284.76336) (xy 123.054885 -284.71654)
			(xy 123.042706 -284.667126) (xy 123.038611 -284.616398) (xy 122.730514 -284.616398) (xy 122.730002 -284.641844)
			(xy 122.721838 -284.692078) (xy 122.705722 -284.740352) (xy 122.682071 -284.785415) (xy 122.651498 -284.826101)
			(xy 122.614794 -284.861356) (xy 122.57291 -284.890266) (xy 122.526931 -284.912083) (xy 122.478047 -284.926243)
			(xy 122.427526 -284.932377) (xy 122.376674 -284.930328) (xy 122.32681 -284.920148) (xy 122.279224 -284.902101)
			(xy 122.23515 -284.876655) (xy 122.195728 -284.844468) (xy 122.16198 -284.806374) (xy 122.134779 -284.76336)
			(xy 122.114831 -284.71654) (xy 122.102652 -284.667126) (xy 122.098557 -284.616398) (xy 121.792746 -284.616398)
			(xy 121.792256 -284.641387) (xy 121.784437 -284.69075) (xy 121.768993 -284.738282) (xy 121.746303 -284.782814)
			(xy 121.716927 -284.823247) (xy 121.681587 -284.858587) (xy 121.641154 -284.887963) (xy 121.596622 -284.910653)
			(xy 121.54909 -284.926097) (xy 121.499727 -284.933916) (xy 121.449749 -284.933916) (xy 121.400386 -284.926097)
			(xy 121.352854 -284.910653) (xy 121.308322 -284.887963) (xy 121.267889 -284.858587) (xy 121.232549 -284.823247)
			(xy 121.203173 -284.782814) (xy 121.180483 -284.738282) (xy 121.165039 -284.69075) (xy 121.15722 -284.641387)
			(xy 120.849903 -284.641387) (xy 120.849894 -284.641844) (xy 120.84173 -284.692078) (xy 120.825614 -284.740352)
			(xy 120.801963 -284.785415) (xy 120.77139 -284.826101) (xy 120.734686 -284.861356) (xy 120.692802 -284.890266)
			(xy 120.646823 -284.912083) (xy 120.597939 -284.926243) (xy 120.547418 -284.932377) (xy 120.496566 -284.930328)
			(xy 120.446702 -284.920148) (xy 120.399116 -284.902101) (xy 120.355042 -284.876655) (xy 120.31562 -284.844468)
			(xy 120.281872 -284.806374) (xy 120.254671 -284.76336) (xy 120.234723 -284.71654) (xy 120.222544 -284.667126)
			(xy 120.218449 -284.616398) (xy 119.910352 -284.616398) (xy 119.90984 -284.641844) (xy 119.901676 -284.692078)
			(xy 119.88556 -284.740352) (xy 119.861909 -284.785415) (xy 119.831336 -284.826101) (xy 119.794632 -284.861356)
			(xy 119.752748 -284.890266) (xy 119.706769 -284.912083) (xy 119.657885 -284.926243) (xy 119.607364 -284.932377)
			(xy 119.556512 -284.930328) (xy 119.506648 -284.920148) (xy 119.459062 -284.902101) (xy 119.414988 -284.876655)
			(xy 119.375566 -284.844468) (xy 119.341818 -284.806374) (xy 119.314617 -284.76336) (xy 119.294669 -284.71654)
			(xy 119.28249 -284.667126) (xy 119.278395 -284.616398) (xy 118.972838 -284.616398) (xy 118.972348 -284.641387)
			(xy 118.964529 -284.69075) (xy 118.949085 -284.738282) (xy 118.926395 -284.782814) (xy 118.897019 -284.823247)
			(xy 118.861679 -284.858587) (xy 118.821246 -284.887963) (xy 118.776714 -284.910653) (xy 118.729182 -284.926097)
			(xy 118.679819 -284.933916) (xy 118.629841 -284.933916) (xy 118.580478 -284.926097) (xy 118.532946 -284.910653)
			(xy 118.488414 -284.887963) (xy 118.447981 -284.858587) (xy 118.412641 -284.823247) (xy 118.383265 -284.782814)
			(xy 118.360575 -284.738282) (xy 118.345131 -284.69075) (xy 118.337312 -284.641387) (xy 118.029995 -284.641387)
			(xy 118.029986 -284.641844) (xy 118.021822 -284.692078) (xy 118.005706 -284.740352) (xy 117.982055 -284.785415)
			(xy 117.951482 -284.826101) (xy 117.914778 -284.861356) (xy 117.872894 -284.890266) (xy 117.826915 -284.912083)
			(xy 117.778031 -284.926243) (xy 117.72751 -284.932377) (xy 117.676658 -284.930328) (xy 117.626794 -284.920148)
			(xy 117.579208 -284.902101) (xy 117.535134 -284.876655) (xy 117.495712 -284.844468) (xy 117.461964 -284.806374)
			(xy 117.434763 -284.76336) (xy 117.414815 -284.71654) (xy 117.402636 -284.667126) (xy 117.398541 -284.616398)
			(xy 117.090444 -284.616398) (xy 117.089932 -284.641844) (xy 117.081768 -284.692078) (xy 117.065652 -284.740352)
			(xy 117.042001 -284.785415) (xy 117.011428 -284.826101) (xy 116.974724 -284.861356) (xy 116.93284 -284.890266)
			(xy 116.886861 -284.912083) (xy 116.837977 -284.926243) (xy 116.787456 -284.932377) (xy 116.736604 -284.930328)
			(xy 116.68674 -284.920148) (xy 116.639154 -284.902101) (xy 116.59508 -284.876655) (xy 116.555658 -284.844468)
			(xy 116.52191 -284.806374) (xy 116.494709 -284.76336) (xy 116.474761 -284.71654) (xy 116.462582 -284.667126)
			(xy 116.458487 -284.616398) (xy 116.152676 -284.616398) (xy 116.152186 -284.641387) (xy 116.144367 -284.69075)
			(xy 116.128923 -284.738282) (xy 116.106233 -284.782814) (xy 116.076857 -284.823247) (xy 116.041517 -284.858587)
			(xy 116.001084 -284.887963) (xy 115.956552 -284.910653) (xy 115.90902 -284.926097) (xy 115.859657 -284.933916)
			(xy 115.809679 -284.933916) (xy 115.760316 -284.926097) (xy 115.712784 -284.910653) (xy 115.668252 -284.887963)
			(xy 115.627819 -284.858587) (xy 115.592479 -284.823247) (xy 115.563103 -284.782814) (xy 115.540413 -284.738282)
			(xy 115.524969 -284.69075) (xy 115.51715 -284.641387) (xy 115.212132 -284.641387) (xy 115.204313 -284.69075)
			(xy 115.188869 -284.738282) (xy 115.166179 -284.782814) (xy 115.136803 -284.823247) (xy 115.101463 -284.858587)
			(xy 115.06103 -284.887963) (xy 115.016498 -284.910653) (xy 114.968966 -284.926097) (xy 114.919603 -284.933916)
			(xy 114.869625 -284.933916) (xy 114.820262 -284.926097) (xy 114.77273 -284.910653) (xy 114.728198 -284.887963)
			(xy 114.687765 -284.858587) (xy 114.652425 -284.823247) (xy 114.623049 -284.782814) (xy 114.600359 -284.738282)
			(xy 114.584915 -284.69075) (xy 114.577096 -284.641387) (xy 114.272332 -284.641387) (xy 114.264513 -284.69075)
			(xy 114.249069 -284.738282) (xy 114.226379 -284.782814) (xy 114.197003 -284.823247) (xy 114.161663 -284.858587)
			(xy 114.12123 -284.887963) (xy 114.076698 -284.910653) (xy 114.029166 -284.926097) (xy 113.979803 -284.933916)
			(xy 113.929825 -284.933916) (xy 113.880462 -284.926097) (xy 113.83293 -284.910653) (xy 113.788398 -284.887963)
			(xy 113.747965 -284.858587) (xy 113.712625 -284.823247) (xy 113.683249 -284.782814) (xy 113.660559 -284.738282)
			(xy 113.645115 -284.69075) (xy 113.637296 -284.641387) (xy 110.518466 -284.641387) (xy 110.510647 -284.69075)
			(xy 110.495203 -284.738282) (xy 110.472513 -284.782814) (xy 110.443137 -284.823247) (xy 110.407797 -284.858587)
			(xy 110.367364 -284.887963) (xy 110.322832 -284.910653) (xy 110.2753 -284.926097) (xy 110.225937 -284.933916)
			(xy 110.175959 -284.933916) (xy 110.126596 -284.926097) (xy 110.079064 -284.910653) (xy 110.034532 -284.887963)
			(xy 109.994099 -284.858587) (xy 109.958759 -284.823247) (xy 109.929383 -284.782814) (xy 109.906693 -284.738282)
			(xy 109.891249 -284.69075) (xy 109.88343 -284.641387) (xy 109.578666 -284.641387) (xy 109.570847 -284.69075)
			(xy 109.555403 -284.738282) (xy 109.532713 -284.782814) (xy 109.503337 -284.823247) (xy 109.467997 -284.858587)
			(xy 109.427564 -284.887963) (xy 109.383032 -284.910653) (xy 109.3355 -284.926097) (xy 109.286137 -284.933916)
			(xy 109.236159 -284.933916) (xy 109.186796 -284.926097) (xy 109.139264 -284.910653) (xy 109.094732 -284.887963)
			(xy 109.054299 -284.858587) (xy 109.018959 -284.823247) (xy 108.989583 -284.782814) (xy 108.966893 -284.738282)
			(xy 108.951449 -284.69075) (xy 108.94363 -284.641387) (xy 108.638612 -284.641387) (xy 108.630793 -284.69075)
			(xy 108.615349 -284.738282) (xy 108.592659 -284.782814) (xy 108.563283 -284.823247) (xy 108.527943 -284.858587)
			(xy 108.48751 -284.887963) (xy 108.442978 -284.910653) (xy 108.395446 -284.926097) (xy 108.346083 -284.933916)
			(xy 108.296105 -284.933916) (xy 108.246742 -284.926097) (xy 108.19921 -284.910653) (xy 108.154678 -284.887963)
			(xy 108.114245 -284.858587) (xy 108.078905 -284.823247) (xy 108.049529 -284.782814) (xy 108.026839 -284.738282)
			(xy 108.011395 -284.69075) (xy 108.003576 -284.641387) (xy 107.696259 -284.641387) (xy 107.69625 -284.641844)
			(xy 107.688086 -284.692078) (xy 107.67197 -284.740352) (xy 107.648319 -284.785415) (xy 107.617746 -284.826101)
			(xy 107.581042 -284.861356) (xy 107.539158 -284.890266) (xy 107.493179 -284.912083) (xy 107.444295 -284.926243)
			(xy 107.393774 -284.932377) (xy 107.342922 -284.930328) (xy 107.293058 -284.920148) (xy 107.245472 -284.902101)
			(xy 107.201398 -284.876655) (xy 107.161976 -284.844468) (xy 107.128228 -284.806374) (xy 107.101027 -284.76336)
			(xy 107.081079 -284.71654) (xy 107.0689 -284.667126) (xy 107.064805 -284.616398) (xy 106.756708 -284.616398)
			(xy 106.756196 -284.641844) (xy 106.748032 -284.692078) (xy 106.731916 -284.740352) (xy 106.708265 -284.785415)
			(xy 106.677692 -284.826101) (xy 106.640988 -284.861356) (xy 106.599104 -284.890266) (xy 106.553125 -284.912083)
			(xy 106.504241 -284.926243) (xy 106.45372 -284.932377) (xy 106.402868 -284.930328) (xy 106.353004 -284.920148)
			(xy 106.305418 -284.902101) (xy 106.261344 -284.876655) (xy 106.221922 -284.844468) (xy 106.188174 -284.806374)
			(xy 106.160973 -284.76336) (xy 106.141025 -284.71654) (xy 106.128846 -284.667126) (xy 106.124751 -284.616398)
			(xy 105.81894 -284.616398) (xy 105.81845 -284.641387) (xy 105.810631 -284.69075) (xy 105.795187 -284.738282)
			(xy 105.772497 -284.782814) (xy 105.743121 -284.823247) (xy 105.707781 -284.858587) (xy 105.667348 -284.887963)
			(xy 105.622816 -284.910653) (xy 105.575284 -284.926097) (xy 105.525921 -284.933916) (xy 105.475943 -284.933916)
			(xy 105.42658 -284.926097) (xy 105.379048 -284.910653) (xy 105.334516 -284.887963) (xy 105.294083 -284.858587)
			(xy 105.258743 -284.823247) (xy 105.229367 -284.782814) (xy 105.206677 -284.738282) (xy 105.191233 -284.69075)
			(xy 105.183414 -284.641387) (xy 104.876351 -284.641387) (xy 104.876342 -284.641844) (xy 104.868178 -284.692078)
			(xy 104.852062 -284.740352) (xy 104.828411 -284.785415) (xy 104.797838 -284.826101) (xy 104.761134 -284.861356)
			(xy 104.71925 -284.890266) (xy 104.673271 -284.912083) (xy 104.624387 -284.926243) (xy 104.573866 -284.932377)
			(xy 104.523014 -284.930328) (xy 104.47315 -284.920148) (xy 104.425564 -284.902101) (xy 104.38149 -284.876655)
			(xy 104.342068 -284.844468) (xy 104.30832 -284.806374) (xy 104.281119 -284.76336) (xy 104.261171 -284.71654)
			(xy 104.248992 -284.667126) (xy 104.244897 -284.616398) (xy 103.9368 -284.616398) (xy 103.936288 -284.641844)
			(xy 103.928124 -284.692078) (xy 103.912008 -284.740352) (xy 103.888357 -284.785415) (xy 103.857784 -284.826101)
			(xy 103.82108 -284.861356) (xy 103.779196 -284.890266) (xy 103.733217 -284.912083) (xy 103.684333 -284.926243)
			(xy 103.633812 -284.932377) (xy 103.58296 -284.930328) (xy 103.533096 -284.920148) (xy 103.48551 -284.902101)
			(xy 103.441436 -284.876655) (xy 103.402014 -284.844468) (xy 103.368266 -284.806374) (xy 103.341065 -284.76336)
			(xy 103.321117 -284.71654) (xy 103.308938 -284.667126) (xy 103.304843 -284.616398) (xy 102.999032 -284.616398)
			(xy 102.998542 -284.641387) (xy 102.990723 -284.69075) (xy 102.975279 -284.738282) (xy 102.952589 -284.782814)
			(xy 102.923213 -284.823247) (xy 102.887873 -284.858587) (xy 102.84744 -284.887963) (xy 102.802908 -284.910653)
			(xy 102.755376 -284.926097) (xy 102.706013 -284.933916) (xy 102.656035 -284.933916) (xy 102.606672 -284.926097)
			(xy 102.55914 -284.910653) (xy 102.514608 -284.887963) (xy 102.474175 -284.858587) (xy 102.438835 -284.823247)
			(xy 102.409459 -284.782814) (xy 102.386769 -284.738282) (xy 102.371325 -284.69075) (xy 102.363506 -284.641387)
			(xy 102.056189 -284.641387) (xy 102.05618 -284.641844) (xy 102.048016 -284.692078) (xy 102.0319 -284.740352)
			(xy 102.008249 -284.785415) (xy 101.977676 -284.826101) (xy 101.940972 -284.861356) (xy 101.899088 -284.890266)
			(xy 101.853109 -284.912083) (xy 101.804225 -284.926243) (xy 101.753704 -284.932377) (xy 101.702852 -284.930328)
			(xy 101.652988 -284.920148) (xy 101.605402 -284.902101) (xy 101.561328 -284.876655) (xy 101.521906 -284.844468)
			(xy 101.488158 -284.806374) (xy 101.460957 -284.76336) (xy 101.441009 -284.71654) (xy 101.42883 -284.667126)
			(xy 101.424735 -284.616398) (xy 101.116892 -284.616398) (xy 101.11638 -284.641844) (xy 101.108216 -284.692078)
			(xy 101.0921 -284.740352) (xy 101.068449 -284.785415) (xy 101.037876 -284.826101) (xy 101.001172 -284.861356)
			(xy 100.959288 -284.890266) (xy 100.913309 -284.912083) (xy 100.864425 -284.926243) (xy 100.813904 -284.932377)
			(xy 100.763052 -284.930328) (xy 100.713188 -284.920148) (xy 100.665602 -284.902101) (xy 100.621528 -284.876655)
			(xy 100.582106 -284.844468) (xy 100.548358 -284.806374) (xy 100.521157 -284.76336) (xy 100.501209 -284.71654)
			(xy 100.48903 -284.667126) (xy 100.484935 -284.616398) (xy 100.179124 -284.616398) (xy 100.178634 -284.641387)
			(xy 100.170815 -284.69075) (xy 100.155371 -284.738282) (xy 100.132681 -284.782814) (xy 100.103305 -284.823247)
			(xy 100.067965 -284.858587) (xy 100.027532 -284.887963) (xy 99.983 -284.910653) (xy 99.935468 -284.926097)
			(xy 99.886105 -284.933916) (xy 99.836127 -284.933916) (xy 99.786764 -284.926097) (xy 99.739232 -284.910653)
			(xy 99.6947 -284.887963) (xy 99.654267 -284.858587) (xy 99.618927 -284.823247) (xy 99.589551 -284.782814)
			(xy 99.566861 -284.738282) (xy 99.551417 -284.69075) (xy 99.543598 -284.641387) (xy 99.236281 -284.641387)
			(xy 99.236272 -284.641844) (xy 99.228108 -284.692078) (xy 99.211992 -284.740352) (xy 99.188341 -284.785415)
			(xy 99.157768 -284.826101) (xy 99.121064 -284.861356) (xy 99.07918 -284.890266) (xy 99.033201 -284.912083)
			(xy 98.984317 -284.926243) (xy 98.933796 -284.932377) (xy 98.882944 -284.930328) (xy 98.83308 -284.920148)
			(xy 98.785494 -284.902101) (xy 98.74142 -284.876655) (xy 98.701998 -284.844468) (xy 98.66825 -284.806374)
			(xy 98.641049 -284.76336) (xy 98.621101 -284.71654) (xy 98.608922 -284.667126) (xy 98.604827 -284.616398)
			(xy 98.29673 -284.616398) (xy 98.296218 -284.641844) (xy 98.288054 -284.692078) (xy 98.271938 -284.740352)
			(xy 98.248287 -284.785415) (xy 98.217714 -284.826101) (xy 98.18101 -284.861356) (xy 98.139126 -284.890266)
			(xy 98.093147 -284.912083) (xy 98.044263 -284.926243) (xy 97.993742 -284.932377) (xy 97.94289 -284.930328)
			(xy 97.893026 -284.920148) (xy 97.84544 -284.902101) (xy 97.801366 -284.876655) (xy 97.761944 -284.844468)
			(xy 97.728196 -284.806374) (xy 97.700995 -284.76336) (xy 97.681047 -284.71654) (xy 97.668868 -284.667126)
			(xy 97.664773 -284.616398) (xy 97.358962 -284.616398) (xy 97.358472 -284.641387) (xy 97.350653 -284.69075)
			(xy 97.335209 -284.738282) (xy 97.312519 -284.782814) (xy 97.283143 -284.823247) (xy 97.247803 -284.858587)
			(xy 97.20737 -284.887963) (xy 97.162838 -284.910653) (xy 97.115306 -284.926097) (xy 97.065943 -284.933916)
			(xy 97.015965 -284.933916) (xy 96.966602 -284.926097) (xy 96.91907 -284.910653) (xy 96.874538 -284.887963)
			(xy 96.834105 -284.858587) (xy 96.798765 -284.823247) (xy 96.769389 -284.782814) (xy 96.746699 -284.738282)
			(xy 96.731255 -284.69075) (xy 96.723436 -284.641387) (xy 96.416373 -284.641387) (xy 96.416364 -284.641844)
			(xy 96.4082 -284.692078) (xy 96.392084 -284.740352) (xy 96.368433 -284.785415) (xy 96.33786 -284.826101)
			(xy 96.301156 -284.861356) (xy 96.259272 -284.890266) (xy 96.213293 -284.912083) (xy 96.164409 -284.926243)
			(xy 96.113888 -284.932377) (xy 96.063036 -284.930328) (xy 96.013172 -284.920148) (xy 95.965586 -284.902101)
			(xy 95.921512 -284.876655) (xy 95.88209 -284.844468) (xy 95.848342 -284.806374) (xy 95.821141 -284.76336)
			(xy 95.801193 -284.71654) (xy 95.789014 -284.667126) (xy 95.784919 -284.616398) (xy 95.479108 -284.616398)
			(xy 95.478618 -284.641387) (xy 95.470799 -284.69075) (xy 95.455355 -284.738282) (xy 95.432665 -284.782814)
			(xy 95.403289 -284.823247) (xy 95.367949 -284.858587) (xy 95.327516 -284.887963) (xy 95.282984 -284.910653)
			(xy 95.235452 -284.926097) (xy 95.186089 -284.933916) (xy 95.136111 -284.933916) (xy 95.086748 -284.926097)
			(xy 95.039216 -284.910653) (xy 94.994684 -284.887963) (xy 94.954251 -284.858587) (xy 94.918911 -284.823247)
			(xy 94.889535 -284.782814) (xy 94.866845 -284.738282) (xy 94.851401 -284.69075) (xy 94.843582 -284.641387)
			(xy 94.536265 -284.641387) (xy 94.536256 -284.641844) (xy 94.528092 -284.692078) (xy 94.511976 -284.740352)
			(xy 94.488325 -284.785415) (xy 94.457752 -284.826101) (xy 94.421048 -284.861356) (xy 94.379164 -284.890266)
			(xy 94.333185 -284.912083) (xy 94.284301 -284.926243) (xy 94.23378 -284.932377) (xy 94.182928 -284.930328)
			(xy 94.133064 -284.920148) (xy 94.085478 -284.902101) (xy 94.041404 -284.876655) (xy 94.001982 -284.844468)
			(xy 93.968234 -284.806374) (xy 93.941033 -284.76336) (xy 93.921085 -284.71654) (xy 93.908906 -284.667126)
			(xy 93.904811 -284.616398) (xy 93.599 -284.616398) (xy 93.59851 -284.641387) (xy 93.590691 -284.69075)
			(xy 93.575247 -284.738282) (xy 93.552557 -284.782814) (xy 93.523181 -284.823247) (xy 93.487841 -284.858587)
			(xy 93.447408 -284.887963) (xy 93.402876 -284.910653) (xy 93.355344 -284.926097) (xy 93.305981 -284.933916)
			(xy 93.256003 -284.933916) (xy 93.20664 -284.926097) (xy 93.159108 -284.910653) (xy 93.114576 -284.887963)
			(xy 93.074143 -284.858587) (xy 93.038803 -284.823247) (xy 93.009427 -284.782814) (xy 92.986737 -284.738282)
			(xy 92.971293 -284.69075) (xy 92.963474 -284.641387) (xy 92.656157 -284.641387) (xy 92.656148 -284.641844)
			(xy 92.647984 -284.692078) (xy 92.631868 -284.740352) (xy 92.608217 -284.785415) (xy 92.577644 -284.826101)
			(xy 92.54094 -284.861356) (xy 92.499056 -284.890266) (xy 92.453077 -284.912083) (xy 92.404193 -284.926243)
			(xy 92.353672 -284.932377) (xy 92.30282 -284.930328) (xy 92.252956 -284.920148) (xy 92.20537 -284.902101)
			(xy 92.161296 -284.876655) (xy 92.121874 -284.844468) (xy 92.088126 -284.806374) (xy 92.060925 -284.76336)
			(xy 92.040977 -284.71654) (xy 92.028798 -284.667126) (xy 92.024703 -284.616398) (xy 91.861386 -284.616398)
			(xy 91.861386 -285.07944) (xy 91.88704 -285.108142) (xy 91.906598 -285.110428) (xy 91.932162 -285.113811)
			(xy 91.9818 -285.127777) (xy 92.028533 -285.149569) (xy 92.071138 -285.178616) (xy 92.108498 -285.214157)
			(xy 92.139633 -285.255261) (xy 92.163728 -285.30085) (xy 92.18015 -285.349729) (xy 92.188471 -285.400618)
			(xy 92.188471 -285.426404) (xy 92.494857 -285.426404) (xy 92.498952 -285.375676) (xy 92.511131 -285.326262)
			(xy 92.531079 -285.279442) (xy 92.55828 -285.236428) (xy 92.592028 -285.198334) (xy 92.63145 -285.166147)
			(xy 92.675524 -285.140701) (xy 92.72311 -285.122654) (xy 92.772974 -285.112474) (xy 92.823826 -285.110425)
			(xy 92.874347 -285.116559) (xy 92.923231 -285.130719) (xy 92.96921 -285.152536) (xy 93.011094 -285.181446)
			(xy 93.047798 -285.216701) (xy 93.078371 -285.257387) (xy 93.102022 -285.30245) (xy 93.118138 -285.350724)
			(xy 93.126302 -285.400958) (xy 93.126814 -285.426404) (xy 93.126311 -285.451393) (xy 93.433628 -285.451393)
			(xy 93.433628 -285.401415) (xy 93.441447 -285.352052) (xy 93.456891 -285.30452) (xy 93.479581 -285.259988)
			(xy 93.508957 -285.219555) (xy 93.544297 -285.184215) (xy 93.58473 -285.154839) (xy 93.629262 -285.132149)
			(xy 93.676794 -285.116705) (xy 93.726157 -285.108886) (xy 93.776135 -285.108886) (xy 93.825498 -285.116705)
			(xy 93.87303 -285.132149) (xy 93.917562 -285.154839) (xy 93.957995 -285.184215) (xy 93.993335 -285.219555)
			(xy 94.022711 -285.259988) (xy 94.045401 -285.30452) (xy 94.060845 -285.352052) (xy 94.068664 -285.401415)
			(xy 94.069154 -285.426404) (xy 94.374711 -285.426404) (xy 94.378806 -285.375676) (xy 94.390985 -285.326262)
			(xy 94.410933 -285.279442) (xy 94.438134 -285.236428) (xy 94.471882 -285.198334) (xy 94.511304 -285.166147)
			(xy 94.555378 -285.140701) (xy 94.602964 -285.122654) (xy 94.652828 -285.112474) (xy 94.70368 -285.110425)
			(xy 94.754201 -285.116559) (xy 94.803085 -285.130719) (xy 94.849064 -285.152536) (xy 94.890948 -285.181446)
			(xy 94.927652 -285.216701) (xy 94.958225 -285.257387) (xy 94.981876 -285.30245) (xy 94.997992 -285.350724)
			(xy 95.006156 -285.400958) (xy 95.006668 -285.426404) (xy 95.314765 -285.426404) (xy 95.31886 -285.375676)
			(xy 95.331039 -285.326262) (xy 95.350987 -285.279442) (xy 95.378188 -285.236428) (xy 95.411936 -285.198334)
			(xy 95.451358 -285.166147) (xy 95.495432 -285.140701) (xy 95.543018 -285.122654) (xy 95.592882 -285.112474)
			(xy 95.643734 -285.110425) (xy 95.694255 -285.116559) (xy 95.743139 -285.130719) (xy 95.789118 -285.152536)
			(xy 95.831002 -285.181446) (xy 95.867706 -285.216701) (xy 95.898279 -285.257387) (xy 95.92193 -285.30245)
			(xy 95.938046 -285.350724) (xy 95.94621 -285.400958) (xy 95.946722 -285.426404) (xy 95.946219 -285.451393)
			(xy 96.253536 -285.451393) (xy 96.253536 -285.401415) (xy 96.261355 -285.352052) (xy 96.276799 -285.30452)
			(xy 96.299489 -285.259988) (xy 96.328865 -285.219555) (xy 96.364205 -285.184215) (xy 96.404638 -285.154839)
			(xy 96.44917 -285.132149) (xy 96.496702 -285.116705) (xy 96.546065 -285.108886) (xy 96.596043 -285.108886)
			(xy 96.645406 -285.116705) (xy 96.692938 -285.132149) (xy 96.73747 -285.154839) (xy 96.777903 -285.184215)
			(xy 96.813243 -285.219555) (xy 96.842619 -285.259988) (xy 96.865309 -285.30452) (xy 96.880753 -285.352052)
			(xy 96.888572 -285.401415) (xy 96.889062 -285.426404) (xy 96.888572 -285.451393) (xy 97.19359 -285.451393)
			(xy 97.19359 -285.401415) (xy 97.201409 -285.352052) (xy 97.216853 -285.30452) (xy 97.239543 -285.259988)
			(xy 97.268919 -285.219555) (xy 97.304259 -285.184215) (xy 97.344692 -285.154839) (xy 97.389224 -285.132149)
			(xy 97.436756 -285.116705) (xy 97.486119 -285.108886) (xy 97.536097 -285.108886) (xy 97.58546 -285.116705)
			(xy 97.632992 -285.132149) (xy 97.677524 -285.154839) (xy 97.717957 -285.184215) (xy 97.753297 -285.219555)
			(xy 97.782673 -285.259988) (xy 97.805363 -285.30452) (xy 97.820807 -285.352052) (xy 97.828626 -285.401415)
			(xy 97.829116 -285.426404) (xy 97.828626 -285.451393) (xy 98.133644 -285.451393) (xy 98.133644 -285.401415)
			(xy 98.141463 -285.352052) (xy 98.156907 -285.30452) (xy 98.179597 -285.259988) (xy 98.208973 -285.219555)
			(xy 98.244313 -285.184215) (xy 98.284746 -285.154839) (xy 98.329278 -285.132149) (xy 98.37681 -285.116705)
			(xy 98.426173 -285.108886) (xy 98.476151 -285.108886) (xy 98.525514 -285.116705) (xy 98.573046 -285.132149)
			(xy 98.617578 -285.154839) (xy 98.658011 -285.184215) (xy 98.693351 -285.219555) (xy 98.722727 -285.259988)
			(xy 98.745417 -285.30452) (xy 98.760861 -285.352052) (xy 98.76868 -285.401415) (xy 98.76917 -285.426404)
			(xy 98.76868 -285.451393) (xy 99.073444 -285.451393) (xy 99.073444 -285.401415) (xy 99.081263 -285.352052)
			(xy 99.096707 -285.30452) (xy 99.119397 -285.259988) (xy 99.148773 -285.219555) (xy 99.184113 -285.184215)
			(xy 99.224546 -285.154839) (xy 99.269078 -285.132149) (xy 99.31661 -285.116705) (xy 99.365973 -285.108886)
			(xy 99.415951 -285.108886) (xy 99.465314 -285.116705) (xy 99.512846 -285.132149) (xy 99.557378 -285.154839)
			(xy 99.597811 -285.184215) (xy 99.633151 -285.219555) (xy 99.662527 -285.259988) (xy 99.685217 -285.30452)
			(xy 99.700661 -285.352052) (xy 99.70848 -285.401415) (xy 99.70897 -285.426404) (xy 99.70848 -285.451393)
			(xy 100.013498 -285.451393) (xy 100.013498 -285.401415) (xy 100.021317 -285.352052) (xy 100.036761 -285.30452)
			(xy 100.059451 -285.259988) (xy 100.088827 -285.219555) (xy 100.124167 -285.184215) (xy 100.1646 -285.154839)
			(xy 100.209132 -285.132149) (xy 100.256664 -285.116705) (xy 100.306027 -285.108886) (xy 100.356005 -285.108886)
			(xy 100.405368 -285.116705) (xy 100.4529 -285.132149) (xy 100.497432 -285.154839) (xy 100.537865 -285.184215)
			(xy 100.573205 -285.219555) (xy 100.602581 -285.259988) (xy 100.625271 -285.30452) (xy 100.640715 -285.352052)
			(xy 100.648534 -285.401415) (xy 100.649024 -285.426404) (xy 100.648534 -285.451393) (xy 100.953552 -285.451393)
			(xy 100.953552 -285.401415) (xy 100.961371 -285.352052) (xy 100.976815 -285.30452) (xy 100.999505 -285.259988)
			(xy 101.028881 -285.219555) (xy 101.064221 -285.184215) (xy 101.104654 -285.154839) (xy 101.149186 -285.132149)
			(xy 101.196718 -285.116705) (xy 101.246081 -285.108886) (xy 101.296059 -285.108886) (xy 101.345422 -285.116705)
			(xy 101.392954 -285.132149) (xy 101.437486 -285.154839) (xy 101.477919 -285.184215) (xy 101.513259 -285.219555)
			(xy 101.542635 -285.259988) (xy 101.565325 -285.30452) (xy 101.580769 -285.352052) (xy 101.588588 -285.401415)
			(xy 101.589078 -285.426404) (xy 101.588588 -285.451393) (xy 101.893606 -285.451393) (xy 101.893606 -285.401415)
			(xy 101.901425 -285.352052) (xy 101.916869 -285.30452) (xy 101.939559 -285.259988) (xy 101.968935 -285.219555)
			(xy 102.004275 -285.184215) (xy 102.044708 -285.154839) (xy 102.08924 -285.132149) (xy 102.136772 -285.116705)
			(xy 102.186135 -285.108886) (xy 102.236113 -285.108886) (xy 102.285476 -285.116705) (xy 102.333008 -285.132149)
			(xy 102.37754 -285.154839) (xy 102.417973 -285.184215) (xy 102.453313 -285.219555) (xy 102.482689 -285.259988)
			(xy 102.505379 -285.30452) (xy 102.520823 -285.352052) (xy 102.528642 -285.401415) (xy 102.529132 -285.426404)
			(xy 102.528642 -285.451393) (xy 102.83366 -285.451393) (xy 102.83366 -285.401415) (xy 102.841479 -285.352052)
			(xy 102.856923 -285.30452) (xy 102.879613 -285.259988) (xy 102.908989 -285.219555) (xy 102.944329 -285.184215)
			(xy 102.984762 -285.154839) (xy 103.029294 -285.132149) (xy 103.076826 -285.116705) (xy 103.126189 -285.108886)
			(xy 103.176167 -285.108886) (xy 103.22553 -285.116705) (xy 103.273062 -285.132149) (xy 103.317594 -285.154839)
			(xy 103.358027 -285.184215) (xy 103.393367 -285.219555) (xy 103.422743 -285.259988) (xy 103.445433 -285.30452)
			(xy 103.460877 -285.352052) (xy 103.468696 -285.401415) (xy 103.469186 -285.426404) (xy 103.468696 -285.451393)
			(xy 103.77346 -285.451393) (xy 103.77346 -285.401415) (xy 103.781279 -285.352052) (xy 103.796723 -285.30452)
			(xy 103.819413 -285.259988) (xy 103.848789 -285.219555) (xy 103.884129 -285.184215) (xy 103.924562 -285.154839)
			(xy 103.969094 -285.132149) (xy 104.016626 -285.116705) (xy 104.065989 -285.108886) (xy 104.115967 -285.108886)
			(xy 104.16533 -285.116705) (xy 104.212862 -285.132149) (xy 104.257394 -285.154839) (xy 104.297827 -285.184215)
			(xy 104.333167 -285.219555) (xy 104.362543 -285.259988) (xy 104.385233 -285.30452) (xy 104.400677 -285.352052)
			(xy 104.408496 -285.401415) (xy 104.408986 -285.426404) (xy 104.408496 -285.451393) (xy 104.713514 -285.451393)
			(xy 104.713514 -285.401415) (xy 104.721333 -285.352052) (xy 104.736777 -285.30452) (xy 104.759467 -285.259988)
			(xy 104.788843 -285.219555) (xy 104.824183 -285.184215) (xy 104.864616 -285.154839) (xy 104.909148 -285.132149)
			(xy 104.95668 -285.116705) (xy 105.006043 -285.108886) (xy 105.056021 -285.108886) (xy 105.105384 -285.116705)
			(xy 105.152916 -285.132149) (xy 105.197448 -285.154839) (xy 105.237881 -285.184215) (xy 105.273221 -285.219555)
			(xy 105.302597 -285.259988) (xy 105.325287 -285.30452) (xy 105.340731 -285.352052) (xy 105.34855 -285.401415)
			(xy 105.34904 -285.426404) (xy 105.34855 -285.451393) (xy 105.653568 -285.451393) (xy 105.653568 -285.401415)
			(xy 105.661387 -285.352052) (xy 105.676831 -285.30452) (xy 105.699521 -285.259988) (xy 105.728897 -285.219555)
			(xy 105.764237 -285.184215) (xy 105.80467 -285.154839) (xy 105.849202 -285.132149) (xy 105.896734 -285.116705)
			(xy 105.946097 -285.108886) (xy 105.996075 -285.108886) (xy 106.045438 -285.116705) (xy 106.09297 -285.132149)
			(xy 106.137502 -285.154839) (xy 106.177935 -285.184215) (xy 106.213275 -285.219555) (xy 106.242651 -285.259988)
			(xy 106.265341 -285.30452) (xy 106.280785 -285.352052) (xy 106.288604 -285.401415) (xy 106.289094 -285.426404)
			(xy 106.288604 -285.451393) (xy 106.593622 -285.451393) (xy 106.593622 -285.401415) (xy 106.601441 -285.352052)
			(xy 106.616885 -285.30452) (xy 106.639575 -285.259988) (xy 106.668951 -285.219555) (xy 106.704291 -285.184215)
			(xy 106.744724 -285.154839) (xy 106.789256 -285.132149) (xy 106.836788 -285.116705) (xy 106.886151 -285.108886)
			(xy 106.936129 -285.108886) (xy 106.985492 -285.116705) (xy 107.033024 -285.132149) (xy 107.077556 -285.154839)
			(xy 107.117989 -285.184215) (xy 107.153329 -285.219555) (xy 107.182705 -285.259988) (xy 107.205395 -285.30452)
			(xy 107.220839 -285.352052) (xy 107.228658 -285.401415) (xy 107.229148 -285.426404) (xy 107.228658 -285.451393)
			(xy 107.533422 -285.451393) (xy 107.533422 -285.401415) (xy 107.541241 -285.352052) (xy 107.556685 -285.30452)
			(xy 107.579375 -285.259988) (xy 107.608751 -285.219555) (xy 107.644091 -285.184215) (xy 107.684524 -285.154839)
			(xy 107.729056 -285.132149) (xy 107.776588 -285.116705) (xy 107.825951 -285.108886) (xy 107.875929 -285.108886)
			(xy 107.925292 -285.116705) (xy 107.972824 -285.132149) (xy 108.017356 -285.154839) (xy 108.057789 -285.184215)
			(xy 108.093129 -285.219555) (xy 108.122505 -285.259988) (xy 108.145195 -285.30452) (xy 108.160639 -285.352052)
			(xy 108.168458 -285.401415) (xy 108.168948 -285.426404) (xy 108.474759 -285.426404) (xy 108.478854 -285.375676)
			(xy 108.491033 -285.326262) (xy 108.510981 -285.279442) (xy 108.538182 -285.236428) (xy 108.57193 -285.198334)
			(xy 108.611352 -285.166147) (xy 108.655426 -285.140701) (xy 108.703012 -285.122654) (xy 108.752876 -285.112474)
			(xy 108.803728 -285.110425) (xy 108.854249 -285.116559) (xy 108.903133 -285.130719) (xy 108.949112 -285.152536)
			(xy 108.990996 -285.181446) (xy 109.0277 -285.216701) (xy 109.058273 -285.257387) (xy 109.081924 -285.30245)
			(xy 109.09804 -285.350724) (xy 109.106204 -285.400958) (xy 109.106716 -285.426404) (xy 109.414813 -285.426404)
			(xy 109.418908 -285.375676) (xy 109.431087 -285.326262) (xy 109.451035 -285.279442) (xy 109.478236 -285.236428)
			(xy 109.511984 -285.198334) (xy 109.551406 -285.166147) (xy 109.59548 -285.140701) (xy 109.643066 -285.122654)
			(xy 109.69293 -285.112474) (xy 109.743782 -285.110425) (xy 109.794303 -285.116559) (xy 109.843187 -285.130719)
			(xy 109.889166 -285.152536) (xy 109.93105 -285.181446) (xy 109.967754 -285.216701) (xy 109.998327 -285.257387)
			(xy 110.021978 -285.30245) (xy 110.038094 -285.350724) (xy 110.046258 -285.400958) (xy 110.04677 -285.426404)
			(xy 110.046267 -285.451393) (xy 110.353584 -285.451393) (xy 110.353584 -285.401415) (xy 110.361403 -285.352052)
			(xy 110.376847 -285.30452) (xy 110.399537 -285.259988) (xy 110.428913 -285.219555) (xy 110.464253 -285.184215)
			(xy 110.504686 -285.154839) (xy 110.549218 -285.132149) (xy 110.59675 -285.116705) (xy 110.646113 -285.108886)
			(xy 110.696091 -285.108886) (xy 110.745454 -285.116705) (xy 110.792986 -285.132149) (xy 110.837518 -285.154839)
			(xy 110.877951 -285.184215) (xy 110.913291 -285.219555) (xy 110.942667 -285.259988) (xy 110.965357 -285.30452)
			(xy 110.980801 -285.352052) (xy 110.98862 -285.401415) (xy 110.98911 -285.426404) (xy 110.98862 -285.451393)
			(xy 113.167142 -285.451393) (xy 113.167142 -285.401415) (xy 113.174961 -285.352052) (xy 113.190405 -285.30452)
			(xy 113.213095 -285.259988) (xy 113.242471 -285.219555) (xy 113.277811 -285.184215) (xy 113.318244 -285.154839)
			(xy 113.362776 -285.132149) (xy 113.410308 -285.116705) (xy 113.459671 -285.108886) (xy 113.509649 -285.108886)
			(xy 113.559012 -285.116705) (xy 113.606544 -285.132149) (xy 113.651076 -285.154839) (xy 113.691509 -285.184215)
			(xy 113.726849 -285.219555) (xy 113.756225 -285.259988) (xy 113.778915 -285.30452) (xy 113.794359 -285.352052)
			(xy 113.802178 -285.401415) (xy 113.802668 -285.426404) (xy 114.108479 -285.426404) (xy 114.112574 -285.375676)
			(xy 114.124753 -285.326262) (xy 114.144701 -285.279442) (xy 114.171902 -285.236428) (xy 114.20565 -285.198334)
			(xy 114.245072 -285.166147) (xy 114.289146 -285.140701) (xy 114.336732 -285.122654) (xy 114.386596 -285.112474)
			(xy 114.437448 -285.110425) (xy 114.487969 -285.116559) (xy 114.536853 -285.130719) (xy 114.582832 -285.152536)
			(xy 114.624716 -285.181446) (xy 114.66142 -285.216701) (xy 114.691993 -285.257387) (xy 114.715644 -285.30245)
			(xy 114.73176 -285.350724) (xy 114.739924 -285.400958) (xy 114.740436 -285.426404) (xy 115.048533 -285.426404)
			(xy 115.052628 -285.375676) (xy 115.064807 -285.326262) (xy 115.084755 -285.279442) (xy 115.111956 -285.236428)
			(xy 115.145704 -285.198334) (xy 115.185126 -285.166147) (xy 115.2292 -285.140701) (xy 115.276786 -285.122654)
			(xy 115.32665 -285.112474) (xy 115.377502 -285.110425) (xy 115.428023 -285.116559) (xy 115.476907 -285.130719)
			(xy 115.522886 -285.152536) (xy 115.56477 -285.181446) (xy 115.601474 -285.216701) (xy 115.632047 -285.257387)
			(xy 115.655698 -285.30245) (xy 115.671814 -285.350724) (xy 115.679978 -285.400958) (xy 115.68049 -285.426404)
			(xy 115.679987 -285.451393) (xy 115.987304 -285.451393) (xy 115.987304 -285.401415) (xy 115.995123 -285.352052)
			(xy 116.010567 -285.30452) (xy 116.033257 -285.259988) (xy 116.062633 -285.219555) (xy 116.097973 -285.184215)
			(xy 116.138406 -285.154839) (xy 116.182938 -285.132149) (xy 116.23047 -285.116705) (xy 116.279833 -285.108886)
			(xy 116.329811 -285.108886) (xy 116.379174 -285.116705) (xy 116.426706 -285.132149) (xy 116.471238 -285.154839)
			(xy 116.511671 -285.184215) (xy 116.547011 -285.219555) (xy 116.576387 -285.259988) (xy 116.599077 -285.30452)
			(xy 116.614521 -285.352052) (xy 116.62234 -285.401415) (xy 116.62283 -285.426404) (xy 116.62234 -285.451393)
			(xy 116.927104 -285.451393) (xy 116.927104 -285.401415) (xy 116.934923 -285.352052) (xy 116.950367 -285.30452)
			(xy 116.973057 -285.259988) (xy 117.002433 -285.219555) (xy 117.037773 -285.184215) (xy 117.078206 -285.154839)
			(xy 117.122738 -285.132149) (xy 117.17027 -285.116705) (xy 117.219633 -285.108886) (xy 117.269611 -285.108886)
			(xy 117.318974 -285.116705) (xy 117.366506 -285.132149) (xy 117.411038 -285.154839) (xy 117.451471 -285.184215)
			(xy 117.486811 -285.219555) (xy 117.516187 -285.259988) (xy 117.538877 -285.30452) (xy 117.554321 -285.352052)
			(xy 117.56214 -285.401415) (xy 117.56263 -285.426404) (xy 117.56214 -285.451393) (xy 117.867158 -285.451393)
			(xy 117.867158 -285.401415) (xy 117.874977 -285.352052) (xy 117.890421 -285.30452) (xy 117.913111 -285.259988)
			(xy 117.942487 -285.219555) (xy 117.977827 -285.184215) (xy 118.01826 -285.154839) (xy 118.062792 -285.132149)
			(xy 118.110324 -285.116705) (xy 118.159687 -285.108886) (xy 118.209665 -285.108886) (xy 118.259028 -285.116705)
			(xy 118.30656 -285.132149) (xy 118.351092 -285.154839) (xy 118.391525 -285.184215) (xy 118.426865 -285.219555)
			(xy 118.456241 -285.259988) (xy 118.478931 -285.30452) (xy 118.494375 -285.352052) (xy 118.502194 -285.401415)
			(xy 118.502684 -285.426404) (xy 118.502194 -285.451393) (xy 118.807212 -285.451393) (xy 118.807212 -285.401415)
			(xy 118.815031 -285.352052) (xy 118.830475 -285.30452) (xy 118.853165 -285.259988) (xy 118.882541 -285.219555)
			(xy 118.917881 -285.184215) (xy 118.958314 -285.154839) (xy 119.002846 -285.132149) (xy 119.050378 -285.116705)
			(xy 119.099741 -285.108886) (xy 119.149719 -285.108886) (xy 119.199082 -285.116705) (xy 119.246614 -285.132149)
			(xy 119.291146 -285.154839) (xy 119.331579 -285.184215) (xy 119.366919 -285.219555) (xy 119.396295 -285.259988)
			(xy 119.418985 -285.30452) (xy 119.434429 -285.352052) (xy 119.442248 -285.401415) (xy 119.442738 -285.426404)
			(xy 119.442248 -285.451393) (xy 119.747266 -285.451393) (xy 119.747266 -285.401415) (xy 119.755085 -285.352052)
			(xy 119.770529 -285.30452) (xy 119.793219 -285.259988) (xy 119.822595 -285.219555) (xy 119.857935 -285.184215)
			(xy 119.898368 -285.154839) (xy 119.9429 -285.132149) (xy 119.990432 -285.116705) (xy 120.039795 -285.108886)
			(xy 120.089773 -285.108886) (xy 120.139136 -285.116705) (xy 120.186668 -285.132149) (xy 120.2312 -285.154839)
			(xy 120.271633 -285.184215) (xy 120.306973 -285.219555) (xy 120.336349 -285.259988) (xy 120.359039 -285.30452)
			(xy 120.374483 -285.352052) (xy 120.382302 -285.401415) (xy 120.382792 -285.426404) (xy 120.382302 -285.451393)
			(xy 120.68732 -285.451393) (xy 120.68732 -285.401415) (xy 120.695139 -285.352052) (xy 120.710583 -285.30452)
			(xy 120.733273 -285.259988) (xy 120.762649 -285.219555) (xy 120.797989 -285.184215) (xy 120.838422 -285.154839)
			(xy 120.882954 -285.132149) (xy 120.930486 -285.116705) (xy 120.979849 -285.108886) (xy 121.029827 -285.108886)
			(xy 121.07919 -285.116705) (xy 121.126722 -285.132149) (xy 121.171254 -285.154839) (xy 121.211687 -285.184215)
			(xy 121.247027 -285.219555) (xy 121.276403 -285.259988) (xy 121.299093 -285.30452) (xy 121.314537 -285.352052)
			(xy 121.322356 -285.401415) (xy 121.322846 -285.426404) (xy 121.322356 -285.451393) (xy 121.62712 -285.451393)
			(xy 121.62712 -285.401415) (xy 121.634939 -285.352052) (xy 121.650383 -285.30452) (xy 121.673073 -285.259988)
			(xy 121.702449 -285.219555) (xy 121.737789 -285.184215) (xy 121.778222 -285.154839) (xy 121.822754 -285.132149)
			(xy 121.870286 -285.116705) (xy 121.919649 -285.108886) (xy 121.969627 -285.108886) (xy 122.01899 -285.116705)
			(xy 122.066522 -285.132149) (xy 122.111054 -285.154839) (xy 122.151487 -285.184215) (xy 122.186827 -285.219555)
			(xy 122.216203 -285.259988) (xy 122.238893 -285.30452) (xy 122.254337 -285.352052) (xy 122.262156 -285.401415)
			(xy 122.262646 -285.426404) (xy 122.262156 -285.451393) (xy 122.567174 -285.451393) (xy 122.567174 -285.401415)
			(xy 122.574993 -285.352052) (xy 122.590437 -285.30452) (xy 122.613127 -285.259988) (xy 122.642503 -285.219555)
			(xy 122.677843 -285.184215) (xy 122.718276 -285.154839) (xy 122.762808 -285.132149) (xy 122.81034 -285.116705)
			(xy 122.859703 -285.108886) (xy 122.909681 -285.108886) (xy 122.959044 -285.116705) (xy 123.006576 -285.132149)
			(xy 123.051108 -285.154839) (xy 123.091541 -285.184215) (xy 123.126881 -285.219555) (xy 123.156257 -285.259988)
			(xy 123.178947 -285.30452) (xy 123.194391 -285.352052) (xy 123.20221 -285.401415) (xy 123.2027 -285.426404)
			(xy 123.20221 -285.451393) (xy 123.507228 -285.451393) (xy 123.507228 -285.401415) (xy 123.515047 -285.352052)
			(xy 123.530491 -285.30452) (xy 123.553181 -285.259988) (xy 123.582557 -285.219555) (xy 123.617897 -285.184215)
			(xy 123.65833 -285.154839) (xy 123.702862 -285.132149) (xy 123.750394 -285.116705) (xy 123.799757 -285.108886)
			(xy 123.849735 -285.108886) (xy 123.899098 -285.116705) (xy 123.94663 -285.132149) (xy 123.991162 -285.154839)
			(xy 124.031595 -285.184215) (xy 124.066935 -285.219555) (xy 124.096311 -285.259988) (xy 124.119001 -285.30452)
			(xy 124.134445 -285.352052) (xy 124.142264 -285.401415) (xy 124.142754 -285.426404) (xy 124.142264 -285.451393)
			(xy 124.447282 -285.451393) (xy 124.447282 -285.401415) (xy 124.455101 -285.352052) (xy 124.470545 -285.30452)
			(xy 124.493235 -285.259988) (xy 124.522611 -285.219555) (xy 124.557951 -285.184215) (xy 124.598384 -285.154839)
			(xy 124.642916 -285.132149) (xy 124.690448 -285.116705) (xy 124.739811 -285.108886) (xy 124.789789 -285.108886)
			(xy 124.839152 -285.116705) (xy 124.886684 -285.132149) (xy 124.931216 -285.154839) (xy 124.971649 -285.184215)
			(xy 125.006989 -285.219555) (xy 125.036365 -285.259988) (xy 125.059055 -285.30452) (xy 125.074499 -285.352052)
			(xy 125.082318 -285.401415) (xy 125.082808 -285.426404) (xy 125.082318 -285.451393) (xy 125.387336 -285.451393)
			(xy 125.387336 -285.401415) (xy 125.395155 -285.352052) (xy 125.410599 -285.30452) (xy 125.433289 -285.259988)
			(xy 125.462665 -285.219555) (xy 125.498005 -285.184215) (xy 125.538438 -285.154839) (xy 125.58297 -285.132149)
			(xy 125.630502 -285.116705) (xy 125.679865 -285.108886) (xy 125.729843 -285.108886) (xy 125.779206 -285.116705)
			(xy 125.826738 -285.132149) (xy 125.87127 -285.154839) (xy 125.911703 -285.184215) (xy 125.947043 -285.219555)
			(xy 125.976419 -285.259988) (xy 125.999109 -285.30452) (xy 126.014553 -285.352052) (xy 126.022372 -285.401415)
			(xy 126.022862 -285.426404) (xy 126.022372 -285.451393) (xy 126.014553 -285.500756) (xy 125.999109 -285.548288)
			(xy 125.976419 -285.59282) (xy 125.947043 -285.633253) (xy 125.911703 -285.668593) (xy 125.87127 -285.697969)
			(xy 125.826738 -285.720659) (xy 125.779206 -285.736103) (xy 125.729843 -285.743922) (xy 125.679865 -285.743922)
			(xy 125.630502 -285.736103) (xy 125.58297 -285.720659) (xy 125.538438 -285.697969) (xy 125.498005 -285.668593)
			(xy 125.462665 -285.633253) (xy 125.433289 -285.59282) (xy 125.410599 -285.548288) (xy 125.395155 -285.500756)
			(xy 125.387336 -285.451393) (xy 125.082318 -285.451393) (xy 125.074499 -285.500756) (xy 125.059055 -285.548288)
			(xy 125.036365 -285.59282) (xy 125.006989 -285.633253) (xy 124.971649 -285.668593) (xy 124.931216 -285.697969)
			(xy 124.886684 -285.720659) (xy 124.839152 -285.736103) (xy 124.789789 -285.743922) (xy 124.739811 -285.743922)
			(xy 124.690448 -285.736103) (xy 124.642916 -285.720659) (xy 124.598384 -285.697969) (xy 124.557951 -285.668593)
			(xy 124.522611 -285.633253) (xy 124.493235 -285.59282) (xy 124.470545 -285.548288) (xy 124.455101 -285.500756)
			(xy 124.447282 -285.451393) (xy 124.142264 -285.451393) (xy 124.134445 -285.500756) (xy 124.119001 -285.548288)
			(xy 124.096311 -285.59282) (xy 124.066935 -285.633253) (xy 124.031595 -285.668593) (xy 123.991162 -285.697969)
			(xy 123.94663 -285.720659) (xy 123.899098 -285.736103) (xy 123.849735 -285.743922) (xy 123.799757 -285.743922)
			(xy 123.750394 -285.736103) (xy 123.702862 -285.720659) (xy 123.65833 -285.697969) (xy 123.617897 -285.668593)
			(xy 123.582557 -285.633253) (xy 123.553181 -285.59282) (xy 123.530491 -285.548288) (xy 123.515047 -285.500756)
			(xy 123.507228 -285.451393) (xy 123.20221 -285.451393) (xy 123.194391 -285.500756) (xy 123.178947 -285.548288)
			(xy 123.156257 -285.59282) (xy 123.126881 -285.633253) (xy 123.091541 -285.668593) (xy 123.051108 -285.697969)
			(xy 123.006576 -285.720659) (xy 122.959044 -285.736103) (xy 122.909681 -285.743922) (xy 122.859703 -285.743922)
			(xy 122.81034 -285.736103) (xy 122.762808 -285.720659) (xy 122.718276 -285.697969) (xy 122.677843 -285.668593)
			(xy 122.642503 -285.633253) (xy 122.613127 -285.59282) (xy 122.590437 -285.548288) (xy 122.574993 -285.500756)
			(xy 122.567174 -285.451393) (xy 122.262156 -285.451393) (xy 122.254337 -285.500756) (xy 122.238893 -285.548288)
			(xy 122.216203 -285.59282) (xy 122.186827 -285.633253) (xy 122.151487 -285.668593) (xy 122.111054 -285.697969)
			(xy 122.066522 -285.720659) (xy 122.01899 -285.736103) (xy 121.969627 -285.743922) (xy 121.919649 -285.743922)
			(xy 121.870286 -285.736103) (xy 121.822754 -285.720659) (xy 121.778222 -285.697969) (xy 121.737789 -285.668593)
			(xy 121.702449 -285.633253) (xy 121.673073 -285.59282) (xy 121.650383 -285.548288) (xy 121.634939 -285.500756)
			(xy 121.62712 -285.451393) (xy 121.322356 -285.451393) (xy 121.314537 -285.500756) (xy 121.299093 -285.548288)
			(xy 121.276403 -285.59282) (xy 121.247027 -285.633253) (xy 121.211687 -285.668593) (xy 121.171254 -285.697969)
			(xy 121.126722 -285.720659) (xy 121.07919 -285.736103) (xy 121.029827 -285.743922) (xy 120.979849 -285.743922)
			(xy 120.930486 -285.736103) (xy 120.882954 -285.720659) (xy 120.838422 -285.697969) (xy 120.797989 -285.668593)
			(xy 120.762649 -285.633253) (xy 120.733273 -285.59282) (xy 120.710583 -285.548288) (xy 120.695139 -285.500756)
			(xy 120.68732 -285.451393) (xy 120.382302 -285.451393) (xy 120.374483 -285.500756) (xy 120.359039 -285.548288)
			(xy 120.336349 -285.59282) (xy 120.306973 -285.633253) (xy 120.271633 -285.668593) (xy 120.2312 -285.697969)
			(xy 120.186668 -285.720659) (xy 120.139136 -285.736103) (xy 120.089773 -285.743922) (xy 120.039795 -285.743922)
			(xy 119.990432 -285.736103) (xy 119.9429 -285.720659) (xy 119.898368 -285.697969) (xy 119.857935 -285.668593)
			(xy 119.822595 -285.633253) (xy 119.793219 -285.59282) (xy 119.770529 -285.548288) (xy 119.755085 -285.500756)
			(xy 119.747266 -285.451393) (xy 119.442248 -285.451393) (xy 119.434429 -285.500756) (xy 119.418985 -285.548288)
			(xy 119.396295 -285.59282) (xy 119.366919 -285.633253) (xy 119.331579 -285.668593) (xy 119.291146 -285.697969)
			(xy 119.246614 -285.720659) (xy 119.199082 -285.736103) (xy 119.149719 -285.743922) (xy 119.099741 -285.743922)
			(xy 119.050378 -285.736103) (xy 119.002846 -285.720659) (xy 118.958314 -285.697969) (xy 118.917881 -285.668593)
			(xy 118.882541 -285.633253) (xy 118.853165 -285.59282) (xy 118.830475 -285.548288) (xy 118.815031 -285.500756)
			(xy 118.807212 -285.451393) (xy 118.502194 -285.451393) (xy 118.494375 -285.500756) (xy 118.478931 -285.548288)
			(xy 118.456241 -285.59282) (xy 118.426865 -285.633253) (xy 118.391525 -285.668593) (xy 118.351092 -285.697969)
			(xy 118.30656 -285.720659) (xy 118.259028 -285.736103) (xy 118.209665 -285.743922) (xy 118.159687 -285.743922)
			(xy 118.110324 -285.736103) (xy 118.062792 -285.720659) (xy 118.01826 -285.697969) (xy 117.977827 -285.668593)
			(xy 117.942487 -285.633253) (xy 117.913111 -285.59282) (xy 117.890421 -285.548288) (xy 117.874977 -285.500756)
			(xy 117.867158 -285.451393) (xy 117.56214 -285.451393) (xy 117.554321 -285.500756) (xy 117.538877 -285.548288)
			(xy 117.516187 -285.59282) (xy 117.486811 -285.633253) (xy 117.451471 -285.668593) (xy 117.411038 -285.697969)
			(xy 117.366506 -285.720659) (xy 117.318974 -285.736103) (xy 117.269611 -285.743922) (xy 117.219633 -285.743922)
			(xy 117.17027 -285.736103) (xy 117.122738 -285.720659) (xy 117.078206 -285.697969) (xy 117.037773 -285.668593)
			(xy 117.002433 -285.633253) (xy 116.973057 -285.59282) (xy 116.950367 -285.548288) (xy 116.934923 -285.500756)
			(xy 116.927104 -285.451393) (xy 116.62234 -285.451393) (xy 116.614521 -285.500756) (xy 116.599077 -285.548288)
			(xy 116.576387 -285.59282) (xy 116.547011 -285.633253) (xy 116.511671 -285.668593) (xy 116.471238 -285.697969)
			(xy 116.426706 -285.720659) (xy 116.379174 -285.736103) (xy 116.329811 -285.743922) (xy 116.279833 -285.743922)
			(xy 116.23047 -285.736103) (xy 116.182938 -285.720659) (xy 116.138406 -285.697969) (xy 116.097973 -285.668593)
			(xy 116.062633 -285.633253) (xy 116.033257 -285.59282) (xy 116.010567 -285.548288) (xy 115.995123 -285.500756)
			(xy 115.987304 -285.451393) (xy 115.679987 -285.451393) (xy 115.679978 -285.45185) (xy 115.671814 -285.502084)
			(xy 115.655698 -285.550358) (xy 115.632047 -285.595421) (xy 115.601474 -285.636107) (xy 115.56477 -285.671362)
			(xy 115.522886 -285.700272) (xy 115.476907 -285.722089) (xy 115.428023 -285.736249) (xy 115.377502 -285.742383)
			(xy 115.32665 -285.740334) (xy 115.276786 -285.730154) (xy 115.2292 -285.712107) (xy 115.185126 -285.686661)
			(xy 115.145704 -285.654474) (xy 115.111956 -285.61638) (xy 115.084755 -285.573366) (xy 115.064807 -285.526546)
			(xy 115.052628 -285.477132) (xy 115.048533 -285.426404) (xy 114.740436 -285.426404) (xy 114.739924 -285.45185)
			(xy 114.73176 -285.502084) (xy 114.715644 -285.550358) (xy 114.691993 -285.595421) (xy 114.66142 -285.636107)
			(xy 114.624716 -285.671362) (xy 114.582832 -285.700272) (xy 114.536853 -285.722089) (xy 114.487969 -285.736249)
			(xy 114.437448 -285.742383) (xy 114.386596 -285.740334) (xy 114.336732 -285.730154) (xy 114.289146 -285.712107)
			(xy 114.245072 -285.686661) (xy 114.20565 -285.654474) (xy 114.171902 -285.61638) (xy 114.144701 -285.573366)
			(xy 114.124753 -285.526546) (xy 114.112574 -285.477132) (xy 114.108479 -285.426404) (xy 113.802668 -285.426404)
			(xy 113.802178 -285.451393) (xy 113.794359 -285.500756) (xy 113.778915 -285.548288) (xy 113.756225 -285.59282)
			(xy 113.726849 -285.633253) (xy 113.691509 -285.668593) (xy 113.651076 -285.697969) (xy 113.606544 -285.720659)
			(xy 113.559012 -285.736103) (xy 113.509649 -285.743922) (xy 113.459671 -285.743922) (xy 113.410308 -285.736103)
			(xy 113.362776 -285.720659) (xy 113.318244 -285.697969) (xy 113.277811 -285.668593) (xy 113.242471 -285.633253)
			(xy 113.213095 -285.59282) (xy 113.190405 -285.548288) (xy 113.174961 -285.500756) (xy 113.167142 -285.451393)
			(xy 110.98862 -285.451393) (xy 110.980801 -285.500756) (xy 110.965357 -285.548288) (xy 110.942667 -285.59282)
			(xy 110.913291 -285.633253) (xy 110.877951 -285.668593) (xy 110.837518 -285.697969) (xy 110.792986 -285.720659)
			(xy 110.745454 -285.736103) (xy 110.696091 -285.743922) (xy 110.646113 -285.743922) (xy 110.59675 -285.736103)
			(xy 110.549218 -285.720659) (xy 110.504686 -285.697969) (xy 110.464253 -285.668593) (xy 110.428913 -285.633253)
			(xy 110.399537 -285.59282) (xy 110.376847 -285.548288) (xy 110.361403 -285.500756) (xy 110.353584 -285.451393)
			(xy 110.046267 -285.451393) (xy 110.046258 -285.45185) (xy 110.038094 -285.502084) (xy 110.021978 -285.550358)
			(xy 109.998327 -285.595421) (xy 109.967754 -285.636107) (xy 109.93105 -285.671362) (xy 109.889166 -285.700272)
			(xy 109.843187 -285.722089) (xy 109.794303 -285.736249) (xy 109.743782 -285.742383) (xy 109.69293 -285.740334)
			(xy 109.643066 -285.730154) (xy 109.59548 -285.712107) (xy 109.551406 -285.686661) (xy 109.511984 -285.654474)
			(xy 109.478236 -285.61638) (xy 109.451035 -285.573366) (xy 109.431087 -285.526546) (xy 109.418908 -285.477132)
			(xy 109.414813 -285.426404) (xy 109.106716 -285.426404) (xy 109.106204 -285.45185) (xy 109.09804 -285.502084)
			(xy 109.081924 -285.550358) (xy 109.058273 -285.595421) (xy 109.0277 -285.636107) (xy 108.990996 -285.671362)
			(xy 108.949112 -285.700272) (xy 108.903133 -285.722089) (xy 108.854249 -285.736249) (xy 108.803728 -285.742383)
			(xy 108.752876 -285.740334) (xy 108.703012 -285.730154) (xy 108.655426 -285.712107) (xy 108.611352 -285.686661)
			(xy 108.57193 -285.654474) (xy 108.538182 -285.61638) (xy 108.510981 -285.573366) (xy 108.491033 -285.526546)
			(xy 108.478854 -285.477132) (xy 108.474759 -285.426404) (xy 108.168948 -285.426404) (xy 108.168458 -285.451393)
			(xy 108.160639 -285.500756) (xy 108.145195 -285.548288) (xy 108.122505 -285.59282) (xy 108.093129 -285.633253)
			(xy 108.057789 -285.668593) (xy 108.017356 -285.697969) (xy 107.972824 -285.720659) (xy 107.925292 -285.736103)
			(xy 107.875929 -285.743922) (xy 107.825951 -285.743922) (xy 107.776588 -285.736103) (xy 107.729056 -285.720659)
			(xy 107.684524 -285.697969) (xy 107.644091 -285.668593) (xy 107.608751 -285.633253) (xy 107.579375 -285.59282)
			(xy 107.556685 -285.548288) (xy 107.541241 -285.500756) (xy 107.533422 -285.451393) (xy 107.228658 -285.451393)
			(xy 107.220839 -285.500756) (xy 107.205395 -285.548288) (xy 107.182705 -285.59282) (xy 107.153329 -285.633253)
			(xy 107.117989 -285.668593) (xy 107.077556 -285.697969) (xy 107.033024 -285.720659) (xy 106.985492 -285.736103)
			(xy 106.936129 -285.743922) (xy 106.886151 -285.743922) (xy 106.836788 -285.736103) (xy 106.789256 -285.720659)
			(xy 106.744724 -285.697969) (xy 106.704291 -285.668593) (xy 106.668951 -285.633253) (xy 106.639575 -285.59282)
			(xy 106.616885 -285.548288) (xy 106.601441 -285.500756) (xy 106.593622 -285.451393) (xy 106.288604 -285.451393)
			(xy 106.280785 -285.500756) (xy 106.265341 -285.548288) (xy 106.242651 -285.59282) (xy 106.213275 -285.633253)
			(xy 106.177935 -285.668593) (xy 106.137502 -285.697969) (xy 106.09297 -285.720659) (xy 106.045438 -285.736103)
			(xy 105.996075 -285.743922) (xy 105.946097 -285.743922) (xy 105.896734 -285.736103) (xy 105.849202 -285.720659)
			(xy 105.80467 -285.697969) (xy 105.764237 -285.668593) (xy 105.728897 -285.633253) (xy 105.699521 -285.59282)
			(xy 105.676831 -285.548288) (xy 105.661387 -285.500756) (xy 105.653568 -285.451393) (xy 105.34855 -285.451393)
			(xy 105.340731 -285.500756) (xy 105.325287 -285.548288) (xy 105.302597 -285.59282) (xy 105.273221 -285.633253)
			(xy 105.237881 -285.668593) (xy 105.197448 -285.697969) (xy 105.152916 -285.720659) (xy 105.105384 -285.736103)
			(xy 105.056021 -285.743922) (xy 105.006043 -285.743922) (xy 104.95668 -285.736103) (xy 104.909148 -285.720659)
			(xy 104.864616 -285.697969) (xy 104.824183 -285.668593) (xy 104.788843 -285.633253) (xy 104.759467 -285.59282)
			(xy 104.736777 -285.548288) (xy 104.721333 -285.500756) (xy 104.713514 -285.451393) (xy 104.408496 -285.451393)
			(xy 104.400677 -285.500756) (xy 104.385233 -285.548288) (xy 104.362543 -285.59282) (xy 104.333167 -285.633253)
			(xy 104.297827 -285.668593) (xy 104.257394 -285.697969) (xy 104.212862 -285.720659) (xy 104.16533 -285.736103)
			(xy 104.115967 -285.743922) (xy 104.065989 -285.743922) (xy 104.016626 -285.736103) (xy 103.969094 -285.720659)
			(xy 103.924562 -285.697969) (xy 103.884129 -285.668593) (xy 103.848789 -285.633253) (xy 103.819413 -285.59282)
			(xy 103.796723 -285.548288) (xy 103.781279 -285.500756) (xy 103.77346 -285.451393) (xy 103.468696 -285.451393)
			(xy 103.460877 -285.500756) (xy 103.445433 -285.548288) (xy 103.422743 -285.59282) (xy 103.393367 -285.633253)
			(xy 103.358027 -285.668593) (xy 103.317594 -285.697969) (xy 103.273062 -285.720659) (xy 103.22553 -285.736103)
			(xy 103.176167 -285.743922) (xy 103.126189 -285.743922) (xy 103.076826 -285.736103) (xy 103.029294 -285.720659)
			(xy 102.984762 -285.697969) (xy 102.944329 -285.668593) (xy 102.908989 -285.633253) (xy 102.879613 -285.59282)
			(xy 102.856923 -285.548288) (xy 102.841479 -285.500756) (xy 102.83366 -285.451393) (xy 102.528642 -285.451393)
			(xy 102.520823 -285.500756) (xy 102.505379 -285.548288) (xy 102.482689 -285.59282) (xy 102.453313 -285.633253)
			(xy 102.417973 -285.668593) (xy 102.37754 -285.697969) (xy 102.333008 -285.720659) (xy 102.285476 -285.736103)
			(xy 102.236113 -285.743922) (xy 102.186135 -285.743922) (xy 102.136772 -285.736103) (xy 102.08924 -285.720659)
			(xy 102.044708 -285.697969) (xy 102.004275 -285.668593) (xy 101.968935 -285.633253) (xy 101.939559 -285.59282)
			(xy 101.916869 -285.548288) (xy 101.901425 -285.500756) (xy 101.893606 -285.451393) (xy 101.588588 -285.451393)
			(xy 101.580769 -285.500756) (xy 101.565325 -285.548288) (xy 101.542635 -285.59282) (xy 101.513259 -285.633253)
			(xy 101.477919 -285.668593) (xy 101.437486 -285.697969) (xy 101.392954 -285.720659) (xy 101.345422 -285.736103)
			(xy 101.296059 -285.743922) (xy 101.246081 -285.743922) (xy 101.196718 -285.736103) (xy 101.149186 -285.720659)
			(xy 101.104654 -285.697969) (xy 101.064221 -285.668593) (xy 101.028881 -285.633253) (xy 100.999505 -285.59282)
			(xy 100.976815 -285.548288) (xy 100.961371 -285.500756) (xy 100.953552 -285.451393) (xy 100.648534 -285.451393)
			(xy 100.640715 -285.500756) (xy 100.625271 -285.548288) (xy 100.602581 -285.59282) (xy 100.573205 -285.633253)
			(xy 100.537865 -285.668593) (xy 100.497432 -285.697969) (xy 100.4529 -285.720659) (xy 100.405368 -285.736103)
			(xy 100.356005 -285.743922) (xy 100.306027 -285.743922) (xy 100.256664 -285.736103) (xy 100.209132 -285.720659)
			(xy 100.1646 -285.697969) (xy 100.124167 -285.668593) (xy 100.088827 -285.633253) (xy 100.059451 -285.59282)
			(xy 100.036761 -285.548288) (xy 100.021317 -285.500756) (xy 100.013498 -285.451393) (xy 99.70848 -285.451393)
			(xy 99.700661 -285.500756) (xy 99.685217 -285.548288) (xy 99.662527 -285.59282) (xy 99.633151 -285.633253)
			(xy 99.597811 -285.668593) (xy 99.557378 -285.697969) (xy 99.512846 -285.720659) (xy 99.465314 -285.736103)
			(xy 99.415951 -285.743922) (xy 99.365973 -285.743922) (xy 99.31661 -285.736103) (xy 99.269078 -285.720659)
			(xy 99.224546 -285.697969) (xy 99.184113 -285.668593) (xy 99.148773 -285.633253) (xy 99.119397 -285.59282)
			(xy 99.096707 -285.548288) (xy 99.081263 -285.500756) (xy 99.073444 -285.451393) (xy 98.76868 -285.451393)
			(xy 98.760861 -285.500756) (xy 98.745417 -285.548288) (xy 98.722727 -285.59282) (xy 98.693351 -285.633253)
			(xy 98.658011 -285.668593) (xy 98.617578 -285.697969) (xy 98.573046 -285.720659) (xy 98.525514 -285.736103)
			(xy 98.476151 -285.743922) (xy 98.426173 -285.743922) (xy 98.37681 -285.736103) (xy 98.329278 -285.720659)
			(xy 98.284746 -285.697969) (xy 98.244313 -285.668593) (xy 98.208973 -285.633253) (xy 98.179597 -285.59282)
			(xy 98.156907 -285.548288) (xy 98.141463 -285.500756) (xy 98.133644 -285.451393) (xy 97.828626 -285.451393)
			(xy 97.820807 -285.500756) (xy 97.805363 -285.548288) (xy 97.782673 -285.59282) (xy 97.753297 -285.633253)
			(xy 97.717957 -285.668593) (xy 97.677524 -285.697969) (xy 97.632992 -285.720659) (xy 97.58546 -285.736103)
			(xy 97.536097 -285.743922) (xy 97.486119 -285.743922) (xy 97.436756 -285.736103) (xy 97.389224 -285.720659)
			(xy 97.344692 -285.697969) (xy 97.304259 -285.668593) (xy 97.268919 -285.633253) (xy 97.239543 -285.59282)
			(xy 97.216853 -285.548288) (xy 97.201409 -285.500756) (xy 97.19359 -285.451393) (xy 96.888572 -285.451393)
			(xy 96.880753 -285.500756) (xy 96.865309 -285.548288) (xy 96.842619 -285.59282) (xy 96.813243 -285.633253)
			(xy 96.777903 -285.668593) (xy 96.73747 -285.697969) (xy 96.692938 -285.720659) (xy 96.645406 -285.736103)
			(xy 96.596043 -285.743922) (xy 96.546065 -285.743922) (xy 96.496702 -285.736103) (xy 96.44917 -285.720659)
			(xy 96.404638 -285.697969) (xy 96.364205 -285.668593) (xy 96.328865 -285.633253) (xy 96.299489 -285.59282)
			(xy 96.276799 -285.548288) (xy 96.261355 -285.500756) (xy 96.253536 -285.451393) (xy 95.946219 -285.451393)
			(xy 95.94621 -285.45185) (xy 95.938046 -285.502084) (xy 95.92193 -285.550358) (xy 95.898279 -285.595421)
			(xy 95.867706 -285.636107) (xy 95.831002 -285.671362) (xy 95.789118 -285.700272) (xy 95.743139 -285.722089)
			(xy 95.694255 -285.736249) (xy 95.643734 -285.742383) (xy 95.592882 -285.740334) (xy 95.543018 -285.730154)
			(xy 95.495432 -285.712107) (xy 95.451358 -285.686661) (xy 95.411936 -285.654474) (xy 95.378188 -285.61638)
			(xy 95.350987 -285.573366) (xy 95.331039 -285.526546) (xy 95.31886 -285.477132) (xy 95.314765 -285.426404)
			(xy 95.006668 -285.426404) (xy 95.006156 -285.45185) (xy 94.997992 -285.502084) (xy 94.981876 -285.550358)
			(xy 94.958225 -285.595421) (xy 94.927652 -285.636107) (xy 94.890948 -285.671362) (xy 94.849064 -285.700272)
			(xy 94.803085 -285.722089) (xy 94.754201 -285.736249) (xy 94.70368 -285.742383) (xy 94.652828 -285.740334)
			(xy 94.602964 -285.730154) (xy 94.555378 -285.712107) (xy 94.511304 -285.686661) (xy 94.471882 -285.654474)
			(xy 94.438134 -285.61638) (xy 94.410933 -285.573366) (xy 94.390985 -285.526546) (xy 94.378806 -285.477132)
			(xy 94.374711 -285.426404) (xy 94.069154 -285.426404) (xy 94.068664 -285.451393) (xy 94.060845 -285.500756)
			(xy 94.045401 -285.548288) (xy 94.022711 -285.59282) (xy 93.993335 -285.633253) (xy 93.957995 -285.668593)
			(xy 93.917562 -285.697969) (xy 93.87303 -285.720659) (xy 93.825498 -285.736103) (xy 93.776135 -285.743922)
			(xy 93.726157 -285.743922) (xy 93.676794 -285.736103) (xy 93.629262 -285.720659) (xy 93.58473 -285.697969)
			(xy 93.544297 -285.668593) (xy 93.508957 -285.633253) (xy 93.479581 -285.59282) (xy 93.456891 -285.548288)
			(xy 93.441447 -285.500756) (xy 93.433628 -285.451393) (xy 93.126311 -285.451393) (xy 93.126302 -285.45185)
			(xy 93.118138 -285.502084) (xy 93.102022 -285.550358) (xy 93.078371 -285.595421) (xy 93.047798 -285.636107)
			(xy 93.011094 -285.671362) (xy 92.96921 -285.700272) (xy 92.923231 -285.722089) (xy 92.874347 -285.736249)
			(xy 92.823826 -285.742383) (xy 92.772974 -285.740334) (xy 92.72311 -285.730154) (xy 92.675524 -285.712107)
			(xy 92.63145 -285.686661) (xy 92.592028 -285.654474) (xy 92.55828 -285.61638) (xy 92.531079 -285.573366)
			(xy 92.511131 -285.526546) (xy 92.498952 -285.477132) (xy 92.494857 -285.426404) (xy 92.188471 -285.426404)
			(xy 92.188471 -285.452183) (xy 92.18015 -285.503072) (xy 92.163727 -285.551951) (xy 92.139633 -285.59754)
			(xy 92.108497 -285.638644) (xy 92.071138 -285.674185) (xy 92.028533 -285.703232) (xy 91.981799 -285.725024)
			(xy 91.932161 -285.738989) (xy 91.906598 -285.74238) (xy 91.88704 -285.744666) (xy 91.861386 -285.773368)
			(xy 91.861386 -286.23641) (xy 92.024703 -286.23641) (xy 92.028798 -286.185682) (xy 92.040977 -286.136268)
			(xy 92.060925 -286.089448) (xy 92.088126 -286.046434) (xy 92.121874 -286.00834) (xy 92.161296 -285.976153)
			(xy 92.20537 -285.950707) (xy 92.252956 -285.93266) (xy 92.30282 -285.92248) (xy 92.353672 -285.920431)
			(xy 92.404193 -285.926565) (xy 92.453077 -285.940725) (xy 92.499056 -285.962542) (xy 92.54094 -285.991452)
			(xy 92.577644 -286.026707) (xy 92.608217 -286.067393) (xy 92.631868 -286.112456) (xy 92.647984 -286.16073)
			(xy 92.656148 -286.210964) (xy 92.65666 -286.23641) (xy 92.656157 -286.261399) (xy 92.963474 -286.261399)
			(xy 92.963474 -286.211421) (xy 92.971293 -286.162058) (xy 92.986737 -286.114526) (xy 93.009427 -286.069994)
			(xy 93.038803 -286.029561) (xy 93.074143 -285.994221) (xy 93.114576 -285.964845) (xy 93.159108 -285.942155)
			(xy 93.20664 -285.926711) (xy 93.256003 -285.918892) (xy 93.305981 -285.918892) (xy 93.355344 -285.926711)
			(xy 93.402876 -285.942155) (xy 93.447408 -285.964845) (xy 93.487841 -285.994221) (xy 93.523181 -286.029561)
			(xy 93.552557 -286.069994) (xy 93.575247 -286.114526) (xy 93.590691 -286.162058) (xy 93.59851 -286.211421)
			(xy 93.599 -286.23641) (xy 93.904811 -286.23641) (xy 93.908906 -286.185682) (xy 93.921085 -286.136268)
			(xy 93.941033 -286.089448) (xy 93.968234 -286.046434) (xy 94.001982 -286.00834) (xy 94.041404 -285.976153)
			(xy 94.085478 -285.950707) (xy 94.133064 -285.93266) (xy 94.182928 -285.92248) (xy 94.23378 -285.920431)
			(xy 94.284301 -285.926565) (xy 94.333185 -285.940725) (xy 94.379164 -285.962542) (xy 94.421048 -285.991452)
			(xy 94.457752 -286.026707) (xy 94.488325 -286.067393) (xy 94.511976 -286.112456) (xy 94.528092 -286.16073)
			(xy 94.536256 -286.210964) (xy 94.536768 -286.23641) (xy 94.536265 -286.261399) (xy 94.843582 -286.261399)
			(xy 94.843582 -286.211421) (xy 94.851401 -286.162058) (xy 94.866845 -286.114526) (xy 94.889535 -286.069994)
			(xy 94.918911 -286.029561) (xy 94.954251 -285.994221) (xy 94.994684 -285.964845) (xy 95.039216 -285.942155)
			(xy 95.086748 -285.926711) (xy 95.136111 -285.918892) (xy 95.186089 -285.918892) (xy 95.235452 -285.926711)
			(xy 95.282984 -285.942155) (xy 95.327516 -285.964845) (xy 95.367949 -285.994221) (xy 95.403289 -286.029561)
			(xy 95.432665 -286.069994) (xy 95.455355 -286.114526) (xy 95.470799 -286.162058) (xy 95.478618 -286.211421)
			(xy 95.479108 -286.23641) (xy 95.784919 -286.23641) (xy 95.789014 -286.185682) (xy 95.801193 -286.136268)
			(xy 95.821141 -286.089448) (xy 95.848342 -286.046434) (xy 95.88209 -286.00834) (xy 95.921512 -285.976153)
			(xy 95.965586 -285.950707) (xy 96.013172 -285.93266) (xy 96.063036 -285.92248) (xy 96.113888 -285.920431)
			(xy 96.164409 -285.926565) (xy 96.213293 -285.940725) (xy 96.259272 -285.962542) (xy 96.301156 -285.991452)
			(xy 96.33786 -286.026707) (xy 96.368433 -286.067393) (xy 96.392084 -286.112456) (xy 96.4082 -286.16073)
			(xy 96.416364 -286.210964) (xy 96.416876 -286.23641) (xy 96.416373 -286.261399) (xy 96.723436 -286.261399)
			(xy 96.723436 -286.211421) (xy 96.731255 -286.162058) (xy 96.746699 -286.114526) (xy 96.769389 -286.069994)
			(xy 96.798765 -286.029561) (xy 96.834105 -285.994221) (xy 96.874538 -285.964845) (xy 96.91907 -285.942155)
			(xy 96.966602 -285.926711) (xy 97.015965 -285.918892) (xy 97.065943 -285.918892) (xy 97.115306 -285.926711)
			(xy 97.162838 -285.942155) (xy 97.20737 -285.964845) (xy 97.247803 -285.994221) (xy 97.283143 -286.029561)
			(xy 97.312519 -286.069994) (xy 97.335209 -286.114526) (xy 97.350653 -286.162058) (xy 97.358472 -286.211421)
			(xy 97.358962 -286.23641) (xy 97.664773 -286.23641) (xy 97.668868 -286.185682) (xy 97.681047 -286.136268)
			(xy 97.700995 -286.089448) (xy 97.728196 -286.046434) (xy 97.761944 -286.00834) (xy 97.801366 -285.976153)
			(xy 97.84544 -285.950707) (xy 97.893026 -285.93266) (xy 97.94289 -285.92248) (xy 97.993742 -285.920431)
			(xy 98.044263 -285.926565) (xy 98.093147 -285.940725) (xy 98.139126 -285.962542) (xy 98.18101 -285.991452)
			(xy 98.217714 -286.026707) (xy 98.248287 -286.067393) (xy 98.271938 -286.112456) (xy 98.288054 -286.16073)
			(xy 98.296218 -286.210964) (xy 98.29673 -286.23641) (xy 98.604827 -286.23641) (xy 98.608922 -286.185682)
			(xy 98.621101 -286.136268) (xy 98.641049 -286.089448) (xy 98.66825 -286.046434) (xy 98.701998 -286.00834)
			(xy 98.74142 -285.976153) (xy 98.785494 -285.950707) (xy 98.83308 -285.93266) (xy 98.882944 -285.92248)
			(xy 98.933796 -285.920431) (xy 98.984317 -285.926565) (xy 99.033201 -285.940725) (xy 99.07918 -285.962542)
			(xy 99.121064 -285.991452) (xy 99.157768 -286.026707) (xy 99.188341 -286.067393) (xy 99.211992 -286.112456)
			(xy 99.228108 -286.16073) (xy 99.236272 -286.210964) (xy 99.236784 -286.23641) (xy 99.236281 -286.261399)
			(xy 99.543598 -286.261399) (xy 99.543598 -286.211421) (xy 99.551417 -286.162058) (xy 99.566861 -286.114526)
			(xy 99.589551 -286.069994) (xy 99.618927 -286.029561) (xy 99.654267 -285.994221) (xy 99.6947 -285.964845)
			(xy 99.739232 -285.942155) (xy 99.786764 -285.926711) (xy 99.836127 -285.918892) (xy 99.886105 -285.918892)
			(xy 99.935468 -285.926711) (xy 99.983 -285.942155) (xy 100.027532 -285.964845) (xy 100.067965 -285.994221)
			(xy 100.103305 -286.029561) (xy 100.132681 -286.069994) (xy 100.155371 -286.114526) (xy 100.170815 -286.162058)
			(xy 100.178634 -286.211421) (xy 100.179124 -286.23641) (xy 100.484935 -286.23641) (xy 100.48903 -286.185682)
			(xy 100.501209 -286.136268) (xy 100.521157 -286.089448) (xy 100.548358 -286.046434) (xy 100.582106 -286.00834)
			(xy 100.621528 -285.976153) (xy 100.665602 -285.950707) (xy 100.713188 -285.93266) (xy 100.763052 -285.92248)
			(xy 100.813904 -285.920431) (xy 100.864425 -285.926565) (xy 100.913309 -285.940725) (xy 100.959288 -285.962542)
			(xy 101.001172 -285.991452) (xy 101.037876 -286.026707) (xy 101.068449 -286.067393) (xy 101.0921 -286.112456)
			(xy 101.108216 -286.16073) (xy 101.11638 -286.210964) (xy 101.116892 -286.23641) (xy 101.424735 -286.23641)
			(xy 101.42883 -286.185682) (xy 101.441009 -286.136268) (xy 101.460957 -286.089448) (xy 101.488158 -286.046434)
			(xy 101.521906 -286.00834) (xy 101.561328 -285.976153) (xy 101.605402 -285.950707) (xy 101.652988 -285.93266)
			(xy 101.702852 -285.92248) (xy 101.753704 -285.920431) (xy 101.804225 -285.926565) (xy 101.853109 -285.940725)
			(xy 101.899088 -285.962542) (xy 101.940972 -285.991452) (xy 101.977676 -286.026707) (xy 102.008249 -286.067393)
			(xy 102.0319 -286.112456) (xy 102.048016 -286.16073) (xy 102.05618 -286.210964) (xy 102.056692 -286.23641)
			(xy 102.056189 -286.261399) (xy 102.363506 -286.261399) (xy 102.363506 -286.211421) (xy 102.371325 -286.162058)
			(xy 102.386769 -286.114526) (xy 102.409459 -286.069994) (xy 102.438835 -286.029561) (xy 102.474175 -285.994221)
			(xy 102.514608 -285.964845) (xy 102.55914 -285.942155) (xy 102.606672 -285.926711) (xy 102.656035 -285.918892)
			(xy 102.706013 -285.918892) (xy 102.755376 -285.926711) (xy 102.802908 -285.942155) (xy 102.84744 -285.964845)
			(xy 102.887873 -285.994221) (xy 102.923213 -286.029561) (xy 102.952589 -286.069994) (xy 102.975279 -286.114526)
			(xy 102.990723 -286.162058) (xy 102.998542 -286.211421) (xy 102.999032 -286.23641) (xy 103.304843 -286.23641)
			(xy 103.308938 -286.185682) (xy 103.321117 -286.136268) (xy 103.341065 -286.089448) (xy 103.368266 -286.046434)
			(xy 103.402014 -286.00834) (xy 103.441436 -285.976153) (xy 103.48551 -285.950707) (xy 103.533096 -285.93266)
			(xy 103.58296 -285.92248) (xy 103.633812 -285.920431) (xy 103.684333 -285.926565) (xy 103.733217 -285.940725)
			(xy 103.779196 -285.962542) (xy 103.82108 -285.991452) (xy 103.857784 -286.026707) (xy 103.888357 -286.067393)
			(xy 103.912008 -286.112456) (xy 103.928124 -286.16073) (xy 103.936288 -286.210964) (xy 103.9368 -286.23641)
			(xy 104.244897 -286.23641) (xy 104.248992 -286.185682) (xy 104.261171 -286.136268) (xy 104.281119 -286.089448)
			(xy 104.30832 -286.046434) (xy 104.342068 -286.00834) (xy 104.38149 -285.976153) (xy 104.425564 -285.950707)
			(xy 104.47315 -285.93266) (xy 104.523014 -285.92248) (xy 104.573866 -285.920431) (xy 104.624387 -285.926565)
			(xy 104.673271 -285.940725) (xy 104.71925 -285.962542) (xy 104.761134 -285.991452) (xy 104.797838 -286.026707)
			(xy 104.828411 -286.067393) (xy 104.852062 -286.112456) (xy 104.868178 -286.16073) (xy 104.876342 -286.210964)
			(xy 104.876854 -286.23641) (xy 104.876351 -286.261399) (xy 105.183414 -286.261399) (xy 105.183414 -286.211421)
			(xy 105.191233 -286.162058) (xy 105.206677 -286.114526) (xy 105.229367 -286.069994) (xy 105.258743 -286.029561)
			(xy 105.294083 -285.994221) (xy 105.334516 -285.964845) (xy 105.379048 -285.942155) (xy 105.42658 -285.926711)
			(xy 105.475943 -285.918892) (xy 105.525921 -285.918892) (xy 105.575284 -285.926711) (xy 105.622816 -285.942155)
			(xy 105.667348 -285.964845) (xy 105.707781 -285.994221) (xy 105.743121 -286.029561) (xy 105.772497 -286.069994)
			(xy 105.795187 -286.114526) (xy 105.810631 -286.162058) (xy 105.81845 -286.211421) (xy 105.81894 -286.23641)
			(xy 106.124751 -286.23641) (xy 106.128846 -286.185682) (xy 106.141025 -286.136268) (xy 106.160973 -286.089448)
			(xy 106.188174 -286.046434) (xy 106.221922 -286.00834) (xy 106.261344 -285.976153) (xy 106.305418 -285.950707)
			(xy 106.353004 -285.93266) (xy 106.402868 -285.92248) (xy 106.45372 -285.920431) (xy 106.504241 -285.926565)
			(xy 106.553125 -285.940725) (xy 106.599104 -285.962542) (xy 106.640988 -285.991452) (xy 106.677692 -286.026707)
			(xy 106.708265 -286.067393) (xy 106.731916 -286.112456) (xy 106.748032 -286.16073) (xy 106.756196 -286.210964)
			(xy 106.756708 -286.23641) (xy 107.064805 -286.23641) (xy 107.0689 -286.185682) (xy 107.081079 -286.136268)
			(xy 107.101027 -286.089448) (xy 107.128228 -286.046434) (xy 107.161976 -286.00834) (xy 107.201398 -285.976153)
			(xy 107.245472 -285.950707) (xy 107.293058 -285.93266) (xy 107.342922 -285.92248) (xy 107.393774 -285.920431)
			(xy 107.444295 -285.926565) (xy 107.493179 -285.940725) (xy 107.539158 -285.962542) (xy 107.581042 -285.991452)
			(xy 107.617746 -286.026707) (xy 107.648319 -286.067393) (xy 107.67197 -286.112456) (xy 107.688086 -286.16073)
			(xy 107.69625 -286.210964) (xy 107.696762 -286.23641) (xy 107.696259 -286.261399) (xy 108.003576 -286.261399)
			(xy 108.003576 -286.211421) (xy 108.011395 -286.162058) (xy 108.026839 -286.114526) (xy 108.049529 -286.069994)
			(xy 108.078905 -286.029561) (xy 108.114245 -285.994221) (xy 108.154678 -285.964845) (xy 108.19921 -285.942155)
			(xy 108.246742 -285.926711) (xy 108.296105 -285.918892) (xy 108.346083 -285.918892) (xy 108.395446 -285.926711)
			(xy 108.442978 -285.942155) (xy 108.48751 -285.964845) (xy 108.527943 -285.994221) (xy 108.563283 -286.029561)
			(xy 108.592659 -286.069994) (xy 108.615349 -286.114526) (xy 108.630793 -286.162058) (xy 108.638612 -286.211421)
			(xy 108.639102 -286.23641) (xy 108.638612 -286.261399) (xy 115.51715 -286.261399) (xy 115.51715 -286.211421)
			(xy 115.524969 -286.162058) (xy 115.540413 -286.114526) (xy 115.563103 -286.069994) (xy 115.592479 -286.029561)
			(xy 115.627819 -285.994221) (xy 115.668252 -285.964845) (xy 115.712784 -285.942155) (xy 115.760316 -285.926711)
			(xy 115.809679 -285.918892) (xy 115.859657 -285.918892) (xy 115.90902 -285.926711) (xy 115.956552 -285.942155)
			(xy 116.001084 -285.964845) (xy 116.041517 -285.994221) (xy 116.076857 -286.029561) (xy 116.106233 -286.069994)
			(xy 116.128923 -286.114526) (xy 116.144367 -286.162058) (xy 116.152186 -286.211421) (xy 116.152676 -286.23641)
			(xy 116.458487 -286.23641) (xy 116.462582 -286.185682) (xy 116.474761 -286.136268) (xy 116.494709 -286.089448)
			(xy 116.52191 -286.046434) (xy 116.555658 -286.00834) (xy 116.59508 -285.976153) (xy 116.639154 -285.950707)
			(xy 116.68674 -285.93266) (xy 116.736604 -285.92248) (xy 116.787456 -285.920431) (xy 116.837977 -285.926565)
			(xy 116.886861 -285.940725) (xy 116.93284 -285.962542) (xy 116.974724 -285.991452) (xy 117.011428 -286.026707)
			(xy 117.042001 -286.067393) (xy 117.065652 -286.112456) (xy 117.081768 -286.16073) (xy 117.089932 -286.210964)
			(xy 117.090444 -286.23641) (xy 117.398541 -286.23641) (xy 117.402636 -286.185682) (xy 117.414815 -286.136268)
			(xy 117.434763 -286.089448) (xy 117.461964 -286.046434) (xy 117.495712 -286.00834) (xy 117.535134 -285.976153)
			(xy 117.579208 -285.950707) (xy 117.626794 -285.93266) (xy 117.676658 -285.92248) (xy 117.72751 -285.920431)
			(xy 117.778031 -285.926565) (xy 117.826915 -285.940725) (xy 117.872894 -285.962542) (xy 117.914778 -285.991452)
			(xy 117.951482 -286.026707) (xy 117.982055 -286.067393) (xy 118.005706 -286.112456) (xy 118.021822 -286.16073)
			(xy 118.029986 -286.210964) (xy 118.030498 -286.23641) (xy 118.029995 -286.261399) (xy 118.337312 -286.261399)
			(xy 118.337312 -286.211421) (xy 118.345131 -286.162058) (xy 118.360575 -286.114526) (xy 118.383265 -286.069994)
			(xy 118.412641 -286.029561) (xy 118.447981 -285.994221) (xy 118.488414 -285.964845) (xy 118.532946 -285.942155)
			(xy 118.580478 -285.926711) (xy 118.629841 -285.918892) (xy 118.679819 -285.918892) (xy 118.729182 -285.926711)
			(xy 118.776714 -285.942155) (xy 118.821246 -285.964845) (xy 118.861679 -285.994221) (xy 118.897019 -286.029561)
			(xy 118.926395 -286.069994) (xy 118.949085 -286.114526) (xy 118.964529 -286.162058) (xy 118.972348 -286.211421)
			(xy 118.972838 -286.23641) (xy 119.278395 -286.23641) (xy 119.28249 -286.185682) (xy 119.294669 -286.136268)
			(xy 119.314617 -286.089448) (xy 119.341818 -286.046434) (xy 119.375566 -286.00834) (xy 119.414988 -285.976153)
			(xy 119.459062 -285.950707) (xy 119.506648 -285.93266) (xy 119.556512 -285.92248) (xy 119.607364 -285.920431)
			(xy 119.657885 -285.926565) (xy 119.706769 -285.940725) (xy 119.752748 -285.962542) (xy 119.794632 -285.991452)
			(xy 119.831336 -286.026707) (xy 119.861909 -286.067393) (xy 119.88556 -286.112456) (xy 119.901676 -286.16073)
			(xy 119.90984 -286.210964) (xy 119.910352 -286.23641) (xy 120.218449 -286.23641) (xy 120.222544 -286.185682)
			(xy 120.234723 -286.136268) (xy 120.254671 -286.089448) (xy 120.281872 -286.046434) (xy 120.31562 -286.00834)
			(xy 120.355042 -285.976153) (xy 120.399116 -285.950707) (xy 120.446702 -285.93266) (xy 120.496566 -285.92248)
			(xy 120.547418 -285.920431) (xy 120.597939 -285.926565) (xy 120.646823 -285.940725) (xy 120.692802 -285.962542)
			(xy 120.734686 -285.991452) (xy 120.77139 -286.026707) (xy 120.801963 -286.067393) (xy 120.825614 -286.112456)
			(xy 120.84173 -286.16073) (xy 120.849894 -286.210964) (xy 120.850406 -286.23641) (xy 120.849903 -286.261399)
			(xy 121.15722 -286.261399) (xy 121.15722 -286.211421) (xy 121.165039 -286.162058) (xy 121.180483 -286.114526)
			(xy 121.203173 -286.069994) (xy 121.232549 -286.029561) (xy 121.267889 -285.994221) (xy 121.308322 -285.964845)
			(xy 121.352854 -285.942155) (xy 121.400386 -285.926711) (xy 121.449749 -285.918892) (xy 121.499727 -285.918892)
			(xy 121.54909 -285.926711) (xy 121.596622 -285.942155) (xy 121.641154 -285.964845) (xy 121.681587 -285.994221)
			(xy 121.716927 -286.029561) (xy 121.746303 -286.069994) (xy 121.768993 -286.114526) (xy 121.784437 -286.162058)
			(xy 121.792256 -286.211421) (xy 121.792746 -286.23641) (xy 122.098557 -286.23641) (xy 122.102652 -286.185682)
			(xy 122.114831 -286.136268) (xy 122.134779 -286.089448) (xy 122.16198 -286.046434) (xy 122.195728 -286.00834)
			(xy 122.23515 -285.976153) (xy 122.279224 -285.950707) (xy 122.32681 -285.93266) (xy 122.376674 -285.92248)
			(xy 122.427526 -285.920431) (xy 122.478047 -285.926565) (xy 122.526931 -285.940725) (xy 122.57291 -285.962542)
			(xy 122.614794 -285.991452) (xy 122.651498 -286.026707) (xy 122.682071 -286.067393) (xy 122.705722 -286.112456)
			(xy 122.721838 -286.16073) (xy 122.730002 -286.210964) (xy 122.730514 -286.23641) (xy 123.038611 -286.23641)
			(xy 123.042706 -286.185682) (xy 123.054885 -286.136268) (xy 123.074833 -286.089448) (xy 123.102034 -286.046434)
			(xy 123.135782 -286.00834) (xy 123.175204 -285.976153) (xy 123.219278 -285.950707) (xy 123.266864 -285.93266)
			(xy 123.316728 -285.92248) (xy 123.36758 -285.920431) (xy 123.418101 -285.926565) (xy 123.466985 -285.940725)
			(xy 123.512964 -285.962542) (xy 123.554848 -285.991452) (xy 123.591552 -286.026707) (xy 123.622125 -286.067393)
			(xy 123.645776 -286.112456) (xy 123.661892 -286.16073) (xy 123.670056 -286.210964) (xy 123.670568 -286.23641)
			(xy 123.670065 -286.261399) (xy 123.977128 -286.261399) (xy 123.977128 -286.211421) (xy 123.984947 -286.162058)
			(xy 124.000391 -286.114526) (xy 124.023081 -286.069994) (xy 124.052457 -286.029561) (xy 124.087797 -285.994221)
			(xy 124.12823 -285.964845) (xy 124.172762 -285.942155) (xy 124.220294 -285.926711) (xy 124.269657 -285.918892)
			(xy 124.319635 -285.918892) (xy 124.368998 -285.926711) (xy 124.41653 -285.942155) (xy 124.461062 -285.964845)
			(xy 124.501495 -285.994221) (xy 124.536835 -286.029561) (xy 124.566211 -286.069994) (xy 124.588901 -286.114526)
			(xy 124.604345 -286.162058) (xy 124.612164 -286.211421) (xy 124.612654 -286.23641) (xy 124.918465 -286.23641)
			(xy 124.92256 -286.185682) (xy 124.934739 -286.136268) (xy 124.954687 -286.089448) (xy 124.981888 -286.046434)
			(xy 125.015636 -286.00834) (xy 125.055058 -285.976153) (xy 125.099132 -285.950707) (xy 125.146718 -285.93266)
			(xy 125.196582 -285.92248) (xy 125.247434 -285.920431) (xy 125.297955 -285.926565) (xy 125.346839 -285.940725)
			(xy 125.392818 -285.962542) (xy 125.434702 -285.991452) (xy 125.471406 -286.026707) (xy 125.501979 -286.067393)
			(xy 125.52563 -286.112456) (xy 125.541746 -286.16073) (xy 125.54991 -286.210964) (xy 125.550422 -286.23641)
			(xy 125.858519 -286.23641) (xy 125.862614 -286.185682) (xy 125.874793 -286.136268) (xy 125.894741 -286.089448)
			(xy 125.921942 -286.046434) (xy 125.95569 -286.00834) (xy 125.995112 -285.976153) (xy 126.039186 -285.950707)
			(xy 126.086772 -285.93266) (xy 126.136636 -285.92248) (xy 126.187488 -285.920431) (xy 126.238009 -285.926565)
			(xy 126.286893 -285.940725) (xy 126.332872 -285.962542) (xy 126.374756 -285.991452) (xy 126.41146 -286.026707)
			(xy 126.442033 -286.067393) (xy 126.465684 -286.112456) (xy 126.4818 -286.16073) (xy 126.489964 -286.210964)
			(xy 126.490476 -286.23641) (xy 126.489964 -286.261856) (xy 126.4818 -286.31209) (xy 126.465684 -286.360364)
			(xy 126.442033 -286.405427) (xy 126.41146 -286.446113) (xy 126.374756 -286.481368) (xy 126.332872 -286.510278)
			(xy 126.286893 -286.532095) (xy 126.238009 -286.546255) (xy 126.187488 -286.552389) (xy 126.136636 -286.55034)
			(xy 126.086772 -286.54016) (xy 126.039186 -286.522113) (xy 125.995112 -286.496667) (xy 125.95569 -286.46448)
			(xy 125.921942 -286.426386) (xy 125.894741 -286.383372) (xy 125.874793 -286.336552) (xy 125.862614 -286.287138)
			(xy 125.858519 -286.23641) (xy 125.550422 -286.23641) (xy 125.54991 -286.261856) (xy 125.541746 -286.31209)
			(xy 125.52563 -286.360364) (xy 125.501979 -286.405427) (xy 125.471406 -286.446113) (xy 125.434702 -286.481368)
			(xy 125.392818 -286.510278) (xy 125.346839 -286.532095) (xy 125.297955 -286.546255) (xy 125.247434 -286.552389)
			(xy 125.196582 -286.55034) (xy 125.146718 -286.54016) (xy 125.099132 -286.522113) (xy 125.055058 -286.496667)
			(xy 125.015636 -286.46448) (xy 124.981888 -286.426386) (xy 124.954687 -286.383372) (xy 124.934739 -286.336552)
			(xy 124.92256 -286.287138) (xy 124.918465 -286.23641) (xy 124.612654 -286.23641) (xy 124.612164 -286.261399)
			(xy 124.604345 -286.310762) (xy 124.588901 -286.358294) (xy 124.566211 -286.402826) (xy 124.536835 -286.443259)
			(xy 124.501495 -286.478599) (xy 124.461062 -286.507975) (xy 124.41653 -286.530665) (xy 124.368998 -286.546109)
			(xy 124.319635 -286.553928) (xy 124.269657 -286.553928) (xy 124.220294 -286.546109) (xy 124.172762 -286.530665)
			(xy 124.12823 -286.507975) (xy 124.087797 -286.478599) (xy 124.052457 -286.443259) (xy 124.023081 -286.402826)
			(xy 124.000391 -286.358294) (xy 123.984947 -286.310762) (xy 123.977128 -286.261399) (xy 123.670065 -286.261399)
			(xy 123.670056 -286.261856) (xy 123.661892 -286.31209) (xy 123.645776 -286.360364) (xy 123.622125 -286.405427)
			(xy 123.591552 -286.446113) (xy 123.554848 -286.481368) (xy 123.512964 -286.510278) (xy 123.466985 -286.532095)
			(xy 123.418101 -286.546255) (xy 123.36758 -286.552389) (xy 123.316728 -286.55034) (xy 123.266864 -286.54016)
			(xy 123.219278 -286.522113) (xy 123.175204 -286.496667) (xy 123.135782 -286.46448) (xy 123.102034 -286.426386)
			(xy 123.074833 -286.383372) (xy 123.054885 -286.336552) (xy 123.042706 -286.287138) (xy 123.038611 -286.23641)
			(xy 122.730514 -286.23641) (xy 122.730002 -286.261856) (xy 122.721838 -286.31209) (xy 122.705722 -286.360364)
			(xy 122.682071 -286.405427) (xy 122.651498 -286.446113) (xy 122.614794 -286.481368) (xy 122.57291 -286.510278)
			(xy 122.526931 -286.532095) (xy 122.478047 -286.546255) (xy 122.427526 -286.552389) (xy 122.376674 -286.55034)
			(xy 122.32681 -286.54016) (xy 122.279224 -286.522113) (xy 122.23515 -286.496667) (xy 122.195728 -286.46448)
			(xy 122.16198 -286.426386) (xy 122.134779 -286.383372) (xy 122.114831 -286.336552) (xy 122.102652 -286.287138)
			(xy 122.098557 -286.23641) (xy 121.792746 -286.23641) (xy 121.792256 -286.261399) (xy 121.784437 -286.310762)
			(xy 121.768993 -286.358294) (xy 121.746303 -286.402826) (xy 121.716927 -286.443259) (xy 121.681587 -286.478599)
			(xy 121.641154 -286.507975) (xy 121.596622 -286.530665) (xy 121.54909 -286.546109) (xy 121.499727 -286.553928)
			(xy 121.449749 -286.553928) (xy 121.400386 -286.546109) (xy 121.352854 -286.530665) (xy 121.308322 -286.507975)
			(xy 121.267889 -286.478599) (xy 121.232549 -286.443259) (xy 121.203173 -286.402826) (xy 121.180483 -286.358294)
			(xy 121.165039 -286.310762) (xy 121.15722 -286.261399) (xy 120.849903 -286.261399) (xy 120.849894 -286.261856)
			(xy 120.84173 -286.31209) (xy 120.825614 -286.360364) (xy 120.801963 -286.405427) (xy 120.77139 -286.446113)
			(xy 120.734686 -286.481368) (xy 120.692802 -286.510278) (xy 120.646823 -286.532095) (xy 120.597939 -286.546255)
			(xy 120.547418 -286.552389) (xy 120.496566 -286.55034) (xy 120.446702 -286.54016) (xy 120.399116 -286.522113)
			(xy 120.355042 -286.496667) (xy 120.31562 -286.46448) (xy 120.281872 -286.426386) (xy 120.254671 -286.383372)
			(xy 120.234723 -286.336552) (xy 120.222544 -286.287138) (xy 120.218449 -286.23641) (xy 119.910352 -286.23641)
			(xy 119.90984 -286.261856) (xy 119.901676 -286.31209) (xy 119.88556 -286.360364) (xy 119.861909 -286.405427)
			(xy 119.831336 -286.446113) (xy 119.794632 -286.481368) (xy 119.752748 -286.510278) (xy 119.706769 -286.532095)
			(xy 119.657885 -286.546255) (xy 119.607364 -286.552389) (xy 119.556512 -286.55034) (xy 119.506648 -286.54016)
			(xy 119.459062 -286.522113) (xy 119.414988 -286.496667) (xy 119.375566 -286.46448) (xy 119.341818 -286.426386)
			(xy 119.314617 -286.383372) (xy 119.294669 -286.336552) (xy 119.28249 -286.287138) (xy 119.278395 -286.23641)
			(xy 118.972838 -286.23641) (xy 118.972348 -286.261399) (xy 118.964529 -286.310762) (xy 118.949085 -286.358294)
			(xy 118.926395 -286.402826) (xy 118.897019 -286.443259) (xy 118.861679 -286.478599) (xy 118.821246 -286.507975)
			(xy 118.776714 -286.530665) (xy 118.729182 -286.546109) (xy 118.679819 -286.553928) (xy 118.629841 -286.553928)
			(xy 118.580478 -286.546109) (xy 118.532946 -286.530665) (xy 118.488414 -286.507975) (xy 118.447981 -286.478599)
			(xy 118.412641 -286.443259) (xy 118.383265 -286.402826) (xy 118.360575 -286.358294) (xy 118.345131 -286.310762)
			(xy 118.337312 -286.261399) (xy 118.029995 -286.261399) (xy 118.029986 -286.261856) (xy 118.021822 -286.31209)
			(xy 118.005706 -286.360364) (xy 117.982055 -286.405427) (xy 117.951482 -286.446113) (xy 117.914778 -286.481368)
			(xy 117.872894 -286.510278) (xy 117.826915 -286.532095) (xy 117.778031 -286.546255) (xy 117.72751 -286.552389)
			(xy 117.676658 -286.55034) (xy 117.626794 -286.54016) (xy 117.579208 -286.522113) (xy 117.535134 -286.496667)
			(xy 117.495712 -286.46448) (xy 117.461964 -286.426386) (xy 117.434763 -286.383372) (xy 117.414815 -286.336552)
			(xy 117.402636 -286.287138) (xy 117.398541 -286.23641) (xy 117.090444 -286.23641) (xy 117.089932 -286.261856)
			(xy 117.081768 -286.31209) (xy 117.065652 -286.360364) (xy 117.042001 -286.405427) (xy 117.011428 -286.446113)
			(xy 116.974724 -286.481368) (xy 116.93284 -286.510278) (xy 116.886861 -286.532095) (xy 116.837977 -286.546255)
			(xy 116.787456 -286.552389) (xy 116.736604 -286.55034) (xy 116.68674 -286.54016) (xy 116.639154 -286.522113)
			(xy 116.59508 -286.496667) (xy 116.555658 -286.46448) (xy 116.52191 -286.426386) (xy 116.494709 -286.383372)
			(xy 116.474761 -286.336552) (xy 116.462582 -286.287138) (xy 116.458487 -286.23641) (xy 116.152676 -286.23641)
			(xy 116.152186 -286.261399) (xy 116.144367 -286.310762) (xy 116.128923 -286.358294) (xy 116.106233 -286.402826)
			(xy 116.076857 -286.443259) (xy 116.041517 -286.478599) (xy 116.001084 -286.507975) (xy 115.956552 -286.530665)
			(xy 115.90902 -286.546109) (xy 115.859657 -286.553928) (xy 115.809679 -286.553928) (xy 115.760316 -286.546109)
			(xy 115.712784 -286.530665) (xy 115.668252 -286.507975) (xy 115.627819 -286.478599) (xy 115.592479 -286.443259)
			(xy 115.563103 -286.402826) (xy 115.540413 -286.358294) (xy 115.524969 -286.310762) (xy 115.51715 -286.261399)
			(xy 108.638612 -286.261399) (xy 108.630793 -286.310762) (xy 108.615349 -286.358294) (xy 108.592659 -286.402826)
			(xy 108.563283 -286.443259) (xy 108.527943 -286.478599) (xy 108.48751 -286.507975) (xy 108.442978 -286.530665)
			(xy 108.395446 -286.546109) (xy 108.346083 -286.553928) (xy 108.296105 -286.553928) (xy 108.246742 -286.546109)
			(xy 108.19921 -286.530665) (xy 108.154678 -286.507975) (xy 108.114245 -286.478599) (xy 108.078905 -286.443259)
			(xy 108.049529 -286.402826) (xy 108.026839 -286.358294) (xy 108.011395 -286.310762) (xy 108.003576 -286.261399)
			(xy 107.696259 -286.261399) (xy 107.69625 -286.261856) (xy 107.688086 -286.31209) (xy 107.67197 -286.360364)
			(xy 107.648319 -286.405427) (xy 107.617746 -286.446113) (xy 107.581042 -286.481368) (xy 107.539158 -286.510278)
			(xy 107.493179 -286.532095) (xy 107.444295 -286.546255) (xy 107.393774 -286.552389) (xy 107.342922 -286.55034)
			(xy 107.293058 -286.54016) (xy 107.245472 -286.522113) (xy 107.201398 -286.496667) (xy 107.161976 -286.46448)
			(xy 107.128228 -286.426386) (xy 107.101027 -286.383372) (xy 107.081079 -286.336552) (xy 107.0689 -286.287138)
			(xy 107.064805 -286.23641) (xy 106.756708 -286.23641) (xy 106.756196 -286.261856) (xy 106.748032 -286.31209)
			(xy 106.731916 -286.360364) (xy 106.708265 -286.405427) (xy 106.677692 -286.446113) (xy 106.640988 -286.481368)
			(xy 106.599104 -286.510278) (xy 106.553125 -286.532095) (xy 106.504241 -286.546255) (xy 106.45372 -286.552389)
			(xy 106.402868 -286.55034) (xy 106.353004 -286.54016) (xy 106.305418 -286.522113) (xy 106.261344 -286.496667)
			(xy 106.221922 -286.46448) (xy 106.188174 -286.426386) (xy 106.160973 -286.383372) (xy 106.141025 -286.336552)
			(xy 106.128846 -286.287138) (xy 106.124751 -286.23641) (xy 105.81894 -286.23641) (xy 105.81845 -286.261399)
			(xy 105.810631 -286.310762) (xy 105.795187 -286.358294) (xy 105.772497 -286.402826) (xy 105.743121 -286.443259)
			(xy 105.707781 -286.478599) (xy 105.667348 -286.507975) (xy 105.622816 -286.530665) (xy 105.575284 -286.546109)
			(xy 105.525921 -286.553928) (xy 105.475943 -286.553928) (xy 105.42658 -286.546109) (xy 105.379048 -286.530665)
			(xy 105.334516 -286.507975) (xy 105.294083 -286.478599) (xy 105.258743 -286.443259) (xy 105.229367 -286.402826)
			(xy 105.206677 -286.358294) (xy 105.191233 -286.310762) (xy 105.183414 -286.261399) (xy 104.876351 -286.261399)
			(xy 104.876342 -286.261856) (xy 104.868178 -286.31209) (xy 104.852062 -286.360364) (xy 104.828411 -286.405427)
			(xy 104.797838 -286.446113) (xy 104.761134 -286.481368) (xy 104.71925 -286.510278) (xy 104.673271 -286.532095)
			(xy 104.624387 -286.546255) (xy 104.573866 -286.552389) (xy 104.523014 -286.55034) (xy 104.47315 -286.54016)
			(xy 104.425564 -286.522113) (xy 104.38149 -286.496667) (xy 104.342068 -286.46448) (xy 104.30832 -286.426386)
			(xy 104.281119 -286.383372) (xy 104.261171 -286.336552) (xy 104.248992 -286.287138) (xy 104.244897 -286.23641)
			(xy 103.9368 -286.23641) (xy 103.936288 -286.261856) (xy 103.928124 -286.31209) (xy 103.912008 -286.360364)
			(xy 103.888357 -286.405427) (xy 103.857784 -286.446113) (xy 103.82108 -286.481368) (xy 103.779196 -286.510278)
			(xy 103.733217 -286.532095) (xy 103.684333 -286.546255) (xy 103.633812 -286.552389) (xy 103.58296 -286.55034)
			(xy 103.533096 -286.54016) (xy 103.48551 -286.522113) (xy 103.441436 -286.496667) (xy 103.402014 -286.46448)
			(xy 103.368266 -286.426386) (xy 103.341065 -286.383372) (xy 103.321117 -286.336552) (xy 103.308938 -286.287138)
			(xy 103.304843 -286.23641) (xy 102.999032 -286.23641) (xy 102.998542 -286.261399) (xy 102.990723 -286.310762)
			(xy 102.975279 -286.358294) (xy 102.952589 -286.402826) (xy 102.923213 -286.443259) (xy 102.887873 -286.478599)
			(xy 102.84744 -286.507975) (xy 102.802908 -286.530665) (xy 102.755376 -286.546109) (xy 102.706013 -286.553928)
			(xy 102.656035 -286.553928) (xy 102.606672 -286.546109) (xy 102.55914 -286.530665) (xy 102.514608 -286.507975)
			(xy 102.474175 -286.478599) (xy 102.438835 -286.443259) (xy 102.409459 -286.402826) (xy 102.386769 -286.358294)
			(xy 102.371325 -286.310762) (xy 102.363506 -286.261399) (xy 102.056189 -286.261399) (xy 102.05618 -286.261856)
			(xy 102.048016 -286.31209) (xy 102.0319 -286.360364) (xy 102.008249 -286.405427) (xy 101.977676 -286.446113)
			(xy 101.940972 -286.481368) (xy 101.899088 -286.510278) (xy 101.853109 -286.532095) (xy 101.804225 -286.546255)
			(xy 101.753704 -286.552389) (xy 101.702852 -286.55034) (xy 101.652988 -286.54016) (xy 101.605402 -286.522113)
			(xy 101.561328 -286.496667) (xy 101.521906 -286.46448) (xy 101.488158 -286.426386) (xy 101.460957 -286.383372)
			(xy 101.441009 -286.336552) (xy 101.42883 -286.287138) (xy 101.424735 -286.23641) (xy 101.116892 -286.23641)
			(xy 101.11638 -286.261856) (xy 101.108216 -286.31209) (xy 101.0921 -286.360364) (xy 101.068449 -286.405427)
			(xy 101.037876 -286.446113) (xy 101.001172 -286.481368) (xy 100.959288 -286.510278) (xy 100.913309 -286.532095)
			(xy 100.864425 -286.546255) (xy 100.813904 -286.552389) (xy 100.763052 -286.55034) (xy 100.713188 -286.54016)
			(xy 100.665602 -286.522113) (xy 100.621528 -286.496667) (xy 100.582106 -286.46448) (xy 100.548358 -286.426386)
			(xy 100.521157 -286.383372) (xy 100.501209 -286.336552) (xy 100.48903 -286.287138) (xy 100.484935 -286.23641)
			(xy 100.179124 -286.23641) (xy 100.178634 -286.261399) (xy 100.170815 -286.310762) (xy 100.155371 -286.358294)
			(xy 100.132681 -286.402826) (xy 100.103305 -286.443259) (xy 100.067965 -286.478599) (xy 100.027532 -286.507975)
			(xy 99.983 -286.530665) (xy 99.935468 -286.546109) (xy 99.886105 -286.553928) (xy 99.836127 -286.553928)
			(xy 99.786764 -286.546109) (xy 99.739232 -286.530665) (xy 99.6947 -286.507975) (xy 99.654267 -286.478599)
			(xy 99.618927 -286.443259) (xy 99.589551 -286.402826) (xy 99.566861 -286.358294) (xy 99.551417 -286.310762)
			(xy 99.543598 -286.261399) (xy 99.236281 -286.261399) (xy 99.236272 -286.261856) (xy 99.228108 -286.31209)
			(xy 99.211992 -286.360364) (xy 99.188341 -286.405427) (xy 99.157768 -286.446113) (xy 99.121064 -286.481368)
			(xy 99.07918 -286.510278) (xy 99.033201 -286.532095) (xy 98.984317 -286.546255) (xy 98.933796 -286.552389)
			(xy 98.882944 -286.55034) (xy 98.83308 -286.54016) (xy 98.785494 -286.522113) (xy 98.74142 -286.496667)
			(xy 98.701998 -286.46448) (xy 98.66825 -286.426386) (xy 98.641049 -286.383372) (xy 98.621101 -286.336552)
			(xy 98.608922 -286.287138) (xy 98.604827 -286.23641) (xy 98.29673 -286.23641) (xy 98.296218 -286.261856)
			(xy 98.288054 -286.31209) (xy 98.271938 -286.360364) (xy 98.248287 -286.405427) (xy 98.217714 -286.446113)
			(xy 98.18101 -286.481368) (xy 98.139126 -286.510278) (xy 98.093147 -286.532095) (xy 98.044263 -286.546255)
			(xy 97.993742 -286.552389) (xy 97.94289 -286.55034) (xy 97.893026 -286.54016) (xy 97.84544 -286.522113)
			(xy 97.801366 -286.496667) (xy 97.761944 -286.46448) (xy 97.728196 -286.426386) (xy 97.700995 -286.383372)
			(xy 97.681047 -286.336552) (xy 97.668868 -286.287138) (xy 97.664773 -286.23641) (xy 97.358962 -286.23641)
			(xy 97.358472 -286.261399) (xy 97.350653 -286.310762) (xy 97.335209 -286.358294) (xy 97.312519 -286.402826)
			(xy 97.283143 -286.443259) (xy 97.247803 -286.478599) (xy 97.20737 -286.507975) (xy 97.162838 -286.530665)
			(xy 97.115306 -286.546109) (xy 97.065943 -286.553928) (xy 97.015965 -286.553928) (xy 96.966602 -286.546109)
			(xy 96.91907 -286.530665) (xy 96.874538 -286.507975) (xy 96.834105 -286.478599) (xy 96.798765 -286.443259)
			(xy 96.769389 -286.402826) (xy 96.746699 -286.358294) (xy 96.731255 -286.310762) (xy 96.723436 -286.261399)
			(xy 96.416373 -286.261399) (xy 96.416364 -286.261856) (xy 96.4082 -286.31209) (xy 96.392084 -286.360364)
			(xy 96.368433 -286.405427) (xy 96.33786 -286.446113) (xy 96.301156 -286.481368) (xy 96.259272 -286.510278)
			(xy 96.213293 -286.532095) (xy 96.164409 -286.546255) (xy 96.113888 -286.552389) (xy 96.063036 -286.55034)
			(xy 96.013172 -286.54016) (xy 95.965586 -286.522113) (xy 95.921512 -286.496667) (xy 95.88209 -286.46448)
			(xy 95.848342 -286.426386) (xy 95.821141 -286.383372) (xy 95.801193 -286.336552) (xy 95.789014 -286.287138)
			(xy 95.784919 -286.23641) (xy 95.479108 -286.23641) (xy 95.478618 -286.261399) (xy 95.470799 -286.310762)
			(xy 95.455355 -286.358294) (xy 95.432665 -286.402826) (xy 95.403289 -286.443259) (xy 95.367949 -286.478599)
			(xy 95.327516 -286.507975) (xy 95.282984 -286.530665) (xy 95.235452 -286.546109) (xy 95.186089 -286.553928)
			(xy 95.136111 -286.553928) (xy 95.086748 -286.546109) (xy 95.039216 -286.530665) (xy 94.994684 -286.507975)
			(xy 94.954251 -286.478599) (xy 94.918911 -286.443259) (xy 94.889535 -286.402826) (xy 94.866845 -286.358294)
			(xy 94.851401 -286.310762) (xy 94.843582 -286.261399) (xy 94.536265 -286.261399) (xy 94.536256 -286.261856)
			(xy 94.528092 -286.31209) (xy 94.511976 -286.360364) (xy 94.488325 -286.405427) (xy 94.457752 -286.446113)
			(xy 94.421048 -286.481368) (xy 94.379164 -286.510278) (xy 94.333185 -286.532095) (xy 94.284301 -286.546255)
			(xy 94.23378 -286.552389) (xy 94.182928 -286.55034) (xy 94.133064 -286.54016) (xy 94.085478 -286.522113)
			(xy 94.041404 -286.496667) (xy 94.001982 -286.46448) (xy 93.968234 -286.426386) (xy 93.941033 -286.383372)
			(xy 93.921085 -286.336552) (xy 93.908906 -286.287138) (xy 93.904811 -286.23641) (xy 93.599 -286.23641)
			(xy 93.59851 -286.261399) (xy 93.590691 -286.310762) (xy 93.575247 -286.358294) (xy 93.552557 -286.402826)
			(xy 93.523181 -286.443259) (xy 93.487841 -286.478599) (xy 93.447408 -286.507975) (xy 93.402876 -286.530665)
			(xy 93.355344 -286.546109) (xy 93.305981 -286.553928) (xy 93.256003 -286.553928) (xy 93.20664 -286.546109)
			(xy 93.159108 -286.530665) (xy 93.114576 -286.507975) (xy 93.074143 -286.478599) (xy 93.038803 -286.443259)
			(xy 93.009427 -286.402826) (xy 92.986737 -286.358294) (xy 92.971293 -286.310762) (xy 92.963474 -286.261399)
			(xy 92.656157 -286.261399) (xy 92.656148 -286.261856) (xy 92.647984 -286.31209) (xy 92.631868 -286.360364)
			(xy 92.608217 -286.405427) (xy 92.577644 -286.446113) (xy 92.54094 -286.481368) (xy 92.499056 -286.510278)
			(xy 92.453077 -286.532095) (xy 92.404193 -286.546255) (xy 92.353672 -286.552389) (xy 92.30282 -286.55034)
			(xy 92.252956 -286.54016) (xy 92.20537 -286.522113) (xy 92.161296 -286.496667) (xy 92.121874 -286.46448)
			(xy 92.088126 -286.426386) (xy 92.060925 -286.383372) (xy 92.040977 -286.336552) (xy 92.028798 -286.287138)
			(xy 92.024703 -286.23641) (xy 91.861386 -286.23641) (xy 91.861386 -286.699198) (xy 91.88704 -286.7279)
			(xy 91.906598 -286.730186) (xy 91.932166 -286.73357) (xy 91.98181 -286.747536) (xy 92.02855 -286.76933)
			(xy 92.071161 -286.79838) (xy 92.108526 -286.833926) (xy 92.139666 -286.875034) (xy 92.163764 -286.920629)
			(xy 92.18019 -286.969515) (xy 92.188512 -287.02041) (xy 92.188512 -287.046162) (xy 92.494857 -287.046162)
			(xy 92.498952 -286.995434) (xy 92.511131 -286.94602) (xy 92.531079 -286.8992) (xy 92.55828 -286.856186)
			(xy 92.592028 -286.818092) (xy 92.63145 -286.785905) (xy 92.675524 -286.760459) (xy 92.72311 -286.742412)
			(xy 92.772974 -286.732232) (xy 92.823826 -286.730183) (xy 92.874347 -286.736317) (xy 92.923231 -286.750477)
			(xy 92.96921 -286.772294) (xy 93.011094 -286.801204) (xy 93.047798 -286.836459) (xy 93.078371 -286.877145)
			(xy 93.102022 -286.922208) (xy 93.118138 -286.970482) (xy 93.126302 -287.020716) (xy 93.126814 -287.046162)
			(xy 93.126311 -287.071151) (xy 93.433628 -287.071151) (xy 93.433628 -287.021173) (xy 93.441447 -286.97181)
			(xy 93.456891 -286.924278) (xy 93.479581 -286.879746) (xy 93.508957 -286.839313) (xy 93.544297 -286.803973)
			(xy 93.58473 -286.774597) (xy 93.629262 -286.751907) (xy 93.676794 -286.736463) (xy 93.726157 -286.728644)
			(xy 93.776135 -286.728644) (xy 93.825498 -286.736463) (xy 93.87303 -286.751907) (xy 93.917562 -286.774597)
			(xy 93.957995 -286.803973) (xy 93.993335 -286.839313) (xy 94.022711 -286.879746) (xy 94.045401 -286.924278)
			(xy 94.060845 -286.97181) (xy 94.068664 -287.021173) (xy 94.069154 -287.046162) (xy 94.374711 -287.046162)
			(xy 94.378806 -286.995434) (xy 94.390985 -286.94602) (xy 94.410933 -286.8992) (xy 94.438134 -286.856186)
			(xy 94.471882 -286.818092) (xy 94.511304 -286.785905) (xy 94.555378 -286.760459) (xy 94.602964 -286.742412)
			(xy 94.652828 -286.732232) (xy 94.70368 -286.730183) (xy 94.754201 -286.736317) (xy 94.803085 -286.750477)
			(xy 94.849064 -286.772294) (xy 94.890948 -286.801204) (xy 94.927652 -286.836459) (xy 94.958225 -286.877145)
			(xy 94.981876 -286.922208) (xy 94.997992 -286.970482) (xy 95.006156 -287.020716) (xy 95.006668 -287.046162)
			(xy 95.314765 -287.046162) (xy 95.31886 -286.995434) (xy 95.331039 -286.94602) (xy 95.350987 -286.8992)
			(xy 95.378188 -286.856186) (xy 95.411936 -286.818092) (xy 95.451358 -286.785905) (xy 95.495432 -286.760459)
			(xy 95.543018 -286.742412) (xy 95.592882 -286.732232) (xy 95.643734 -286.730183) (xy 95.694255 -286.736317)
			(xy 95.743139 -286.750477) (xy 95.789118 -286.772294) (xy 95.831002 -286.801204) (xy 95.867706 -286.836459)
			(xy 95.898279 -286.877145) (xy 95.92193 -286.922208) (xy 95.938046 -286.970482) (xy 95.94621 -287.020716)
			(xy 95.946722 -287.046162) (xy 95.946219 -287.071151) (xy 96.253536 -287.071151) (xy 96.253536 -287.021173)
			(xy 96.261355 -286.97181) (xy 96.276799 -286.924278) (xy 96.299489 -286.879746) (xy 96.328865 -286.839313)
			(xy 96.364205 -286.803973) (xy 96.404638 -286.774597) (xy 96.44917 -286.751907) (xy 96.496702 -286.736463)
			(xy 96.546065 -286.728644) (xy 96.596043 -286.728644) (xy 96.645406 -286.736463) (xy 96.692938 -286.751907)
			(xy 96.73747 -286.774597) (xy 96.777903 -286.803973) (xy 96.813243 -286.839313) (xy 96.842619 -286.879746)
			(xy 96.865309 -286.924278) (xy 96.880753 -286.97181) (xy 96.888572 -287.021173) (xy 96.889062 -287.046162)
			(xy 96.888572 -287.071151) (xy 96.888492 -287.071659) (xy 99.073698 -287.071659) (xy 99.073698 -287.021681)
			(xy 99.081517 -286.972318) (xy 99.096961 -286.924786) (xy 99.119651 -286.880254) (xy 99.149027 -286.839821)
			(xy 99.184367 -286.804481) (xy 99.2248 -286.775105) (xy 99.269332 -286.752415) (xy 99.316864 -286.736971)
			(xy 99.366227 -286.729152) (xy 99.416205 -286.729152) (xy 99.465568 -286.736971) (xy 99.5131 -286.752415)
			(xy 99.557632 -286.775105) (xy 99.598065 -286.804481) (xy 99.633405 -286.839821) (xy 99.662781 -286.880254)
			(xy 99.685471 -286.924786) (xy 99.700915 -286.972318) (xy 99.708734 -287.021681) (xy 99.709224 -287.04667)
			(xy 99.708744 -287.071151) (xy 101.893606 -287.071151) (xy 101.893606 -287.021173) (xy 101.901425 -286.97181)
			(xy 101.916869 -286.924278) (xy 101.939559 -286.879746) (xy 101.968935 -286.839313) (xy 102.004275 -286.803973)
			(xy 102.044708 -286.774597) (xy 102.08924 -286.751907) (xy 102.136772 -286.736463) (xy 102.186135 -286.728644)
			(xy 102.236113 -286.728644) (xy 102.285476 -286.736463) (xy 102.333008 -286.751907) (xy 102.37754 -286.774597)
			(xy 102.417973 -286.803973) (xy 102.453313 -286.839313) (xy 102.482689 -286.879746) (xy 102.505379 -286.924278)
			(xy 102.520823 -286.97181) (xy 102.528642 -287.021173) (xy 102.529132 -287.046162) (xy 102.528642 -287.071151)
			(xy 104.713514 -287.071151) (xy 104.713514 -287.021173) (xy 104.721333 -286.97181) (xy 104.736777 -286.924278)
			(xy 104.759467 -286.879746) (xy 104.788843 -286.839313) (xy 104.824183 -286.803973) (xy 104.864616 -286.774597)
			(xy 104.909148 -286.751907) (xy 104.95668 -286.736463) (xy 105.006043 -286.728644) (xy 105.056021 -286.728644)
			(xy 105.105384 -286.736463) (xy 105.152916 -286.751907) (xy 105.197448 -286.774597) (xy 105.237881 -286.803973)
			(xy 105.273221 -286.839313) (xy 105.302597 -286.879746) (xy 105.325287 -286.924278) (xy 105.340731 -286.97181)
			(xy 105.34855 -287.021173) (xy 105.34904 -287.046162) (xy 105.34855 -287.071151) (xy 105.34847 -287.071659)
			(xy 107.533676 -287.071659) (xy 107.533676 -287.021681) (xy 107.541495 -286.972318) (xy 107.556939 -286.924786)
			(xy 107.579629 -286.880254) (xy 107.609005 -286.839821) (xy 107.644345 -286.804481) (xy 107.684778 -286.775105)
			(xy 107.72931 -286.752415) (xy 107.776842 -286.736971) (xy 107.826205 -286.729152) (xy 107.876183 -286.729152)
			(xy 107.925546 -286.736971) (xy 107.973078 -286.752415) (xy 108.01761 -286.775105) (xy 108.058043 -286.804481)
			(xy 108.093383 -286.839821) (xy 108.122759 -286.880254) (xy 108.145449 -286.924786) (xy 108.160893 -286.972318)
			(xy 108.168712 -287.021681) (xy 108.169192 -287.046162) (xy 108.474759 -287.046162) (xy 108.478854 -286.995434)
			(xy 108.491033 -286.94602) (xy 108.510981 -286.8992) (xy 108.538182 -286.856186) (xy 108.57193 -286.818092)
			(xy 108.611352 -286.785905) (xy 108.655426 -286.760459) (xy 108.703012 -286.742412) (xy 108.752876 -286.732232)
			(xy 108.803728 -286.730183) (xy 108.854249 -286.736317) (xy 108.903133 -286.750477) (xy 108.949112 -286.772294)
			(xy 108.990996 -286.801204) (xy 109.0277 -286.836459) (xy 109.058273 -286.877145) (xy 109.081924 -286.922208)
			(xy 109.09804 -286.970482) (xy 109.106204 -287.020716) (xy 109.106716 -287.046162) (xy 109.414813 -287.046162)
			(xy 109.418908 -286.995434) (xy 109.431087 -286.94602) (xy 109.451035 -286.8992) (xy 109.478236 -286.856186)
			(xy 109.511984 -286.818092) (xy 109.551406 -286.785905) (xy 109.59548 -286.760459) (xy 109.643066 -286.742412)
			(xy 109.69293 -286.732232) (xy 109.743782 -286.730183) (xy 109.794303 -286.736317) (xy 109.843187 -286.750477)
			(xy 109.889166 -286.772294) (xy 109.93105 -286.801204) (xy 109.967754 -286.836459) (xy 109.998327 -286.877145)
			(xy 110.021978 -286.922208) (xy 110.038094 -286.970482) (xy 110.046258 -287.020716) (xy 110.04677 -287.046162)
			(xy 110.046267 -287.071151) (xy 110.353584 -287.071151) (xy 110.353584 -287.021173) (xy 110.361403 -286.97181)
			(xy 110.376847 -286.924278) (xy 110.399537 -286.879746) (xy 110.428913 -286.839313) (xy 110.464253 -286.803973)
			(xy 110.504686 -286.774597) (xy 110.549218 -286.751907) (xy 110.59675 -286.736463) (xy 110.646113 -286.728644)
			(xy 110.696091 -286.728644) (xy 110.745454 -286.736463) (xy 110.792986 -286.751907) (xy 110.837518 -286.774597)
			(xy 110.877951 -286.803973) (xy 110.913291 -286.839313) (xy 110.942667 -286.879746) (xy 110.965357 -286.924278)
			(xy 110.980801 -286.97181) (xy 110.98862 -287.021173) (xy 110.98911 -287.046162) (xy 110.98862 -287.071151)
			(xy 113.167142 -287.071151) (xy 113.167142 -287.021173) (xy 113.174961 -286.97181) (xy 113.190405 -286.924278)
			(xy 113.213095 -286.879746) (xy 113.242471 -286.839313) (xy 113.277811 -286.803973) (xy 113.318244 -286.774597)
			(xy 113.362776 -286.751907) (xy 113.410308 -286.736463) (xy 113.459671 -286.728644) (xy 113.509649 -286.728644)
			(xy 113.559012 -286.736463) (xy 113.606544 -286.751907) (xy 113.651076 -286.774597) (xy 113.691509 -286.803973)
			(xy 113.726849 -286.839313) (xy 113.756225 -286.879746) (xy 113.778915 -286.924278) (xy 113.794359 -286.97181)
			(xy 113.802178 -287.021173) (xy 113.802668 -287.046162) (xy 114.108479 -287.046162) (xy 114.112574 -286.995434)
			(xy 114.124753 -286.94602) (xy 114.144701 -286.8992) (xy 114.171902 -286.856186) (xy 114.20565 -286.818092)
			(xy 114.245072 -286.785905) (xy 114.289146 -286.760459) (xy 114.336732 -286.742412) (xy 114.386596 -286.732232)
			(xy 114.437448 -286.730183) (xy 114.487969 -286.736317) (xy 114.536853 -286.750477) (xy 114.582832 -286.772294)
			(xy 114.624716 -286.801204) (xy 114.66142 -286.836459) (xy 114.691993 -286.877145) (xy 114.715644 -286.922208)
			(xy 114.73176 -286.970482) (xy 114.739924 -287.020716) (xy 114.740436 -287.046162) (xy 115.048533 -287.046162)
			(xy 115.052628 -286.995434) (xy 115.064807 -286.94602) (xy 115.084755 -286.8992) (xy 115.111956 -286.856186)
			(xy 115.145704 -286.818092) (xy 115.185126 -286.785905) (xy 115.2292 -286.760459) (xy 115.276786 -286.742412)
			(xy 115.32665 -286.732232) (xy 115.377502 -286.730183) (xy 115.428023 -286.736317) (xy 115.476907 -286.750477)
			(xy 115.522886 -286.772294) (xy 115.56477 -286.801204) (xy 115.601474 -286.836459) (xy 115.632047 -286.877145)
			(xy 115.655698 -286.922208) (xy 115.671814 -286.970482) (xy 115.679978 -287.020716) (xy 115.68049 -287.046162)
			(xy 115.679982 -287.071405) (xy 115.987304 -287.071405) (xy 115.987304 -287.021427) (xy 115.995123 -286.972064)
			(xy 116.010567 -286.924532) (xy 116.033257 -286.88) (xy 116.062633 -286.839567) (xy 116.097973 -286.804227)
			(xy 116.138406 -286.774851) (xy 116.182938 -286.752161) (xy 116.23047 -286.736717) (xy 116.279833 -286.728898)
			(xy 116.329811 -286.728898) (xy 116.379174 -286.736717) (xy 116.426706 -286.752161) (xy 116.471238 -286.774851)
			(xy 116.511671 -286.804227) (xy 116.547011 -286.839567) (xy 116.576387 -286.88) (xy 116.599077 -286.924532)
			(xy 116.614521 -286.972064) (xy 116.62234 -287.021427) (xy 116.62283 -287.046416) (xy 116.622345 -287.071151)
			(xy 118.807212 -287.071151) (xy 118.807212 -287.021173) (xy 118.815031 -286.97181) (xy 118.830475 -286.924278)
			(xy 118.853165 -286.879746) (xy 118.882541 -286.839313) (xy 118.917881 -286.803973) (xy 118.958314 -286.774597)
			(xy 119.002846 -286.751907) (xy 119.050378 -286.736463) (xy 119.099741 -286.728644) (xy 119.149719 -286.728644)
			(xy 119.199082 -286.736463) (xy 119.246614 -286.751907) (xy 119.291146 -286.774597) (xy 119.331579 -286.803973)
			(xy 119.366919 -286.839313) (xy 119.396295 -286.879746) (xy 119.418985 -286.924278) (xy 119.434429 -286.97181)
			(xy 119.442248 -287.021173) (xy 119.442738 -287.046162) (xy 119.442248 -287.071151) (xy 121.62712 -287.071151)
			(xy 121.62712 -287.021173) (xy 121.634939 -286.97181) (xy 121.650383 -286.924278) (xy 121.673073 -286.879746)
			(xy 121.702449 -286.839313) (xy 121.737789 -286.803973) (xy 121.778222 -286.774597) (xy 121.822754 -286.751907)
			(xy 121.870286 -286.736463) (xy 121.919649 -286.728644) (xy 121.969627 -286.728644) (xy 122.01899 -286.736463)
			(xy 122.066522 -286.751907) (xy 122.111054 -286.774597) (xy 122.151487 -286.803973) (xy 122.186827 -286.839313)
			(xy 122.216203 -286.879746) (xy 122.238893 -286.924278) (xy 122.254337 -286.97181) (xy 122.262156 -287.021173)
			(xy 122.262646 -287.046162) (xy 122.262156 -287.071151) (xy 124.447282 -287.071151) (xy 124.447282 -287.021173)
			(xy 124.455101 -286.97181) (xy 124.470545 -286.924278) (xy 124.493235 -286.879746) (xy 124.522611 -286.839313)
			(xy 124.557951 -286.803973) (xy 124.598384 -286.774597) (xy 124.642916 -286.751907) (xy 124.690448 -286.736463)
			(xy 124.739811 -286.728644) (xy 124.789789 -286.728644) (xy 124.839152 -286.736463) (xy 124.886684 -286.751907)
			(xy 124.931216 -286.774597) (xy 124.971649 -286.803973) (xy 125.006989 -286.839313) (xy 125.036365 -286.879746)
			(xy 125.059055 -286.924278) (xy 125.074499 -286.97181) (xy 125.082318 -287.021173) (xy 125.082808 -287.046162)
			(xy 125.082318 -287.071151) (xy 125.074499 -287.120514) (xy 125.059055 -287.168046) (xy 125.036365 -287.212578)
			(xy 125.006989 -287.253011) (xy 124.971649 -287.288351) (xy 124.931216 -287.317727) (xy 124.886684 -287.340417)
			(xy 124.839152 -287.355861) (xy 124.789789 -287.36368) (xy 124.739811 -287.36368) (xy 124.690448 -287.355861)
			(xy 124.642916 -287.340417) (xy 124.598384 -287.317727) (xy 124.557951 -287.288351) (xy 124.522611 -287.253011)
			(xy 124.493235 -287.212578) (xy 124.470545 -287.168046) (xy 124.455101 -287.120514) (xy 124.447282 -287.071151)
			(xy 122.262156 -287.071151) (xy 122.254337 -287.120514) (xy 122.238893 -287.168046) (xy 122.216203 -287.212578)
			(xy 122.186827 -287.253011) (xy 122.151487 -287.288351) (xy 122.111054 -287.317727) (xy 122.066522 -287.340417)
			(xy 122.01899 -287.355861) (xy 121.969627 -287.36368) (xy 121.919649 -287.36368) (xy 121.870286 -287.355861)
			(xy 121.822754 -287.340417) (xy 121.778222 -287.317727) (xy 121.737789 -287.288351) (xy 121.702449 -287.253011)
			(xy 121.673073 -287.212578) (xy 121.650383 -287.168046) (xy 121.634939 -287.120514) (xy 121.62712 -287.071151)
			(xy 119.442248 -287.071151) (xy 119.434429 -287.120514) (xy 119.418985 -287.168046) (xy 119.396295 -287.212578)
			(xy 119.366919 -287.253011) (xy 119.331579 -287.288351) (xy 119.291146 -287.317727) (xy 119.246614 -287.340417)
			(xy 119.199082 -287.355861) (xy 119.149719 -287.36368) (xy 119.099741 -287.36368) (xy 119.050378 -287.355861)
			(xy 119.002846 -287.340417) (xy 118.958314 -287.317727) (xy 118.917881 -287.288351) (xy 118.882541 -287.253011)
			(xy 118.853165 -287.212578) (xy 118.830475 -287.168046) (xy 118.815031 -287.120514) (xy 118.807212 -287.071151)
			(xy 116.622345 -287.071151) (xy 116.62234 -287.071405) (xy 116.614521 -287.120768) (xy 116.599077 -287.1683)
			(xy 116.576387 -287.212832) (xy 116.547011 -287.253265) (xy 116.511671 -287.288605) (xy 116.471238 -287.317981)
			(xy 116.426706 -287.340671) (xy 116.379174 -287.356115) (xy 116.329811 -287.363934) (xy 116.279833 -287.363934)
			(xy 116.23047 -287.356115) (xy 116.182938 -287.340671) (xy 116.138406 -287.317981) (xy 116.097973 -287.288605)
			(xy 116.062633 -287.253265) (xy 116.033257 -287.212832) (xy 116.010567 -287.1683) (xy 115.995123 -287.120768)
			(xy 115.987304 -287.071405) (xy 115.679982 -287.071405) (xy 115.679978 -287.071608) (xy 115.671814 -287.121842)
			(xy 115.655698 -287.170116) (xy 115.632047 -287.215179) (xy 115.601474 -287.255865) (xy 115.56477 -287.29112)
			(xy 115.522886 -287.32003) (xy 115.476907 -287.341847) (xy 115.428023 -287.356007) (xy 115.377502 -287.362141)
			(xy 115.32665 -287.360092) (xy 115.276786 -287.349912) (xy 115.2292 -287.331865) (xy 115.185126 -287.306419)
			(xy 115.145704 -287.274232) (xy 115.111956 -287.236138) (xy 115.084755 -287.193124) (xy 115.064807 -287.146304)
			(xy 115.052628 -287.09689) (xy 115.048533 -287.046162) (xy 114.740436 -287.046162) (xy 114.739924 -287.071608)
			(xy 114.73176 -287.121842) (xy 114.715644 -287.170116) (xy 114.691993 -287.215179) (xy 114.66142 -287.255865)
			(xy 114.624716 -287.29112) (xy 114.582832 -287.32003) (xy 114.536853 -287.341847) (xy 114.487969 -287.356007)
			(xy 114.437448 -287.362141) (xy 114.386596 -287.360092) (xy 114.336732 -287.349912) (xy 114.289146 -287.331865)
			(xy 114.245072 -287.306419) (xy 114.20565 -287.274232) (xy 114.171902 -287.236138) (xy 114.144701 -287.193124)
			(xy 114.124753 -287.146304) (xy 114.112574 -287.09689) (xy 114.108479 -287.046162) (xy 113.802668 -287.046162)
			(xy 113.802178 -287.071151) (xy 113.794359 -287.120514) (xy 113.778915 -287.168046) (xy 113.756225 -287.212578)
			(xy 113.726849 -287.253011) (xy 113.691509 -287.288351) (xy 113.651076 -287.317727) (xy 113.606544 -287.340417)
			(xy 113.559012 -287.355861) (xy 113.509649 -287.36368) (xy 113.459671 -287.36368) (xy 113.410308 -287.355861)
			(xy 113.362776 -287.340417) (xy 113.318244 -287.317727) (xy 113.277811 -287.288351) (xy 113.242471 -287.253011)
			(xy 113.213095 -287.212578) (xy 113.190405 -287.168046) (xy 113.174961 -287.120514) (xy 113.167142 -287.071151)
			(xy 110.98862 -287.071151) (xy 110.980801 -287.120514) (xy 110.965357 -287.168046) (xy 110.942667 -287.212578)
			(xy 110.913291 -287.253011) (xy 110.877951 -287.288351) (xy 110.837518 -287.317727) (xy 110.792986 -287.340417)
			(xy 110.745454 -287.355861) (xy 110.696091 -287.36368) (xy 110.646113 -287.36368) (xy 110.59675 -287.355861)
			(xy 110.549218 -287.340417) (xy 110.504686 -287.317727) (xy 110.464253 -287.288351) (xy 110.428913 -287.253011)
			(xy 110.399537 -287.212578) (xy 110.376847 -287.168046) (xy 110.361403 -287.120514) (xy 110.353584 -287.071151)
			(xy 110.046267 -287.071151) (xy 110.046258 -287.071608) (xy 110.038094 -287.121842) (xy 110.021978 -287.170116)
			(xy 109.998327 -287.215179) (xy 109.967754 -287.255865) (xy 109.93105 -287.29112) (xy 109.889166 -287.32003)
			(xy 109.843187 -287.341847) (xy 109.794303 -287.356007) (xy 109.743782 -287.362141) (xy 109.69293 -287.360092)
			(xy 109.643066 -287.349912) (xy 109.59548 -287.331865) (xy 109.551406 -287.306419) (xy 109.511984 -287.274232)
			(xy 109.478236 -287.236138) (xy 109.451035 -287.193124) (xy 109.431087 -287.146304) (xy 109.418908 -287.09689)
			(xy 109.414813 -287.046162) (xy 109.106716 -287.046162) (xy 109.106204 -287.071608) (xy 109.09804 -287.121842)
			(xy 109.081924 -287.170116) (xy 109.058273 -287.215179) (xy 109.0277 -287.255865) (xy 108.990996 -287.29112)
			(xy 108.949112 -287.32003) (xy 108.903133 -287.341847) (xy 108.854249 -287.356007) (xy 108.803728 -287.362141)
			(xy 108.752876 -287.360092) (xy 108.703012 -287.349912) (xy 108.655426 -287.331865) (xy 108.611352 -287.306419)
			(xy 108.57193 -287.274232) (xy 108.538182 -287.236138) (xy 108.510981 -287.193124) (xy 108.491033 -287.146304)
			(xy 108.478854 -287.09689) (xy 108.474759 -287.046162) (xy 108.169192 -287.046162) (xy 108.169202 -287.04667)
			(xy 108.168712 -287.071659) (xy 108.160893 -287.121022) (xy 108.145449 -287.168554) (xy 108.122759 -287.213086)
			(xy 108.093383 -287.253519) (xy 108.058043 -287.288859) (xy 108.01761 -287.318235) (xy 107.973078 -287.340925)
			(xy 107.925546 -287.356369) (xy 107.876183 -287.364188) (xy 107.826205 -287.364188) (xy 107.776842 -287.356369)
			(xy 107.72931 -287.340925) (xy 107.684778 -287.318235) (xy 107.644345 -287.288859) (xy 107.609005 -287.253519)
			(xy 107.579629 -287.213086) (xy 107.556939 -287.168554) (xy 107.541495 -287.121022) (xy 107.533676 -287.071659)
			(xy 105.34847 -287.071659) (xy 105.340731 -287.120514) (xy 105.325287 -287.168046) (xy 105.302597 -287.212578)
			(xy 105.273221 -287.253011) (xy 105.237881 -287.288351) (xy 105.197448 -287.317727) (xy 105.152916 -287.340417)
			(xy 105.105384 -287.355861) (xy 105.056021 -287.36368) (xy 105.006043 -287.36368) (xy 104.95668 -287.355861)
			(xy 104.909148 -287.340417) (xy 104.864616 -287.317727) (xy 104.824183 -287.288351) (xy 104.788843 -287.253011)
			(xy 104.759467 -287.212578) (xy 104.736777 -287.168046) (xy 104.721333 -287.120514) (xy 104.713514 -287.071151)
			(xy 102.528642 -287.071151) (xy 102.520823 -287.120514) (xy 102.505379 -287.168046) (xy 102.482689 -287.212578)
			(xy 102.453313 -287.253011) (xy 102.417973 -287.288351) (xy 102.37754 -287.317727) (xy 102.333008 -287.340417)
			(xy 102.285476 -287.355861) (xy 102.236113 -287.36368) (xy 102.186135 -287.36368) (xy 102.136772 -287.355861)
			(xy 102.08924 -287.340417) (xy 102.044708 -287.317727) (xy 102.004275 -287.288351) (xy 101.968935 -287.253011)
			(xy 101.939559 -287.212578) (xy 101.916869 -287.168046) (xy 101.901425 -287.120514) (xy 101.893606 -287.071151)
			(xy 99.708744 -287.071151) (xy 99.708734 -287.071659) (xy 99.700915 -287.121022) (xy 99.685471 -287.168554)
			(xy 99.662781 -287.213086) (xy 99.633405 -287.253519) (xy 99.598065 -287.288859) (xy 99.557632 -287.318235)
			(xy 99.5131 -287.340925) (xy 99.465568 -287.356369) (xy 99.416205 -287.364188) (xy 99.366227 -287.364188)
			(xy 99.316864 -287.356369) (xy 99.269332 -287.340925) (xy 99.2248 -287.318235) (xy 99.184367 -287.288859)
			(xy 99.149027 -287.253519) (xy 99.119651 -287.213086) (xy 99.096961 -287.168554) (xy 99.081517 -287.121022)
			(xy 99.073698 -287.071659) (xy 96.888492 -287.071659) (xy 96.880753 -287.120514) (xy 96.865309 -287.168046)
			(xy 96.842619 -287.212578) (xy 96.813243 -287.253011) (xy 96.777903 -287.288351) (xy 96.73747 -287.317727)
			(xy 96.692938 -287.340417) (xy 96.645406 -287.355861) (xy 96.596043 -287.36368) (xy 96.546065 -287.36368)
			(xy 96.496702 -287.355861) (xy 96.44917 -287.340417) (xy 96.404638 -287.317727) (xy 96.364205 -287.288351)
			(xy 96.328865 -287.253011) (xy 96.299489 -287.212578) (xy 96.276799 -287.168046) (xy 96.261355 -287.120514)
			(xy 96.253536 -287.071151) (xy 95.946219 -287.071151) (xy 95.94621 -287.071608) (xy 95.938046 -287.121842)
			(xy 95.92193 -287.170116) (xy 95.898279 -287.215179) (xy 95.867706 -287.255865) (xy 95.831002 -287.29112)
			(xy 95.789118 -287.32003) (xy 95.743139 -287.341847) (xy 95.694255 -287.356007) (xy 95.643734 -287.362141)
			(xy 95.592882 -287.360092) (xy 95.543018 -287.349912) (xy 95.495432 -287.331865) (xy 95.451358 -287.306419)
			(xy 95.411936 -287.274232) (xy 95.378188 -287.236138) (xy 95.350987 -287.193124) (xy 95.331039 -287.146304)
			(xy 95.31886 -287.09689) (xy 95.314765 -287.046162) (xy 95.006668 -287.046162) (xy 95.006156 -287.071608)
			(xy 94.997992 -287.121842) (xy 94.981876 -287.170116) (xy 94.958225 -287.215179) (xy 94.927652 -287.255865)
			(xy 94.890948 -287.29112) (xy 94.849064 -287.32003) (xy 94.803085 -287.341847) (xy 94.754201 -287.356007)
			(xy 94.70368 -287.362141) (xy 94.652828 -287.360092) (xy 94.602964 -287.349912) (xy 94.555378 -287.331865)
			(xy 94.511304 -287.306419) (xy 94.471882 -287.274232) (xy 94.438134 -287.236138) (xy 94.410933 -287.193124)
			(xy 94.390985 -287.146304) (xy 94.378806 -287.09689) (xy 94.374711 -287.046162) (xy 94.069154 -287.046162)
			(xy 94.068664 -287.071151) (xy 94.060845 -287.120514) (xy 94.045401 -287.168046) (xy 94.022711 -287.212578)
			(xy 93.993335 -287.253011) (xy 93.957995 -287.288351) (xy 93.917562 -287.317727) (xy 93.87303 -287.340417)
			(xy 93.825498 -287.355861) (xy 93.776135 -287.36368) (xy 93.726157 -287.36368) (xy 93.676794 -287.355861)
			(xy 93.629262 -287.340417) (xy 93.58473 -287.317727) (xy 93.544297 -287.288351) (xy 93.508957 -287.253011)
			(xy 93.479581 -287.212578) (xy 93.456891 -287.168046) (xy 93.441447 -287.120514) (xy 93.433628 -287.071151)
			(xy 93.126311 -287.071151) (xy 93.126302 -287.071608) (xy 93.118138 -287.121842) (xy 93.102022 -287.170116)
			(xy 93.078371 -287.215179) (xy 93.047798 -287.255865) (xy 93.011094 -287.29112) (xy 92.96921 -287.32003)
			(xy 92.923231 -287.341847) (xy 92.874347 -287.356007) (xy 92.823826 -287.362141) (xy 92.772974 -287.360092)
			(xy 92.72311 -287.349912) (xy 92.675524 -287.331865) (xy 92.63145 -287.306419) (xy 92.592028 -287.274232)
			(xy 92.55828 -287.236138) (xy 92.531079 -287.193124) (xy 92.511131 -287.146304) (xy 92.498952 -287.09689)
			(xy 92.494857 -287.046162) (xy 92.188512 -287.046162) (xy 92.188513 -287.071981) (xy 92.180192 -287.122877)
			(xy 92.163768 -287.171763) (xy 92.13967 -287.217359) (xy 92.108532 -287.258468) (xy 92.071168 -287.294014)
			(xy 92.028557 -287.323066) (xy 91.981818 -287.344861) (xy 91.932174 -287.358829) (xy 91.906598 -287.362138)
			(xy 91.88704 -287.364424) (xy 91.861386 -287.393126) (xy 91.861386 -287.856422) (xy 92.024703 -287.856422)
			(xy 92.028798 -287.805694) (xy 92.040977 -287.75628) (xy 92.060925 -287.70946) (xy 92.088126 -287.666446)
			(xy 92.121874 -287.628352) (xy 92.161296 -287.596165) (xy 92.20537 -287.570719) (xy 92.252956 -287.552672)
			(xy 92.30282 -287.542492) (xy 92.353672 -287.540443) (xy 92.404193 -287.546577) (xy 92.453077 -287.560737)
			(xy 92.499056 -287.582554) (xy 92.54094 -287.611464) (xy 92.577644 -287.646719) (xy 92.608217 -287.687405)
			(xy 92.631868 -287.732468) (xy 92.647984 -287.780742) (xy 92.656148 -287.830976) (xy 92.65666 -287.856422)
			(xy 92.656157 -287.881411) (xy 92.963474 -287.881411) (xy 92.963474 -287.831433) (xy 92.971293 -287.78207)
			(xy 92.986737 -287.734538) (xy 93.009427 -287.690006) (xy 93.038803 -287.649573) (xy 93.074143 -287.614233)
			(xy 93.114576 -287.584857) (xy 93.159108 -287.562167) (xy 93.20664 -287.546723) (xy 93.256003 -287.538904)
			(xy 93.305981 -287.538904) (xy 93.355344 -287.546723) (xy 93.402876 -287.562167) (xy 93.447408 -287.584857)
			(xy 93.487841 -287.614233) (xy 93.523181 -287.649573) (xy 93.552557 -287.690006) (xy 93.575247 -287.734538)
			(xy 93.590691 -287.78207) (xy 93.59851 -287.831433) (xy 93.599 -287.856422) (xy 93.904811 -287.856422)
			(xy 93.908906 -287.805694) (xy 93.921085 -287.75628) (xy 93.941033 -287.70946) (xy 93.968234 -287.666446)
			(xy 94.001982 -287.628352) (xy 94.041404 -287.596165) (xy 94.085478 -287.570719) (xy 94.133064 -287.552672)
			(xy 94.182928 -287.542492) (xy 94.23378 -287.540443) (xy 94.284301 -287.546577) (xy 94.333185 -287.560737)
			(xy 94.379164 -287.582554) (xy 94.421048 -287.611464) (xy 94.457752 -287.646719) (xy 94.488325 -287.687405)
			(xy 94.511976 -287.732468) (xy 94.528092 -287.780742) (xy 94.536256 -287.830976) (xy 94.536768 -287.856422)
			(xy 94.536265 -287.881411) (xy 94.843582 -287.881411) (xy 94.843582 -287.831433) (xy 94.851401 -287.78207)
			(xy 94.866845 -287.734538) (xy 94.889535 -287.690006) (xy 94.918911 -287.649573) (xy 94.954251 -287.614233)
			(xy 94.994684 -287.584857) (xy 95.039216 -287.562167) (xy 95.086748 -287.546723) (xy 95.136111 -287.538904)
			(xy 95.186089 -287.538904) (xy 95.235452 -287.546723) (xy 95.282984 -287.562167) (xy 95.327516 -287.584857)
			(xy 95.367949 -287.614233) (xy 95.403289 -287.649573) (xy 95.432665 -287.690006) (xy 95.455355 -287.734538)
			(xy 95.470799 -287.78207) (xy 95.478618 -287.831433) (xy 95.479108 -287.856422) (xy 95.784919 -287.856422)
			(xy 95.789014 -287.805694) (xy 95.801193 -287.75628) (xy 95.821141 -287.70946) (xy 95.848342 -287.666446)
			(xy 95.88209 -287.628352) (xy 95.921512 -287.596165) (xy 95.965586 -287.570719) (xy 96.013172 -287.552672)
			(xy 96.063036 -287.542492) (xy 96.113888 -287.540443) (xy 96.164409 -287.546577) (xy 96.213293 -287.560737)
			(xy 96.259272 -287.582554) (xy 96.301156 -287.611464) (xy 96.33786 -287.646719) (xy 96.368433 -287.687405)
			(xy 96.392084 -287.732468) (xy 96.4082 -287.780742) (xy 96.416364 -287.830976) (xy 96.416876 -287.856422)
			(xy 96.416373 -287.881411) (xy 96.723436 -287.881411) (xy 96.723436 -287.831433) (xy 96.731255 -287.78207)
			(xy 96.746699 -287.734538) (xy 96.769389 -287.690006) (xy 96.798765 -287.649573) (xy 96.834105 -287.614233)
			(xy 96.874538 -287.584857) (xy 96.91907 -287.562167) (xy 96.966602 -287.546723) (xy 97.015965 -287.538904)
			(xy 97.065943 -287.538904) (xy 97.115306 -287.546723) (xy 97.162838 -287.562167) (xy 97.20737 -287.584857)
			(xy 97.247803 -287.614233) (xy 97.283143 -287.649573) (xy 97.312519 -287.690006) (xy 97.335209 -287.734538)
			(xy 97.350653 -287.78207) (xy 97.358472 -287.831433) (xy 97.358962 -287.856422) (xy 97.664773 -287.856422)
			(xy 97.668868 -287.805694) (xy 97.681047 -287.75628) (xy 97.700995 -287.70946) (xy 97.728196 -287.666446)
			(xy 97.761944 -287.628352) (xy 97.801366 -287.596165) (xy 97.84544 -287.570719) (xy 97.893026 -287.552672)
			(xy 97.94289 -287.542492) (xy 97.993742 -287.540443) (xy 98.044263 -287.546577) (xy 98.093147 -287.560737)
			(xy 98.139126 -287.582554) (xy 98.18101 -287.611464) (xy 98.217714 -287.646719) (xy 98.248287 -287.687405)
			(xy 98.271938 -287.732468) (xy 98.288054 -287.780742) (xy 98.296218 -287.830976) (xy 98.29673 -287.856422)
			(xy 98.604827 -287.856422) (xy 98.608922 -287.805694) (xy 98.621101 -287.75628) (xy 98.641049 -287.70946)
			(xy 98.66825 -287.666446) (xy 98.701998 -287.628352) (xy 98.74142 -287.596165) (xy 98.785494 -287.570719)
			(xy 98.83308 -287.552672) (xy 98.882944 -287.542492) (xy 98.933796 -287.540443) (xy 98.984317 -287.546577)
			(xy 99.033201 -287.560737) (xy 99.07918 -287.582554) (xy 99.121064 -287.611464) (xy 99.157768 -287.646719)
			(xy 99.188341 -287.687405) (xy 99.211992 -287.732468) (xy 99.228108 -287.780742) (xy 99.236272 -287.830976)
			(xy 99.236784 -287.856422) (xy 99.236281 -287.881411) (xy 99.543598 -287.881411) (xy 99.543598 -287.831433)
			(xy 99.551417 -287.78207) (xy 99.566861 -287.734538) (xy 99.589551 -287.690006) (xy 99.618927 -287.649573)
			(xy 99.654267 -287.614233) (xy 99.6947 -287.584857) (xy 99.739232 -287.562167) (xy 99.786764 -287.546723)
			(xy 99.836127 -287.538904) (xy 99.886105 -287.538904) (xy 99.935468 -287.546723) (xy 99.983 -287.562167)
			(xy 100.027532 -287.584857) (xy 100.067965 -287.614233) (xy 100.103305 -287.649573) (xy 100.132681 -287.690006)
			(xy 100.155371 -287.734538) (xy 100.170815 -287.78207) (xy 100.178634 -287.831433) (xy 100.179124 -287.856422)
			(xy 100.484935 -287.856422) (xy 100.48903 -287.805694) (xy 100.501209 -287.75628) (xy 100.521157 -287.70946)
			(xy 100.548358 -287.666446) (xy 100.582106 -287.628352) (xy 100.621528 -287.596165) (xy 100.665602 -287.570719)
			(xy 100.713188 -287.552672) (xy 100.763052 -287.542492) (xy 100.813904 -287.540443) (xy 100.864425 -287.546577)
			(xy 100.913309 -287.560737) (xy 100.959288 -287.582554) (xy 101.001172 -287.611464) (xy 101.037876 -287.646719)
			(xy 101.068449 -287.687405) (xy 101.0921 -287.732468) (xy 101.108216 -287.780742) (xy 101.11638 -287.830976)
			(xy 101.116892 -287.856422) (xy 101.424735 -287.856422) (xy 101.42883 -287.805694) (xy 101.441009 -287.75628)
			(xy 101.460957 -287.70946) (xy 101.488158 -287.666446) (xy 101.521906 -287.628352) (xy 101.561328 -287.596165)
			(xy 101.605402 -287.570719) (xy 101.652988 -287.552672) (xy 101.702852 -287.542492) (xy 101.753704 -287.540443)
			(xy 101.804225 -287.546577) (xy 101.853109 -287.560737) (xy 101.899088 -287.582554) (xy 101.940972 -287.611464)
			(xy 101.977676 -287.646719) (xy 102.008249 -287.687405) (xy 102.0319 -287.732468) (xy 102.048016 -287.780742)
			(xy 102.05618 -287.830976) (xy 102.056692 -287.856422) (xy 102.056189 -287.881411) (xy 102.363506 -287.881411)
			(xy 102.363506 -287.831433) (xy 102.371325 -287.78207) (xy 102.386769 -287.734538) (xy 102.409459 -287.690006)
			(xy 102.438835 -287.649573) (xy 102.474175 -287.614233) (xy 102.514608 -287.584857) (xy 102.55914 -287.562167)
			(xy 102.606672 -287.546723) (xy 102.656035 -287.538904) (xy 102.706013 -287.538904) (xy 102.755376 -287.546723)
			(xy 102.802908 -287.562167) (xy 102.84744 -287.584857) (xy 102.887873 -287.614233) (xy 102.923213 -287.649573)
			(xy 102.952589 -287.690006) (xy 102.975279 -287.734538) (xy 102.990723 -287.78207) (xy 102.998542 -287.831433)
			(xy 102.999032 -287.856422) (xy 103.304843 -287.856422) (xy 103.308938 -287.805694) (xy 103.321117 -287.75628)
			(xy 103.341065 -287.70946) (xy 103.368266 -287.666446) (xy 103.402014 -287.628352) (xy 103.441436 -287.596165)
			(xy 103.48551 -287.570719) (xy 103.533096 -287.552672) (xy 103.58296 -287.542492) (xy 103.633812 -287.540443)
			(xy 103.684333 -287.546577) (xy 103.733217 -287.560737) (xy 103.779196 -287.582554) (xy 103.82108 -287.611464)
			(xy 103.857784 -287.646719) (xy 103.888357 -287.687405) (xy 103.912008 -287.732468) (xy 103.928124 -287.780742)
			(xy 103.936288 -287.830976) (xy 103.9368 -287.856422) (xy 104.244897 -287.856422) (xy 104.248992 -287.805694)
			(xy 104.261171 -287.75628) (xy 104.281119 -287.70946) (xy 104.30832 -287.666446) (xy 104.342068 -287.628352)
			(xy 104.38149 -287.596165) (xy 104.425564 -287.570719) (xy 104.47315 -287.552672) (xy 104.523014 -287.542492)
			(xy 104.573866 -287.540443) (xy 104.624387 -287.546577) (xy 104.673271 -287.560737) (xy 104.71925 -287.582554)
			(xy 104.761134 -287.611464) (xy 104.797838 -287.646719) (xy 104.828411 -287.687405) (xy 104.852062 -287.732468)
			(xy 104.868178 -287.780742) (xy 104.876342 -287.830976) (xy 104.876854 -287.856422) (xy 104.876351 -287.881411)
			(xy 105.183414 -287.881411) (xy 105.183414 -287.831433) (xy 105.191233 -287.78207) (xy 105.206677 -287.734538)
			(xy 105.229367 -287.690006) (xy 105.258743 -287.649573) (xy 105.294083 -287.614233) (xy 105.334516 -287.584857)
			(xy 105.379048 -287.562167) (xy 105.42658 -287.546723) (xy 105.475943 -287.538904) (xy 105.525921 -287.538904)
			(xy 105.575284 -287.546723) (xy 105.622816 -287.562167) (xy 105.667348 -287.584857) (xy 105.707781 -287.614233)
			(xy 105.743121 -287.649573) (xy 105.772497 -287.690006) (xy 105.795187 -287.734538) (xy 105.810631 -287.78207)
			(xy 105.81845 -287.831433) (xy 105.81894 -287.856422) (xy 106.124751 -287.856422) (xy 106.128846 -287.805694)
			(xy 106.141025 -287.75628) (xy 106.160973 -287.70946) (xy 106.188174 -287.666446) (xy 106.221922 -287.628352)
			(xy 106.261344 -287.596165) (xy 106.305418 -287.570719) (xy 106.353004 -287.552672) (xy 106.402868 -287.542492)
			(xy 106.45372 -287.540443) (xy 106.504241 -287.546577) (xy 106.553125 -287.560737) (xy 106.599104 -287.582554)
			(xy 106.640988 -287.611464) (xy 106.677692 -287.646719) (xy 106.708265 -287.687405) (xy 106.731916 -287.732468)
			(xy 106.748032 -287.780742) (xy 106.756196 -287.830976) (xy 106.756708 -287.856422) (xy 107.064805 -287.856422)
			(xy 107.0689 -287.805694) (xy 107.081079 -287.75628) (xy 107.101027 -287.70946) (xy 107.128228 -287.666446)
			(xy 107.161976 -287.628352) (xy 107.201398 -287.596165) (xy 107.245472 -287.570719) (xy 107.293058 -287.552672)
			(xy 107.342922 -287.542492) (xy 107.393774 -287.540443) (xy 107.444295 -287.546577) (xy 107.493179 -287.560737)
			(xy 107.539158 -287.582554) (xy 107.581042 -287.611464) (xy 107.617746 -287.646719) (xy 107.648319 -287.687405)
			(xy 107.67197 -287.732468) (xy 107.688086 -287.780742) (xy 107.69625 -287.830976) (xy 107.696762 -287.856422)
			(xy 107.696259 -287.881411) (xy 108.003576 -287.881411) (xy 108.003576 -287.831433) (xy 108.011395 -287.78207)
			(xy 108.026839 -287.734538) (xy 108.049529 -287.690006) (xy 108.078905 -287.649573) (xy 108.114245 -287.614233)
			(xy 108.154678 -287.584857) (xy 108.19921 -287.562167) (xy 108.246742 -287.546723) (xy 108.296105 -287.538904)
			(xy 108.346083 -287.538904) (xy 108.395446 -287.546723) (xy 108.442978 -287.562167) (xy 108.48751 -287.584857)
			(xy 108.527943 -287.614233) (xy 108.563283 -287.649573) (xy 108.592659 -287.690006) (xy 108.615349 -287.734538)
			(xy 108.630793 -287.78207) (xy 108.638612 -287.831433) (xy 108.639102 -287.856422) (xy 108.638612 -287.881411)
			(xy 108.94363 -287.881411) (xy 108.94363 -287.831433) (xy 108.951449 -287.78207) (xy 108.966893 -287.734538)
			(xy 108.989583 -287.690006) (xy 109.018959 -287.649573) (xy 109.054299 -287.614233) (xy 109.094732 -287.584857)
			(xy 109.139264 -287.562167) (xy 109.186796 -287.546723) (xy 109.236159 -287.538904) (xy 109.286137 -287.538904)
			(xy 109.3355 -287.546723) (xy 109.383032 -287.562167) (xy 109.427564 -287.584857) (xy 109.467997 -287.614233)
			(xy 109.503337 -287.649573) (xy 109.532713 -287.690006) (xy 109.555403 -287.734538) (xy 109.570847 -287.78207)
			(xy 109.578666 -287.831433) (xy 109.579156 -287.856422) (xy 109.578666 -287.881411) (xy 109.88343 -287.881411)
			(xy 109.88343 -287.831433) (xy 109.891249 -287.78207) (xy 109.906693 -287.734538) (xy 109.929383 -287.690006)
			(xy 109.958759 -287.649573) (xy 109.994099 -287.614233) (xy 110.034532 -287.584857) (xy 110.079064 -287.562167)
			(xy 110.126596 -287.546723) (xy 110.175959 -287.538904) (xy 110.225937 -287.538904) (xy 110.2753 -287.546723)
			(xy 110.322832 -287.562167) (xy 110.367364 -287.584857) (xy 110.407797 -287.614233) (xy 110.443137 -287.649573)
			(xy 110.472513 -287.690006) (xy 110.495203 -287.734538) (xy 110.510647 -287.78207) (xy 110.518466 -287.831433)
			(xy 110.518956 -287.856422) (xy 110.518466 -287.881411) (xy 113.637296 -287.881411) (xy 113.637296 -287.831433)
			(xy 113.645115 -287.78207) (xy 113.660559 -287.734538) (xy 113.683249 -287.690006) (xy 113.712625 -287.649573)
			(xy 113.747965 -287.614233) (xy 113.788398 -287.584857) (xy 113.83293 -287.562167) (xy 113.880462 -287.546723)
			(xy 113.929825 -287.538904) (xy 113.979803 -287.538904) (xy 114.029166 -287.546723) (xy 114.076698 -287.562167)
			(xy 114.12123 -287.584857) (xy 114.161663 -287.614233) (xy 114.197003 -287.649573) (xy 114.226379 -287.690006)
			(xy 114.249069 -287.734538) (xy 114.264513 -287.78207) (xy 114.272332 -287.831433) (xy 114.272822 -287.856422)
			(xy 114.272332 -287.881411) (xy 114.577096 -287.881411) (xy 114.577096 -287.831433) (xy 114.584915 -287.78207)
			(xy 114.600359 -287.734538) (xy 114.623049 -287.690006) (xy 114.652425 -287.649573) (xy 114.687765 -287.614233)
			(xy 114.728198 -287.584857) (xy 114.77273 -287.562167) (xy 114.820262 -287.546723) (xy 114.869625 -287.538904)
			(xy 114.919603 -287.538904) (xy 114.968966 -287.546723) (xy 115.016498 -287.562167) (xy 115.06103 -287.584857)
			(xy 115.101463 -287.614233) (xy 115.136803 -287.649573) (xy 115.166179 -287.690006) (xy 115.188869 -287.734538)
			(xy 115.204313 -287.78207) (xy 115.212132 -287.831433) (xy 115.212622 -287.856422) (xy 115.212132 -287.881411)
			(xy 115.51715 -287.881411) (xy 115.51715 -287.831433) (xy 115.524969 -287.78207) (xy 115.540413 -287.734538)
			(xy 115.563103 -287.690006) (xy 115.592479 -287.649573) (xy 115.627819 -287.614233) (xy 115.668252 -287.584857)
			(xy 115.712784 -287.562167) (xy 115.760316 -287.546723) (xy 115.809679 -287.538904) (xy 115.859657 -287.538904)
			(xy 115.90902 -287.546723) (xy 115.956552 -287.562167) (xy 116.001084 -287.584857) (xy 116.041517 -287.614233)
			(xy 116.076857 -287.649573) (xy 116.106233 -287.690006) (xy 116.128923 -287.734538) (xy 116.144367 -287.78207)
			(xy 116.152186 -287.831433) (xy 116.152676 -287.856422) (xy 116.458487 -287.856422) (xy 116.462582 -287.805694)
			(xy 116.474761 -287.75628) (xy 116.494709 -287.70946) (xy 116.52191 -287.666446) (xy 116.555658 -287.628352)
			(xy 116.59508 -287.596165) (xy 116.639154 -287.570719) (xy 116.68674 -287.552672) (xy 116.736604 -287.542492)
			(xy 116.787456 -287.540443) (xy 116.837977 -287.546577) (xy 116.886861 -287.560737) (xy 116.93284 -287.582554)
			(xy 116.974724 -287.611464) (xy 117.011428 -287.646719) (xy 117.042001 -287.687405) (xy 117.065652 -287.732468)
			(xy 117.081768 -287.780742) (xy 117.089932 -287.830976) (xy 117.090444 -287.856422) (xy 117.398541 -287.856422)
			(xy 117.402636 -287.805694) (xy 117.414815 -287.75628) (xy 117.434763 -287.70946) (xy 117.461964 -287.666446)
			(xy 117.495712 -287.628352) (xy 117.535134 -287.596165) (xy 117.579208 -287.570719) (xy 117.626794 -287.552672)
			(xy 117.676658 -287.542492) (xy 117.72751 -287.540443) (xy 117.778031 -287.546577) (xy 117.826915 -287.560737)
			(xy 117.872894 -287.582554) (xy 117.914778 -287.611464) (xy 117.951482 -287.646719) (xy 117.982055 -287.687405)
			(xy 118.005706 -287.732468) (xy 118.021822 -287.780742) (xy 118.029986 -287.830976) (xy 118.030498 -287.856422)
			(xy 118.029995 -287.881411) (xy 118.337312 -287.881411) (xy 118.337312 -287.831433) (xy 118.345131 -287.78207)
			(xy 118.360575 -287.734538) (xy 118.383265 -287.690006) (xy 118.412641 -287.649573) (xy 118.447981 -287.614233)
			(xy 118.488414 -287.584857) (xy 118.532946 -287.562167) (xy 118.580478 -287.546723) (xy 118.629841 -287.538904)
			(xy 118.679819 -287.538904) (xy 118.729182 -287.546723) (xy 118.776714 -287.562167) (xy 118.821246 -287.584857)
			(xy 118.861679 -287.614233) (xy 118.897019 -287.649573) (xy 118.926395 -287.690006) (xy 118.949085 -287.734538)
			(xy 118.964529 -287.78207) (xy 118.972348 -287.831433) (xy 118.972838 -287.856422) (xy 119.278395 -287.856422)
			(xy 119.28249 -287.805694) (xy 119.294669 -287.75628) (xy 119.314617 -287.70946) (xy 119.341818 -287.666446)
			(xy 119.375566 -287.628352) (xy 119.414988 -287.596165) (xy 119.459062 -287.570719) (xy 119.506648 -287.552672)
			(xy 119.556512 -287.542492) (xy 119.607364 -287.540443) (xy 119.657885 -287.546577) (xy 119.706769 -287.560737)
			(xy 119.752748 -287.582554) (xy 119.794632 -287.611464) (xy 119.831336 -287.646719) (xy 119.861909 -287.687405)
			(xy 119.88556 -287.732468) (xy 119.901676 -287.780742) (xy 119.90984 -287.830976) (xy 119.910352 -287.856422)
			(xy 120.218449 -287.856422) (xy 120.222544 -287.805694) (xy 120.234723 -287.75628) (xy 120.254671 -287.70946)
			(xy 120.281872 -287.666446) (xy 120.31562 -287.628352) (xy 120.355042 -287.596165) (xy 120.399116 -287.570719)
			(xy 120.446702 -287.552672) (xy 120.496566 -287.542492) (xy 120.547418 -287.540443) (xy 120.597939 -287.546577)
			(xy 120.646823 -287.560737) (xy 120.692802 -287.582554) (xy 120.734686 -287.611464) (xy 120.77139 -287.646719)
			(xy 120.801963 -287.687405) (xy 120.825614 -287.732468) (xy 120.84173 -287.780742) (xy 120.849894 -287.830976)
			(xy 120.850406 -287.856422) (xy 120.849903 -287.881411) (xy 121.15722 -287.881411) (xy 121.15722 -287.831433)
			(xy 121.165039 -287.78207) (xy 121.180483 -287.734538) (xy 121.203173 -287.690006) (xy 121.232549 -287.649573)
			(xy 121.267889 -287.614233) (xy 121.308322 -287.584857) (xy 121.352854 -287.562167) (xy 121.400386 -287.546723)
			(xy 121.449749 -287.538904) (xy 121.499727 -287.538904) (xy 121.54909 -287.546723) (xy 121.596622 -287.562167)
			(xy 121.641154 -287.584857) (xy 121.681587 -287.614233) (xy 121.716927 -287.649573) (xy 121.746303 -287.690006)
			(xy 121.768993 -287.734538) (xy 121.784437 -287.78207) (xy 121.792256 -287.831433) (xy 121.792746 -287.856422)
			(xy 122.098557 -287.856422) (xy 122.102652 -287.805694) (xy 122.114831 -287.75628) (xy 122.134779 -287.70946)
			(xy 122.16198 -287.666446) (xy 122.195728 -287.628352) (xy 122.23515 -287.596165) (xy 122.279224 -287.570719)
			(xy 122.32681 -287.552672) (xy 122.376674 -287.542492) (xy 122.427526 -287.540443) (xy 122.478047 -287.546577)
			(xy 122.526931 -287.560737) (xy 122.57291 -287.582554) (xy 122.614794 -287.611464) (xy 122.651498 -287.646719)
			(xy 122.682071 -287.687405) (xy 122.705722 -287.732468) (xy 122.721838 -287.780742) (xy 122.730002 -287.830976)
			(xy 122.730514 -287.856422) (xy 123.038611 -287.856422) (xy 123.042706 -287.805694) (xy 123.054885 -287.75628)
			(xy 123.074833 -287.70946) (xy 123.102034 -287.666446) (xy 123.135782 -287.628352) (xy 123.175204 -287.596165)
			(xy 123.219278 -287.570719) (xy 123.266864 -287.552672) (xy 123.316728 -287.542492) (xy 123.36758 -287.540443)
			(xy 123.418101 -287.546577) (xy 123.466985 -287.560737) (xy 123.512964 -287.582554) (xy 123.554848 -287.611464)
			(xy 123.591552 -287.646719) (xy 123.622125 -287.687405) (xy 123.645776 -287.732468) (xy 123.661892 -287.780742)
			(xy 123.670056 -287.830976) (xy 123.670568 -287.856422) (xy 123.670065 -287.881411) (xy 123.977128 -287.881411)
			(xy 123.977128 -287.831433) (xy 123.984947 -287.78207) (xy 124.000391 -287.734538) (xy 124.023081 -287.690006)
			(xy 124.052457 -287.649573) (xy 124.087797 -287.614233) (xy 124.12823 -287.584857) (xy 124.172762 -287.562167)
			(xy 124.220294 -287.546723) (xy 124.269657 -287.538904) (xy 124.319635 -287.538904) (xy 124.368998 -287.546723)
			(xy 124.41653 -287.562167) (xy 124.461062 -287.584857) (xy 124.501495 -287.614233) (xy 124.536835 -287.649573)
			(xy 124.566211 -287.690006) (xy 124.588901 -287.734538) (xy 124.604345 -287.78207) (xy 124.612164 -287.831433)
			(xy 124.612654 -287.856422) (xy 124.918465 -287.856422) (xy 124.92256 -287.805694) (xy 124.934739 -287.75628)
			(xy 124.954687 -287.70946) (xy 124.981888 -287.666446) (xy 125.015636 -287.628352) (xy 125.055058 -287.596165)
			(xy 125.099132 -287.570719) (xy 125.146718 -287.552672) (xy 125.196582 -287.542492) (xy 125.247434 -287.540443)
			(xy 125.297955 -287.546577) (xy 125.346839 -287.560737) (xy 125.392818 -287.582554) (xy 125.434702 -287.611464)
			(xy 125.471406 -287.646719) (xy 125.501979 -287.687405) (xy 125.52563 -287.732468) (xy 125.541746 -287.780742)
			(xy 125.54991 -287.830976) (xy 125.550422 -287.856422) (xy 125.858519 -287.856422) (xy 125.862614 -287.805694)
			(xy 125.874793 -287.75628) (xy 125.894741 -287.70946) (xy 125.921942 -287.666446) (xy 125.95569 -287.628352)
			(xy 125.995112 -287.596165) (xy 126.039186 -287.570719) (xy 126.086772 -287.552672) (xy 126.136636 -287.542492)
			(xy 126.187488 -287.540443) (xy 126.238009 -287.546577) (xy 126.286893 -287.560737) (xy 126.332872 -287.582554)
			(xy 126.374756 -287.611464) (xy 126.41146 -287.646719) (xy 126.442033 -287.687405) (xy 126.465684 -287.732468)
			(xy 126.4818 -287.780742) (xy 126.489964 -287.830976) (xy 126.490476 -287.856422) (xy 126.489964 -287.881868)
			(xy 126.4818 -287.932102) (xy 126.465684 -287.980376) (xy 126.442033 -288.025439) (xy 126.41146 -288.066125)
			(xy 126.374756 -288.10138) (xy 126.332872 -288.13029) (xy 126.286893 -288.152107) (xy 126.238009 -288.166267)
			(xy 126.187488 -288.172401) (xy 126.136636 -288.170352) (xy 126.086772 -288.160172) (xy 126.039186 -288.142125)
			(xy 125.995112 -288.116679) (xy 125.95569 -288.084492) (xy 125.921942 -288.046398) (xy 125.894741 -288.003384)
			(xy 125.874793 -287.956564) (xy 125.862614 -287.90715) (xy 125.858519 -287.856422) (xy 125.550422 -287.856422)
			(xy 125.54991 -287.881868) (xy 125.541746 -287.932102) (xy 125.52563 -287.980376) (xy 125.501979 -288.025439)
			(xy 125.471406 -288.066125) (xy 125.434702 -288.10138) (xy 125.392818 -288.13029) (xy 125.346839 -288.152107)
			(xy 125.297955 -288.166267) (xy 125.247434 -288.172401) (xy 125.196582 -288.170352) (xy 125.146718 -288.160172)
			(xy 125.099132 -288.142125) (xy 125.055058 -288.116679) (xy 125.015636 -288.084492) (xy 124.981888 -288.046398)
			(xy 124.954687 -288.003384) (xy 124.934739 -287.956564) (xy 124.92256 -287.90715) (xy 124.918465 -287.856422)
			(xy 124.612654 -287.856422) (xy 124.612164 -287.881411) (xy 124.604345 -287.930774) (xy 124.588901 -287.978306)
			(xy 124.566211 -288.022838) (xy 124.536835 -288.063271) (xy 124.501495 -288.098611) (xy 124.461062 -288.127987)
			(xy 124.41653 -288.150677) (xy 124.368998 -288.166121) (xy 124.319635 -288.17394) (xy 124.269657 -288.17394)
			(xy 124.220294 -288.166121) (xy 124.172762 -288.150677) (xy 124.12823 -288.127987) (xy 124.087797 -288.098611)
			(xy 124.052457 -288.063271) (xy 124.023081 -288.022838) (xy 124.000391 -287.978306) (xy 123.984947 -287.930774)
			(xy 123.977128 -287.881411) (xy 123.670065 -287.881411) (xy 123.670056 -287.881868) (xy 123.661892 -287.932102)
			(xy 123.645776 -287.980376) (xy 123.622125 -288.025439) (xy 123.591552 -288.066125) (xy 123.554848 -288.10138)
			(xy 123.512964 -288.13029) (xy 123.466985 -288.152107) (xy 123.418101 -288.166267) (xy 123.36758 -288.172401)
			(xy 123.316728 -288.170352) (xy 123.266864 -288.160172) (xy 123.219278 -288.142125) (xy 123.175204 -288.116679)
			(xy 123.135782 -288.084492) (xy 123.102034 -288.046398) (xy 123.074833 -288.003384) (xy 123.054885 -287.956564)
			(xy 123.042706 -287.90715) (xy 123.038611 -287.856422) (xy 122.730514 -287.856422) (xy 122.730002 -287.881868)
			(xy 122.721838 -287.932102) (xy 122.705722 -287.980376) (xy 122.682071 -288.025439) (xy 122.651498 -288.066125)
			(xy 122.614794 -288.10138) (xy 122.57291 -288.13029) (xy 122.526931 -288.152107) (xy 122.478047 -288.166267)
			(xy 122.427526 -288.172401) (xy 122.376674 -288.170352) (xy 122.32681 -288.160172) (xy 122.279224 -288.142125)
			(xy 122.23515 -288.116679) (xy 122.195728 -288.084492) (xy 122.16198 -288.046398) (xy 122.134779 -288.003384)
			(xy 122.114831 -287.956564) (xy 122.102652 -287.90715) (xy 122.098557 -287.856422) (xy 121.792746 -287.856422)
			(xy 121.792256 -287.881411) (xy 121.784437 -287.930774) (xy 121.768993 -287.978306) (xy 121.746303 -288.022838)
			(xy 121.716927 -288.063271) (xy 121.681587 -288.098611) (xy 121.641154 -288.127987) (xy 121.596622 -288.150677)
			(xy 121.54909 -288.166121) (xy 121.499727 -288.17394) (xy 121.449749 -288.17394) (xy 121.400386 -288.166121)
			(xy 121.352854 -288.150677) (xy 121.308322 -288.127987) (xy 121.267889 -288.098611) (xy 121.232549 -288.063271)
			(xy 121.203173 -288.022838) (xy 121.180483 -287.978306) (xy 121.165039 -287.930774) (xy 121.15722 -287.881411)
			(xy 120.849903 -287.881411) (xy 120.849894 -287.881868) (xy 120.84173 -287.932102) (xy 120.825614 -287.980376)
			(xy 120.801963 -288.025439) (xy 120.77139 -288.066125) (xy 120.734686 -288.10138) (xy 120.692802 -288.13029)
			(xy 120.646823 -288.152107) (xy 120.597939 -288.166267) (xy 120.547418 -288.172401) (xy 120.496566 -288.170352)
			(xy 120.446702 -288.160172) (xy 120.399116 -288.142125) (xy 120.355042 -288.116679) (xy 120.31562 -288.084492)
			(xy 120.281872 -288.046398) (xy 120.254671 -288.003384) (xy 120.234723 -287.956564) (xy 120.222544 -287.90715)
			(xy 120.218449 -287.856422) (xy 119.910352 -287.856422) (xy 119.90984 -287.881868) (xy 119.901676 -287.932102)
			(xy 119.88556 -287.980376) (xy 119.861909 -288.025439) (xy 119.831336 -288.066125) (xy 119.794632 -288.10138)
			(xy 119.752748 -288.13029) (xy 119.706769 -288.152107) (xy 119.657885 -288.166267) (xy 119.607364 -288.172401)
			(xy 119.556512 -288.170352) (xy 119.506648 -288.160172) (xy 119.459062 -288.142125) (xy 119.414988 -288.116679)
			(xy 119.375566 -288.084492) (xy 119.341818 -288.046398) (xy 119.314617 -288.003384) (xy 119.294669 -287.956564)
			(xy 119.28249 -287.90715) (xy 119.278395 -287.856422) (xy 118.972838 -287.856422) (xy 118.972348 -287.881411)
			(xy 118.964529 -287.930774) (xy 118.949085 -287.978306) (xy 118.926395 -288.022838) (xy 118.897019 -288.063271)
			(xy 118.861679 -288.098611) (xy 118.821246 -288.127987) (xy 118.776714 -288.150677) (xy 118.729182 -288.166121)
			(xy 118.679819 -288.17394) (xy 118.629841 -288.17394) (xy 118.580478 -288.166121) (xy 118.532946 -288.150677)
			(xy 118.488414 -288.127987) (xy 118.447981 -288.098611) (xy 118.412641 -288.063271) (xy 118.383265 -288.022838)
			(xy 118.360575 -287.978306) (xy 118.345131 -287.930774) (xy 118.337312 -287.881411) (xy 118.029995 -287.881411)
			(xy 118.029986 -287.881868) (xy 118.021822 -287.932102) (xy 118.005706 -287.980376) (xy 117.982055 -288.025439)
			(xy 117.951482 -288.066125) (xy 117.914778 -288.10138) (xy 117.872894 -288.13029) (xy 117.826915 -288.152107)
			(xy 117.778031 -288.166267) (xy 117.72751 -288.172401) (xy 117.676658 -288.170352) (xy 117.626794 -288.160172)
			(xy 117.579208 -288.142125) (xy 117.535134 -288.116679) (xy 117.495712 -288.084492) (xy 117.461964 -288.046398)
			(xy 117.434763 -288.003384) (xy 117.414815 -287.956564) (xy 117.402636 -287.90715) (xy 117.398541 -287.856422)
			(xy 117.090444 -287.856422) (xy 117.089932 -287.881868) (xy 117.081768 -287.932102) (xy 117.065652 -287.980376)
			(xy 117.042001 -288.025439) (xy 117.011428 -288.066125) (xy 116.974724 -288.10138) (xy 116.93284 -288.13029)
			(xy 116.886861 -288.152107) (xy 116.837977 -288.166267) (xy 116.787456 -288.172401) (xy 116.736604 -288.170352)
			(xy 116.68674 -288.160172) (xy 116.639154 -288.142125) (xy 116.59508 -288.116679) (xy 116.555658 -288.084492)
			(xy 116.52191 -288.046398) (xy 116.494709 -288.003384) (xy 116.474761 -287.956564) (xy 116.462582 -287.90715)
			(xy 116.458487 -287.856422) (xy 116.152676 -287.856422) (xy 116.152186 -287.881411) (xy 116.144367 -287.930774)
			(xy 116.128923 -287.978306) (xy 116.106233 -288.022838) (xy 116.076857 -288.063271) (xy 116.041517 -288.098611)
			(xy 116.001084 -288.127987) (xy 115.956552 -288.150677) (xy 115.90902 -288.166121) (xy 115.859657 -288.17394)
			(xy 115.809679 -288.17394) (xy 115.760316 -288.166121) (xy 115.712784 -288.150677) (xy 115.668252 -288.127987)
			(xy 115.627819 -288.098611) (xy 115.592479 -288.063271) (xy 115.563103 -288.022838) (xy 115.540413 -287.978306)
			(xy 115.524969 -287.930774) (xy 115.51715 -287.881411) (xy 115.212132 -287.881411) (xy 115.204313 -287.930774)
			(xy 115.188869 -287.978306) (xy 115.166179 -288.022838) (xy 115.136803 -288.063271) (xy 115.101463 -288.098611)
			(xy 115.06103 -288.127987) (xy 115.016498 -288.150677) (xy 114.968966 -288.166121) (xy 114.919603 -288.17394)
			(xy 114.869625 -288.17394) (xy 114.820262 -288.166121) (xy 114.77273 -288.150677) (xy 114.728198 -288.127987)
			(xy 114.687765 -288.098611) (xy 114.652425 -288.063271) (xy 114.623049 -288.022838) (xy 114.600359 -287.978306)
			(xy 114.584915 -287.930774) (xy 114.577096 -287.881411) (xy 114.272332 -287.881411) (xy 114.264513 -287.930774)
			(xy 114.249069 -287.978306) (xy 114.226379 -288.022838) (xy 114.197003 -288.063271) (xy 114.161663 -288.098611)
			(xy 114.12123 -288.127987) (xy 114.076698 -288.150677) (xy 114.029166 -288.166121) (xy 113.979803 -288.17394)
			(xy 113.929825 -288.17394) (xy 113.880462 -288.166121) (xy 113.83293 -288.150677) (xy 113.788398 -288.127987)
			(xy 113.747965 -288.098611) (xy 113.712625 -288.063271) (xy 113.683249 -288.022838) (xy 113.660559 -287.978306)
			(xy 113.645115 -287.930774) (xy 113.637296 -287.881411) (xy 110.518466 -287.881411) (xy 110.510647 -287.930774)
			(xy 110.495203 -287.978306) (xy 110.472513 -288.022838) (xy 110.443137 -288.063271) (xy 110.407797 -288.098611)
			(xy 110.367364 -288.127987) (xy 110.322832 -288.150677) (xy 110.2753 -288.166121) (xy 110.225937 -288.17394)
			(xy 110.175959 -288.17394) (xy 110.126596 -288.166121) (xy 110.079064 -288.150677) (xy 110.034532 -288.127987)
			(xy 109.994099 -288.098611) (xy 109.958759 -288.063271) (xy 109.929383 -288.022838) (xy 109.906693 -287.978306)
			(xy 109.891249 -287.930774) (xy 109.88343 -287.881411) (xy 109.578666 -287.881411) (xy 109.570847 -287.930774)
			(xy 109.555403 -287.978306) (xy 109.532713 -288.022838) (xy 109.503337 -288.063271) (xy 109.467997 -288.098611)
			(xy 109.427564 -288.127987) (xy 109.383032 -288.150677) (xy 109.3355 -288.166121) (xy 109.286137 -288.17394)
			(xy 109.236159 -288.17394) (xy 109.186796 -288.166121) (xy 109.139264 -288.150677) (xy 109.094732 -288.127987)
			(xy 109.054299 -288.098611) (xy 109.018959 -288.063271) (xy 108.989583 -288.022838) (xy 108.966893 -287.978306)
			(xy 108.951449 -287.930774) (xy 108.94363 -287.881411) (xy 108.638612 -287.881411) (xy 108.630793 -287.930774)
			(xy 108.615349 -287.978306) (xy 108.592659 -288.022838) (xy 108.563283 -288.063271) (xy 108.527943 -288.098611)
			(xy 108.48751 -288.127987) (xy 108.442978 -288.150677) (xy 108.395446 -288.166121) (xy 108.346083 -288.17394)
			(xy 108.296105 -288.17394) (xy 108.246742 -288.166121) (xy 108.19921 -288.150677) (xy 108.154678 -288.127987)
			(xy 108.114245 -288.098611) (xy 108.078905 -288.063271) (xy 108.049529 -288.022838) (xy 108.026839 -287.978306)
			(xy 108.011395 -287.930774) (xy 108.003576 -287.881411) (xy 107.696259 -287.881411) (xy 107.69625 -287.881868)
			(xy 107.688086 -287.932102) (xy 107.67197 -287.980376) (xy 107.648319 -288.025439) (xy 107.617746 -288.066125)
			(xy 107.581042 -288.10138) (xy 107.539158 -288.13029) (xy 107.493179 -288.152107) (xy 107.444295 -288.166267)
			(xy 107.393774 -288.172401) (xy 107.342922 -288.170352) (xy 107.293058 -288.160172) (xy 107.245472 -288.142125)
			(xy 107.201398 -288.116679) (xy 107.161976 -288.084492) (xy 107.128228 -288.046398) (xy 107.101027 -288.003384)
			(xy 107.081079 -287.956564) (xy 107.0689 -287.90715) (xy 107.064805 -287.856422) (xy 106.756708 -287.856422)
			(xy 106.756196 -287.881868) (xy 106.748032 -287.932102) (xy 106.731916 -287.980376) (xy 106.708265 -288.025439)
			(xy 106.677692 -288.066125) (xy 106.640988 -288.10138) (xy 106.599104 -288.13029) (xy 106.553125 -288.152107)
			(xy 106.504241 -288.166267) (xy 106.45372 -288.172401) (xy 106.402868 -288.170352) (xy 106.353004 -288.160172)
			(xy 106.305418 -288.142125) (xy 106.261344 -288.116679) (xy 106.221922 -288.084492) (xy 106.188174 -288.046398)
			(xy 106.160973 -288.003384) (xy 106.141025 -287.956564) (xy 106.128846 -287.90715) (xy 106.124751 -287.856422)
			(xy 105.81894 -287.856422) (xy 105.81845 -287.881411) (xy 105.810631 -287.930774) (xy 105.795187 -287.978306)
			(xy 105.772497 -288.022838) (xy 105.743121 -288.063271) (xy 105.707781 -288.098611) (xy 105.667348 -288.127987)
			(xy 105.622816 -288.150677) (xy 105.575284 -288.166121) (xy 105.525921 -288.17394) (xy 105.475943 -288.17394)
			(xy 105.42658 -288.166121) (xy 105.379048 -288.150677) (xy 105.334516 -288.127987) (xy 105.294083 -288.098611)
			(xy 105.258743 -288.063271) (xy 105.229367 -288.022838) (xy 105.206677 -287.978306) (xy 105.191233 -287.930774)
			(xy 105.183414 -287.881411) (xy 104.876351 -287.881411) (xy 104.876342 -287.881868) (xy 104.868178 -287.932102)
			(xy 104.852062 -287.980376) (xy 104.828411 -288.025439) (xy 104.797838 -288.066125) (xy 104.761134 -288.10138)
			(xy 104.71925 -288.13029) (xy 104.673271 -288.152107) (xy 104.624387 -288.166267) (xy 104.573866 -288.172401)
			(xy 104.523014 -288.170352) (xy 104.47315 -288.160172) (xy 104.425564 -288.142125) (xy 104.38149 -288.116679)
			(xy 104.342068 -288.084492) (xy 104.30832 -288.046398) (xy 104.281119 -288.003384) (xy 104.261171 -287.956564)
			(xy 104.248992 -287.90715) (xy 104.244897 -287.856422) (xy 103.9368 -287.856422) (xy 103.936288 -287.881868)
			(xy 103.928124 -287.932102) (xy 103.912008 -287.980376) (xy 103.888357 -288.025439) (xy 103.857784 -288.066125)
			(xy 103.82108 -288.10138) (xy 103.779196 -288.13029) (xy 103.733217 -288.152107) (xy 103.684333 -288.166267)
			(xy 103.633812 -288.172401) (xy 103.58296 -288.170352) (xy 103.533096 -288.160172) (xy 103.48551 -288.142125)
			(xy 103.441436 -288.116679) (xy 103.402014 -288.084492) (xy 103.368266 -288.046398) (xy 103.341065 -288.003384)
			(xy 103.321117 -287.956564) (xy 103.308938 -287.90715) (xy 103.304843 -287.856422) (xy 102.999032 -287.856422)
			(xy 102.998542 -287.881411) (xy 102.990723 -287.930774) (xy 102.975279 -287.978306) (xy 102.952589 -288.022838)
			(xy 102.923213 -288.063271) (xy 102.887873 -288.098611) (xy 102.84744 -288.127987) (xy 102.802908 -288.150677)
			(xy 102.755376 -288.166121) (xy 102.706013 -288.17394) (xy 102.656035 -288.17394) (xy 102.606672 -288.166121)
			(xy 102.55914 -288.150677) (xy 102.514608 -288.127987) (xy 102.474175 -288.098611) (xy 102.438835 -288.063271)
			(xy 102.409459 -288.022838) (xy 102.386769 -287.978306) (xy 102.371325 -287.930774) (xy 102.363506 -287.881411)
			(xy 102.056189 -287.881411) (xy 102.05618 -287.881868) (xy 102.048016 -287.932102) (xy 102.0319 -287.980376)
			(xy 102.008249 -288.025439) (xy 101.977676 -288.066125) (xy 101.940972 -288.10138) (xy 101.899088 -288.13029)
			(xy 101.853109 -288.152107) (xy 101.804225 -288.166267) (xy 101.753704 -288.172401) (xy 101.702852 -288.170352)
			(xy 101.652988 -288.160172) (xy 101.605402 -288.142125) (xy 101.561328 -288.116679) (xy 101.521906 -288.084492)
			(xy 101.488158 -288.046398) (xy 101.460957 -288.003384) (xy 101.441009 -287.956564) (xy 101.42883 -287.90715)
			(xy 101.424735 -287.856422) (xy 101.116892 -287.856422) (xy 101.11638 -287.881868) (xy 101.108216 -287.932102)
			(xy 101.0921 -287.980376) (xy 101.068449 -288.025439) (xy 101.037876 -288.066125) (xy 101.001172 -288.10138)
			(xy 100.959288 -288.13029) (xy 100.913309 -288.152107) (xy 100.864425 -288.166267) (xy 100.813904 -288.172401)
			(xy 100.763052 -288.170352) (xy 100.713188 -288.160172) (xy 100.665602 -288.142125) (xy 100.621528 -288.116679)
			(xy 100.582106 -288.084492) (xy 100.548358 -288.046398) (xy 100.521157 -288.003384) (xy 100.501209 -287.956564)
			(xy 100.48903 -287.90715) (xy 100.484935 -287.856422) (xy 100.179124 -287.856422) (xy 100.178634 -287.881411)
			(xy 100.170815 -287.930774) (xy 100.155371 -287.978306) (xy 100.132681 -288.022838) (xy 100.103305 -288.063271)
			(xy 100.067965 -288.098611) (xy 100.027532 -288.127987) (xy 99.983 -288.150677) (xy 99.935468 -288.166121)
			(xy 99.886105 -288.17394) (xy 99.836127 -288.17394) (xy 99.786764 -288.166121) (xy 99.739232 -288.150677)
			(xy 99.6947 -288.127987) (xy 99.654267 -288.098611) (xy 99.618927 -288.063271) (xy 99.589551 -288.022838)
			(xy 99.566861 -287.978306) (xy 99.551417 -287.930774) (xy 99.543598 -287.881411) (xy 99.236281 -287.881411)
			(xy 99.236272 -287.881868) (xy 99.228108 -287.932102) (xy 99.211992 -287.980376) (xy 99.188341 -288.025439)
			(xy 99.157768 -288.066125) (xy 99.121064 -288.10138) (xy 99.07918 -288.13029) (xy 99.033201 -288.152107)
			(xy 98.984317 -288.166267) (xy 98.933796 -288.172401) (xy 98.882944 -288.170352) (xy 98.83308 -288.160172)
			(xy 98.785494 -288.142125) (xy 98.74142 -288.116679) (xy 98.701998 -288.084492) (xy 98.66825 -288.046398)
			(xy 98.641049 -288.003384) (xy 98.621101 -287.956564) (xy 98.608922 -287.90715) (xy 98.604827 -287.856422)
			(xy 98.29673 -287.856422) (xy 98.296218 -287.881868) (xy 98.288054 -287.932102) (xy 98.271938 -287.980376)
			(xy 98.248287 -288.025439) (xy 98.217714 -288.066125) (xy 98.18101 -288.10138) (xy 98.139126 -288.13029)
			(xy 98.093147 -288.152107) (xy 98.044263 -288.166267) (xy 97.993742 -288.172401) (xy 97.94289 -288.170352)
			(xy 97.893026 -288.160172) (xy 97.84544 -288.142125) (xy 97.801366 -288.116679) (xy 97.761944 -288.084492)
			(xy 97.728196 -288.046398) (xy 97.700995 -288.003384) (xy 97.681047 -287.956564) (xy 97.668868 -287.90715)
			(xy 97.664773 -287.856422) (xy 97.358962 -287.856422) (xy 97.358472 -287.881411) (xy 97.350653 -287.930774)
			(xy 97.335209 -287.978306) (xy 97.312519 -288.022838) (xy 97.283143 -288.063271) (xy 97.247803 -288.098611)
			(xy 97.20737 -288.127987) (xy 97.162838 -288.150677) (xy 97.115306 -288.166121) (xy 97.065943 -288.17394)
			(xy 97.015965 -288.17394) (xy 96.966602 -288.166121) (xy 96.91907 -288.150677) (xy 96.874538 -288.127987)
			(xy 96.834105 -288.098611) (xy 96.798765 -288.063271) (xy 96.769389 -288.022838) (xy 96.746699 -287.978306)
			(xy 96.731255 -287.930774) (xy 96.723436 -287.881411) (xy 96.416373 -287.881411) (xy 96.416364 -287.881868)
			(xy 96.4082 -287.932102) (xy 96.392084 -287.980376) (xy 96.368433 -288.025439) (xy 96.33786 -288.066125)
			(xy 96.301156 -288.10138) (xy 96.259272 -288.13029) (xy 96.213293 -288.152107) (xy 96.164409 -288.166267)
			(xy 96.113888 -288.172401) (xy 96.063036 -288.170352) (xy 96.013172 -288.160172) (xy 95.965586 -288.142125)
			(xy 95.921512 -288.116679) (xy 95.88209 -288.084492) (xy 95.848342 -288.046398) (xy 95.821141 -288.003384)
			(xy 95.801193 -287.956564) (xy 95.789014 -287.90715) (xy 95.784919 -287.856422) (xy 95.479108 -287.856422)
			(xy 95.478618 -287.881411) (xy 95.470799 -287.930774) (xy 95.455355 -287.978306) (xy 95.432665 -288.022838)
			(xy 95.403289 -288.063271) (xy 95.367949 -288.098611) (xy 95.327516 -288.127987) (xy 95.282984 -288.150677)
			(xy 95.235452 -288.166121) (xy 95.186089 -288.17394) (xy 95.136111 -288.17394) (xy 95.086748 -288.166121)
			(xy 95.039216 -288.150677) (xy 94.994684 -288.127987) (xy 94.954251 -288.098611) (xy 94.918911 -288.063271)
			(xy 94.889535 -288.022838) (xy 94.866845 -287.978306) (xy 94.851401 -287.930774) (xy 94.843582 -287.881411)
			(xy 94.536265 -287.881411) (xy 94.536256 -287.881868) (xy 94.528092 -287.932102) (xy 94.511976 -287.980376)
			(xy 94.488325 -288.025439) (xy 94.457752 -288.066125) (xy 94.421048 -288.10138) (xy 94.379164 -288.13029)
			(xy 94.333185 -288.152107) (xy 94.284301 -288.166267) (xy 94.23378 -288.172401) (xy 94.182928 -288.170352)
			(xy 94.133064 -288.160172) (xy 94.085478 -288.142125) (xy 94.041404 -288.116679) (xy 94.001982 -288.084492)
			(xy 93.968234 -288.046398) (xy 93.941033 -288.003384) (xy 93.921085 -287.956564) (xy 93.908906 -287.90715)
			(xy 93.904811 -287.856422) (xy 93.599 -287.856422) (xy 93.59851 -287.881411) (xy 93.590691 -287.930774)
			(xy 93.575247 -287.978306) (xy 93.552557 -288.022838) (xy 93.523181 -288.063271) (xy 93.487841 -288.098611)
			(xy 93.447408 -288.127987) (xy 93.402876 -288.150677) (xy 93.355344 -288.166121) (xy 93.305981 -288.17394)
			(xy 93.256003 -288.17394) (xy 93.20664 -288.166121) (xy 93.159108 -288.150677) (xy 93.114576 -288.127987)
			(xy 93.074143 -288.098611) (xy 93.038803 -288.063271) (xy 93.009427 -288.022838) (xy 92.986737 -287.978306)
			(xy 92.971293 -287.930774) (xy 92.963474 -287.881411) (xy 92.656157 -287.881411) (xy 92.656148 -287.881868)
			(xy 92.647984 -287.932102) (xy 92.631868 -287.980376) (xy 92.608217 -288.025439) (xy 92.577644 -288.066125)
			(xy 92.54094 -288.10138) (xy 92.499056 -288.13029) (xy 92.453077 -288.152107) (xy 92.404193 -288.166267)
			(xy 92.353672 -288.172401) (xy 92.30282 -288.170352) (xy 92.252956 -288.160172) (xy 92.20537 -288.142125)
			(xy 92.161296 -288.116679) (xy 92.121874 -288.084492) (xy 92.088126 -288.046398) (xy 92.060925 -288.003384)
			(xy 92.040977 -287.956564) (xy 92.028798 -287.90715) (xy 92.024703 -287.856422) (xy 91.861386 -287.856422)
			(xy 91.861386 -288.03473) (xy 91.861451 -288.038335) (xy 91.862475 -288.045473) (xy 91.863418 -288.048954)
			(xy 91.86926 -288.06902) (xy 91.87307 -288.075116) (xy 91.899129 -288.117711) (xy 91.944366 -288.20674)
			(xy 91.981437 -288.299467) (xy 91.99626 -288.34715) (xy 91.999054 -288.356548) (xy 92.014294 -288.375598)
			(xy 92.017342 -288.379408) (xy 92.020898 -288.382456) (xy 92.030296 -288.390584) (xy 92.034106 -288.39287)
			(xy 92.055582 -288.406254) (xy 92.094385 -288.438732) (xy 92.12756 -288.476939) (xy 92.154272 -288.519915)
			(xy 92.173849 -288.566575) (xy 92.185797 -288.615746) (xy 92.189813 -288.666174) (xy 92.494857 -288.666174)
			(xy 92.498952 -288.615446) (xy 92.511131 -288.566032) (xy 92.531079 -288.519212) (xy 92.55828 -288.476198)
			(xy 92.592028 -288.438104) (xy 92.63145 -288.405917) (xy 92.675524 -288.380471) (xy 92.72311 -288.362424)
			(xy 92.772974 -288.352244) (xy 92.823826 -288.350195) (xy 92.874347 -288.356329) (xy 92.923231 -288.370489)
			(xy 92.96921 -288.392306) (xy 93.011094 -288.421216) (xy 93.047798 -288.456471) (xy 93.078371 -288.497157)
			(xy 93.102022 -288.54222) (xy 93.118138 -288.590494) (xy 93.126302 -288.640728) (xy 93.126814 -288.666174)
			(xy 93.126311 -288.691163) (xy 93.433628 -288.691163) (xy 93.433628 -288.641185) (xy 93.441447 -288.591822)
			(xy 93.456891 -288.54429) (xy 93.479581 -288.499758) (xy 93.508957 -288.459325) (xy 93.544297 -288.423985)
			(xy 93.58473 -288.394609) (xy 93.629262 -288.371919) (xy 93.676794 -288.356475) (xy 93.726157 -288.348656)
			(xy 93.776135 -288.348656) (xy 93.825498 -288.356475) (xy 93.87303 -288.371919) (xy 93.917562 -288.394609)
			(xy 93.957995 -288.423985) (xy 93.993335 -288.459325) (xy 94.022711 -288.499758) (xy 94.045401 -288.54429)
			(xy 94.060845 -288.591822) (xy 94.068664 -288.641185) (xy 94.069154 -288.666174) (xy 94.374711 -288.666174)
			(xy 94.378806 -288.615446) (xy 94.390985 -288.566032) (xy 94.410933 -288.519212) (xy 94.438134 -288.476198)
			(xy 94.471882 -288.438104) (xy 94.511304 -288.405917) (xy 94.555378 -288.380471) (xy 94.602964 -288.362424)
			(xy 94.652828 -288.352244) (xy 94.70368 -288.350195) (xy 94.754201 -288.356329) (xy 94.803085 -288.370489)
			(xy 94.849064 -288.392306) (xy 94.890948 -288.421216) (xy 94.927652 -288.456471) (xy 94.958225 -288.497157)
			(xy 94.981876 -288.54222) (xy 94.997992 -288.590494) (xy 95.006156 -288.640728) (xy 95.006668 -288.666174)
			(xy 95.314765 -288.666174) (xy 95.31886 -288.615446) (xy 95.331039 -288.566032) (xy 95.350987 -288.519212)
			(xy 95.378188 -288.476198) (xy 95.411936 -288.438104) (xy 95.451358 -288.405917) (xy 95.495432 -288.380471)
			(xy 95.543018 -288.362424) (xy 95.592882 -288.352244) (xy 95.643734 -288.350195) (xy 95.694255 -288.356329)
			(xy 95.743139 -288.370489) (xy 95.789118 -288.392306) (xy 95.831002 -288.421216) (xy 95.867706 -288.456471)
			(xy 95.898279 -288.497157) (xy 95.92193 -288.54222) (xy 95.938046 -288.590494) (xy 95.94621 -288.640728)
			(xy 95.946722 -288.666174) (xy 95.946219 -288.691163) (xy 96.253536 -288.691163) (xy 96.253536 -288.641185)
			(xy 96.261355 -288.591822) (xy 96.276799 -288.54429) (xy 96.299489 -288.499758) (xy 96.328865 -288.459325)
			(xy 96.364205 -288.423985) (xy 96.404638 -288.394609) (xy 96.44917 -288.371919) (xy 96.496702 -288.356475)
			(xy 96.546065 -288.348656) (xy 96.596043 -288.348656) (xy 96.645406 -288.356475) (xy 96.692938 -288.371919)
			(xy 96.73747 -288.394609) (xy 96.777903 -288.423985) (xy 96.813243 -288.459325) (xy 96.842619 -288.499758)
			(xy 96.865309 -288.54429) (xy 96.880753 -288.591822) (xy 96.888572 -288.641185) (xy 96.889062 -288.666174)
			(xy 96.888572 -288.691163) (xy 97.19359 -288.691163) (xy 97.19359 -288.641185) (xy 97.201409 -288.591822)
			(xy 97.216853 -288.54429) (xy 97.239543 -288.499758) (xy 97.268919 -288.459325) (xy 97.304259 -288.423985)
			(xy 97.344692 -288.394609) (xy 97.389224 -288.371919) (xy 97.436756 -288.356475) (xy 97.486119 -288.348656)
			(xy 97.536097 -288.348656) (xy 97.58546 -288.356475) (xy 97.632992 -288.371919) (xy 97.677524 -288.394609)
			(xy 97.717957 -288.423985) (xy 97.753297 -288.459325) (xy 97.782673 -288.499758) (xy 97.805363 -288.54429)
			(xy 97.820807 -288.591822) (xy 97.828626 -288.641185) (xy 97.829116 -288.666174) (xy 97.828626 -288.691163)
			(xy 98.133644 -288.691163) (xy 98.133644 -288.641185) (xy 98.141463 -288.591822) (xy 98.156907 -288.54429)
			(xy 98.179597 -288.499758) (xy 98.208973 -288.459325) (xy 98.244313 -288.423985) (xy 98.284746 -288.394609)
			(xy 98.329278 -288.371919) (xy 98.37681 -288.356475) (xy 98.426173 -288.348656) (xy 98.476151 -288.348656)
			(xy 98.525514 -288.356475) (xy 98.573046 -288.371919) (xy 98.617578 -288.394609) (xy 98.658011 -288.423985)
			(xy 98.693351 -288.459325) (xy 98.722727 -288.499758) (xy 98.745417 -288.54429) (xy 98.760861 -288.591822)
			(xy 98.76868 -288.641185) (xy 98.76917 -288.666174) (xy 98.76868 -288.691163) (xy 99.073444 -288.691163)
			(xy 99.073444 -288.641185) (xy 99.081263 -288.591822) (xy 99.096707 -288.54429) (xy 99.119397 -288.499758)
			(xy 99.148773 -288.459325) (xy 99.184113 -288.423985) (xy 99.224546 -288.394609) (xy 99.269078 -288.371919)
			(xy 99.31661 -288.356475) (xy 99.365973 -288.348656) (xy 99.415951 -288.348656) (xy 99.465314 -288.356475)
			(xy 99.512846 -288.371919) (xy 99.557378 -288.394609) (xy 99.597811 -288.423985) (xy 99.633151 -288.459325)
			(xy 99.662527 -288.499758) (xy 99.685217 -288.54429) (xy 99.700661 -288.591822) (xy 99.70848 -288.641185)
			(xy 99.70897 -288.666174) (xy 99.70848 -288.691163) (xy 100.013498 -288.691163) (xy 100.013498 -288.641185)
			(xy 100.021317 -288.591822) (xy 100.036761 -288.54429) (xy 100.059451 -288.499758) (xy 100.088827 -288.459325)
			(xy 100.124167 -288.423985) (xy 100.1646 -288.394609) (xy 100.209132 -288.371919) (xy 100.256664 -288.356475)
			(xy 100.306027 -288.348656) (xy 100.356005 -288.348656) (xy 100.405368 -288.356475) (xy 100.4529 -288.371919)
			(xy 100.497432 -288.394609) (xy 100.537865 -288.423985) (xy 100.573205 -288.459325) (xy 100.602581 -288.499758)
			(xy 100.625271 -288.54429) (xy 100.640715 -288.591822) (xy 100.648534 -288.641185) (xy 100.649024 -288.666174)
			(xy 100.648534 -288.691163) (xy 100.953552 -288.691163) (xy 100.953552 -288.641185) (xy 100.961371 -288.591822)
			(xy 100.976815 -288.54429) (xy 100.999505 -288.499758) (xy 101.028881 -288.459325) (xy 101.064221 -288.423985)
			(xy 101.104654 -288.394609) (xy 101.149186 -288.371919) (xy 101.196718 -288.356475) (xy 101.246081 -288.348656)
			(xy 101.296059 -288.348656) (xy 101.345422 -288.356475) (xy 101.392954 -288.371919) (xy 101.437486 -288.394609)
			(xy 101.477919 -288.423985) (xy 101.513259 -288.459325) (xy 101.542635 -288.499758) (xy 101.565325 -288.54429)
			(xy 101.580769 -288.591822) (xy 101.588588 -288.641185) (xy 101.589078 -288.666174) (xy 101.588588 -288.691163)
			(xy 101.893606 -288.691163) (xy 101.893606 -288.641185) (xy 101.901425 -288.591822) (xy 101.916869 -288.54429)
			(xy 101.939559 -288.499758) (xy 101.968935 -288.459325) (xy 102.004275 -288.423985) (xy 102.044708 -288.394609)
			(xy 102.08924 -288.371919) (xy 102.136772 -288.356475) (xy 102.186135 -288.348656) (xy 102.236113 -288.348656)
			(xy 102.285476 -288.356475) (xy 102.333008 -288.371919) (xy 102.37754 -288.394609) (xy 102.417973 -288.423985)
			(xy 102.453313 -288.459325) (xy 102.482689 -288.499758) (xy 102.505379 -288.54429) (xy 102.520823 -288.591822)
			(xy 102.528642 -288.641185) (xy 102.529132 -288.666174) (xy 102.528642 -288.691163) (xy 102.83366 -288.691163)
			(xy 102.83366 -288.641185) (xy 102.841479 -288.591822) (xy 102.856923 -288.54429) (xy 102.879613 -288.499758)
			(xy 102.908989 -288.459325) (xy 102.944329 -288.423985) (xy 102.984762 -288.394609) (xy 103.029294 -288.371919)
			(xy 103.076826 -288.356475) (xy 103.126189 -288.348656) (xy 103.176167 -288.348656) (xy 103.22553 -288.356475)
			(xy 103.273062 -288.371919) (xy 103.317594 -288.394609) (xy 103.358027 -288.423985) (xy 103.393367 -288.459325)
			(xy 103.422743 -288.499758) (xy 103.445433 -288.54429) (xy 103.460877 -288.591822) (xy 103.468696 -288.641185)
			(xy 103.469186 -288.666174) (xy 103.468696 -288.691163) (xy 103.77346 -288.691163) (xy 103.77346 -288.641185)
			(xy 103.781279 -288.591822) (xy 103.796723 -288.54429) (xy 103.819413 -288.499758) (xy 103.848789 -288.459325)
			(xy 103.884129 -288.423985) (xy 103.924562 -288.394609) (xy 103.969094 -288.371919) (xy 104.016626 -288.356475)
			(xy 104.065989 -288.348656) (xy 104.115967 -288.348656) (xy 104.16533 -288.356475) (xy 104.212862 -288.371919)
			(xy 104.257394 -288.394609) (xy 104.297827 -288.423985) (xy 104.333167 -288.459325) (xy 104.362543 -288.499758)
			(xy 104.385233 -288.54429) (xy 104.400677 -288.591822) (xy 104.408496 -288.641185) (xy 104.408986 -288.666174)
			(xy 104.408496 -288.691163) (xy 104.713514 -288.691163) (xy 104.713514 -288.641185) (xy 104.721333 -288.591822)
			(xy 104.736777 -288.54429) (xy 104.759467 -288.499758) (xy 104.788843 -288.459325) (xy 104.824183 -288.423985)
			(xy 104.864616 -288.394609) (xy 104.909148 -288.371919) (xy 104.95668 -288.356475) (xy 105.006043 -288.348656)
			(xy 105.056021 -288.348656) (xy 105.105384 -288.356475) (xy 105.152916 -288.371919) (xy 105.197448 -288.394609)
			(xy 105.237881 -288.423985) (xy 105.273221 -288.459325) (xy 105.302597 -288.499758) (xy 105.325287 -288.54429)
			(xy 105.340731 -288.591822) (xy 105.34855 -288.641185) (xy 105.34904 -288.666174) (xy 105.34855 -288.691163)
			(xy 105.653568 -288.691163) (xy 105.653568 -288.641185) (xy 105.661387 -288.591822) (xy 105.676831 -288.54429)
			(xy 105.699521 -288.499758) (xy 105.728897 -288.459325) (xy 105.764237 -288.423985) (xy 105.80467 -288.394609)
			(xy 105.849202 -288.371919) (xy 105.896734 -288.356475) (xy 105.946097 -288.348656) (xy 105.996075 -288.348656)
			(xy 106.045438 -288.356475) (xy 106.09297 -288.371919) (xy 106.137502 -288.394609) (xy 106.177935 -288.423985)
			(xy 106.213275 -288.459325) (xy 106.242651 -288.499758) (xy 106.265341 -288.54429) (xy 106.280785 -288.591822)
			(xy 106.288604 -288.641185) (xy 106.289094 -288.666174) (xy 106.288604 -288.691163) (xy 106.593622 -288.691163)
			(xy 106.593622 -288.641185) (xy 106.601441 -288.591822) (xy 106.616885 -288.54429) (xy 106.639575 -288.499758)
			(xy 106.668951 -288.459325) (xy 106.704291 -288.423985) (xy 106.744724 -288.394609) (xy 106.789256 -288.371919)
			(xy 106.836788 -288.356475) (xy 106.886151 -288.348656) (xy 106.936129 -288.348656) (xy 106.985492 -288.356475)
			(xy 107.033024 -288.371919) (xy 107.077556 -288.394609) (xy 107.117989 -288.423985) (xy 107.153329 -288.459325)
			(xy 107.182705 -288.499758) (xy 107.205395 -288.54429) (xy 107.220839 -288.591822) (xy 107.228658 -288.641185)
			(xy 107.229148 -288.666174) (xy 107.228658 -288.691163) (xy 107.533422 -288.691163) (xy 107.533422 -288.641185)
			(xy 107.541241 -288.591822) (xy 107.556685 -288.54429) (xy 107.579375 -288.499758) (xy 107.608751 -288.459325)
			(xy 107.644091 -288.423985) (xy 107.684524 -288.394609) (xy 107.729056 -288.371919) (xy 107.776588 -288.356475)
			(xy 107.825951 -288.348656) (xy 107.875929 -288.348656) (xy 107.925292 -288.356475) (xy 107.972824 -288.371919)
			(xy 108.017356 -288.394609) (xy 108.057789 -288.423985) (xy 108.093129 -288.459325) (xy 108.122505 -288.499758)
			(xy 108.145195 -288.54429) (xy 108.160639 -288.591822) (xy 108.168458 -288.641185) (xy 108.168948 -288.666174)
			(xy 108.474759 -288.666174) (xy 108.478854 -288.615446) (xy 108.491033 -288.566032) (xy 108.510981 -288.519212)
			(xy 108.538182 -288.476198) (xy 108.57193 -288.438104) (xy 108.611352 -288.405917) (xy 108.655426 -288.380471)
			(xy 108.703012 -288.362424) (xy 108.752876 -288.352244) (xy 108.803728 -288.350195) (xy 108.854249 -288.356329)
			(xy 108.903133 -288.370489) (xy 108.949112 -288.392306) (xy 108.990996 -288.421216) (xy 109.0277 -288.456471)
			(xy 109.058273 -288.497157) (xy 109.081924 -288.54222) (xy 109.09804 -288.590494) (xy 109.106204 -288.640728)
			(xy 109.106716 -288.666174) (xy 109.414813 -288.666174) (xy 109.418908 -288.615446) (xy 109.431087 -288.566032)
			(xy 109.451035 -288.519212) (xy 109.478236 -288.476198) (xy 109.511984 -288.438104) (xy 109.551406 -288.405917)
			(xy 109.59548 -288.380471) (xy 109.643066 -288.362424) (xy 109.69293 -288.352244) (xy 109.743782 -288.350195)
			(xy 109.794303 -288.356329) (xy 109.843187 -288.370489) (xy 109.889166 -288.392306) (xy 109.93105 -288.421216)
			(xy 109.967754 -288.456471) (xy 109.998327 -288.497157) (xy 110.021978 -288.54222) (xy 110.038094 -288.590494)
			(xy 110.046258 -288.640728) (xy 110.04677 -288.666174) (xy 110.046267 -288.691163) (xy 110.353584 -288.691163)
			(xy 110.353584 -288.641185) (xy 110.361403 -288.591822) (xy 110.376847 -288.54429) (xy 110.399537 -288.499758)
			(xy 110.428913 -288.459325) (xy 110.464253 -288.423985) (xy 110.504686 -288.394609) (xy 110.549218 -288.371919)
			(xy 110.59675 -288.356475) (xy 110.646113 -288.348656) (xy 110.696091 -288.348656) (xy 110.745454 -288.356475)
			(xy 110.792986 -288.371919) (xy 110.837518 -288.394609) (xy 110.877951 -288.423985) (xy 110.913291 -288.459325)
			(xy 110.942667 -288.499758) (xy 110.965357 -288.54429) (xy 110.980801 -288.591822) (xy 110.98862 -288.641185)
			(xy 110.98911 -288.666174) (xy 110.98862 -288.691163) (xy 113.167142 -288.691163) (xy 113.167142 -288.641185)
			(xy 113.174961 -288.591822) (xy 113.190405 -288.54429) (xy 113.213095 -288.499758) (xy 113.242471 -288.459325)
			(xy 113.277811 -288.423985) (xy 113.318244 -288.394609) (xy 113.362776 -288.371919) (xy 113.410308 -288.356475)
			(xy 113.459671 -288.348656) (xy 113.509649 -288.348656) (xy 113.559012 -288.356475) (xy 113.606544 -288.371919)
			(xy 113.651076 -288.394609) (xy 113.691509 -288.423985) (xy 113.726849 -288.459325) (xy 113.756225 -288.499758)
			(xy 113.778915 -288.54429) (xy 113.794359 -288.591822) (xy 113.802178 -288.641185) (xy 113.802668 -288.666174)
			(xy 114.108479 -288.666174) (xy 114.112574 -288.615446) (xy 114.124753 -288.566032) (xy 114.144701 -288.519212)
			(xy 114.171902 -288.476198) (xy 114.20565 -288.438104) (xy 114.245072 -288.405917) (xy 114.289146 -288.380471)
			(xy 114.336732 -288.362424) (xy 114.386596 -288.352244) (xy 114.437448 -288.350195) (xy 114.487969 -288.356329)
			(xy 114.536853 -288.370489) (xy 114.582832 -288.392306) (xy 114.624716 -288.421216) (xy 114.66142 -288.456471)
			(xy 114.691993 -288.497157) (xy 114.715644 -288.54222) (xy 114.73176 -288.590494) (xy 114.739924 -288.640728)
			(xy 114.740436 -288.666174) (xy 115.048533 -288.666174) (xy 115.052628 -288.615446) (xy 115.064807 -288.566032)
			(xy 115.084755 -288.519212) (xy 115.111956 -288.476198) (xy 115.145704 -288.438104) (xy 115.185126 -288.405917)
			(xy 115.2292 -288.380471) (xy 115.276786 -288.362424) (xy 115.32665 -288.352244) (xy 115.377502 -288.350195)
			(xy 115.428023 -288.356329) (xy 115.476907 -288.370489) (xy 115.522886 -288.392306) (xy 115.56477 -288.421216)
			(xy 115.601474 -288.456471) (xy 115.632047 -288.497157) (xy 115.655698 -288.54222) (xy 115.671814 -288.590494)
			(xy 115.679978 -288.640728) (xy 115.68049 -288.666174) (xy 115.679987 -288.691163) (xy 115.987304 -288.691163)
			(xy 115.987304 -288.641185) (xy 115.995123 -288.591822) (xy 116.010567 -288.54429) (xy 116.033257 -288.499758)
			(xy 116.062633 -288.459325) (xy 116.097973 -288.423985) (xy 116.138406 -288.394609) (xy 116.182938 -288.371919)
			(xy 116.23047 -288.356475) (xy 116.279833 -288.348656) (xy 116.329811 -288.348656) (xy 116.379174 -288.356475)
			(xy 116.426706 -288.371919) (xy 116.471238 -288.394609) (xy 116.511671 -288.423985) (xy 116.547011 -288.459325)
			(xy 116.576387 -288.499758) (xy 116.599077 -288.54429) (xy 116.614521 -288.591822) (xy 116.62234 -288.641185)
			(xy 116.62283 -288.666174) (xy 116.62234 -288.691163) (xy 116.927104 -288.691163) (xy 116.927104 -288.641185)
			(xy 116.934923 -288.591822) (xy 116.950367 -288.54429) (xy 116.973057 -288.499758) (xy 117.002433 -288.459325)
			(xy 117.037773 -288.423985) (xy 117.078206 -288.394609) (xy 117.122738 -288.371919) (xy 117.17027 -288.356475)
			(xy 117.219633 -288.348656) (xy 117.269611 -288.348656) (xy 117.318974 -288.356475) (xy 117.366506 -288.371919)
			(xy 117.411038 -288.394609) (xy 117.451471 -288.423985) (xy 117.486811 -288.459325) (xy 117.516187 -288.499758)
			(xy 117.538877 -288.54429) (xy 117.554321 -288.591822) (xy 117.56214 -288.641185) (xy 117.56263 -288.666174)
			(xy 117.56214 -288.691163) (xy 117.867158 -288.691163) (xy 117.867158 -288.641185) (xy 117.874977 -288.591822)
			(xy 117.890421 -288.54429) (xy 117.913111 -288.499758) (xy 117.942487 -288.459325) (xy 117.977827 -288.423985)
			(xy 118.01826 -288.394609) (xy 118.062792 -288.371919) (xy 118.110324 -288.356475) (xy 118.159687 -288.348656)
			(xy 118.209665 -288.348656) (xy 118.259028 -288.356475) (xy 118.30656 -288.371919) (xy 118.351092 -288.394609)
			(xy 118.391525 -288.423985) (xy 118.426865 -288.459325) (xy 118.456241 -288.499758) (xy 118.478931 -288.54429)
			(xy 118.494375 -288.591822) (xy 118.502194 -288.641185) (xy 118.502684 -288.666174) (xy 118.502194 -288.691163)
			(xy 118.807212 -288.691163) (xy 118.807212 -288.641185) (xy 118.815031 -288.591822) (xy 118.830475 -288.54429)
			(xy 118.853165 -288.499758) (xy 118.882541 -288.459325) (xy 118.917881 -288.423985) (xy 118.958314 -288.394609)
			(xy 119.002846 -288.371919) (xy 119.050378 -288.356475) (xy 119.099741 -288.348656) (xy 119.149719 -288.348656)
			(xy 119.199082 -288.356475) (xy 119.246614 -288.371919) (xy 119.291146 -288.394609) (xy 119.331579 -288.423985)
			(xy 119.366919 -288.459325) (xy 119.396295 -288.499758) (xy 119.418985 -288.54429) (xy 119.434429 -288.591822)
			(xy 119.442248 -288.641185) (xy 119.442738 -288.666174) (xy 119.442248 -288.691163) (xy 119.747266 -288.691163)
			(xy 119.747266 -288.641185) (xy 119.755085 -288.591822) (xy 119.770529 -288.54429) (xy 119.793219 -288.499758)
			(xy 119.822595 -288.459325) (xy 119.857935 -288.423985) (xy 119.898368 -288.394609) (xy 119.9429 -288.371919)
			(xy 119.990432 -288.356475) (xy 120.039795 -288.348656) (xy 120.089773 -288.348656) (xy 120.139136 -288.356475)
			(xy 120.186668 -288.371919) (xy 120.2312 -288.394609) (xy 120.271633 -288.423985) (xy 120.306973 -288.459325)
			(xy 120.336349 -288.499758) (xy 120.359039 -288.54429) (xy 120.374483 -288.591822) (xy 120.382302 -288.641185)
			(xy 120.382792 -288.666174) (xy 120.382302 -288.691163) (xy 120.68732 -288.691163) (xy 120.68732 -288.641185)
			(xy 120.695139 -288.591822) (xy 120.710583 -288.54429) (xy 120.733273 -288.499758) (xy 120.762649 -288.459325)
			(xy 120.797989 -288.423985) (xy 120.838422 -288.394609) (xy 120.882954 -288.371919) (xy 120.930486 -288.356475)
			(xy 120.979849 -288.348656) (xy 121.029827 -288.348656) (xy 121.07919 -288.356475) (xy 121.126722 -288.371919)
			(xy 121.171254 -288.394609) (xy 121.211687 -288.423985) (xy 121.247027 -288.459325) (xy 121.276403 -288.499758)
			(xy 121.299093 -288.54429) (xy 121.314537 -288.591822) (xy 121.322356 -288.641185) (xy 121.322846 -288.666174)
			(xy 121.322356 -288.691163) (xy 121.62712 -288.691163) (xy 121.62712 -288.641185) (xy 121.634939 -288.591822)
			(xy 121.650383 -288.54429) (xy 121.673073 -288.499758) (xy 121.702449 -288.459325) (xy 121.737789 -288.423985)
			(xy 121.778222 -288.394609) (xy 121.822754 -288.371919) (xy 121.870286 -288.356475) (xy 121.919649 -288.348656)
			(xy 121.969627 -288.348656) (xy 122.01899 -288.356475) (xy 122.066522 -288.371919) (xy 122.111054 -288.394609)
			(xy 122.151487 -288.423985) (xy 122.186827 -288.459325) (xy 122.216203 -288.499758) (xy 122.238893 -288.54429)
			(xy 122.254337 -288.591822) (xy 122.262156 -288.641185) (xy 122.262646 -288.666174) (xy 122.262156 -288.691163)
			(xy 122.567174 -288.691163) (xy 122.567174 -288.641185) (xy 122.574993 -288.591822) (xy 122.590437 -288.54429)
			(xy 122.613127 -288.499758) (xy 122.642503 -288.459325) (xy 122.677843 -288.423985) (xy 122.718276 -288.394609)
			(xy 122.762808 -288.371919) (xy 122.81034 -288.356475) (xy 122.859703 -288.348656) (xy 122.909681 -288.348656)
			(xy 122.959044 -288.356475) (xy 123.006576 -288.371919) (xy 123.051108 -288.394609) (xy 123.091541 -288.423985)
			(xy 123.126881 -288.459325) (xy 123.156257 -288.499758) (xy 123.178947 -288.54429) (xy 123.194391 -288.591822)
			(xy 123.20221 -288.641185) (xy 123.2027 -288.666174) (xy 123.20221 -288.691163) (xy 123.507228 -288.691163)
			(xy 123.507228 -288.641185) (xy 123.515047 -288.591822) (xy 123.530491 -288.54429) (xy 123.553181 -288.499758)
			(xy 123.582557 -288.459325) (xy 123.617897 -288.423985) (xy 123.65833 -288.394609) (xy 123.702862 -288.371919)
			(xy 123.750394 -288.356475) (xy 123.799757 -288.348656) (xy 123.849735 -288.348656) (xy 123.899098 -288.356475)
			(xy 123.94663 -288.371919) (xy 123.991162 -288.394609) (xy 124.031595 -288.423985) (xy 124.066935 -288.459325)
			(xy 124.096311 -288.499758) (xy 124.119001 -288.54429) (xy 124.134445 -288.591822) (xy 124.142264 -288.641185)
			(xy 124.142754 -288.666174) (xy 124.142264 -288.691163) (xy 124.447282 -288.691163) (xy 124.447282 -288.641185)
			(xy 124.455101 -288.591822) (xy 124.470545 -288.54429) (xy 124.493235 -288.499758) (xy 124.522611 -288.459325)
			(xy 124.557951 -288.423985) (xy 124.598384 -288.394609) (xy 124.642916 -288.371919) (xy 124.690448 -288.356475)
			(xy 124.739811 -288.348656) (xy 124.789789 -288.348656) (xy 124.839152 -288.356475) (xy 124.886684 -288.371919)
			(xy 124.931216 -288.394609) (xy 124.971649 -288.423985) (xy 125.006989 -288.459325) (xy 125.036365 -288.499758)
			(xy 125.059055 -288.54429) (xy 125.074499 -288.591822) (xy 125.082318 -288.641185) (xy 125.082808 -288.666174)
			(xy 125.082318 -288.691163) (xy 125.387336 -288.691163) (xy 125.387336 -288.641185) (xy 125.395155 -288.591822)
			(xy 125.410599 -288.54429) (xy 125.433289 -288.499758) (xy 125.462665 -288.459325) (xy 125.498005 -288.423985)
			(xy 125.538438 -288.394609) (xy 125.58297 -288.371919) (xy 125.630502 -288.356475) (xy 125.679865 -288.348656)
			(xy 125.729843 -288.348656) (xy 125.779206 -288.356475) (xy 125.826738 -288.371919) (xy 125.87127 -288.394609)
			(xy 125.911703 -288.423985) (xy 125.947043 -288.459325) (xy 125.976419 -288.499758) (xy 125.999109 -288.54429)
			(xy 126.014553 -288.591822) (xy 126.022372 -288.641185) (xy 126.022862 -288.666174) (xy 126.022372 -288.691163)
			(xy 126.014553 -288.740526) (xy 125.999109 -288.788058) (xy 125.976419 -288.83259) (xy 125.947043 -288.873023)
			(xy 125.911703 -288.908363) (xy 125.87127 -288.937739) (xy 125.826738 -288.960429) (xy 125.779206 -288.975873)
			(xy 125.729843 -288.983692) (xy 125.679865 -288.983692) (xy 125.630502 -288.975873) (xy 125.58297 -288.960429)
			(xy 125.538438 -288.937739) (xy 125.498005 -288.908363) (xy 125.462665 -288.873023) (xy 125.433289 -288.83259)
			(xy 125.410599 -288.788058) (xy 125.395155 -288.740526) (xy 125.387336 -288.691163) (xy 125.082318 -288.691163)
			(xy 125.074499 -288.740526) (xy 125.059055 -288.788058) (xy 125.036365 -288.83259) (xy 125.006989 -288.873023)
			(xy 124.971649 -288.908363) (xy 124.931216 -288.937739) (xy 124.886684 -288.960429) (xy 124.839152 -288.975873)
			(xy 124.789789 -288.983692) (xy 124.739811 -288.983692) (xy 124.690448 -288.975873) (xy 124.642916 -288.960429)
			(xy 124.598384 -288.937739) (xy 124.557951 -288.908363) (xy 124.522611 -288.873023) (xy 124.493235 -288.83259)
			(xy 124.470545 -288.788058) (xy 124.455101 -288.740526) (xy 124.447282 -288.691163) (xy 124.142264 -288.691163)
			(xy 124.134445 -288.740526) (xy 124.119001 -288.788058) (xy 124.096311 -288.83259) (xy 124.066935 -288.873023)
			(xy 124.031595 -288.908363) (xy 123.991162 -288.937739) (xy 123.94663 -288.960429) (xy 123.899098 -288.975873)
			(xy 123.849735 -288.983692) (xy 123.799757 -288.983692) (xy 123.750394 -288.975873) (xy 123.702862 -288.960429)
			(xy 123.65833 -288.937739) (xy 123.617897 -288.908363) (xy 123.582557 -288.873023) (xy 123.553181 -288.83259)
			(xy 123.530491 -288.788058) (xy 123.515047 -288.740526) (xy 123.507228 -288.691163) (xy 123.20221 -288.691163)
			(xy 123.194391 -288.740526) (xy 123.178947 -288.788058) (xy 123.156257 -288.83259) (xy 123.126881 -288.873023)
			(xy 123.091541 -288.908363) (xy 123.051108 -288.937739) (xy 123.006576 -288.960429) (xy 122.959044 -288.975873)
			(xy 122.909681 -288.983692) (xy 122.859703 -288.983692) (xy 122.81034 -288.975873) (xy 122.762808 -288.960429)
			(xy 122.718276 -288.937739) (xy 122.677843 -288.908363) (xy 122.642503 -288.873023) (xy 122.613127 -288.83259)
			(xy 122.590437 -288.788058) (xy 122.574993 -288.740526) (xy 122.567174 -288.691163) (xy 122.262156 -288.691163)
			(xy 122.254337 -288.740526) (xy 122.238893 -288.788058) (xy 122.216203 -288.83259) (xy 122.186827 -288.873023)
			(xy 122.151487 -288.908363) (xy 122.111054 -288.937739) (xy 122.066522 -288.960429) (xy 122.01899 -288.975873)
			(xy 121.969627 -288.983692) (xy 121.919649 -288.983692) (xy 121.870286 -288.975873) (xy 121.822754 -288.960429)
			(xy 121.778222 -288.937739) (xy 121.737789 -288.908363) (xy 121.702449 -288.873023) (xy 121.673073 -288.83259)
			(xy 121.650383 -288.788058) (xy 121.634939 -288.740526) (xy 121.62712 -288.691163) (xy 121.322356 -288.691163)
			(xy 121.314537 -288.740526) (xy 121.299093 -288.788058) (xy 121.276403 -288.83259) (xy 121.247027 -288.873023)
			(xy 121.211687 -288.908363) (xy 121.171254 -288.937739) (xy 121.126722 -288.960429) (xy 121.07919 -288.975873)
			(xy 121.029827 -288.983692) (xy 120.979849 -288.983692) (xy 120.930486 -288.975873) (xy 120.882954 -288.960429)
			(xy 120.838422 -288.937739) (xy 120.797989 -288.908363) (xy 120.762649 -288.873023) (xy 120.733273 -288.83259)
			(xy 120.710583 -288.788058) (xy 120.695139 -288.740526) (xy 120.68732 -288.691163) (xy 120.382302 -288.691163)
			(xy 120.374483 -288.740526) (xy 120.359039 -288.788058) (xy 120.336349 -288.83259) (xy 120.306973 -288.873023)
			(xy 120.271633 -288.908363) (xy 120.2312 -288.937739) (xy 120.186668 -288.960429) (xy 120.139136 -288.975873)
			(xy 120.089773 -288.983692) (xy 120.039795 -288.983692) (xy 119.990432 -288.975873) (xy 119.9429 -288.960429)
			(xy 119.898368 -288.937739) (xy 119.857935 -288.908363) (xy 119.822595 -288.873023) (xy 119.793219 -288.83259)
			(xy 119.770529 -288.788058) (xy 119.755085 -288.740526) (xy 119.747266 -288.691163) (xy 119.442248 -288.691163)
			(xy 119.434429 -288.740526) (xy 119.418985 -288.788058) (xy 119.396295 -288.83259) (xy 119.366919 -288.873023)
			(xy 119.331579 -288.908363) (xy 119.291146 -288.937739) (xy 119.246614 -288.960429) (xy 119.199082 -288.975873)
			(xy 119.149719 -288.983692) (xy 119.099741 -288.983692) (xy 119.050378 -288.975873) (xy 119.002846 -288.960429)
			(xy 118.958314 -288.937739) (xy 118.917881 -288.908363) (xy 118.882541 -288.873023) (xy 118.853165 -288.83259)
			(xy 118.830475 -288.788058) (xy 118.815031 -288.740526) (xy 118.807212 -288.691163) (xy 118.502194 -288.691163)
			(xy 118.494375 -288.740526) (xy 118.478931 -288.788058) (xy 118.456241 -288.83259) (xy 118.426865 -288.873023)
			(xy 118.391525 -288.908363) (xy 118.351092 -288.937739) (xy 118.30656 -288.960429) (xy 118.259028 -288.975873)
			(xy 118.209665 -288.983692) (xy 118.159687 -288.983692) (xy 118.110324 -288.975873) (xy 118.062792 -288.960429)
			(xy 118.01826 -288.937739) (xy 117.977827 -288.908363) (xy 117.942487 -288.873023) (xy 117.913111 -288.83259)
			(xy 117.890421 -288.788058) (xy 117.874977 -288.740526) (xy 117.867158 -288.691163) (xy 117.56214 -288.691163)
			(xy 117.554321 -288.740526) (xy 117.538877 -288.788058) (xy 117.516187 -288.83259) (xy 117.486811 -288.873023)
			(xy 117.451471 -288.908363) (xy 117.411038 -288.937739) (xy 117.366506 -288.960429) (xy 117.318974 -288.975873)
			(xy 117.269611 -288.983692) (xy 117.219633 -288.983692) (xy 117.17027 -288.975873) (xy 117.122738 -288.960429)
			(xy 117.078206 -288.937739) (xy 117.037773 -288.908363) (xy 117.002433 -288.873023) (xy 116.973057 -288.83259)
			(xy 116.950367 -288.788058) (xy 116.934923 -288.740526) (xy 116.927104 -288.691163) (xy 116.62234 -288.691163)
			(xy 116.614521 -288.740526) (xy 116.599077 -288.788058) (xy 116.576387 -288.83259) (xy 116.547011 -288.873023)
			(xy 116.511671 -288.908363) (xy 116.471238 -288.937739) (xy 116.426706 -288.960429) (xy 116.379174 -288.975873)
			(xy 116.329811 -288.983692) (xy 116.279833 -288.983692) (xy 116.23047 -288.975873) (xy 116.182938 -288.960429)
			(xy 116.138406 -288.937739) (xy 116.097973 -288.908363) (xy 116.062633 -288.873023) (xy 116.033257 -288.83259)
			(xy 116.010567 -288.788058) (xy 115.995123 -288.740526) (xy 115.987304 -288.691163) (xy 115.679987 -288.691163)
			(xy 115.679978 -288.69162) (xy 115.671814 -288.741854) (xy 115.655698 -288.790128) (xy 115.632047 -288.835191)
			(xy 115.601474 -288.875877) (xy 115.56477 -288.911132) (xy 115.522886 -288.940042) (xy 115.476907 -288.961859)
			(xy 115.428023 -288.976019) (xy 115.377502 -288.982153) (xy 115.32665 -288.980104) (xy 115.276786 -288.969924)
			(xy 115.2292 -288.951877) (xy 115.185126 -288.926431) (xy 115.145704 -288.894244) (xy 115.111956 -288.85615)
			(xy 115.084755 -288.813136) (xy 115.064807 -288.766316) (xy 115.052628 -288.716902) (xy 115.048533 -288.666174)
			(xy 114.740436 -288.666174) (xy 114.739924 -288.69162) (xy 114.73176 -288.741854) (xy 114.715644 -288.790128)
			(xy 114.691993 -288.835191) (xy 114.66142 -288.875877) (xy 114.624716 -288.911132) (xy 114.582832 -288.940042)
			(xy 114.536853 -288.961859) (xy 114.487969 -288.976019) (xy 114.437448 -288.982153) (xy 114.386596 -288.980104)
			(xy 114.336732 -288.969924) (xy 114.289146 -288.951877) (xy 114.245072 -288.926431) (xy 114.20565 -288.894244)
			(xy 114.171902 -288.85615) (xy 114.144701 -288.813136) (xy 114.124753 -288.766316) (xy 114.112574 -288.716902)
			(xy 114.108479 -288.666174) (xy 113.802668 -288.666174) (xy 113.802178 -288.691163) (xy 113.794359 -288.740526)
			(xy 113.778915 -288.788058) (xy 113.756225 -288.83259) (xy 113.726849 -288.873023) (xy 113.691509 -288.908363)
			(xy 113.651076 -288.937739) (xy 113.606544 -288.960429) (xy 113.559012 -288.975873) (xy 113.509649 -288.983692)
			(xy 113.459671 -288.983692) (xy 113.410308 -288.975873) (xy 113.362776 -288.960429) (xy 113.318244 -288.937739)
			(xy 113.277811 -288.908363) (xy 113.242471 -288.873023) (xy 113.213095 -288.83259) (xy 113.190405 -288.788058)
			(xy 113.174961 -288.740526) (xy 113.167142 -288.691163) (xy 110.98862 -288.691163) (xy 110.980801 -288.740526)
			(xy 110.965357 -288.788058) (xy 110.942667 -288.83259) (xy 110.913291 -288.873023) (xy 110.877951 -288.908363)
			(xy 110.837518 -288.937739) (xy 110.792986 -288.960429) (xy 110.745454 -288.975873) (xy 110.696091 -288.983692)
			(xy 110.646113 -288.983692) (xy 110.59675 -288.975873) (xy 110.549218 -288.960429) (xy 110.504686 -288.937739)
			(xy 110.464253 -288.908363) (xy 110.428913 -288.873023) (xy 110.399537 -288.83259) (xy 110.376847 -288.788058)
			(xy 110.361403 -288.740526) (xy 110.353584 -288.691163) (xy 110.046267 -288.691163) (xy 110.046258 -288.69162)
			(xy 110.038094 -288.741854) (xy 110.021978 -288.790128) (xy 109.998327 -288.835191) (xy 109.967754 -288.875877)
			(xy 109.93105 -288.911132) (xy 109.889166 -288.940042) (xy 109.843187 -288.961859) (xy 109.794303 -288.976019)
			(xy 109.743782 -288.982153) (xy 109.69293 -288.980104) (xy 109.643066 -288.969924) (xy 109.59548 -288.951877)
			(xy 109.551406 -288.926431) (xy 109.511984 -288.894244) (xy 109.478236 -288.85615) (xy 109.451035 -288.813136)
			(xy 109.431087 -288.766316) (xy 109.418908 -288.716902) (xy 109.414813 -288.666174) (xy 109.106716 -288.666174)
			(xy 109.106204 -288.69162) (xy 109.09804 -288.741854) (xy 109.081924 -288.790128) (xy 109.058273 -288.835191)
			(xy 109.0277 -288.875877) (xy 108.990996 -288.911132) (xy 108.949112 -288.940042) (xy 108.903133 -288.961859)
			(xy 108.854249 -288.976019) (xy 108.803728 -288.982153) (xy 108.752876 -288.980104) (xy 108.703012 -288.969924)
			(xy 108.655426 -288.951877) (xy 108.611352 -288.926431) (xy 108.57193 -288.894244) (xy 108.538182 -288.85615)
			(xy 108.510981 -288.813136) (xy 108.491033 -288.766316) (xy 108.478854 -288.716902) (xy 108.474759 -288.666174)
			(xy 108.168948 -288.666174) (xy 108.168458 -288.691163) (xy 108.160639 -288.740526) (xy 108.145195 -288.788058)
			(xy 108.122505 -288.83259) (xy 108.093129 -288.873023) (xy 108.057789 -288.908363) (xy 108.017356 -288.937739)
			(xy 107.972824 -288.960429) (xy 107.925292 -288.975873) (xy 107.875929 -288.983692) (xy 107.825951 -288.983692)
			(xy 107.776588 -288.975873) (xy 107.729056 -288.960429) (xy 107.684524 -288.937739) (xy 107.644091 -288.908363)
			(xy 107.608751 -288.873023) (xy 107.579375 -288.83259) (xy 107.556685 -288.788058) (xy 107.541241 -288.740526)
			(xy 107.533422 -288.691163) (xy 107.228658 -288.691163) (xy 107.220839 -288.740526) (xy 107.205395 -288.788058)
			(xy 107.182705 -288.83259) (xy 107.153329 -288.873023) (xy 107.117989 -288.908363) (xy 107.077556 -288.937739)
			(xy 107.033024 -288.960429) (xy 106.985492 -288.975873) (xy 106.936129 -288.983692) (xy 106.886151 -288.983692)
			(xy 106.836788 -288.975873) (xy 106.789256 -288.960429) (xy 106.744724 -288.937739) (xy 106.704291 -288.908363)
			(xy 106.668951 -288.873023) (xy 106.639575 -288.83259) (xy 106.616885 -288.788058) (xy 106.601441 -288.740526)
			(xy 106.593622 -288.691163) (xy 106.288604 -288.691163) (xy 106.280785 -288.740526) (xy 106.265341 -288.788058)
			(xy 106.242651 -288.83259) (xy 106.213275 -288.873023) (xy 106.177935 -288.908363) (xy 106.137502 -288.937739)
			(xy 106.09297 -288.960429) (xy 106.045438 -288.975873) (xy 105.996075 -288.983692) (xy 105.946097 -288.983692)
			(xy 105.896734 -288.975873) (xy 105.849202 -288.960429) (xy 105.80467 -288.937739) (xy 105.764237 -288.908363)
			(xy 105.728897 -288.873023) (xy 105.699521 -288.83259) (xy 105.676831 -288.788058) (xy 105.661387 -288.740526)
			(xy 105.653568 -288.691163) (xy 105.34855 -288.691163) (xy 105.340731 -288.740526) (xy 105.325287 -288.788058)
			(xy 105.302597 -288.83259) (xy 105.273221 -288.873023) (xy 105.237881 -288.908363) (xy 105.197448 -288.937739)
			(xy 105.152916 -288.960429) (xy 105.105384 -288.975873) (xy 105.056021 -288.983692) (xy 105.006043 -288.983692)
			(xy 104.95668 -288.975873) (xy 104.909148 -288.960429) (xy 104.864616 -288.937739) (xy 104.824183 -288.908363)
			(xy 104.788843 -288.873023) (xy 104.759467 -288.83259) (xy 104.736777 -288.788058) (xy 104.721333 -288.740526)
			(xy 104.713514 -288.691163) (xy 104.408496 -288.691163) (xy 104.400677 -288.740526) (xy 104.385233 -288.788058)
			(xy 104.362543 -288.83259) (xy 104.333167 -288.873023) (xy 104.297827 -288.908363) (xy 104.257394 -288.937739)
			(xy 104.212862 -288.960429) (xy 104.16533 -288.975873) (xy 104.115967 -288.983692) (xy 104.065989 -288.983692)
			(xy 104.016626 -288.975873) (xy 103.969094 -288.960429) (xy 103.924562 -288.937739) (xy 103.884129 -288.908363)
			(xy 103.848789 -288.873023) (xy 103.819413 -288.83259) (xy 103.796723 -288.788058) (xy 103.781279 -288.740526)
			(xy 103.77346 -288.691163) (xy 103.468696 -288.691163) (xy 103.460877 -288.740526) (xy 103.445433 -288.788058)
			(xy 103.422743 -288.83259) (xy 103.393367 -288.873023) (xy 103.358027 -288.908363) (xy 103.317594 -288.937739)
			(xy 103.273062 -288.960429) (xy 103.22553 -288.975873) (xy 103.176167 -288.983692) (xy 103.126189 -288.983692)
			(xy 103.076826 -288.975873) (xy 103.029294 -288.960429) (xy 102.984762 -288.937739) (xy 102.944329 -288.908363)
			(xy 102.908989 -288.873023) (xy 102.879613 -288.83259) (xy 102.856923 -288.788058) (xy 102.841479 -288.740526)
			(xy 102.83366 -288.691163) (xy 102.528642 -288.691163) (xy 102.520823 -288.740526) (xy 102.505379 -288.788058)
			(xy 102.482689 -288.83259) (xy 102.453313 -288.873023) (xy 102.417973 -288.908363) (xy 102.37754 -288.937739)
			(xy 102.333008 -288.960429) (xy 102.285476 -288.975873) (xy 102.236113 -288.983692) (xy 102.186135 -288.983692)
			(xy 102.136772 -288.975873) (xy 102.08924 -288.960429) (xy 102.044708 -288.937739) (xy 102.004275 -288.908363)
			(xy 101.968935 -288.873023) (xy 101.939559 -288.83259) (xy 101.916869 -288.788058) (xy 101.901425 -288.740526)
			(xy 101.893606 -288.691163) (xy 101.588588 -288.691163) (xy 101.580769 -288.740526) (xy 101.565325 -288.788058)
			(xy 101.542635 -288.83259) (xy 101.513259 -288.873023) (xy 101.477919 -288.908363) (xy 101.437486 -288.937739)
			(xy 101.392954 -288.960429) (xy 101.345422 -288.975873) (xy 101.296059 -288.983692) (xy 101.246081 -288.983692)
			(xy 101.196718 -288.975873) (xy 101.149186 -288.960429) (xy 101.104654 -288.937739) (xy 101.064221 -288.908363)
			(xy 101.028881 -288.873023) (xy 100.999505 -288.83259) (xy 100.976815 -288.788058) (xy 100.961371 -288.740526)
			(xy 100.953552 -288.691163) (xy 100.648534 -288.691163) (xy 100.640715 -288.740526) (xy 100.625271 -288.788058)
			(xy 100.602581 -288.83259) (xy 100.573205 -288.873023) (xy 100.537865 -288.908363) (xy 100.497432 -288.937739)
			(xy 100.4529 -288.960429) (xy 100.405368 -288.975873) (xy 100.356005 -288.983692) (xy 100.306027 -288.983692)
			(xy 100.256664 -288.975873) (xy 100.209132 -288.960429) (xy 100.1646 -288.937739) (xy 100.124167 -288.908363)
			(xy 100.088827 -288.873023) (xy 100.059451 -288.83259) (xy 100.036761 -288.788058) (xy 100.021317 -288.740526)
			(xy 100.013498 -288.691163) (xy 99.70848 -288.691163) (xy 99.700661 -288.740526) (xy 99.685217 -288.788058)
			(xy 99.662527 -288.83259) (xy 99.633151 -288.873023) (xy 99.597811 -288.908363) (xy 99.557378 -288.937739)
			(xy 99.512846 -288.960429) (xy 99.465314 -288.975873) (xy 99.415951 -288.983692) (xy 99.365973 -288.983692)
			(xy 99.31661 -288.975873) (xy 99.269078 -288.960429) (xy 99.224546 -288.937739) (xy 99.184113 -288.908363)
			(xy 99.148773 -288.873023) (xy 99.119397 -288.83259) (xy 99.096707 -288.788058) (xy 99.081263 -288.740526)
			(xy 99.073444 -288.691163) (xy 98.76868 -288.691163) (xy 98.760861 -288.740526) (xy 98.745417 -288.788058)
			(xy 98.722727 -288.83259) (xy 98.693351 -288.873023) (xy 98.658011 -288.908363) (xy 98.617578 -288.937739)
			(xy 98.573046 -288.960429) (xy 98.525514 -288.975873) (xy 98.476151 -288.983692) (xy 98.426173 -288.983692)
			(xy 98.37681 -288.975873) (xy 98.329278 -288.960429) (xy 98.284746 -288.937739) (xy 98.244313 -288.908363)
			(xy 98.208973 -288.873023) (xy 98.179597 -288.83259) (xy 98.156907 -288.788058) (xy 98.141463 -288.740526)
			(xy 98.133644 -288.691163) (xy 97.828626 -288.691163) (xy 97.820807 -288.740526) (xy 97.805363 -288.788058)
			(xy 97.782673 -288.83259) (xy 97.753297 -288.873023) (xy 97.717957 -288.908363) (xy 97.677524 -288.937739)
			(xy 97.632992 -288.960429) (xy 97.58546 -288.975873) (xy 97.536097 -288.983692) (xy 97.486119 -288.983692)
			(xy 97.436756 -288.975873) (xy 97.389224 -288.960429) (xy 97.344692 -288.937739) (xy 97.304259 -288.908363)
			(xy 97.268919 -288.873023) (xy 97.239543 -288.83259) (xy 97.216853 -288.788058) (xy 97.201409 -288.740526)
			(xy 97.19359 -288.691163) (xy 96.888572 -288.691163) (xy 96.880753 -288.740526) (xy 96.865309 -288.788058)
			(xy 96.842619 -288.83259) (xy 96.813243 -288.873023) (xy 96.777903 -288.908363) (xy 96.73747 -288.937739)
			(xy 96.692938 -288.960429) (xy 96.645406 -288.975873) (xy 96.596043 -288.983692) (xy 96.546065 -288.983692)
			(xy 96.496702 -288.975873) (xy 96.44917 -288.960429) (xy 96.404638 -288.937739) (xy 96.364205 -288.908363)
			(xy 96.328865 -288.873023) (xy 96.299489 -288.83259) (xy 96.276799 -288.788058) (xy 96.261355 -288.740526)
			(xy 96.253536 -288.691163) (xy 95.946219 -288.691163) (xy 95.94621 -288.69162) (xy 95.938046 -288.741854)
			(xy 95.92193 -288.790128) (xy 95.898279 -288.835191) (xy 95.867706 -288.875877) (xy 95.831002 -288.911132)
			(xy 95.789118 -288.940042) (xy 95.743139 -288.961859) (xy 95.694255 -288.976019) (xy 95.643734 -288.982153)
			(xy 95.592882 -288.980104) (xy 95.543018 -288.969924) (xy 95.495432 -288.951877) (xy 95.451358 -288.926431)
			(xy 95.411936 -288.894244) (xy 95.378188 -288.85615) (xy 95.350987 -288.813136) (xy 95.331039 -288.766316)
			(xy 95.31886 -288.716902) (xy 95.314765 -288.666174) (xy 95.006668 -288.666174) (xy 95.006156 -288.69162)
			(xy 94.997992 -288.741854) (xy 94.981876 -288.790128) (xy 94.958225 -288.835191) (xy 94.927652 -288.875877)
			(xy 94.890948 -288.911132) (xy 94.849064 -288.940042) (xy 94.803085 -288.961859) (xy 94.754201 -288.976019)
			(xy 94.70368 -288.982153) (xy 94.652828 -288.980104) (xy 94.602964 -288.969924) (xy 94.555378 -288.951877)
			(xy 94.511304 -288.926431) (xy 94.471882 -288.894244) (xy 94.438134 -288.85615) (xy 94.410933 -288.813136)
			(xy 94.390985 -288.766316) (xy 94.378806 -288.716902) (xy 94.374711 -288.666174) (xy 94.069154 -288.666174)
			(xy 94.068664 -288.691163) (xy 94.060845 -288.740526) (xy 94.045401 -288.788058) (xy 94.022711 -288.83259)
			(xy 93.993335 -288.873023) (xy 93.957995 -288.908363) (xy 93.917562 -288.937739) (xy 93.87303 -288.960429)
			(xy 93.825498 -288.975873) (xy 93.776135 -288.983692) (xy 93.726157 -288.983692) (xy 93.676794 -288.975873)
			(xy 93.629262 -288.960429) (xy 93.58473 -288.937739) (xy 93.544297 -288.908363) (xy 93.508957 -288.873023)
			(xy 93.479581 -288.83259) (xy 93.456891 -288.788058) (xy 93.441447 -288.740526) (xy 93.433628 -288.691163)
			(xy 93.126311 -288.691163) (xy 93.126302 -288.69162) (xy 93.118138 -288.741854) (xy 93.102022 -288.790128)
			(xy 93.078371 -288.835191) (xy 93.047798 -288.875877) (xy 93.011094 -288.911132) (xy 92.96921 -288.940042)
			(xy 92.923231 -288.961859) (xy 92.874347 -288.976019) (xy 92.823826 -288.982153) (xy 92.772974 -288.980104)
			(xy 92.72311 -288.969924) (xy 92.675524 -288.951877) (xy 92.63145 -288.926431) (xy 92.592028 -288.894244)
			(xy 92.55828 -288.85615) (xy 92.531079 -288.813136) (xy 92.511131 -288.766316) (xy 92.498952 -288.716902)
			(xy 92.494857 -288.666174) (xy 92.189813 -288.666174) (xy 92.189814 -288.666187) (xy 92.185801 -288.716628)
			(xy 92.173857 -288.765799) (xy 92.154285 -288.812461) (xy 92.127576 -288.855439) (xy 92.094404 -288.89365)
			(xy 92.055604 -288.926131) (xy 92.034106 -288.939478) (xy 92.030042 -288.941764) (xy 92.020898 -288.949892)
			(xy 92.014548 -288.956496) (xy 91.999054 -288.9758) (xy 91.99626 -288.985198) (xy 91.981435 -289.032881)
			(xy 91.944366 -289.125608) (xy 91.899132 -289.214639) (xy 91.87307 -289.257232) (xy 91.86926 -289.263328)
			(xy 91.863418 -289.283394) (xy 91.86247 -289.286873) (xy 91.861453 -289.294012) (xy 91.861386 -289.297618)
			(xy 91.861386 -289.47618) (xy 92.024703 -289.47618) (xy 92.028798 -289.425452) (xy 92.040977 -289.376038)
			(xy 92.060925 -289.329218) (xy 92.088126 -289.286204) (xy 92.121874 -289.24811) (xy 92.161296 -289.215923)
			(xy 92.20537 -289.190477) (xy 92.252956 -289.17243) (xy 92.30282 -289.16225) (xy 92.353672 -289.160201)
			(xy 92.404193 -289.166335) (xy 92.453077 -289.180495) (xy 92.499056 -289.202312) (xy 92.54094 -289.231222)
			(xy 92.577644 -289.266477) (xy 92.608217 -289.307163) (xy 92.631868 -289.352226) (xy 92.647984 -289.4005)
			(xy 92.656148 -289.450734) (xy 92.65666 -289.47618) (xy 92.656157 -289.501169) (xy 92.963474 -289.501169)
			(xy 92.963474 -289.451191) (xy 92.971293 -289.401828) (xy 92.986737 -289.354296) (xy 93.009427 -289.309764)
			(xy 93.038803 -289.269331) (xy 93.074143 -289.233991) (xy 93.114576 -289.204615) (xy 93.159108 -289.181925)
			(xy 93.20664 -289.166481) (xy 93.256003 -289.158662) (xy 93.305981 -289.158662) (xy 93.355344 -289.166481)
			(xy 93.402876 -289.181925) (xy 93.447408 -289.204615) (xy 93.487841 -289.233991) (xy 93.523181 -289.269331)
			(xy 93.552557 -289.309764) (xy 93.575247 -289.354296) (xy 93.590691 -289.401828) (xy 93.59851 -289.451191)
			(xy 93.599 -289.47618) (xy 93.904811 -289.47618) (xy 93.908906 -289.425452) (xy 93.921085 -289.376038)
			(xy 93.941033 -289.329218) (xy 93.968234 -289.286204) (xy 94.001982 -289.24811) (xy 94.041404 -289.215923)
			(xy 94.085478 -289.190477) (xy 94.133064 -289.17243) (xy 94.182928 -289.16225) (xy 94.23378 -289.160201)
			(xy 94.284301 -289.166335) (xy 94.333185 -289.180495) (xy 94.379164 -289.202312) (xy 94.421048 -289.231222)
			(xy 94.457752 -289.266477) (xy 94.488325 -289.307163) (xy 94.511976 -289.352226) (xy 94.528092 -289.4005)
			(xy 94.536256 -289.450734) (xy 94.536768 -289.47618) (xy 94.536265 -289.501169) (xy 94.843582 -289.501169)
			(xy 94.843582 -289.451191) (xy 94.851401 -289.401828) (xy 94.866845 -289.354296) (xy 94.889535 -289.309764)
			(xy 94.918911 -289.269331) (xy 94.954251 -289.233991) (xy 94.994684 -289.204615) (xy 95.039216 -289.181925)
			(xy 95.086748 -289.166481) (xy 95.136111 -289.158662) (xy 95.186089 -289.158662) (xy 95.235452 -289.166481)
			(xy 95.282984 -289.181925) (xy 95.327516 -289.204615) (xy 95.367949 -289.233991) (xy 95.403289 -289.269331)
			(xy 95.432665 -289.309764) (xy 95.455355 -289.354296) (xy 95.470799 -289.401828) (xy 95.478618 -289.451191)
			(xy 95.479108 -289.47618) (xy 95.784919 -289.47618) (xy 95.789014 -289.425452) (xy 95.801193 -289.376038)
			(xy 95.821141 -289.329218) (xy 95.848342 -289.286204) (xy 95.88209 -289.24811) (xy 95.921512 -289.215923)
			(xy 95.965586 -289.190477) (xy 96.013172 -289.17243) (xy 96.063036 -289.16225) (xy 96.113888 -289.160201)
			(xy 96.164409 -289.166335) (xy 96.213293 -289.180495) (xy 96.259272 -289.202312) (xy 96.301156 -289.231222)
			(xy 96.33786 -289.266477) (xy 96.368433 -289.307163) (xy 96.392084 -289.352226) (xy 96.4082 -289.4005)
			(xy 96.416364 -289.450734) (xy 96.416876 -289.47618) (xy 96.416373 -289.501169) (xy 96.723436 -289.501169)
			(xy 96.723436 -289.451191) (xy 96.731255 -289.401828) (xy 96.746699 -289.354296) (xy 96.769389 -289.309764)
			(xy 96.798765 -289.269331) (xy 96.834105 -289.233991) (xy 96.874538 -289.204615) (xy 96.91907 -289.181925)
			(xy 96.966602 -289.166481) (xy 97.015965 -289.158662) (xy 97.065943 -289.158662) (xy 97.115306 -289.166481)
			(xy 97.162838 -289.181925) (xy 97.20737 -289.204615) (xy 97.247803 -289.233991) (xy 97.283143 -289.269331)
			(xy 97.312519 -289.309764) (xy 97.335209 -289.354296) (xy 97.350653 -289.401828) (xy 97.358472 -289.451191)
			(xy 97.358962 -289.47618) (xy 97.664773 -289.47618) (xy 97.668868 -289.425452) (xy 97.681047 -289.376038)
			(xy 97.700995 -289.329218) (xy 97.728196 -289.286204) (xy 97.761944 -289.24811) (xy 97.801366 -289.215923)
			(xy 97.84544 -289.190477) (xy 97.893026 -289.17243) (xy 97.94289 -289.16225) (xy 97.993742 -289.160201)
			(xy 98.044263 -289.166335) (xy 98.093147 -289.180495) (xy 98.139126 -289.202312) (xy 98.18101 -289.231222)
			(xy 98.217714 -289.266477) (xy 98.248287 -289.307163) (xy 98.271938 -289.352226) (xy 98.288054 -289.4005)
			(xy 98.296218 -289.450734) (xy 98.29673 -289.47618) (xy 98.604827 -289.47618) (xy 98.608922 -289.425452)
			(xy 98.621101 -289.376038) (xy 98.641049 -289.329218) (xy 98.66825 -289.286204) (xy 98.701998 -289.24811)
			(xy 98.74142 -289.215923) (xy 98.785494 -289.190477) (xy 98.83308 -289.17243) (xy 98.882944 -289.16225)
			(xy 98.933796 -289.160201) (xy 98.984317 -289.166335) (xy 99.033201 -289.180495) (xy 99.07918 -289.202312)
			(xy 99.121064 -289.231222) (xy 99.157768 -289.266477) (xy 99.188341 -289.307163) (xy 99.211992 -289.352226)
			(xy 99.228108 -289.4005) (xy 99.236272 -289.450734) (xy 99.236784 -289.47618) (xy 99.236281 -289.501169)
			(xy 99.543598 -289.501169) (xy 99.543598 -289.451191) (xy 99.551417 -289.401828) (xy 99.566861 -289.354296)
			(xy 99.589551 -289.309764) (xy 99.618927 -289.269331) (xy 99.654267 -289.233991) (xy 99.6947 -289.204615)
			(xy 99.739232 -289.181925) (xy 99.786764 -289.166481) (xy 99.836127 -289.158662) (xy 99.886105 -289.158662)
			(xy 99.935468 -289.166481) (xy 99.983 -289.181925) (xy 100.027532 -289.204615) (xy 100.067965 -289.233991)
			(xy 100.103305 -289.269331) (xy 100.132681 -289.309764) (xy 100.155371 -289.354296) (xy 100.170815 -289.401828)
			(xy 100.178634 -289.451191) (xy 100.179124 -289.47618) (xy 100.484935 -289.47618) (xy 100.48903 -289.425452)
			(xy 100.501209 -289.376038) (xy 100.521157 -289.329218) (xy 100.548358 -289.286204) (xy 100.582106 -289.24811)
			(xy 100.621528 -289.215923) (xy 100.665602 -289.190477) (xy 100.713188 -289.17243) (xy 100.763052 -289.16225)
			(xy 100.813904 -289.160201) (xy 100.864425 -289.166335) (xy 100.913309 -289.180495) (xy 100.959288 -289.202312)
			(xy 101.001172 -289.231222) (xy 101.037876 -289.266477) (xy 101.068449 -289.307163) (xy 101.0921 -289.352226)
			(xy 101.108216 -289.4005) (xy 101.11638 -289.450734) (xy 101.116892 -289.47618) (xy 101.424735 -289.47618)
			(xy 101.42883 -289.425452) (xy 101.441009 -289.376038) (xy 101.460957 -289.329218) (xy 101.488158 -289.286204)
			(xy 101.521906 -289.24811) (xy 101.561328 -289.215923) (xy 101.605402 -289.190477) (xy 101.652988 -289.17243)
			(xy 101.702852 -289.16225) (xy 101.753704 -289.160201) (xy 101.804225 -289.166335) (xy 101.853109 -289.180495)
			(xy 101.899088 -289.202312) (xy 101.940972 -289.231222) (xy 101.977676 -289.266477) (xy 102.008249 -289.307163)
			(xy 102.0319 -289.352226) (xy 102.048016 -289.4005) (xy 102.05618 -289.450734) (xy 102.056692 -289.47618)
			(xy 102.056189 -289.501169) (xy 102.363506 -289.501169) (xy 102.363506 -289.451191) (xy 102.371325 -289.401828)
			(xy 102.386769 -289.354296) (xy 102.409459 -289.309764) (xy 102.438835 -289.269331) (xy 102.474175 -289.233991)
			(xy 102.514608 -289.204615) (xy 102.55914 -289.181925) (xy 102.606672 -289.166481) (xy 102.656035 -289.158662)
			(xy 102.706013 -289.158662) (xy 102.755376 -289.166481) (xy 102.802908 -289.181925) (xy 102.84744 -289.204615)
			(xy 102.887873 -289.233991) (xy 102.923213 -289.269331) (xy 102.952589 -289.309764) (xy 102.975279 -289.354296)
			(xy 102.990723 -289.401828) (xy 102.998542 -289.451191) (xy 102.999032 -289.47618) (xy 103.304843 -289.47618)
			(xy 103.308938 -289.425452) (xy 103.321117 -289.376038) (xy 103.341065 -289.329218) (xy 103.368266 -289.286204)
			(xy 103.402014 -289.24811) (xy 103.441436 -289.215923) (xy 103.48551 -289.190477) (xy 103.533096 -289.17243)
			(xy 103.58296 -289.16225) (xy 103.633812 -289.160201) (xy 103.684333 -289.166335) (xy 103.733217 -289.180495)
			(xy 103.779196 -289.202312) (xy 103.82108 -289.231222) (xy 103.857784 -289.266477) (xy 103.888357 -289.307163)
			(xy 103.912008 -289.352226) (xy 103.928124 -289.4005) (xy 103.936288 -289.450734) (xy 103.9368 -289.47618)
			(xy 104.244897 -289.47618) (xy 104.248992 -289.425452) (xy 104.261171 -289.376038) (xy 104.281119 -289.329218)
			(xy 104.30832 -289.286204) (xy 104.342068 -289.24811) (xy 104.38149 -289.215923) (xy 104.425564 -289.190477)
			(xy 104.47315 -289.17243) (xy 104.523014 -289.16225) (xy 104.573866 -289.160201) (xy 104.624387 -289.166335)
			(xy 104.673271 -289.180495) (xy 104.71925 -289.202312) (xy 104.761134 -289.231222) (xy 104.797838 -289.266477)
			(xy 104.828411 -289.307163) (xy 104.852062 -289.352226) (xy 104.868178 -289.4005) (xy 104.876342 -289.450734)
			(xy 104.876854 -289.47618) (xy 104.876351 -289.501169) (xy 105.183414 -289.501169) (xy 105.183414 -289.451191)
			(xy 105.191233 -289.401828) (xy 105.206677 -289.354296) (xy 105.229367 -289.309764) (xy 105.258743 -289.269331)
			(xy 105.294083 -289.233991) (xy 105.334516 -289.204615) (xy 105.379048 -289.181925) (xy 105.42658 -289.166481)
			(xy 105.475943 -289.158662) (xy 105.525921 -289.158662) (xy 105.575284 -289.166481) (xy 105.622816 -289.181925)
			(xy 105.667348 -289.204615) (xy 105.707781 -289.233991) (xy 105.743121 -289.269331) (xy 105.772497 -289.309764)
			(xy 105.795187 -289.354296) (xy 105.810631 -289.401828) (xy 105.81845 -289.451191) (xy 105.81894 -289.47618)
			(xy 106.124751 -289.47618) (xy 106.128846 -289.425452) (xy 106.141025 -289.376038) (xy 106.160973 -289.329218)
			(xy 106.188174 -289.286204) (xy 106.221922 -289.24811) (xy 106.261344 -289.215923) (xy 106.305418 -289.190477)
			(xy 106.353004 -289.17243) (xy 106.402868 -289.16225) (xy 106.45372 -289.160201) (xy 106.504241 -289.166335)
			(xy 106.553125 -289.180495) (xy 106.599104 -289.202312) (xy 106.640988 -289.231222) (xy 106.677692 -289.266477)
			(xy 106.708265 -289.307163) (xy 106.731916 -289.352226) (xy 106.748032 -289.4005) (xy 106.756196 -289.450734)
			(xy 106.756708 -289.47618) (xy 107.064805 -289.47618) (xy 107.0689 -289.425452) (xy 107.081079 -289.376038)
			(xy 107.101027 -289.329218) (xy 107.128228 -289.286204) (xy 107.161976 -289.24811) (xy 107.201398 -289.215923)
			(xy 107.245472 -289.190477) (xy 107.293058 -289.17243) (xy 107.342922 -289.16225) (xy 107.393774 -289.160201)
			(xy 107.444295 -289.166335) (xy 107.493179 -289.180495) (xy 107.539158 -289.202312) (xy 107.581042 -289.231222)
			(xy 107.617746 -289.266477) (xy 107.648319 -289.307163) (xy 107.67197 -289.352226) (xy 107.688086 -289.4005)
			(xy 107.69625 -289.450734) (xy 107.696762 -289.47618) (xy 107.696259 -289.501169) (xy 108.003576 -289.501169)
			(xy 108.003576 -289.451191) (xy 108.011395 -289.401828) (xy 108.026839 -289.354296) (xy 108.049529 -289.309764)
			(xy 108.078905 -289.269331) (xy 108.114245 -289.233991) (xy 108.154678 -289.204615) (xy 108.19921 -289.181925)
			(xy 108.246742 -289.166481) (xy 108.296105 -289.158662) (xy 108.346083 -289.158662) (xy 108.395446 -289.166481)
			(xy 108.442978 -289.181925) (xy 108.48751 -289.204615) (xy 108.527943 -289.233991) (xy 108.563283 -289.269331)
			(xy 108.592659 -289.309764) (xy 108.615349 -289.354296) (xy 108.630793 -289.401828) (xy 108.638612 -289.451191)
			(xy 108.639102 -289.47618) (xy 108.638612 -289.501169) (xy 115.51715 -289.501169) (xy 115.51715 -289.451191)
			(xy 115.524969 -289.401828) (xy 115.540413 -289.354296) (xy 115.563103 -289.309764) (xy 115.592479 -289.269331)
			(xy 115.627819 -289.233991) (xy 115.668252 -289.204615) (xy 115.712784 -289.181925) (xy 115.760316 -289.166481)
			(xy 115.809679 -289.158662) (xy 115.859657 -289.158662) (xy 115.90902 -289.166481) (xy 115.956552 -289.181925)
			(xy 116.001084 -289.204615) (xy 116.041517 -289.233991) (xy 116.076857 -289.269331) (xy 116.106233 -289.309764)
			(xy 116.128923 -289.354296) (xy 116.144367 -289.401828) (xy 116.152186 -289.451191) (xy 116.152676 -289.47618)
			(xy 116.458487 -289.47618) (xy 116.462582 -289.425452) (xy 116.474761 -289.376038) (xy 116.494709 -289.329218)
			(xy 116.52191 -289.286204) (xy 116.555658 -289.24811) (xy 116.59508 -289.215923) (xy 116.639154 -289.190477)
			(xy 116.68674 -289.17243) (xy 116.736604 -289.16225) (xy 116.787456 -289.160201) (xy 116.837977 -289.166335)
			(xy 116.886861 -289.180495) (xy 116.93284 -289.202312) (xy 116.974724 -289.231222) (xy 117.011428 -289.266477)
			(xy 117.042001 -289.307163) (xy 117.065652 -289.352226) (xy 117.081768 -289.4005) (xy 117.089932 -289.450734)
			(xy 117.090444 -289.47618) (xy 117.398541 -289.47618) (xy 117.402636 -289.425452) (xy 117.414815 -289.376038)
			(xy 117.434763 -289.329218) (xy 117.461964 -289.286204) (xy 117.495712 -289.24811) (xy 117.535134 -289.215923)
			(xy 117.579208 -289.190477) (xy 117.626794 -289.17243) (xy 117.676658 -289.16225) (xy 117.72751 -289.160201)
			(xy 117.778031 -289.166335) (xy 117.826915 -289.180495) (xy 117.872894 -289.202312) (xy 117.914778 -289.231222)
			(xy 117.951482 -289.266477) (xy 117.982055 -289.307163) (xy 118.005706 -289.352226) (xy 118.021822 -289.4005)
			(xy 118.029986 -289.450734) (xy 118.030498 -289.47618) (xy 118.029995 -289.501169) (xy 118.337312 -289.501169)
			(xy 118.337312 -289.451191) (xy 118.345131 -289.401828) (xy 118.360575 -289.354296) (xy 118.383265 -289.309764)
			(xy 118.412641 -289.269331) (xy 118.447981 -289.233991) (xy 118.488414 -289.204615) (xy 118.532946 -289.181925)
			(xy 118.580478 -289.166481) (xy 118.629841 -289.158662) (xy 118.679819 -289.158662) (xy 118.729182 -289.166481)
			(xy 118.776714 -289.181925) (xy 118.821246 -289.204615) (xy 118.861679 -289.233991) (xy 118.897019 -289.269331)
			(xy 118.926395 -289.309764) (xy 118.949085 -289.354296) (xy 118.964529 -289.401828) (xy 118.972348 -289.451191)
			(xy 118.972838 -289.47618) (xy 119.278395 -289.47618) (xy 119.28249 -289.425452) (xy 119.294669 -289.376038)
			(xy 119.314617 -289.329218) (xy 119.341818 -289.286204) (xy 119.375566 -289.24811) (xy 119.414988 -289.215923)
			(xy 119.459062 -289.190477) (xy 119.506648 -289.17243) (xy 119.556512 -289.16225) (xy 119.607364 -289.160201)
			(xy 119.657885 -289.166335) (xy 119.706769 -289.180495) (xy 119.752748 -289.202312) (xy 119.794632 -289.231222)
			(xy 119.831336 -289.266477) (xy 119.861909 -289.307163) (xy 119.88556 -289.352226) (xy 119.901676 -289.4005)
			(xy 119.90984 -289.450734) (xy 119.910352 -289.47618) (xy 120.218449 -289.47618) (xy 120.222544 -289.425452)
			(xy 120.234723 -289.376038) (xy 120.254671 -289.329218) (xy 120.281872 -289.286204) (xy 120.31562 -289.24811)
			(xy 120.355042 -289.215923) (xy 120.399116 -289.190477) (xy 120.446702 -289.17243) (xy 120.496566 -289.16225)
			(xy 120.547418 -289.160201) (xy 120.597939 -289.166335) (xy 120.646823 -289.180495) (xy 120.692802 -289.202312)
			(xy 120.734686 -289.231222) (xy 120.77139 -289.266477) (xy 120.801963 -289.307163) (xy 120.825614 -289.352226)
			(xy 120.84173 -289.4005) (xy 120.849894 -289.450734) (xy 120.850406 -289.47618) (xy 120.849903 -289.501169)
			(xy 121.15722 -289.501169) (xy 121.15722 -289.451191) (xy 121.165039 -289.401828) (xy 121.180483 -289.354296)
			(xy 121.203173 -289.309764) (xy 121.232549 -289.269331) (xy 121.267889 -289.233991) (xy 121.308322 -289.204615)
			(xy 121.352854 -289.181925) (xy 121.400386 -289.166481) (xy 121.449749 -289.158662) (xy 121.499727 -289.158662)
			(xy 121.54909 -289.166481) (xy 121.596622 -289.181925) (xy 121.641154 -289.204615) (xy 121.681587 -289.233991)
			(xy 121.716927 -289.269331) (xy 121.746303 -289.309764) (xy 121.768993 -289.354296) (xy 121.784437 -289.401828)
			(xy 121.792256 -289.451191) (xy 121.792746 -289.47618) (xy 122.098557 -289.47618) (xy 122.102652 -289.425452)
			(xy 122.114831 -289.376038) (xy 122.134779 -289.329218) (xy 122.16198 -289.286204) (xy 122.195728 -289.24811)
			(xy 122.23515 -289.215923) (xy 122.279224 -289.190477) (xy 122.32681 -289.17243) (xy 122.376674 -289.16225)
			(xy 122.427526 -289.160201) (xy 122.478047 -289.166335) (xy 122.526931 -289.180495) (xy 122.57291 -289.202312)
			(xy 122.614794 -289.231222) (xy 122.651498 -289.266477) (xy 122.682071 -289.307163) (xy 122.705722 -289.352226)
			(xy 122.721838 -289.4005) (xy 122.730002 -289.450734) (xy 122.730514 -289.47618) (xy 123.038611 -289.47618)
			(xy 123.042706 -289.425452) (xy 123.054885 -289.376038) (xy 123.074833 -289.329218) (xy 123.102034 -289.286204)
			(xy 123.135782 -289.24811) (xy 123.175204 -289.215923) (xy 123.219278 -289.190477) (xy 123.266864 -289.17243)
			(xy 123.316728 -289.16225) (xy 123.36758 -289.160201) (xy 123.418101 -289.166335) (xy 123.466985 -289.180495)
			(xy 123.512964 -289.202312) (xy 123.554848 -289.231222) (xy 123.591552 -289.266477) (xy 123.622125 -289.307163)
			(xy 123.645776 -289.352226) (xy 123.661892 -289.4005) (xy 123.670056 -289.450734) (xy 123.670568 -289.47618)
			(xy 123.670065 -289.501169) (xy 123.977128 -289.501169) (xy 123.977128 -289.451191) (xy 123.984947 -289.401828)
			(xy 124.000391 -289.354296) (xy 124.023081 -289.309764) (xy 124.052457 -289.269331) (xy 124.087797 -289.233991)
			(xy 124.12823 -289.204615) (xy 124.172762 -289.181925) (xy 124.220294 -289.166481) (xy 124.269657 -289.158662)
			(xy 124.319635 -289.158662) (xy 124.368998 -289.166481) (xy 124.41653 -289.181925) (xy 124.461062 -289.204615)
			(xy 124.501495 -289.233991) (xy 124.536835 -289.269331) (xy 124.566211 -289.309764) (xy 124.588901 -289.354296)
			(xy 124.604345 -289.401828) (xy 124.612164 -289.451191) (xy 124.612654 -289.47618) (xy 124.918465 -289.47618)
			(xy 124.92256 -289.425452) (xy 124.934739 -289.376038) (xy 124.954687 -289.329218) (xy 124.981888 -289.286204)
			(xy 125.015636 -289.24811) (xy 125.055058 -289.215923) (xy 125.099132 -289.190477) (xy 125.146718 -289.17243)
			(xy 125.196582 -289.16225) (xy 125.247434 -289.160201) (xy 125.297955 -289.166335) (xy 125.346839 -289.180495)
			(xy 125.392818 -289.202312) (xy 125.434702 -289.231222) (xy 125.471406 -289.266477) (xy 125.501979 -289.307163)
			(xy 125.52563 -289.352226) (xy 125.541746 -289.4005) (xy 125.54991 -289.450734) (xy 125.550422 -289.47618)
			(xy 125.858519 -289.47618) (xy 125.862614 -289.425452) (xy 125.874793 -289.376038) (xy 125.894741 -289.329218)
			(xy 125.921942 -289.286204) (xy 125.95569 -289.24811) (xy 125.995112 -289.215923) (xy 126.039186 -289.190477)
			(xy 126.086772 -289.17243) (xy 126.136636 -289.16225) (xy 126.187488 -289.160201) (xy 126.238009 -289.166335)
			(xy 126.286893 -289.180495) (xy 126.332872 -289.202312) (xy 126.374756 -289.231222) (xy 126.41146 -289.266477)
			(xy 126.442033 -289.307163) (xy 126.465684 -289.352226) (xy 126.4818 -289.4005) (xy 126.489964 -289.450734)
			(xy 126.490476 -289.47618) (xy 126.489964 -289.501626) (xy 126.4818 -289.55186) (xy 126.465684 -289.600134)
			(xy 126.442033 -289.645197) (xy 126.41146 -289.685883) (xy 126.374756 -289.721138) (xy 126.332872 -289.750048)
			(xy 126.286893 -289.771865) (xy 126.238009 -289.786025) (xy 126.187488 -289.792159) (xy 126.136636 -289.79011)
			(xy 126.086772 -289.77993) (xy 126.039186 -289.761883) (xy 125.995112 -289.736437) (xy 125.95569 -289.70425)
			(xy 125.921942 -289.666156) (xy 125.894741 -289.623142) (xy 125.874793 -289.576322) (xy 125.862614 -289.526908)
			(xy 125.858519 -289.47618) (xy 125.550422 -289.47618) (xy 125.54991 -289.501626) (xy 125.541746 -289.55186)
			(xy 125.52563 -289.600134) (xy 125.501979 -289.645197) (xy 125.471406 -289.685883) (xy 125.434702 -289.721138)
			(xy 125.392818 -289.750048) (xy 125.346839 -289.771865) (xy 125.297955 -289.786025) (xy 125.247434 -289.792159)
			(xy 125.196582 -289.79011) (xy 125.146718 -289.77993) (xy 125.099132 -289.761883) (xy 125.055058 -289.736437)
			(xy 125.015636 -289.70425) (xy 124.981888 -289.666156) (xy 124.954687 -289.623142) (xy 124.934739 -289.576322)
			(xy 124.92256 -289.526908) (xy 124.918465 -289.47618) (xy 124.612654 -289.47618) (xy 124.612164 -289.501169)
			(xy 124.604345 -289.550532) (xy 124.588901 -289.598064) (xy 124.566211 -289.642596) (xy 124.536835 -289.683029)
			(xy 124.501495 -289.718369) (xy 124.461062 -289.747745) (xy 124.41653 -289.770435) (xy 124.368998 -289.785879)
			(xy 124.319635 -289.793698) (xy 124.269657 -289.793698) (xy 124.220294 -289.785879) (xy 124.172762 -289.770435)
			(xy 124.12823 -289.747745) (xy 124.087797 -289.718369) (xy 124.052457 -289.683029) (xy 124.023081 -289.642596)
			(xy 124.000391 -289.598064) (xy 123.984947 -289.550532) (xy 123.977128 -289.501169) (xy 123.670065 -289.501169)
			(xy 123.670056 -289.501626) (xy 123.661892 -289.55186) (xy 123.645776 -289.600134) (xy 123.622125 -289.645197)
			(xy 123.591552 -289.685883) (xy 123.554848 -289.721138) (xy 123.512964 -289.750048) (xy 123.466985 -289.771865)
			(xy 123.418101 -289.786025) (xy 123.36758 -289.792159) (xy 123.316728 -289.79011) (xy 123.266864 -289.77993)
			(xy 123.219278 -289.761883) (xy 123.175204 -289.736437) (xy 123.135782 -289.70425) (xy 123.102034 -289.666156)
			(xy 123.074833 -289.623142) (xy 123.054885 -289.576322) (xy 123.042706 -289.526908) (xy 123.038611 -289.47618)
			(xy 122.730514 -289.47618) (xy 122.730002 -289.501626) (xy 122.721838 -289.55186) (xy 122.705722 -289.600134)
			(xy 122.682071 -289.645197) (xy 122.651498 -289.685883) (xy 122.614794 -289.721138) (xy 122.57291 -289.750048)
			(xy 122.526931 -289.771865) (xy 122.478047 -289.786025) (xy 122.427526 -289.792159) (xy 122.376674 -289.79011)
			(xy 122.32681 -289.77993) (xy 122.279224 -289.761883) (xy 122.23515 -289.736437) (xy 122.195728 -289.70425)
			(xy 122.16198 -289.666156) (xy 122.134779 -289.623142) (xy 122.114831 -289.576322) (xy 122.102652 -289.526908)
			(xy 122.098557 -289.47618) (xy 121.792746 -289.47618) (xy 121.792256 -289.501169) (xy 121.784437 -289.550532)
			(xy 121.768993 -289.598064) (xy 121.746303 -289.642596) (xy 121.716927 -289.683029) (xy 121.681587 -289.718369)
			(xy 121.641154 -289.747745) (xy 121.596622 -289.770435) (xy 121.54909 -289.785879) (xy 121.499727 -289.793698)
			(xy 121.449749 -289.793698) (xy 121.400386 -289.785879) (xy 121.352854 -289.770435) (xy 121.308322 -289.747745)
			(xy 121.267889 -289.718369) (xy 121.232549 -289.683029) (xy 121.203173 -289.642596) (xy 121.180483 -289.598064)
			(xy 121.165039 -289.550532) (xy 121.15722 -289.501169) (xy 120.849903 -289.501169) (xy 120.849894 -289.501626)
			(xy 120.84173 -289.55186) (xy 120.825614 -289.600134) (xy 120.801963 -289.645197) (xy 120.77139 -289.685883)
			(xy 120.734686 -289.721138) (xy 120.692802 -289.750048) (xy 120.646823 -289.771865) (xy 120.597939 -289.786025)
			(xy 120.547418 -289.792159) (xy 120.496566 -289.79011) (xy 120.446702 -289.77993) (xy 120.399116 -289.761883)
			(xy 120.355042 -289.736437) (xy 120.31562 -289.70425) (xy 120.281872 -289.666156) (xy 120.254671 -289.623142)
			(xy 120.234723 -289.576322) (xy 120.222544 -289.526908) (xy 120.218449 -289.47618) (xy 119.910352 -289.47618)
			(xy 119.90984 -289.501626) (xy 119.901676 -289.55186) (xy 119.88556 -289.600134) (xy 119.861909 -289.645197)
			(xy 119.831336 -289.685883) (xy 119.794632 -289.721138) (xy 119.752748 -289.750048) (xy 119.706769 -289.771865)
			(xy 119.657885 -289.786025) (xy 119.607364 -289.792159) (xy 119.556512 -289.79011) (xy 119.506648 -289.77993)
			(xy 119.459062 -289.761883) (xy 119.414988 -289.736437) (xy 119.375566 -289.70425) (xy 119.341818 -289.666156)
			(xy 119.314617 -289.623142) (xy 119.294669 -289.576322) (xy 119.28249 -289.526908) (xy 119.278395 -289.47618)
			(xy 118.972838 -289.47618) (xy 118.972348 -289.501169) (xy 118.964529 -289.550532) (xy 118.949085 -289.598064)
			(xy 118.926395 -289.642596) (xy 118.897019 -289.683029) (xy 118.861679 -289.718369) (xy 118.821246 -289.747745)
			(xy 118.776714 -289.770435) (xy 118.729182 -289.785879) (xy 118.679819 -289.793698) (xy 118.629841 -289.793698)
			(xy 118.580478 -289.785879) (xy 118.532946 -289.770435) (xy 118.488414 -289.747745) (xy 118.447981 -289.718369)
			(xy 118.412641 -289.683029) (xy 118.383265 -289.642596) (xy 118.360575 -289.598064) (xy 118.345131 -289.550532)
			(xy 118.337312 -289.501169) (xy 118.029995 -289.501169) (xy 118.029986 -289.501626) (xy 118.021822 -289.55186)
			(xy 118.005706 -289.600134) (xy 117.982055 -289.645197) (xy 117.951482 -289.685883) (xy 117.914778 -289.721138)
			(xy 117.872894 -289.750048) (xy 117.826915 -289.771865) (xy 117.778031 -289.786025) (xy 117.72751 -289.792159)
			(xy 117.676658 -289.79011) (xy 117.626794 -289.77993) (xy 117.579208 -289.761883) (xy 117.535134 -289.736437)
			(xy 117.495712 -289.70425) (xy 117.461964 -289.666156) (xy 117.434763 -289.623142) (xy 117.414815 -289.576322)
			(xy 117.402636 -289.526908) (xy 117.398541 -289.47618) (xy 117.090444 -289.47618) (xy 117.089932 -289.501626)
			(xy 117.081768 -289.55186) (xy 117.065652 -289.600134) (xy 117.042001 -289.645197) (xy 117.011428 -289.685883)
			(xy 116.974724 -289.721138) (xy 116.93284 -289.750048) (xy 116.886861 -289.771865) (xy 116.837977 -289.786025)
			(xy 116.787456 -289.792159) (xy 116.736604 -289.79011) (xy 116.68674 -289.77993) (xy 116.639154 -289.761883)
			(xy 116.59508 -289.736437) (xy 116.555658 -289.70425) (xy 116.52191 -289.666156) (xy 116.494709 -289.623142)
			(xy 116.474761 -289.576322) (xy 116.462582 -289.526908) (xy 116.458487 -289.47618) (xy 116.152676 -289.47618)
			(xy 116.152186 -289.501169) (xy 116.144367 -289.550532) (xy 116.128923 -289.598064) (xy 116.106233 -289.642596)
			(xy 116.076857 -289.683029) (xy 116.041517 -289.718369) (xy 116.001084 -289.747745) (xy 115.956552 -289.770435)
			(xy 115.90902 -289.785879) (xy 115.859657 -289.793698) (xy 115.809679 -289.793698) (xy 115.760316 -289.785879)
			(xy 115.712784 -289.770435) (xy 115.668252 -289.747745) (xy 115.627819 -289.718369) (xy 115.592479 -289.683029)
			(xy 115.563103 -289.642596) (xy 115.540413 -289.598064) (xy 115.524969 -289.550532) (xy 115.51715 -289.501169)
			(xy 108.638612 -289.501169) (xy 108.630793 -289.550532) (xy 108.615349 -289.598064) (xy 108.592659 -289.642596)
			(xy 108.563283 -289.683029) (xy 108.527943 -289.718369) (xy 108.48751 -289.747745) (xy 108.442978 -289.770435)
			(xy 108.395446 -289.785879) (xy 108.346083 -289.793698) (xy 108.296105 -289.793698) (xy 108.246742 -289.785879)
			(xy 108.19921 -289.770435) (xy 108.154678 -289.747745) (xy 108.114245 -289.718369) (xy 108.078905 -289.683029)
			(xy 108.049529 -289.642596) (xy 108.026839 -289.598064) (xy 108.011395 -289.550532) (xy 108.003576 -289.501169)
			(xy 107.696259 -289.501169) (xy 107.69625 -289.501626) (xy 107.688086 -289.55186) (xy 107.67197 -289.600134)
			(xy 107.648319 -289.645197) (xy 107.617746 -289.685883) (xy 107.581042 -289.721138) (xy 107.539158 -289.750048)
			(xy 107.493179 -289.771865) (xy 107.444295 -289.786025) (xy 107.393774 -289.792159) (xy 107.342922 -289.79011)
			(xy 107.293058 -289.77993) (xy 107.245472 -289.761883) (xy 107.201398 -289.736437) (xy 107.161976 -289.70425)
			(xy 107.128228 -289.666156) (xy 107.101027 -289.623142) (xy 107.081079 -289.576322) (xy 107.0689 -289.526908)
			(xy 107.064805 -289.47618) (xy 106.756708 -289.47618) (xy 106.756196 -289.501626) (xy 106.748032 -289.55186)
			(xy 106.731916 -289.600134) (xy 106.708265 -289.645197) (xy 106.677692 -289.685883) (xy 106.640988 -289.721138)
			(xy 106.599104 -289.750048) (xy 106.553125 -289.771865) (xy 106.504241 -289.786025) (xy 106.45372 -289.792159)
			(xy 106.402868 -289.79011) (xy 106.353004 -289.77993) (xy 106.305418 -289.761883) (xy 106.261344 -289.736437)
			(xy 106.221922 -289.70425) (xy 106.188174 -289.666156) (xy 106.160973 -289.623142) (xy 106.141025 -289.576322)
			(xy 106.128846 -289.526908) (xy 106.124751 -289.47618) (xy 105.81894 -289.47618) (xy 105.81845 -289.501169)
			(xy 105.810631 -289.550532) (xy 105.795187 -289.598064) (xy 105.772497 -289.642596) (xy 105.743121 -289.683029)
			(xy 105.707781 -289.718369) (xy 105.667348 -289.747745) (xy 105.622816 -289.770435) (xy 105.575284 -289.785879)
			(xy 105.525921 -289.793698) (xy 105.475943 -289.793698) (xy 105.42658 -289.785879) (xy 105.379048 -289.770435)
			(xy 105.334516 -289.747745) (xy 105.294083 -289.718369) (xy 105.258743 -289.683029) (xy 105.229367 -289.642596)
			(xy 105.206677 -289.598064) (xy 105.191233 -289.550532) (xy 105.183414 -289.501169) (xy 104.876351 -289.501169)
			(xy 104.876342 -289.501626) (xy 104.868178 -289.55186) (xy 104.852062 -289.600134) (xy 104.828411 -289.645197)
			(xy 104.797838 -289.685883) (xy 104.761134 -289.721138) (xy 104.71925 -289.750048) (xy 104.673271 -289.771865)
			(xy 104.624387 -289.786025) (xy 104.573866 -289.792159) (xy 104.523014 -289.79011) (xy 104.47315 -289.77993)
			(xy 104.425564 -289.761883) (xy 104.38149 -289.736437) (xy 104.342068 -289.70425) (xy 104.30832 -289.666156)
			(xy 104.281119 -289.623142) (xy 104.261171 -289.576322) (xy 104.248992 -289.526908) (xy 104.244897 -289.47618)
			(xy 103.9368 -289.47618) (xy 103.936288 -289.501626) (xy 103.928124 -289.55186) (xy 103.912008 -289.600134)
			(xy 103.888357 -289.645197) (xy 103.857784 -289.685883) (xy 103.82108 -289.721138) (xy 103.779196 -289.750048)
			(xy 103.733217 -289.771865) (xy 103.684333 -289.786025) (xy 103.633812 -289.792159) (xy 103.58296 -289.79011)
			(xy 103.533096 -289.77993) (xy 103.48551 -289.761883) (xy 103.441436 -289.736437) (xy 103.402014 -289.70425)
			(xy 103.368266 -289.666156) (xy 103.341065 -289.623142) (xy 103.321117 -289.576322) (xy 103.308938 -289.526908)
			(xy 103.304843 -289.47618) (xy 102.999032 -289.47618) (xy 102.998542 -289.501169) (xy 102.990723 -289.550532)
			(xy 102.975279 -289.598064) (xy 102.952589 -289.642596) (xy 102.923213 -289.683029) (xy 102.887873 -289.718369)
			(xy 102.84744 -289.747745) (xy 102.802908 -289.770435) (xy 102.755376 -289.785879) (xy 102.706013 -289.793698)
			(xy 102.656035 -289.793698) (xy 102.606672 -289.785879) (xy 102.55914 -289.770435) (xy 102.514608 -289.747745)
			(xy 102.474175 -289.718369) (xy 102.438835 -289.683029) (xy 102.409459 -289.642596) (xy 102.386769 -289.598064)
			(xy 102.371325 -289.550532) (xy 102.363506 -289.501169) (xy 102.056189 -289.501169) (xy 102.05618 -289.501626)
			(xy 102.048016 -289.55186) (xy 102.0319 -289.600134) (xy 102.008249 -289.645197) (xy 101.977676 -289.685883)
			(xy 101.940972 -289.721138) (xy 101.899088 -289.750048) (xy 101.853109 -289.771865) (xy 101.804225 -289.786025)
			(xy 101.753704 -289.792159) (xy 101.702852 -289.79011) (xy 101.652988 -289.77993) (xy 101.605402 -289.761883)
			(xy 101.561328 -289.736437) (xy 101.521906 -289.70425) (xy 101.488158 -289.666156) (xy 101.460957 -289.623142)
			(xy 101.441009 -289.576322) (xy 101.42883 -289.526908) (xy 101.424735 -289.47618) (xy 101.116892 -289.47618)
			(xy 101.11638 -289.501626) (xy 101.108216 -289.55186) (xy 101.0921 -289.600134) (xy 101.068449 -289.645197)
			(xy 101.037876 -289.685883) (xy 101.001172 -289.721138) (xy 100.959288 -289.750048) (xy 100.913309 -289.771865)
			(xy 100.864425 -289.786025) (xy 100.813904 -289.792159) (xy 100.763052 -289.79011) (xy 100.713188 -289.77993)
			(xy 100.665602 -289.761883) (xy 100.621528 -289.736437) (xy 100.582106 -289.70425) (xy 100.548358 -289.666156)
			(xy 100.521157 -289.623142) (xy 100.501209 -289.576322) (xy 100.48903 -289.526908) (xy 100.484935 -289.47618)
			(xy 100.179124 -289.47618) (xy 100.178634 -289.501169) (xy 100.170815 -289.550532) (xy 100.155371 -289.598064)
			(xy 100.132681 -289.642596) (xy 100.103305 -289.683029) (xy 100.067965 -289.718369) (xy 100.027532 -289.747745)
			(xy 99.983 -289.770435) (xy 99.935468 -289.785879) (xy 99.886105 -289.793698) (xy 99.836127 -289.793698)
			(xy 99.786764 -289.785879) (xy 99.739232 -289.770435) (xy 99.6947 -289.747745) (xy 99.654267 -289.718369)
			(xy 99.618927 -289.683029) (xy 99.589551 -289.642596) (xy 99.566861 -289.598064) (xy 99.551417 -289.550532)
			(xy 99.543598 -289.501169) (xy 99.236281 -289.501169) (xy 99.236272 -289.501626) (xy 99.228108 -289.55186)
			(xy 99.211992 -289.600134) (xy 99.188341 -289.645197) (xy 99.157768 -289.685883) (xy 99.121064 -289.721138)
			(xy 99.07918 -289.750048) (xy 99.033201 -289.771865) (xy 98.984317 -289.786025) (xy 98.933796 -289.792159)
			(xy 98.882944 -289.79011) (xy 98.83308 -289.77993) (xy 98.785494 -289.761883) (xy 98.74142 -289.736437)
			(xy 98.701998 -289.70425) (xy 98.66825 -289.666156) (xy 98.641049 -289.623142) (xy 98.621101 -289.576322)
			(xy 98.608922 -289.526908) (xy 98.604827 -289.47618) (xy 98.29673 -289.47618) (xy 98.296218 -289.501626)
			(xy 98.288054 -289.55186) (xy 98.271938 -289.600134) (xy 98.248287 -289.645197) (xy 98.217714 -289.685883)
			(xy 98.18101 -289.721138) (xy 98.139126 -289.750048) (xy 98.093147 -289.771865) (xy 98.044263 -289.786025)
			(xy 97.993742 -289.792159) (xy 97.94289 -289.79011) (xy 97.893026 -289.77993) (xy 97.84544 -289.761883)
			(xy 97.801366 -289.736437) (xy 97.761944 -289.70425) (xy 97.728196 -289.666156) (xy 97.700995 -289.623142)
			(xy 97.681047 -289.576322) (xy 97.668868 -289.526908) (xy 97.664773 -289.47618) (xy 97.358962 -289.47618)
			(xy 97.358472 -289.501169) (xy 97.350653 -289.550532) (xy 97.335209 -289.598064) (xy 97.312519 -289.642596)
			(xy 97.283143 -289.683029) (xy 97.247803 -289.718369) (xy 97.20737 -289.747745) (xy 97.162838 -289.770435)
			(xy 97.115306 -289.785879) (xy 97.065943 -289.793698) (xy 97.015965 -289.793698) (xy 96.966602 -289.785879)
			(xy 96.91907 -289.770435) (xy 96.874538 -289.747745) (xy 96.834105 -289.718369) (xy 96.798765 -289.683029)
			(xy 96.769389 -289.642596) (xy 96.746699 -289.598064) (xy 96.731255 -289.550532) (xy 96.723436 -289.501169)
			(xy 96.416373 -289.501169) (xy 96.416364 -289.501626) (xy 96.4082 -289.55186) (xy 96.392084 -289.600134)
			(xy 96.368433 -289.645197) (xy 96.33786 -289.685883) (xy 96.301156 -289.721138) (xy 96.259272 -289.750048)
			(xy 96.213293 -289.771865) (xy 96.164409 -289.786025) (xy 96.113888 -289.792159) (xy 96.063036 -289.79011)
			(xy 96.013172 -289.77993) (xy 95.965586 -289.761883) (xy 95.921512 -289.736437) (xy 95.88209 -289.70425)
			(xy 95.848342 -289.666156) (xy 95.821141 -289.623142) (xy 95.801193 -289.576322) (xy 95.789014 -289.526908)
			(xy 95.784919 -289.47618) (xy 95.479108 -289.47618) (xy 95.478618 -289.501169) (xy 95.470799 -289.550532)
			(xy 95.455355 -289.598064) (xy 95.432665 -289.642596) (xy 95.403289 -289.683029) (xy 95.367949 -289.718369)
			(xy 95.327516 -289.747745) (xy 95.282984 -289.770435) (xy 95.235452 -289.785879) (xy 95.186089 -289.793698)
			(xy 95.136111 -289.793698) (xy 95.086748 -289.785879) (xy 95.039216 -289.770435) (xy 94.994684 -289.747745)
			(xy 94.954251 -289.718369) (xy 94.918911 -289.683029) (xy 94.889535 -289.642596) (xy 94.866845 -289.598064)
			(xy 94.851401 -289.550532) (xy 94.843582 -289.501169) (xy 94.536265 -289.501169) (xy 94.536256 -289.501626)
			(xy 94.528092 -289.55186) (xy 94.511976 -289.600134) (xy 94.488325 -289.645197) (xy 94.457752 -289.685883)
			(xy 94.421048 -289.721138) (xy 94.379164 -289.750048) (xy 94.333185 -289.771865) (xy 94.284301 -289.786025)
			(xy 94.23378 -289.792159) (xy 94.182928 -289.79011) (xy 94.133064 -289.77993) (xy 94.085478 -289.761883)
			(xy 94.041404 -289.736437) (xy 94.001982 -289.70425) (xy 93.968234 -289.666156) (xy 93.941033 -289.623142)
			(xy 93.921085 -289.576322) (xy 93.908906 -289.526908) (xy 93.904811 -289.47618) (xy 93.599 -289.47618)
			(xy 93.59851 -289.501169) (xy 93.590691 -289.550532) (xy 93.575247 -289.598064) (xy 93.552557 -289.642596)
			(xy 93.523181 -289.683029) (xy 93.487841 -289.718369) (xy 93.447408 -289.747745) (xy 93.402876 -289.770435)
			(xy 93.355344 -289.785879) (xy 93.305981 -289.793698) (xy 93.256003 -289.793698) (xy 93.20664 -289.785879)
			(xy 93.159108 -289.770435) (xy 93.114576 -289.747745) (xy 93.074143 -289.718369) (xy 93.038803 -289.683029)
			(xy 93.009427 -289.642596) (xy 92.986737 -289.598064) (xy 92.971293 -289.550532) (xy 92.963474 -289.501169)
			(xy 92.656157 -289.501169) (xy 92.656148 -289.501626) (xy 92.647984 -289.55186) (xy 92.631868 -289.600134)
			(xy 92.608217 -289.645197) (xy 92.577644 -289.685883) (xy 92.54094 -289.721138) (xy 92.499056 -289.750048)
			(xy 92.453077 -289.771865) (xy 92.404193 -289.786025) (xy 92.353672 -289.792159) (xy 92.30282 -289.79011)
			(xy 92.252956 -289.77993) (xy 92.20537 -289.761883) (xy 92.161296 -289.736437) (xy 92.121874 -289.70425)
			(xy 92.088126 -289.666156) (xy 92.060925 -289.623142) (xy 92.040977 -289.576322) (xy 92.028798 -289.526908)
			(xy 92.024703 -289.47618) (xy 91.861386 -289.47618) (xy 91.861386 -289.939222) (xy 91.88704 -289.967924)
			(xy 91.906598 -289.97021) (xy 91.932164 -289.973594) (xy 91.981804 -289.987559) (xy 92.02854 -290.009352)
			(xy 92.071148 -290.038401) (xy 92.10851 -290.073943) (xy 92.139647 -290.115049) (xy 92.163743 -290.160641)
			(xy 92.180167 -290.209523) (xy 92.188488 -290.260415) (xy 92.188488 -290.286186) (xy 92.494857 -290.286186)
			(xy 92.498952 -290.235458) (xy 92.511131 -290.186044) (xy 92.531079 -290.139224) (xy 92.55828 -290.09621)
			(xy 92.592028 -290.058116) (xy 92.63145 -290.025929) (xy 92.675524 -290.000483) (xy 92.72311 -289.982436)
			(xy 92.772974 -289.972256) (xy 92.823826 -289.970207) (xy 92.874347 -289.976341) (xy 92.923231 -289.990501)
			(xy 92.96921 -290.012318) (xy 93.011094 -290.041228) (xy 93.047798 -290.076483) (xy 93.078371 -290.117169)
			(xy 93.102022 -290.162232) (xy 93.118138 -290.210506) (xy 93.126302 -290.26074) (xy 93.126814 -290.286186)
			(xy 93.126311 -290.311175) (xy 93.433628 -290.311175) (xy 93.433628 -290.261197) (xy 93.441447 -290.211834)
			(xy 93.456891 -290.164302) (xy 93.479581 -290.11977) (xy 93.508957 -290.079337) (xy 93.544297 -290.043997)
			(xy 93.58473 -290.014621) (xy 93.629262 -289.991931) (xy 93.676794 -289.976487) (xy 93.726157 -289.968668)
			(xy 93.776135 -289.968668) (xy 93.825498 -289.976487) (xy 93.87303 -289.991931) (xy 93.917562 -290.014621)
			(xy 93.957995 -290.043997) (xy 93.993335 -290.079337) (xy 94.022711 -290.11977) (xy 94.045401 -290.164302)
			(xy 94.060845 -290.211834) (xy 94.068664 -290.261197) (xy 94.069154 -290.286186) (xy 94.374711 -290.286186)
			(xy 94.378806 -290.235458) (xy 94.390985 -290.186044) (xy 94.410933 -290.139224) (xy 94.438134 -290.09621)
			(xy 94.471882 -290.058116) (xy 94.511304 -290.025929) (xy 94.555378 -290.000483) (xy 94.602964 -289.982436)
			(xy 94.652828 -289.972256) (xy 94.70368 -289.970207) (xy 94.754201 -289.976341) (xy 94.803085 -289.990501)
			(xy 94.849064 -290.012318) (xy 94.890948 -290.041228) (xy 94.927652 -290.076483) (xy 94.958225 -290.117169)
			(xy 94.981876 -290.162232) (xy 94.997992 -290.210506) (xy 95.006156 -290.26074) (xy 95.006668 -290.286186)
			(xy 95.314765 -290.286186) (xy 95.31886 -290.235458) (xy 95.331039 -290.186044) (xy 95.350987 -290.139224)
			(xy 95.378188 -290.09621) (xy 95.411936 -290.058116) (xy 95.451358 -290.025929) (xy 95.495432 -290.000483)
			(xy 95.543018 -289.982436) (xy 95.592882 -289.972256) (xy 95.643734 -289.970207) (xy 95.694255 -289.976341)
			(xy 95.743139 -289.990501) (xy 95.789118 -290.012318) (xy 95.831002 -290.041228) (xy 95.867706 -290.076483)
			(xy 95.898279 -290.117169) (xy 95.92193 -290.162232) (xy 95.938046 -290.210506) (xy 95.94621 -290.26074)
			(xy 95.946722 -290.286186) (xy 95.946219 -290.311175) (xy 96.253536 -290.311175) (xy 96.253536 -290.261197)
			(xy 96.261355 -290.211834) (xy 96.276799 -290.164302) (xy 96.299489 -290.11977) (xy 96.328865 -290.079337)
			(xy 96.364205 -290.043997) (xy 96.404638 -290.014621) (xy 96.44917 -289.991931) (xy 96.496702 -289.976487)
			(xy 96.546065 -289.968668) (xy 96.596043 -289.968668) (xy 96.645406 -289.976487) (xy 96.692938 -289.991931)
			(xy 96.73747 -290.014621) (xy 96.777903 -290.043997) (xy 96.813243 -290.079337) (xy 96.842619 -290.11977)
			(xy 96.865309 -290.164302) (xy 96.880753 -290.211834) (xy 96.888572 -290.261197) (xy 96.889062 -290.286186)
			(xy 96.888572 -290.311175) (xy 99.073444 -290.311175) (xy 99.073444 -290.261197) (xy 99.081263 -290.211834)
			(xy 99.096707 -290.164302) (xy 99.119397 -290.11977) (xy 99.148773 -290.079337) (xy 99.184113 -290.043997)
			(xy 99.224546 -290.014621) (xy 99.269078 -289.991931) (xy 99.31661 -289.976487) (xy 99.365973 -289.968668)
			(xy 99.415951 -289.968668) (xy 99.465314 -289.976487) (xy 99.512846 -289.991931) (xy 99.557378 -290.014621)
			(xy 99.597811 -290.043997) (xy 99.633151 -290.079337) (xy 99.662527 -290.11977) (xy 99.685217 -290.164302)
			(xy 99.700661 -290.211834) (xy 99.70848 -290.261197) (xy 99.70897 -290.286186) (xy 99.70848 -290.311175)
			(xy 101.893606 -290.311175) (xy 101.893606 -290.261197) (xy 101.901425 -290.211834) (xy 101.916869 -290.164302)
			(xy 101.939559 -290.11977) (xy 101.968935 -290.079337) (xy 102.004275 -290.043997) (xy 102.044708 -290.014621)
			(xy 102.08924 -289.991931) (xy 102.136772 -289.976487) (xy 102.186135 -289.968668) (xy 102.236113 -289.968668)
			(xy 102.285476 -289.976487) (xy 102.333008 -289.991931) (xy 102.37754 -290.014621) (xy 102.417973 -290.043997)
			(xy 102.453313 -290.079337) (xy 102.482689 -290.11977) (xy 102.505379 -290.164302) (xy 102.520823 -290.211834)
			(xy 102.528642 -290.261197) (xy 102.529132 -290.286186) (xy 102.528642 -290.311175) (xy 104.713514 -290.311175)
			(xy 104.713514 -290.261197) (xy 104.721333 -290.211834) (xy 104.736777 -290.164302) (xy 104.759467 -290.11977)
			(xy 104.788843 -290.079337) (xy 104.824183 -290.043997) (xy 104.864616 -290.014621) (xy 104.909148 -289.991931)
			(xy 104.95668 -289.976487) (xy 105.006043 -289.968668) (xy 105.056021 -289.968668) (xy 105.105384 -289.976487)
			(xy 105.152916 -289.991931) (xy 105.197448 -290.014621) (xy 105.237881 -290.043997) (xy 105.273221 -290.079337)
			(xy 105.302597 -290.11977) (xy 105.325287 -290.164302) (xy 105.340731 -290.211834) (xy 105.34855 -290.261197)
			(xy 105.34904 -290.286186) (xy 105.34855 -290.311175) (xy 107.533422 -290.311175) (xy 107.533422 -290.261197)
			(xy 107.541241 -290.211834) (xy 107.556685 -290.164302) (xy 107.579375 -290.11977) (xy 107.608751 -290.079337)
			(xy 107.644091 -290.043997) (xy 107.684524 -290.014621) (xy 107.729056 -289.991931) (xy 107.776588 -289.976487)
			(xy 107.825951 -289.968668) (xy 107.875929 -289.968668) (xy 107.925292 -289.976487) (xy 107.972824 -289.991931)
			(xy 108.017356 -290.014621) (xy 108.057789 -290.043997) (xy 108.093129 -290.079337) (xy 108.122505 -290.11977)
			(xy 108.145195 -290.164302) (xy 108.160639 -290.211834) (xy 108.168458 -290.261197) (xy 108.168948 -290.286186)
			(xy 108.474759 -290.286186) (xy 108.478854 -290.235458) (xy 108.491033 -290.186044) (xy 108.510981 -290.139224)
			(xy 108.538182 -290.09621) (xy 108.57193 -290.058116) (xy 108.611352 -290.025929) (xy 108.655426 -290.000483)
			(xy 108.703012 -289.982436) (xy 108.752876 -289.972256) (xy 108.803728 -289.970207) (xy 108.854249 -289.976341)
			(xy 108.903133 -289.990501) (xy 108.949112 -290.012318) (xy 108.990996 -290.041228) (xy 109.0277 -290.076483)
			(xy 109.058273 -290.117169) (xy 109.081924 -290.162232) (xy 109.09804 -290.210506) (xy 109.106204 -290.26074)
			(xy 109.106716 -290.286186) (xy 109.414813 -290.286186) (xy 109.418908 -290.235458) (xy 109.431087 -290.186044)
			(xy 109.451035 -290.139224) (xy 109.478236 -290.09621) (xy 109.511984 -290.058116) (xy 109.551406 -290.025929)
			(xy 109.59548 -290.000483) (xy 109.643066 -289.982436) (xy 109.69293 -289.972256) (xy 109.743782 -289.970207)
			(xy 109.794303 -289.976341) (xy 109.843187 -289.990501) (xy 109.889166 -290.012318) (xy 109.93105 -290.041228)
			(xy 109.967754 -290.076483) (xy 109.998327 -290.117169) (xy 110.021978 -290.162232) (xy 110.038094 -290.210506)
			(xy 110.046258 -290.26074) (xy 110.04677 -290.286186) (xy 110.046267 -290.311175) (xy 110.353584 -290.311175)
			(xy 110.353584 -290.261197) (xy 110.361403 -290.211834) (xy 110.376847 -290.164302) (xy 110.399537 -290.11977)
			(xy 110.428913 -290.079337) (xy 110.464253 -290.043997) (xy 110.504686 -290.014621) (xy 110.549218 -289.991931)
			(xy 110.59675 -289.976487) (xy 110.646113 -289.968668) (xy 110.696091 -289.968668) (xy 110.745454 -289.976487)
			(xy 110.792986 -289.991931) (xy 110.837518 -290.014621) (xy 110.877951 -290.043997) (xy 110.913291 -290.079337)
			(xy 110.942667 -290.11977) (xy 110.965357 -290.164302) (xy 110.980801 -290.211834) (xy 110.98862 -290.261197)
			(xy 110.98911 -290.286186) (xy 110.98862 -290.311175) (xy 113.167142 -290.311175) (xy 113.167142 -290.261197)
			(xy 113.174961 -290.211834) (xy 113.190405 -290.164302) (xy 113.213095 -290.11977) (xy 113.242471 -290.079337)
			(xy 113.277811 -290.043997) (xy 113.318244 -290.014621) (xy 113.362776 -289.991931) (xy 113.410308 -289.976487)
			(xy 113.459671 -289.968668) (xy 113.509649 -289.968668) (xy 113.559012 -289.976487) (xy 113.606544 -289.991931)
			(xy 113.651076 -290.014621) (xy 113.691509 -290.043997) (xy 113.726849 -290.079337) (xy 113.756225 -290.11977)
			(xy 113.778915 -290.164302) (xy 113.794359 -290.211834) (xy 113.802178 -290.261197) (xy 113.802668 -290.286186)
			(xy 114.108479 -290.286186) (xy 114.112574 -290.235458) (xy 114.124753 -290.186044) (xy 114.144701 -290.139224)
			(xy 114.171902 -290.09621) (xy 114.20565 -290.058116) (xy 114.245072 -290.025929) (xy 114.289146 -290.000483)
			(xy 114.336732 -289.982436) (xy 114.386596 -289.972256) (xy 114.437448 -289.970207) (xy 114.487969 -289.976341)
			(xy 114.536853 -289.990501) (xy 114.582832 -290.012318) (xy 114.624716 -290.041228) (xy 114.66142 -290.076483)
			(xy 114.691993 -290.117169) (xy 114.715644 -290.162232) (xy 114.73176 -290.210506) (xy 114.739924 -290.26074)
			(xy 114.740436 -290.286186) (xy 115.048533 -290.286186) (xy 115.052628 -290.235458) (xy 115.064807 -290.186044)
			(xy 115.084755 -290.139224) (xy 115.111956 -290.09621) (xy 115.145704 -290.058116) (xy 115.185126 -290.025929)
			(xy 115.2292 -290.000483) (xy 115.276786 -289.982436) (xy 115.32665 -289.972256) (xy 115.377502 -289.970207)
			(xy 115.428023 -289.976341) (xy 115.476907 -289.990501) (xy 115.522886 -290.012318) (xy 115.56477 -290.041228)
			(xy 115.601474 -290.076483) (xy 115.632047 -290.117169) (xy 115.655698 -290.162232) (xy 115.671814 -290.210506)
			(xy 115.679978 -290.26074) (xy 115.68049 -290.286186) (xy 115.679987 -290.311175) (xy 115.987304 -290.311175)
			(xy 115.987304 -290.261197) (xy 115.995123 -290.211834) (xy 116.010567 -290.164302) (xy 116.033257 -290.11977)
			(xy 116.062633 -290.079337) (xy 116.097973 -290.043997) (xy 116.138406 -290.014621) (xy 116.182938 -289.991931)
			(xy 116.23047 -289.976487) (xy 116.279833 -289.968668) (xy 116.329811 -289.968668) (xy 116.379174 -289.976487)
			(xy 116.426706 -289.991931) (xy 116.471238 -290.014621) (xy 116.511671 -290.043997) (xy 116.547011 -290.079337)
			(xy 116.576387 -290.11977) (xy 116.599077 -290.164302) (xy 116.614521 -290.211834) (xy 116.62234 -290.261197)
			(xy 116.62283 -290.286186) (xy 116.62234 -290.311175) (xy 118.807212 -290.311175) (xy 118.807212 -290.261197)
			(xy 118.815031 -290.211834) (xy 118.830475 -290.164302) (xy 118.853165 -290.11977) (xy 118.882541 -290.079337)
			(xy 118.917881 -290.043997) (xy 118.958314 -290.014621) (xy 119.002846 -289.991931) (xy 119.050378 -289.976487)
			(xy 119.099741 -289.968668) (xy 119.149719 -289.968668) (xy 119.199082 -289.976487) (xy 119.246614 -289.991931)
			(xy 119.291146 -290.014621) (xy 119.331579 -290.043997) (xy 119.366919 -290.079337) (xy 119.396295 -290.11977)
			(xy 119.418985 -290.164302) (xy 119.434429 -290.211834) (xy 119.442248 -290.261197) (xy 119.442738 -290.286186)
			(xy 119.442248 -290.311175) (xy 121.62712 -290.311175) (xy 121.62712 -290.261197) (xy 121.634939 -290.211834)
			(xy 121.650383 -290.164302) (xy 121.673073 -290.11977) (xy 121.702449 -290.079337) (xy 121.737789 -290.043997)
			(xy 121.778222 -290.014621) (xy 121.822754 -289.991931) (xy 121.870286 -289.976487) (xy 121.919649 -289.968668)
			(xy 121.969627 -289.968668) (xy 122.01899 -289.976487) (xy 122.066522 -289.991931) (xy 122.111054 -290.014621)
			(xy 122.151487 -290.043997) (xy 122.186827 -290.079337) (xy 122.216203 -290.11977) (xy 122.238893 -290.164302)
			(xy 122.254337 -290.211834) (xy 122.262156 -290.261197) (xy 122.262646 -290.286186) (xy 122.262156 -290.311175)
			(xy 124.447282 -290.311175) (xy 124.447282 -290.261197) (xy 124.455101 -290.211834) (xy 124.470545 -290.164302)
			(xy 124.493235 -290.11977) (xy 124.522611 -290.079337) (xy 124.557951 -290.043997) (xy 124.598384 -290.014621)
			(xy 124.642916 -289.991931) (xy 124.690448 -289.976487) (xy 124.739811 -289.968668) (xy 124.789789 -289.968668)
			(xy 124.839152 -289.976487) (xy 124.886684 -289.991931) (xy 124.931216 -290.014621) (xy 124.971649 -290.043997)
			(xy 125.006989 -290.079337) (xy 125.036365 -290.11977) (xy 125.059055 -290.164302) (xy 125.074499 -290.211834)
			(xy 125.082318 -290.261197) (xy 125.082808 -290.286186) (xy 125.082318 -290.311175) (xy 125.074499 -290.360538)
			(xy 125.059055 -290.40807) (xy 125.036365 -290.452602) (xy 125.006989 -290.493035) (xy 124.971649 -290.528375)
			(xy 124.931216 -290.557751) (xy 124.886684 -290.580441) (xy 124.839152 -290.595885) (xy 124.789789 -290.603704)
			(xy 124.739811 -290.603704) (xy 124.690448 -290.595885) (xy 124.642916 -290.580441) (xy 124.598384 -290.557751)
			(xy 124.557951 -290.528375) (xy 124.522611 -290.493035) (xy 124.493235 -290.452602) (xy 124.470545 -290.40807)
			(xy 124.455101 -290.360538) (xy 124.447282 -290.311175) (xy 122.262156 -290.311175) (xy 122.254337 -290.360538)
			(xy 122.238893 -290.40807) (xy 122.216203 -290.452602) (xy 122.186827 -290.493035) (xy 122.151487 -290.528375)
			(xy 122.111054 -290.557751) (xy 122.066522 -290.580441) (xy 122.01899 -290.595885) (xy 121.969627 -290.603704)
			(xy 121.919649 -290.603704) (xy 121.870286 -290.595885) (xy 121.822754 -290.580441) (xy 121.778222 -290.557751)
			(xy 121.737789 -290.528375) (xy 121.702449 -290.493035) (xy 121.673073 -290.452602) (xy 121.650383 -290.40807)
			(xy 121.634939 -290.360538) (xy 121.62712 -290.311175) (xy 119.442248 -290.311175) (xy 119.434429 -290.360538)
			(xy 119.418985 -290.40807) (xy 119.396295 -290.452602) (xy 119.366919 -290.493035) (xy 119.331579 -290.528375)
			(xy 119.291146 -290.557751) (xy 119.246614 -290.580441) (xy 119.199082 -290.595885) (xy 119.149719 -290.603704)
			(xy 119.099741 -290.603704) (xy 119.050378 -290.595885) (xy 119.002846 -290.580441) (xy 118.958314 -290.557751)
			(xy 118.917881 -290.528375) (xy 118.882541 -290.493035) (xy 118.853165 -290.452602) (xy 118.830475 -290.40807)
			(xy 118.815031 -290.360538) (xy 118.807212 -290.311175) (xy 116.62234 -290.311175) (xy 116.614521 -290.360538)
			(xy 116.599077 -290.40807) (xy 116.576387 -290.452602) (xy 116.547011 -290.493035) (xy 116.511671 -290.528375)
			(xy 116.471238 -290.557751) (xy 116.426706 -290.580441) (xy 116.379174 -290.595885) (xy 116.329811 -290.603704)
			(xy 116.279833 -290.603704) (xy 116.23047 -290.595885) (xy 116.182938 -290.580441) (xy 116.138406 -290.557751)
			(xy 116.097973 -290.528375) (xy 116.062633 -290.493035) (xy 116.033257 -290.452602) (xy 116.010567 -290.40807)
			(xy 115.995123 -290.360538) (xy 115.987304 -290.311175) (xy 115.679987 -290.311175) (xy 115.679978 -290.311632)
			(xy 115.671814 -290.361866) (xy 115.655698 -290.41014) (xy 115.632047 -290.455203) (xy 115.601474 -290.495889)
			(xy 115.56477 -290.531144) (xy 115.522886 -290.560054) (xy 115.476907 -290.581871) (xy 115.428023 -290.596031)
			(xy 115.377502 -290.602165) (xy 115.32665 -290.600116) (xy 115.276786 -290.589936) (xy 115.2292 -290.571889)
			(xy 115.185126 -290.546443) (xy 115.145704 -290.514256) (xy 115.111956 -290.476162) (xy 115.084755 -290.433148)
			(xy 115.064807 -290.386328) (xy 115.052628 -290.336914) (xy 115.048533 -290.286186) (xy 114.740436 -290.286186)
			(xy 114.739924 -290.311632) (xy 114.73176 -290.361866) (xy 114.715644 -290.41014) (xy 114.691993 -290.455203)
			(xy 114.66142 -290.495889) (xy 114.624716 -290.531144) (xy 114.582832 -290.560054) (xy 114.536853 -290.581871)
			(xy 114.487969 -290.596031) (xy 114.437448 -290.602165) (xy 114.386596 -290.600116) (xy 114.336732 -290.589936)
			(xy 114.289146 -290.571889) (xy 114.245072 -290.546443) (xy 114.20565 -290.514256) (xy 114.171902 -290.476162)
			(xy 114.144701 -290.433148) (xy 114.124753 -290.386328) (xy 114.112574 -290.336914) (xy 114.108479 -290.286186)
			(xy 113.802668 -290.286186) (xy 113.802178 -290.311175) (xy 113.794359 -290.360538) (xy 113.778915 -290.40807)
			(xy 113.756225 -290.452602) (xy 113.726849 -290.493035) (xy 113.691509 -290.528375) (xy 113.651076 -290.557751)
			(xy 113.606544 -290.580441) (xy 113.559012 -290.595885) (xy 113.509649 -290.603704) (xy 113.459671 -290.603704)
			(xy 113.410308 -290.595885) (xy 113.362776 -290.580441) (xy 113.318244 -290.557751) (xy 113.277811 -290.528375)
			(xy 113.242471 -290.493035) (xy 113.213095 -290.452602) (xy 113.190405 -290.40807) (xy 113.174961 -290.360538)
			(xy 113.167142 -290.311175) (xy 110.98862 -290.311175) (xy 110.980801 -290.360538) (xy 110.965357 -290.40807)
			(xy 110.942667 -290.452602) (xy 110.913291 -290.493035) (xy 110.877951 -290.528375) (xy 110.837518 -290.557751)
			(xy 110.792986 -290.580441) (xy 110.745454 -290.595885) (xy 110.696091 -290.603704) (xy 110.646113 -290.603704)
			(xy 110.59675 -290.595885) (xy 110.549218 -290.580441) (xy 110.504686 -290.557751) (xy 110.464253 -290.528375)
			(xy 110.428913 -290.493035) (xy 110.399537 -290.452602) (xy 110.376847 -290.40807) (xy 110.361403 -290.360538)
			(xy 110.353584 -290.311175) (xy 110.046267 -290.311175) (xy 110.046258 -290.311632) (xy 110.038094 -290.361866)
			(xy 110.021978 -290.41014) (xy 109.998327 -290.455203) (xy 109.967754 -290.495889) (xy 109.93105 -290.531144)
			(xy 109.889166 -290.560054) (xy 109.843187 -290.581871) (xy 109.794303 -290.596031) (xy 109.743782 -290.602165)
			(xy 109.69293 -290.600116) (xy 109.643066 -290.589936) (xy 109.59548 -290.571889) (xy 109.551406 -290.546443)
			(xy 109.511984 -290.514256) (xy 109.478236 -290.476162) (xy 109.451035 -290.433148) (xy 109.431087 -290.386328)
			(xy 109.418908 -290.336914) (xy 109.414813 -290.286186) (xy 109.106716 -290.286186) (xy 109.106204 -290.311632)
			(xy 109.09804 -290.361866) (xy 109.081924 -290.41014) (xy 109.058273 -290.455203) (xy 109.0277 -290.495889)
			(xy 108.990996 -290.531144) (xy 108.949112 -290.560054) (xy 108.903133 -290.581871) (xy 108.854249 -290.596031)
			(xy 108.803728 -290.602165) (xy 108.752876 -290.600116) (xy 108.703012 -290.589936) (xy 108.655426 -290.571889)
			(xy 108.611352 -290.546443) (xy 108.57193 -290.514256) (xy 108.538182 -290.476162) (xy 108.510981 -290.433148)
			(xy 108.491033 -290.386328) (xy 108.478854 -290.336914) (xy 108.474759 -290.286186) (xy 108.168948 -290.286186)
			(xy 108.168458 -290.311175) (xy 108.160639 -290.360538) (xy 108.145195 -290.40807) (xy 108.122505 -290.452602)
			(xy 108.093129 -290.493035) (xy 108.057789 -290.528375) (xy 108.017356 -290.557751) (xy 107.972824 -290.580441)
			(xy 107.925292 -290.595885) (xy 107.875929 -290.603704) (xy 107.825951 -290.603704) (xy 107.776588 -290.595885)
			(xy 107.729056 -290.580441) (xy 107.684524 -290.557751) (xy 107.644091 -290.528375) (xy 107.608751 -290.493035)
			(xy 107.579375 -290.452602) (xy 107.556685 -290.40807) (xy 107.541241 -290.360538) (xy 107.533422 -290.311175)
			(xy 105.34855 -290.311175) (xy 105.340731 -290.360538) (xy 105.325287 -290.40807) (xy 105.302597 -290.452602)
			(xy 105.273221 -290.493035) (xy 105.237881 -290.528375) (xy 105.197448 -290.557751) (xy 105.152916 -290.580441)
			(xy 105.105384 -290.595885) (xy 105.056021 -290.603704) (xy 105.006043 -290.603704) (xy 104.95668 -290.595885)
			(xy 104.909148 -290.580441) (xy 104.864616 -290.557751) (xy 104.824183 -290.528375) (xy 104.788843 -290.493035)
			(xy 104.759467 -290.452602) (xy 104.736777 -290.40807) (xy 104.721333 -290.360538) (xy 104.713514 -290.311175)
			(xy 102.528642 -290.311175) (xy 102.520823 -290.360538) (xy 102.505379 -290.40807) (xy 102.482689 -290.452602)
			(xy 102.453313 -290.493035) (xy 102.417973 -290.528375) (xy 102.37754 -290.557751) (xy 102.333008 -290.580441)
			(xy 102.285476 -290.595885) (xy 102.236113 -290.603704) (xy 102.186135 -290.603704) (xy 102.136772 -290.595885)
			(xy 102.08924 -290.580441) (xy 102.044708 -290.557751) (xy 102.004275 -290.528375) (xy 101.968935 -290.493035)
			(xy 101.939559 -290.452602) (xy 101.916869 -290.40807) (xy 101.901425 -290.360538) (xy 101.893606 -290.311175)
			(xy 99.70848 -290.311175) (xy 99.700661 -290.360538) (xy 99.685217 -290.40807) (xy 99.662527 -290.452602)
			(xy 99.633151 -290.493035) (xy 99.597811 -290.528375) (xy 99.557378 -290.557751) (xy 99.512846 -290.580441)
			(xy 99.465314 -290.595885) (xy 99.415951 -290.603704) (xy 99.365973 -290.603704) (xy 99.31661 -290.595885)
			(xy 99.269078 -290.580441) (xy 99.224546 -290.557751) (xy 99.184113 -290.528375) (xy 99.148773 -290.493035)
			(xy 99.119397 -290.452602) (xy 99.096707 -290.40807) (xy 99.081263 -290.360538) (xy 99.073444 -290.311175)
			(xy 96.888572 -290.311175) (xy 96.880753 -290.360538) (xy 96.865309 -290.40807) (xy 96.842619 -290.452602)
			(xy 96.813243 -290.493035) (xy 96.777903 -290.528375) (xy 96.73747 -290.557751) (xy 96.692938 -290.580441)
			(xy 96.645406 -290.595885) (xy 96.596043 -290.603704) (xy 96.546065 -290.603704) (xy 96.496702 -290.595885)
			(xy 96.44917 -290.580441) (xy 96.404638 -290.557751) (xy 96.364205 -290.528375) (xy 96.328865 -290.493035)
			(xy 96.299489 -290.452602) (xy 96.276799 -290.40807) (xy 96.261355 -290.360538) (xy 96.253536 -290.311175)
			(xy 95.946219 -290.311175) (xy 95.94621 -290.311632) (xy 95.938046 -290.361866) (xy 95.92193 -290.41014)
			(xy 95.898279 -290.455203) (xy 95.867706 -290.495889) (xy 95.831002 -290.531144) (xy 95.789118 -290.560054)
			(xy 95.743139 -290.581871) (xy 95.694255 -290.596031) (xy 95.643734 -290.602165) (xy 95.592882 -290.600116)
			(xy 95.543018 -290.589936) (xy 95.495432 -290.571889) (xy 95.451358 -290.546443) (xy 95.411936 -290.514256)
			(xy 95.378188 -290.476162) (xy 95.350987 -290.433148) (xy 95.331039 -290.386328) (xy 95.31886 -290.336914)
			(xy 95.314765 -290.286186) (xy 95.006668 -290.286186) (xy 95.006156 -290.311632) (xy 94.997992 -290.361866)
			(xy 94.981876 -290.41014) (xy 94.958225 -290.455203) (xy 94.927652 -290.495889) (xy 94.890948 -290.531144)
			(xy 94.849064 -290.560054) (xy 94.803085 -290.581871) (xy 94.754201 -290.596031) (xy 94.70368 -290.602165)
			(xy 94.652828 -290.600116) (xy 94.602964 -290.589936) (xy 94.555378 -290.571889) (xy 94.511304 -290.546443)
			(xy 94.471882 -290.514256) (xy 94.438134 -290.476162) (xy 94.410933 -290.433148) (xy 94.390985 -290.386328)
			(xy 94.378806 -290.336914) (xy 94.374711 -290.286186) (xy 94.069154 -290.286186) (xy 94.068664 -290.311175)
			(xy 94.060845 -290.360538) (xy 94.045401 -290.40807) (xy 94.022711 -290.452602) (xy 93.993335 -290.493035)
			(xy 93.957995 -290.528375) (xy 93.917562 -290.557751) (xy 93.87303 -290.580441) (xy 93.825498 -290.595885)
			(xy 93.776135 -290.603704) (xy 93.726157 -290.603704) (xy 93.676794 -290.595885) (xy 93.629262 -290.580441)
			(xy 93.58473 -290.557751) (xy 93.544297 -290.528375) (xy 93.508957 -290.493035) (xy 93.479581 -290.452602)
			(xy 93.456891 -290.40807) (xy 93.441447 -290.360538) (xy 93.433628 -290.311175) (xy 93.126311 -290.311175)
			(xy 93.126302 -290.311632) (xy 93.118138 -290.361866) (xy 93.102022 -290.41014) (xy 93.078371 -290.455203)
			(xy 93.047798 -290.495889) (xy 93.011094 -290.531144) (xy 92.96921 -290.560054) (xy 92.923231 -290.581871)
			(xy 92.874347 -290.596031) (xy 92.823826 -290.602165) (xy 92.772974 -290.600116) (xy 92.72311 -290.589936)
			(xy 92.675524 -290.571889) (xy 92.63145 -290.546443) (xy 92.592028 -290.514256) (xy 92.55828 -290.476162)
			(xy 92.531079 -290.433148) (xy 92.511131 -290.386328) (xy 92.498952 -290.336914) (xy 92.494857 -290.286186)
			(xy 92.188488 -290.286186) (xy 92.188489 -290.311982) (xy 92.180168 -290.362874) (xy 92.163745 -290.411756)
			(xy 92.139649 -290.457348) (xy 92.108512 -290.498454) (xy 92.07115 -290.533998) (xy 92.028543 -290.563046)
			(xy 91.981807 -290.58484) (xy 91.932167 -290.598806) (xy 91.906598 -290.602162) (xy 91.88704 -290.604448)
			(xy 91.861386 -290.63315) (xy 91.861386 -291.096192) (xy 92.024703 -291.096192) (xy 92.028798 -291.045464)
			(xy 92.040977 -290.99605) (xy 92.060925 -290.94923) (xy 92.088126 -290.906216) (xy 92.121874 -290.868122)
			(xy 92.161296 -290.835935) (xy 92.20537 -290.810489) (xy 92.252956 -290.792442) (xy 92.30282 -290.782262)
			(xy 92.353672 -290.780213) (xy 92.404193 -290.786347) (xy 92.453077 -290.800507) (xy 92.499056 -290.822324)
			(xy 92.54094 -290.851234) (xy 92.577644 -290.886489) (xy 92.608217 -290.927175) (xy 92.631868 -290.972238)
			(xy 92.647984 -291.020512) (xy 92.656148 -291.070746) (xy 92.65666 -291.096192) (xy 92.656157 -291.121181)
			(xy 92.963474 -291.121181) (xy 92.963474 -291.071203) (xy 92.971293 -291.02184) (xy 92.986737 -290.974308)
			(xy 93.009427 -290.929776) (xy 93.038803 -290.889343) (xy 93.074143 -290.854003) (xy 93.114576 -290.824627)
			(xy 93.159108 -290.801937) (xy 93.20664 -290.786493) (xy 93.256003 -290.778674) (xy 93.305981 -290.778674)
			(xy 93.355344 -290.786493) (xy 93.402876 -290.801937) (xy 93.447408 -290.824627) (xy 93.487841 -290.854003)
			(xy 93.523181 -290.889343) (xy 93.552557 -290.929776) (xy 93.575247 -290.974308) (xy 93.590691 -291.02184)
			(xy 93.59851 -291.071203) (xy 93.599 -291.096192) (xy 93.904811 -291.096192) (xy 93.908906 -291.045464)
			(xy 93.921085 -290.99605) (xy 93.941033 -290.94923) (xy 93.968234 -290.906216) (xy 94.001982 -290.868122)
			(xy 94.041404 -290.835935) (xy 94.085478 -290.810489) (xy 94.133064 -290.792442) (xy 94.182928 -290.782262)
			(xy 94.23378 -290.780213) (xy 94.284301 -290.786347) (xy 94.333185 -290.800507) (xy 94.379164 -290.822324)
			(xy 94.421048 -290.851234) (xy 94.457752 -290.886489) (xy 94.488325 -290.927175) (xy 94.511976 -290.972238)
			(xy 94.528092 -291.020512) (xy 94.536256 -291.070746) (xy 94.536768 -291.096192) (xy 94.536265 -291.121181)
			(xy 94.843582 -291.121181) (xy 94.843582 -291.071203) (xy 94.851401 -291.02184) (xy 94.866845 -290.974308)
			(xy 94.889535 -290.929776) (xy 94.918911 -290.889343) (xy 94.954251 -290.854003) (xy 94.994684 -290.824627)
			(xy 95.039216 -290.801937) (xy 95.086748 -290.786493) (xy 95.136111 -290.778674) (xy 95.186089 -290.778674)
			(xy 95.235452 -290.786493) (xy 95.282984 -290.801937) (xy 95.327516 -290.824627) (xy 95.367949 -290.854003)
			(xy 95.403289 -290.889343) (xy 95.432665 -290.929776) (xy 95.455355 -290.974308) (xy 95.470799 -291.02184)
			(xy 95.478618 -291.071203) (xy 95.479108 -291.096192) (xy 95.784919 -291.096192) (xy 95.789014 -291.045464)
			(xy 95.801193 -290.99605) (xy 95.821141 -290.94923) (xy 95.848342 -290.906216) (xy 95.88209 -290.868122)
			(xy 95.921512 -290.835935) (xy 95.965586 -290.810489) (xy 96.013172 -290.792442) (xy 96.063036 -290.782262)
			(xy 96.113888 -290.780213) (xy 96.164409 -290.786347) (xy 96.213293 -290.800507) (xy 96.259272 -290.822324)
			(xy 96.301156 -290.851234) (xy 96.33786 -290.886489) (xy 96.368433 -290.927175) (xy 96.392084 -290.972238)
			(xy 96.4082 -291.020512) (xy 96.416364 -291.070746) (xy 96.416876 -291.096192) (xy 96.416373 -291.121181)
			(xy 96.723436 -291.121181) (xy 96.723436 -291.071203) (xy 96.731255 -291.02184) (xy 96.746699 -290.974308)
			(xy 96.769389 -290.929776) (xy 96.798765 -290.889343) (xy 96.834105 -290.854003) (xy 96.874538 -290.824627)
			(xy 96.91907 -290.801937) (xy 96.966602 -290.786493) (xy 97.015965 -290.778674) (xy 97.065943 -290.778674)
			(xy 97.115306 -290.786493) (xy 97.162838 -290.801937) (xy 97.20737 -290.824627) (xy 97.247803 -290.854003)
			(xy 97.283143 -290.889343) (xy 97.312519 -290.929776) (xy 97.335209 -290.974308) (xy 97.350653 -291.02184)
			(xy 97.358472 -291.071203) (xy 97.358962 -291.096192) (xy 97.664773 -291.096192) (xy 97.668868 -291.045464)
			(xy 97.681047 -290.99605) (xy 97.700995 -290.94923) (xy 97.728196 -290.906216) (xy 97.761944 -290.868122)
			(xy 97.801366 -290.835935) (xy 97.84544 -290.810489) (xy 97.893026 -290.792442) (xy 97.94289 -290.782262)
			(xy 97.993742 -290.780213) (xy 98.044263 -290.786347) (xy 98.093147 -290.800507) (xy 98.139126 -290.822324)
			(xy 98.18101 -290.851234) (xy 98.217714 -290.886489) (xy 98.248287 -290.927175) (xy 98.271938 -290.972238)
			(xy 98.288054 -291.020512) (xy 98.296218 -291.070746) (xy 98.29673 -291.096192) (xy 98.604827 -291.096192)
			(xy 98.608922 -291.045464) (xy 98.621101 -290.99605) (xy 98.641049 -290.94923) (xy 98.66825 -290.906216)
			(xy 98.701998 -290.868122) (xy 98.74142 -290.835935) (xy 98.785494 -290.810489) (xy 98.83308 -290.792442)
			(xy 98.882944 -290.782262) (xy 98.933796 -290.780213) (xy 98.984317 -290.786347) (xy 99.033201 -290.800507)
			(xy 99.07918 -290.822324) (xy 99.121064 -290.851234) (xy 99.157768 -290.886489) (xy 99.188341 -290.927175)
			(xy 99.211992 -290.972238) (xy 99.228108 -291.020512) (xy 99.236272 -291.070746) (xy 99.236784 -291.096192)
			(xy 99.236281 -291.121181) (xy 99.543598 -291.121181) (xy 99.543598 -291.071203) (xy 99.551417 -291.02184)
			(xy 99.566861 -290.974308) (xy 99.589551 -290.929776) (xy 99.618927 -290.889343) (xy 99.654267 -290.854003)
			(xy 99.6947 -290.824627) (xy 99.739232 -290.801937) (xy 99.786764 -290.786493) (xy 99.836127 -290.778674)
			(xy 99.886105 -290.778674) (xy 99.935468 -290.786493) (xy 99.983 -290.801937) (xy 100.027532 -290.824627)
			(xy 100.067965 -290.854003) (xy 100.103305 -290.889343) (xy 100.132681 -290.929776) (xy 100.155371 -290.974308)
			(xy 100.170815 -291.02184) (xy 100.178634 -291.071203) (xy 100.179124 -291.096192) (xy 100.484935 -291.096192)
			(xy 100.48903 -291.045464) (xy 100.501209 -290.99605) (xy 100.521157 -290.94923) (xy 100.548358 -290.906216)
			(xy 100.582106 -290.868122) (xy 100.621528 -290.835935) (xy 100.665602 -290.810489) (xy 100.713188 -290.792442)
			(xy 100.763052 -290.782262) (xy 100.813904 -290.780213) (xy 100.864425 -290.786347) (xy 100.913309 -290.800507)
			(xy 100.959288 -290.822324) (xy 101.001172 -290.851234) (xy 101.037876 -290.886489) (xy 101.068449 -290.927175)
			(xy 101.0921 -290.972238) (xy 101.108216 -291.020512) (xy 101.11638 -291.070746) (xy 101.116892 -291.096192)
			(xy 101.424735 -291.096192) (xy 101.42883 -291.045464) (xy 101.441009 -290.99605) (xy 101.460957 -290.94923)
			(xy 101.488158 -290.906216) (xy 101.521906 -290.868122) (xy 101.561328 -290.835935) (xy 101.605402 -290.810489)
			(xy 101.652988 -290.792442) (xy 101.702852 -290.782262) (xy 101.753704 -290.780213) (xy 101.804225 -290.786347)
			(xy 101.853109 -290.800507) (xy 101.899088 -290.822324) (xy 101.940972 -290.851234) (xy 101.977676 -290.886489)
			(xy 102.008249 -290.927175) (xy 102.0319 -290.972238) (xy 102.048016 -291.020512) (xy 102.05618 -291.070746)
			(xy 102.056692 -291.096192) (xy 102.056189 -291.121181) (xy 102.363506 -291.121181) (xy 102.363506 -291.071203)
			(xy 102.371325 -291.02184) (xy 102.386769 -290.974308) (xy 102.409459 -290.929776) (xy 102.438835 -290.889343)
			(xy 102.474175 -290.854003) (xy 102.514608 -290.824627) (xy 102.55914 -290.801937) (xy 102.606672 -290.786493)
			(xy 102.656035 -290.778674) (xy 102.706013 -290.778674) (xy 102.755376 -290.786493) (xy 102.802908 -290.801937)
			(xy 102.84744 -290.824627) (xy 102.887873 -290.854003) (xy 102.923213 -290.889343) (xy 102.952589 -290.929776)
			(xy 102.975279 -290.974308) (xy 102.990723 -291.02184) (xy 102.998542 -291.071203) (xy 102.999032 -291.096192)
			(xy 103.304843 -291.096192) (xy 103.308938 -291.045464) (xy 103.321117 -290.99605) (xy 103.341065 -290.94923)
			(xy 103.368266 -290.906216) (xy 103.402014 -290.868122) (xy 103.441436 -290.835935) (xy 103.48551 -290.810489)
			(xy 103.533096 -290.792442) (xy 103.58296 -290.782262) (xy 103.633812 -290.780213) (xy 103.684333 -290.786347)
			(xy 103.733217 -290.800507) (xy 103.779196 -290.822324) (xy 103.82108 -290.851234) (xy 103.857784 -290.886489)
			(xy 103.888357 -290.927175) (xy 103.912008 -290.972238) (xy 103.928124 -291.020512) (xy 103.936288 -291.070746)
			(xy 103.9368 -291.096192) (xy 104.244897 -291.096192) (xy 104.248992 -291.045464) (xy 104.261171 -290.99605)
			(xy 104.281119 -290.94923) (xy 104.30832 -290.906216) (xy 104.342068 -290.868122) (xy 104.38149 -290.835935)
			(xy 104.425564 -290.810489) (xy 104.47315 -290.792442) (xy 104.523014 -290.782262) (xy 104.573866 -290.780213)
			(xy 104.624387 -290.786347) (xy 104.673271 -290.800507) (xy 104.71925 -290.822324) (xy 104.761134 -290.851234)
			(xy 104.797838 -290.886489) (xy 104.828411 -290.927175) (xy 104.852062 -290.972238) (xy 104.868178 -291.020512)
			(xy 104.876342 -291.070746) (xy 104.876854 -291.096192) (xy 104.876351 -291.121181) (xy 105.183414 -291.121181)
			(xy 105.183414 -291.071203) (xy 105.191233 -291.02184) (xy 105.206677 -290.974308) (xy 105.229367 -290.929776)
			(xy 105.258743 -290.889343) (xy 105.294083 -290.854003) (xy 105.334516 -290.824627) (xy 105.379048 -290.801937)
			(xy 105.42658 -290.786493) (xy 105.475943 -290.778674) (xy 105.525921 -290.778674) (xy 105.575284 -290.786493)
			(xy 105.622816 -290.801937) (xy 105.667348 -290.824627) (xy 105.707781 -290.854003) (xy 105.743121 -290.889343)
			(xy 105.772497 -290.929776) (xy 105.795187 -290.974308) (xy 105.810631 -291.02184) (xy 105.81845 -291.071203)
			(xy 105.81894 -291.096192) (xy 106.124751 -291.096192) (xy 106.128846 -291.045464) (xy 106.141025 -290.99605)
			(xy 106.160973 -290.94923) (xy 106.188174 -290.906216) (xy 106.221922 -290.868122) (xy 106.261344 -290.835935)
			(xy 106.305418 -290.810489) (xy 106.353004 -290.792442) (xy 106.402868 -290.782262) (xy 106.45372 -290.780213)
			(xy 106.504241 -290.786347) (xy 106.553125 -290.800507) (xy 106.599104 -290.822324) (xy 106.640988 -290.851234)
			(xy 106.677692 -290.886489) (xy 106.708265 -290.927175) (xy 106.731916 -290.972238) (xy 106.748032 -291.020512)
			(xy 106.756196 -291.070746) (xy 106.756708 -291.096192) (xy 107.064805 -291.096192) (xy 107.0689 -291.045464)
			(xy 107.081079 -290.99605) (xy 107.101027 -290.94923) (xy 107.128228 -290.906216) (xy 107.161976 -290.868122)
			(xy 107.201398 -290.835935) (xy 107.245472 -290.810489) (xy 107.293058 -290.792442) (xy 107.342922 -290.782262)
			(xy 107.393774 -290.780213) (xy 107.444295 -290.786347) (xy 107.493179 -290.800507) (xy 107.539158 -290.822324)
			(xy 107.581042 -290.851234) (xy 107.617746 -290.886489) (xy 107.648319 -290.927175) (xy 107.67197 -290.972238)
			(xy 107.688086 -291.020512) (xy 107.69625 -291.070746) (xy 107.696762 -291.096192) (xy 107.696259 -291.121181)
			(xy 108.003576 -291.121181) (xy 108.003576 -291.071203) (xy 108.011395 -291.02184) (xy 108.026839 -290.974308)
			(xy 108.049529 -290.929776) (xy 108.078905 -290.889343) (xy 108.114245 -290.854003) (xy 108.154678 -290.824627)
			(xy 108.19921 -290.801937) (xy 108.246742 -290.786493) (xy 108.296105 -290.778674) (xy 108.346083 -290.778674)
			(xy 108.395446 -290.786493) (xy 108.442978 -290.801937) (xy 108.48751 -290.824627) (xy 108.527943 -290.854003)
			(xy 108.563283 -290.889343) (xy 108.592659 -290.929776) (xy 108.615349 -290.974308) (xy 108.630793 -291.02184)
			(xy 108.638612 -291.071203) (xy 108.639102 -291.096192) (xy 108.638612 -291.121181) (xy 115.51715 -291.121181)
			(xy 115.51715 -291.071203) (xy 115.524969 -291.02184) (xy 115.540413 -290.974308) (xy 115.563103 -290.929776)
			(xy 115.592479 -290.889343) (xy 115.627819 -290.854003) (xy 115.668252 -290.824627) (xy 115.712784 -290.801937)
			(xy 115.760316 -290.786493) (xy 115.809679 -290.778674) (xy 115.859657 -290.778674) (xy 115.90902 -290.786493)
			(xy 115.956552 -290.801937) (xy 116.001084 -290.824627) (xy 116.041517 -290.854003) (xy 116.076857 -290.889343)
			(xy 116.106233 -290.929776) (xy 116.128923 -290.974308) (xy 116.144367 -291.02184) (xy 116.152186 -291.071203)
			(xy 116.152676 -291.096192) (xy 116.458487 -291.096192) (xy 116.462582 -291.045464) (xy 116.474761 -290.99605)
			(xy 116.494709 -290.94923) (xy 116.52191 -290.906216) (xy 116.555658 -290.868122) (xy 116.59508 -290.835935)
			(xy 116.639154 -290.810489) (xy 116.68674 -290.792442) (xy 116.736604 -290.782262) (xy 116.787456 -290.780213)
			(xy 116.837977 -290.786347) (xy 116.886861 -290.800507) (xy 116.93284 -290.822324) (xy 116.974724 -290.851234)
			(xy 117.011428 -290.886489) (xy 117.042001 -290.927175) (xy 117.065652 -290.972238) (xy 117.081768 -291.020512)
			(xy 117.089932 -291.070746) (xy 117.090444 -291.096192) (xy 117.398541 -291.096192) (xy 117.402636 -291.045464)
			(xy 117.414815 -290.99605) (xy 117.434763 -290.94923) (xy 117.461964 -290.906216) (xy 117.495712 -290.868122)
			(xy 117.535134 -290.835935) (xy 117.579208 -290.810489) (xy 117.626794 -290.792442) (xy 117.676658 -290.782262)
			(xy 117.72751 -290.780213) (xy 117.778031 -290.786347) (xy 117.826915 -290.800507) (xy 117.872894 -290.822324)
			(xy 117.914778 -290.851234) (xy 117.951482 -290.886489) (xy 117.982055 -290.927175) (xy 118.005706 -290.972238)
			(xy 118.021822 -291.020512) (xy 118.029986 -291.070746) (xy 118.030498 -291.096192) (xy 118.029995 -291.121181)
			(xy 118.337312 -291.121181) (xy 118.337312 -291.071203) (xy 118.345131 -291.02184) (xy 118.360575 -290.974308)
			(xy 118.383265 -290.929776) (xy 118.412641 -290.889343) (xy 118.447981 -290.854003) (xy 118.488414 -290.824627)
			(xy 118.532946 -290.801937) (xy 118.580478 -290.786493) (xy 118.629841 -290.778674) (xy 118.679819 -290.778674)
			(xy 118.729182 -290.786493) (xy 118.776714 -290.801937) (xy 118.821246 -290.824627) (xy 118.861679 -290.854003)
			(xy 118.897019 -290.889343) (xy 118.926395 -290.929776) (xy 118.949085 -290.974308) (xy 118.964529 -291.02184)
			(xy 118.972348 -291.071203) (xy 118.972838 -291.096192) (xy 119.278395 -291.096192) (xy 119.28249 -291.045464)
			(xy 119.294669 -290.99605) (xy 119.314617 -290.94923) (xy 119.341818 -290.906216) (xy 119.375566 -290.868122)
			(xy 119.414988 -290.835935) (xy 119.459062 -290.810489) (xy 119.506648 -290.792442) (xy 119.556512 -290.782262)
			(xy 119.607364 -290.780213) (xy 119.657885 -290.786347) (xy 119.706769 -290.800507) (xy 119.752748 -290.822324)
			(xy 119.794632 -290.851234) (xy 119.831336 -290.886489) (xy 119.861909 -290.927175) (xy 119.88556 -290.972238)
			(xy 119.901676 -291.020512) (xy 119.90984 -291.070746) (xy 119.910352 -291.096192) (xy 120.218449 -291.096192)
			(xy 120.222544 -291.045464) (xy 120.234723 -290.99605) (xy 120.254671 -290.94923) (xy 120.281872 -290.906216)
			(xy 120.31562 -290.868122) (xy 120.355042 -290.835935) (xy 120.399116 -290.810489) (xy 120.446702 -290.792442)
			(xy 120.496566 -290.782262) (xy 120.547418 -290.780213) (xy 120.597939 -290.786347) (xy 120.646823 -290.800507)
			(xy 120.692802 -290.822324) (xy 120.734686 -290.851234) (xy 120.77139 -290.886489) (xy 120.801963 -290.927175)
			(xy 120.825614 -290.972238) (xy 120.84173 -291.020512) (xy 120.849894 -291.070746) (xy 120.850406 -291.096192)
			(xy 120.849903 -291.121181) (xy 121.15722 -291.121181) (xy 121.15722 -291.071203) (xy 121.165039 -291.02184)
			(xy 121.180483 -290.974308) (xy 121.203173 -290.929776) (xy 121.232549 -290.889343) (xy 121.267889 -290.854003)
			(xy 121.308322 -290.824627) (xy 121.352854 -290.801937) (xy 121.400386 -290.786493) (xy 121.449749 -290.778674)
			(xy 121.499727 -290.778674) (xy 121.54909 -290.786493) (xy 121.596622 -290.801937) (xy 121.641154 -290.824627)
			(xy 121.681587 -290.854003) (xy 121.716927 -290.889343) (xy 121.746303 -290.929776) (xy 121.768993 -290.974308)
			(xy 121.784437 -291.02184) (xy 121.792256 -291.071203) (xy 121.792746 -291.096192) (xy 122.098557 -291.096192)
			(xy 122.102652 -291.045464) (xy 122.114831 -290.99605) (xy 122.134779 -290.94923) (xy 122.16198 -290.906216)
			(xy 122.195728 -290.868122) (xy 122.23515 -290.835935) (xy 122.279224 -290.810489) (xy 122.32681 -290.792442)
			(xy 122.376674 -290.782262) (xy 122.427526 -290.780213) (xy 122.478047 -290.786347) (xy 122.526931 -290.800507)
			(xy 122.57291 -290.822324) (xy 122.614794 -290.851234) (xy 122.651498 -290.886489) (xy 122.682071 -290.927175)
			(xy 122.705722 -290.972238) (xy 122.721838 -291.020512) (xy 122.730002 -291.070746) (xy 122.730514 -291.096192)
			(xy 123.038611 -291.096192) (xy 123.042706 -291.045464) (xy 123.054885 -290.99605) (xy 123.074833 -290.94923)
			(xy 123.102034 -290.906216) (xy 123.135782 -290.868122) (xy 123.175204 -290.835935) (xy 123.219278 -290.810489)
			(xy 123.266864 -290.792442) (xy 123.316728 -290.782262) (xy 123.36758 -290.780213) (xy 123.418101 -290.786347)
			(xy 123.466985 -290.800507) (xy 123.512964 -290.822324) (xy 123.554848 -290.851234) (xy 123.591552 -290.886489)
			(xy 123.622125 -290.927175) (xy 123.645776 -290.972238) (xy 123.661892 -291.020512) (xy 123.670056 -291.070746)
			(xy 123.670568 -291.096192) (xy 123.670065 -291.121181) (xy 123.977128 -291.121181) (xy 123.977128 -291.071203)
			(xy 123.984947 -291.02184) (xy 124.000391 -290.974308) (xy 124.023081 -290.929776) (xy 124.052457 -290.889343)
			(xy 124.087797 -290.854003) (xy 124.12823 -290.824627) (xy 124.172762 -290.801937) (xy 124.220294 -290.786493)
			(xy 124.269657 -290.778674) (xy 124.319635 -290.778674) (xy 124.368998 -290.786493) (xy 124.41653 -290.801937)
			(xy 124.461062 -290.824627) (xy 124.501495 -290.854003) (xy 124.536835 -290.889343) (xy 124.566211 -290.929776)
			(xy 124.588901 -290.974308) (xy 124.604345 -291.02184) (xy 124.612164 -291.071203) (xy 124.612654 -291.096192)
			(xy 124.918465 -291.096192) (xy 124.92256 -291.045464) (xy 124.934739 -290.99605) (xy 124.954687 -290.94923)
			(xy 124.981888 -290.906216) (xy 125.015636 -290.868122) (xy 125.055058 -290.835935) (xy 125.099132 -290.810489)
			(xy 125.146718 -290.792442) (xy 125.196582 -290.782262) (xy 125.247434 -290.780213) (xy 125.297955 -290.786347)
			(xy 125.346839 -290.800507) (xy 125.392818 -290.822324) (xy 125.434702 -290.851234) (xy 125.471406 -290.886489)
			(xy 125.501979 -290.927175) (xy 125.52563 -290.972238) (xy 125.541746 -291.020512) (xy 125.54991 -291.070746)
			(xy 125.550422 -291.096192) (xy 125.858519 -291.096192) (xy 125.862614 -291.045464) (xy 125.874793 -290.99605)
			(xy 125.894741 -290.94923) (xy 125.921942 -290.906216) (xy 125.95569 -290.868122) (xy 125.995112 -290.835935)
			(xy 126.039186 -290.810489) (xy 126.086772 -290.792442) (xy 126.136636 -290.782262) (xy 126.187488 -290.780213)
			(xy 126.238009 -290.786347) (xy 126.286893 -290.800507) (xy 126.332872 -290.822324) (xy 126.374756 -290.851234)
			(xy 126.41146 -290.886489) (xy 126.442033 -290.927175) (xy 126.465684 -290.972238) (xy 126.4818 -291.020512)
			(xy 126.489964 -291.070746) (xy 126.490476 -291.096192) (xy 126.489973 -291.121181) (xy 126.79729 -291.121181)
			(xy 126.79729 -291.071203) (xy 126.805109 -291.02184) (xy 126.820553 -290.974308) (xy 126.843243 -290.929776)
			(xy 126.872619 -290.889343) (xy 126.907959 -290.854003) (xy 126.948392 -290.824627) (xy 126.992924 -290.801937)
			(xy 127.040456 -290.786493) (xy 127.089819 -290.778674) (xy 127.139797 -290.778674) (xy 127.18916 -290.786493)
			(xy 127.236692 -290.801937) (xy 127.281224 -290.824627) (xy 127.321657 -290.854003) (xy 127.356997 -290.889343)
			(xy 127.386373 -290.929776) (xy 127.409063 -290.974308) (xy 127.424507 -291.02184) (xy 127.432326 -291.071203)
			(xy 127.432816 -291.096192) (xy 127.432326 -291.121181) (xy 127.424507 -291.170544) (xy 127.409063 -291.218076)
			(xy 127.386373 -291.262608) (xy 127.356997 -291.303041) (xy 127.321657 -291.338381) (xy 127.281224 -291.367757)
			(xy 127.236692 -291.390447) (xy 127.18916 -291.405891) (xy 127.139797 -291.41371) (xy 127.089819 -291.41371)
			(xy 127.040456 -291.405891) (xy 126.992924 -291.390447) (xy 126.948392 -291.367757) (xy 126.907959 -291.338381)
			(xy 126.872619 -291.303041) (xy 126.843243 -291.262608) (xy 126.820553 -291.218076) (xy 126.805109 -291.170544)
			(xy 126.79729 -291.121181) (xy 126.489973 -291.121181) (xy 126.489964 -291.121638) (xy 126.4818 -291.171872)
			(xy 126.465684 -291.220146) (xy 126.442033 -291.265209) (xy 126.41146 -291.305895) (xy 126.374756 -291.34115)
			(xy 126.332872 -291.37006) (xy 126.286893 -291.391877) (xy 126.238009 -291.406037) (xy 126.187488 -291.412171)
			(xy 126.136636 -291.410122) (xy 126.086772 -291.399942) (xy 126.039186 -291.381895) (xy 125.995112 -291.356449)
			(xy 125.95569 -291.324262) (xy 125.921942 -291.286168) (xy 125.894741 -291.243154) (xy 125.874793 -291.196334)
			(xy 125.862614 -291.14692) (xy 125.858519 -291.096192) (xy 125.550422 -291.096192) (xy 125.54991 -291.121638)
			(xy 125.541746 -291.171872) (xy 125.52563 -291.220146) (xy 125.501979 -291.265209) (xy 125.471406 -291.305895)
			(xy 125.434702 -291.34115) (xy 125.392818 -291.37006) (xy 125.346839 -291.391877) (xy 125.297955 -291.406037)
			(xy 125.247434 -291.412171) (xy 125.196582 -291.410122) (xy 125.146718 -291.399942) (xy 125.099132 -291.381895)
			(xy 125.055058 -291.356449) (xy 125.015636 -291.324262) (xy 124.981888 -291.286168) (xy 124.954687 -291.243154)
			(xy 124.934739 -291.196334) (xy 124.92256 -291.14692) (xy 124.918465 -291.096192) (xy 124.612654 -291.096192)
			(xy 124.612164 -291.121181) (xy 124.604345 -291.170544) (xy 124.588901 -291.218076) (xy 124.566211 -291.262608)
			(xy 124.536835 -291.303041) (xy 124.501495 -291.338381) (xy 124.461062 -291.367757) (xy 124.41653 -291.390447)
			(xy 124.368998 -291.405891) (xy 124.319635 -291.41371) (xy 124.269657 -291.41371) (xy 124.220294 -291.405891)
			(xy 124.172762 -291.390447) (xy 124.12823 -291.367757) (xy 124.087797 -291.338381) (xy 124.052457 -291.303041)
			(xy 124.023081 -291.262608) (xy 124.000391 -291.218076) (xy 123.984947 -291.170544) (xy 123.977128 -291.121181)
			(xy 123.670065 -291.121181) (xy 123.670056 -291.121638) (xy 123.661892 -291.171872) (xy 123.645776 -291.220146)
			(xy 123.622125 -291.265209) (xy 123.591552 -291.305895) (xy 123.554848 -291.34115) (xy 123.512964 -291.37006)
			(xy 123.466985 -291.391877) (xy 123.418101 -291.406037) (xy 123.36758 -291.412171) (xy 123.316728 -291.410122)
			(xy 123.266864 -291.399942) (xy 123.219278 -291.381895) (xy 123.175204 -291.356449) (xy 123.135782 -291.324262)
			(xy 123.102034 -291.286168) (xy 123.074833 -291.243154) (xy 123.054885 -291.196334) (xy 123.042706 -291.14692)
			(xy 123.038611 -291.096192) (xy 122.730514 -291.096192) (xy 122.730002 -291.121638) (xy 122.721838 -291.171872)
			(xy 122.705722 -291.220146) (xy 122.682071 -291.265209) (xy 122.651498 -291.305895) (xy 122.614794 -291.34115)
			(xy 122.57291 -291.37006) (xy 122.526931 -291.391877) (xy 122.478047 -291.406037) (xy 122.427526 -291.412171)
			(xy 122.376674 -291.410122) (xy 122.32681 -291.399942) (xy 122.279224 -291.381895) (xy 122.23515 -291.356449)
			(xy 122.195728 -291.324262) (xy 122.16198 -291.286168) (xy 122.134779 -291.243154) (xy 122.114831 -291.196334)
			(xy 122.102652 -291.14692) (xy 122.098557 -291.096192) (xy 121.792746 -291.096192) (xy 121.792256 -291.121181)
			(xy 121.784437 -291.170544) (xy 121.768993 -291.218076) (xy 121.746303 -291.262608) (xy 121.716927 -291.303041)
			(xy 121.681587 -291.338381) (xy 121.641154 -291.367757) (xy 121.596622 -291.390447) (xy 121.54909 -291.405891)
			(xy 121.499727 -291.41371) (xy 121.449749 -291.41371) (xy 121.400386 -291.405891) (xy 121.352854 -291.390447)
			(xy 121.308322 -291.367757) (xy 121.267889 -291.338381) (xy 121.232549 -291.303041) (xy 121.203173 -291.262608)
			(xy 121.180483 -291.218076) (xy 121.165039 -291.170544) (xy 121.15722 -291.121181) (xy 120.849903 -291.121181)
			(xy 120.849894 -291.121638) (xy 120.84173 -291.171872) (xy 120.825614 -291.220146) (xy 120.801963 -291.265209)
			(xy 120.77139 -291.305895) (xy 120.734686 -291.34115) (xy 120.692802 -291.37006) (xy 120.646823 -291.391877)
			(xy 120.597939 -291.406037) (xy 120.547418 -291.412171) (xy 120.496566 -291.410122) (xy 120.446702 -291.399942)
			(xy 120.399116 -291.381895) (xy 120.355042 -291.356449) (xy 120.31562 -291.324262) (xy 120.281872 -291.286168)
			(xy 120.254671 -291.243154) (xy 120.234723 -291.196334) (xy 120.222544 -291.14692) (xy 120.218449 -291.096192)
			(xy 119.910352 -291.096192) (xy 119.90984 -291.121638) (xy 119.901676 -291.171872) (xy 119.88556 -291.220146)
			(xy 119.861909 -291.265209) (xy 119.831336 -291.305895) (xy 119.794632 -291.34115) (xy 119.752748 -291.37006)
			(xy 119.706769 -291.391877) (xy 119.657885 -291.406037) (xy 119.607364 -291.412171) (xy 119.556512 -291.410122)
			(xy 119.506648 -291.399942) (xy 119.459062 -291.381895) (xy 119.414988 -291.356449) (xy 119.375566 -291.324262)
			(xy 119.341818 -291.286168) (xy 119.314617 -291.243154) (xy 119.294669 -291.196334) (xy 119.28249 -291.14692)
			(xy 119.278395 -291.096192) (xy 118.972838 -291.096192) (xy 118.972348 -291.121181) (xy 118.964529 -291.170544)
			(xy 118.949085 -291.218076) (xy 118.926395 -291.262608) (xy 118.897019 -291.303041) (xy 118.861679 -291.338381)
			(xy 118.821246 -291.367757) (xy 118.776714 -291.390447) (xy 118.729182 -291.405891) (xy 118.679819 -291.41371)
			(xy 118.629841 -291.41371) (xy 118.580478 -291.405891) (xy 118.532946 -291.390447) (xy 118.488414 -291.367757)
			(xy 118.447981 -291.338381) (xy 118.412641 -291.303041) (xy 118.383265 -291.262608) (xy 118.360575 -291.218076)
			(xy 118.345131 -291.170544) (xy 118.337312 -291.121181) (xy 118.029995 -291.121181) (xy 118.029986 -291.121638)
			(xy 118.021822 -291.171872) (xy 118.005706 -291.220146) (xy 117.982055 -291.265209) (xy 117.951482 -291.305895)
			(xy 117.914778 -291.34115) (xy 117.872894 -291.37006) (xy 117.826915 -291.391877) (xy 117.778031 -291.406037)
			(xy 117.72751 -291.412171) (xy 117.676658 -291.410122) (xy 117.626794 -291.399942) (xy 117.579208 -291.381895)
			(xy 117.535134 -291.356449) (xy 117.495712 -291.324262) (xy 117.461964 -291.286168) (xy 117.434763 -291.243154)
			(xy 117.414815 -291.196334) (xy 117.402636 -291.14692) (xy 117.398541 -291.096192) (xy 117.090444 -291.096192)
			(xy 117.089932 -291.121638) (xy 117.081768 -291.171872) (xy 117.065652 -291.220146) (xy 117.042001 -291.265209)
			(xy 117.011428 -291.305895) (xy 116.974724 -291.34115) (xy 116.93284 -291.37006) (xy 116.886861 -291.391877)
			(xy 116.837977 -291.406037) (xy 116.787456 -291.412171) (xy 116.736604 -291.410122) (xy 116.68674 -291.399942)
			(xy 116.639154 -291.381895) (xy 116.59508 -291.356449) (xy 116.555658 -291.324262) (xy 116.52191 -291.286168)
			(xy 116.494709 -291.243154) (xy 116.474761 -291.196334) (xy 116.462582 -291.14692) (xy 116.458487 -291.096192)
			(xy 116.152676 -291.096192) (xy 116.152186 -291.121181) (xy 116.144367 -291.170544) (xy 116.128923 -291.218076)
			(xy 116.106233 -291.262608) (xy 116.076857 -291.303041) (xy 116.041517 -291.338381) (xy 116.001084 -291.367757)
			(xy 115.956552 -291.390447) (xy 115.90902 -291.405891) (xy 115.859657 -291.41371) (xy 115.809679 -291.41371)
			(xy 115.760316 -291.405891) (xy 115.712784 -291.390447) (xy 115.668252 -291.367757) (xy 115.627819 -291.338381)
			(xy 115.592479 -291.303041) (xy 115.563103 -291.262608) (xy 115.540413 -291.218076) (xy 115.524969 -291.170544)
			(xy 115.51715 -291.121181) (xy 108.638612 -291.121181) (xy 108.630793 -291.170544) (xy 108.615349 -291.218076)
			(xy 108.592659 -291.262608) (xy 108.563283 -291.303041) (xy 108.527943 -291.338381) (xy 108.48751 -291.367757)
			(xy 108.442978 -291.390447) (xy 108.395446 -291.405891) (xy 108.346083 -291.41371) (xy 108.296105 -291.41371)
			(xy 108.246742 -291.405891) (xy 108.19921 -291.390447) (xy 108.154678 -291.367757) (xy 108.114245 -291.338381)
			(xy 108.078905 -291.303041) (xy 108.049529 -291.262608) (xy 108.026839 -291.218076) (xy 108.011395 -291.170544)
			(xy 108.003576 -291.121181) (xy 107.696259 -291.121181) (xy 107.69625 -291.121638) (xy 107.688086 -291.171872)
			(xy 107.67197 -291.220146) (xy 107.648319 -291.265209) (xy 107.617746 -291.305895) (xy 107.581042 -291.34115)
			(xy 107.539158 -291.37006) (xy 107.493179 -291.391877) (xy 107.444295 -291.406037) (xy 107.393774 -291.412171)
			(xy 107.342922 -291.410122) (xy 107.293058 -291.399942) (xy 107.245472 -291.381895) (xy 107.201398 -291.356449)
			(xy 107.161976 -291.324262) (xy 107.128228 -291.286168) (xy 107.101027 -291.243154) (xy 107.081079 -291.196334)
			(xy 107.0689 -291.14692) (xy 107.064805 -291.096192) (xy 106.756708 -291.096192) (xy 106.756196 -291.121638)
			(xy 106.748032 -291.171872) (xy 106.731916 -291.220146) (xy 106.708265 -291.265209) (xy 106.677692 -291.305895)
			(xy 106.640988 -291.34115) (xy 106.599104 -291.37006) (xy 106.553125 -291.391877) (xy 106.504241 -291.406037)
			(xy 106.45372 -291.412171) (xy 106.402868 -291.410122) (xy 106.353004 -291.399942) (xy 106.305418 -291.381895)
			(xy 106.261344 -291.356449) (xy 106.221922 -291.324262) (xy 106.188174 -291.286168) (xy 106.160973 -291.243154)
			(xy 106.141025 -291.196334) (xy 106.128846 -291.14692) (xy 106.124751 -291.096192) (xy 105.81894 -291.096192)
			(xy 105.81845 -291.121181) (xy 105.810631 -291.170544) (xy 105.795187 -291.218076) (xy 105.772497 -291.262608)
			(xy 105.743121 -291.303041) (xy 105.707781 -291.338381) (xy 105.667348 -291.367757) (xy 105.622816 -291.390447)
			(xy 105.575284 -291.405891) (xy 105.525921 -291.41371) (xy 105.475943 -291.41371) (xy 105.42658 -291.405891)
			(xy 105.379048 -291.390447) (xy 105.334516 -291.367757) (xy 105.294083 -291.338381) (xy 105.258743 -291.303041)
			(xy 105.229367 -291.262608) (xy 105.206677 -291.218076) (xy 105.191233 -291.170544) (xy 105.183414 -291.121181)
			(xy 104.876351 -291.121181) (xy 104.876342 -291.121638) (xy 104.868178 -291.171872) (xy 104.852062 -291.220146)
			(xy 104.828411 -291.265209) (xy 104.797838 -291.305895) (xy 104.761134 -291.34115) (xy 104.71925 -291.37006)
			(xy 104.673271 -291.391877) (xy 104.624387 -291.406037) (xy 104.573866 -291.412171) (xy 104.523014 -291.410122)
			(xy 104.47315 -291.399942) (xy 104.425564 -291.381895) (xy 104.38149 -291.356449) (xy 104.342068 -291.324262)
			(xy 104.30832 -291.286168) (xy 104.281119 -291.243154) (xy 104.261171 -291.196334) (xy 104.248992 -291.14692)
			(xy 104.244897 -291.096192) (xy 103.9368 -291.096192) (xy 103.936288 -291.121638) (xy 103.928124 -291.171872)
			(xy 103.912008 -291.220146) (xy 103.888357 -291.265209) (xy 103.857784 -291.305895) (xy 103.82108 -291.34115)
			(xy 103.779196 -291.37006) (xy 103.733217 -291.391877) (xy 103.684333 -291.406037) (xy 103.633812 -291.412171)
			(xy 103.58296 -291.410122) (xy 103.533096 -291.399942) (xy 103.48551 -291.381895) (xy 103.441436 -291.356449)
			(xy 103.402014 -291.324262) (xy 103.368266 -291.286168) (xy 103.341065 -291.243154) (xy 103.321117 -291.196334)
			(xy 103.308938 -291.14692) (xy 103.304843 -291.096192) (xy 102.999032 -291.096192) (xy 102.998542 -291.121181)
			(xy 102.990723 -291.170544) (xy 102.975279 -291.218076) (xy 102.952589 -291.262608) (xy 102.923213 -291.303041)
			(xy 102.887873 -291.338381) (xy 102.84744 -291.367757) (xy 102.802908 -291.390447) (xy 102.755376 -291.405891)
			(xy 102.706013 -291.41371) (xy 102.656035 -291.41371) (xy 102.606672 -291.405891) (xy 102.55914 -291.390447)
			(xy 102.514608 -291.367757) (xy 102.474175 -291.338381) (xy 102.438835 -291.303041) (xy 102.409459 -291.262608)
			(xy 102.386769 -291.218076) (xy 102.371325 -291.170544) (xy 102.363506 -291.121181) (xy 102.056189 -291.121181)
			(xy 102.05618 -291.121638) (xy 102.048016 -291.171872) (xy 102.0319 -291.220146) (xy 102.008249 -291.265209)
			(xy 101.977676 -291.305895) (xy 101.940972 -291.34115) (xy 101.899088 -291.37006) (xy 101.853109 -291.391877)
			(xy 101.804225 -291.406037) (xy 101.753704 -291.412171) (xy 101.702852 -291.410122) (xy 101.652988 -291.399942)
			(xy 101.605402 -291.381895) (xy 101.561328 -291.356449) (xy 101.521906 -291.324262) (xy 101.488158 -291.286168)
			(xy 101.460957 -291.243154) (xy 101.441009 -291.196334) (xy 101.42883 -291.14692) (xy 101.424735 -291.096192)
			(xy 101.116892 -291.096192) (xy 101.11638 -291.121638) (xy 101.108216 -291.171872) (xy 101.0921 -291.220146)
			(xy 101.068449 -291.265209) (xy 101.037876 -291.305895) (xy 101.001172 -291.34115) (xy 100.959288 -291.37006)
			(xy 100.913309 -291.391877) (xy 100.864425 -291.406037) (xy 100.813904 -291.412171) (xy 100.763052 -291.410122)
			(xy 100.713188 -291.399942) (xy 100.665602 -291.381895) (xy 100.621528 -291.356449) (xy 100.582106 -291.324262)
			(xy 100.548358 -291.286168) (xy 100.521157 -291.243154) (xy 100.501209 -291.196334) (xy 100.48903 -291.14692)
			(xy 100.484935 -291.096192) (xy 100.179124 -291.096192) (xy 100.178634 -291.121181) (xy 100.170815 -291.170544)
			(xy 100.155371 -291.218076) (xy 100.132681 -291.262608) (xy 100.103305 -291.303041) (xy 100.067965 -291.338381)
			(xy 100.027532 -291.367757) (xy 99.983 -291.390447) (xy 99.935468 -291.405891) (xy 99.886105 -291.41371)
			(xy 99.836127 -291.41371) (xy 99.786764 -291.405891) (xy 99.739232 -291.390447) (xy 99.6947 -291.367757)
			(xy 99.654267 -291.338381) (xy 99.618927 -291.303041) (xy 99.589551 -291.262608) (xy 99.566861 -291.218076)
			(xy 99.551417 -291.170544) (xy 99.543598 -291.121181) (xy 99.236281 -291.121181) (xy 99.236272 -291.121638)
			(xy 99.228108 -291.171872) (xy 99.211992 -291.220146) (xy 99.188341 -291.265209) (xy 99.157768 -291.305895)
			(xy 99.121064 -291.34115) (xy 99.07918 -291.37006) (xy 99.033201 -291.391877) (xy 98.984317 -291.406037)
			(xy 98.933796 -291.412171) (xy 98.882944 -291.410122) (xy 98.83308 -291.399942) (xy 98.785494 -291.381895)
			(xy 98.74142 -291.356449) (xy 98.701998 -291.324262) (xy 98.66825 -291.286168) (xy 98.641049 -291.243154)
			(xy 98.621101 -291.196334) (xy 98.608922 -291.14692) (xy 98.604827 -291.096192) (xy 98.29673 -291.096192)
			(xy 98.296218 -291.121638) (xy 98.288054 -291.171872) (xy 98.271938 -291.220146) (xy 98.248287 -291.265209)
			(xy 98.217714 -291.305895) (xy 98.18101 -291.34115) (xy 98.139126 -291.37006) (xy 98.093147 -291.391877)
			(xy 98.044263 -291.406037) (xy 97.993742 -291.412171) (xy 97.94289 -291.410122) (xy 97.893026 -291.399942)
			(xy 97.84544 -291.381895) (xy 97.801366 -291.356449) (xy 97.761944 -291.324262) (xy 97.728196 -291.286168)
			(xy 97.700995 -291.243154) (xy 97.681047 -291.196334) (xy 97.668868 -291.14692) (xy 97.664773 -291.096192)
			(xy 97.358962 -291.096192) (xy 97.358472 -291.121181) (xy 97.350653 -291.170544) (xy 97.335209 -291.218076)
			(xy 97.312519 -291.262608) (xy 97.283143 -291.303041) (xy 97.247803 -291.338381) (xy 97.20737 -291.367757)
			(xy 97.162838 -291.390447) (xy 97.115306 -291.405891) (xy 97.065943 -291.41371) (xy 97.015965 -291.41371)
			(xy 96.966602 -291.405891) (xy 96.91907 -291.390447) (xy 96.874538 -291.367757) (xy 96.834105 -291.338381)
			(xy 96.798765 -291.303041) (xy 96.769389 -291.262608) (xy 96.746699 -291.218076) (xy 96.731255 -291.170544)
			(xy 96.723436 -291.121181) (xy 96.416373 -291.121181) (xy 96.416364 -291.121638) (xy 96.4082 -291.171872)
			(xy 96.392084 -291.220146) (xy 96.368433 -291.265209) (xy 96.33786 -291.305895) (xy 96.301156 -291.34115)
			(xy 96.259272 -291.37006) (xy 96.213293 -291.391877) (xy 96.164409 -291.406037) (xy 96.113888 -291.412171)
			(xy 96.063036 -291.410122) (xy 96.013172 -291.399942) (xy 95.965586 -291.381895) (xy 95.921512 -291.356449)
			(xy 95.88209 -291.324262) (xy 95.848342 -291.286168) (xy 95.821141 -291.243154) (xy 95.801193 -291.196334)
			(xy 95.789014 -291.14692) (xy 95.784919 -291.096192) (xy 95.479108 -291.096192) (xy 95.478618 -291.121181)
			(xy 95.470799 -291.170544) (xy 95.455355 -291.218076) (xy 95.432665 -291.262608) (xy 95.403289 -291.303041)
			(xy 95.367949 -291.338381) (xy 95.327516 -291.367757) (xy 95.282984 -291.390447) (xy 95.235452 -291.405891)
			(xy 95.186089 -291.41371) (xy 95.136111 -291.41371) (xy 95.086748 -291.405891) (xy 95.039216 -291.390447)
			(xy 94.994684 -291.367757) (xy 94.954251 -291.338381) (xy 94.918911 -291.303041) (xy 94.889535 -291.262608)
			(xy 94.866845 -291.218076) (xy 94.851401 -291.170544) (xy 94.843582 -291.121181) (xy 94.536265 -291.121181)
			(xy 94.536256 -291.121638) (xy 94.528092 -291.171872) (xy 94.511976 -291.220146) (xy 94.488325 -291.265209)
			(xy 94.457752 -291.305895) (xy 94.421048 -291.34115) (xy 94.379164 -291.37006) (xy 94.333185 -291.391877)
			(xy 94.284301 -291.406037) (xy 94.23378 -291.412171) (xy 94.182928 -291.410122) (xy 94.133064 -291.399942)
			(xy 94.085478 -291.381895) (xy 94.041404 -291.356449) (xy 94.001982 -291.324262) (xy 93.968234 -291.286168)
			(xy 93.941033 -291.243154) (xy 93.921085 -291.196334) (xy 93.908906 -291.14692) (xy 93.904811 -291.096192)
			(xy 93.599 -291.096192) (xy 93.59851 -291.121181) (xy 93.590691 -291.170544) (xy 93.575247 -291.218076)
			(xy 93.552557 -291.262608) (xy 93.523181 -291.303041) (xy 93.487841 -291.338381) (xy 93.447408 -291.367757)
			(xy 93.402876 -291.390447) (xy 93.355344 -291.405891) (xy 93.305981 -291.41371) (xy 93.256003 -291.41371)
			(xy 93.20664 -291.405891) (xy 93.159108 -291.390447) (xy 93.114576 -291.367757) (xy 93.074143 -291.338381)
			(xy 93.038803 -291.303041) (xy 93.009427 -291.262608) (xy 92.986737 -291.218076) (xy 92.971293 -291.170544)
			(xy 92.963474 -291.121181) (xy 92.656157 -291.121181) (xy 92.656148 -291.121638) (xy 92.647984 -291.171872)
			(xy 92.631868 -291.220146) (xy 92.608217 -291.265209) (xy 92.577644 -291.305895) (xy 92.54094 -291.34115)
			(xy 92.499056 -291.37006) (xy 92.453077 -291.391877) (xy 92.404193 -291.406037) (xy 92.353672 -291.412171)
			(xy 92.30282 -291.410122) (xy 92.252956 -291.399942) (xy 92.20537 -291.381895) (xy 92.161296 -291.356449)
			(xy 92.121874 -291.324262) (xy 92.088126 -291.286168) (xy 92.060925 -291.243154) (xy 92.040977 -291.196334)
			(xy 92.028798 -291.14692) (xy 92.024703 -291.096192) (xy 91.861386 -291.096192) (xy 91.861386 -291.274754)
			(xy 91.861453 -291.278359) (xy 91.86248 -291.285496) (xy 91.863418 -291.288978) (xy 91.86926 -291.309044)
			(xy 91.87307 -291.31514) (xy 91.899128 -291.357736) (xy 91.944364 -291.446765) (xy 91.981432 -291.539492)
			(xy 91.99626 -291.587174) (xy 91.999054 -291.596572) (xy 92.014294 -291.615622) (xy 92.017342 -291.619432)
			(xy 92.020898 -291.62248) (xy 92.030296 -291.630608) (xy 92.034106 -291.632894) (xy 92.05558 -291.646278)
			(xy 92.094379 -291.678755) (xy 92.127551 -291.716962) (xy 92.15426 -291.759935) (xy 92.173833 -291.806594)
			(xy 92.185778 -291.855761) (xy 92.189794 -291.906198) (xy 92.494857 -291.906198) (xy 92.498952 -291.85547)
			(xy 92.511131 -291.806056) (xy 92.531079 -291.759236) (xy 92.55828 -291.716222) (xy 92.592028 -291.678128)
			(xy 92.63145 -291.645941) (xy 92.675524 -291.620495) (xy 92.72311 -291.602448) (xy 92.772974 -291.592268)
			(xy 92.823826 -291.590219) (xy 92.874347 -291.596353) (xy 92.923231 -291.610513) (xy 92.96921 -291.63233)
			(xy 93.011094 -291.66124) (xy 93.047798 -291.696495) (xy 93.078371 -291.737181) (xy 93.102022 -291.782244)
			(xy 93.118138 -291.830518) (xy 93.126302 -291.880752) (xy 93.126814 -291.906198) (xy 93.126311 -291.931187)
			(xy 93.433628 -291.931187) (xy 93.433628 -291.881209) (xy 93.441447 -291.831846) (xy 93.456891 -291.784314)
			(xy 93.479581 -291.739782) (xy 93.508957 -291.699349) (xy 93.544297 -291.664009) (xy 93.58473 -291.634633)
			(xy 93.629262 -291.611943) (xy 93.676794 -291.596499) (xy 93.726157 -291.58868) (xy 93.776135 -291.58868)
			(xy 93.825498 -291.596499) (xy 93.87303 -291.611943) (xy 93.917562 -291.634633) (xy 93.957995 -291.664009)
			(xy 93.993335 -291.699349) (xy 94.022711 -291.739782) (xy 94.045401 -291.784314) (xy 94.060845 -291.831846)
			(xy 94.068664 -291.881209) (xy 94.069154 -291.906198) (xy 94.374711 -291.906198) (xy 94.378806 -291.85547)
			(xy 94.390985 -291.806056) (xy 94.410933 -291.759236) (xy 94.438134 -291.716222) (xy 94.471882 -291.678128)
			(xy 94.511304 -291.645941) (xy 94.555378 -291.620495) (xy 94.602964 -291.602448) (xy 94.652828 -291.592268)
			(xy 94.70368 -291.590219) (xy 94.754201 -291.596353) (xy 94.803085 -291.610513) (xy 94.849064 -291.63233)
			(xy 94.890948 -291.66124) (xy 94.927652 -291.696495) (xy 94.958225 -291.737181) (xy 94.981876 -291.782244)
			(xy 94.997992 -291.830518) (xy 95.006156 -291.880752) (xy 95.006668 -291.906198) (xy 95.314765 -291.906198)
			(xy 95.31886 -291.85547) (xy 95.331039 -291.806056) (xy 95.350987 -291.759236) (xy 95.378188 -291.716222)
			(xy 95.411936 -291.678128) (xy 95.451358 -291.645941) (xy 95.495432 -291.620495) (xy 95.543018 -291.602448)
			(xy 95.592882 -291.592268) (xy 95.643734 -291.590219) (xy 95.694255 -291.596353) (xy 95.743139 -291.610513)
			(xy 95.789118 -291.63233) (xy 95.831002 -291.66124) (xy 95.867706 -291.696495) (xy 95.898279 -291.737181)
			(xy 95.92193 -291.782244) (xy 95.938046 -291.830518) (xy 95.94621 -291.880752) (xy 95.946722 -291.906198)
			(xy 95.946219 -291.931187) (xy 97.19359 -291.931187) (xy 97.19359 -291.881209) (xy 97.201409 -291.831846)
			(xy 97.216853 -291.784314) (xy 97.239543 -291.739782) (xy 97.268919 -291.699349) (xy 97.304259 -291.664009)
			(xy 97.344692 -291.634633) (xy 97.389224 -291.611943) (xy 97.436756 -291.596499) (xy 97.486119 -291.58868)
			(xy 97.536097 -291.58868) (xy 97.58546 -291.596499) (xy 97.632992 -291.611943) (xy 97.677524 -291.634633)
			(xy 97.717957 -291.664009) (xy 97.753297 -291.699349) (xy 97.782673 -291.739782) (xy 97.805363 -291.784314)
			(xy 97.820807 -291.831846) (xy 97.828626 -291.881209) (xy 97.829116 -291.906198) (xy 97.828626 -291.931187)
			(xy 98.133644 -291.931187) (xy 98.133644 -291.881209) (xy 98.141463 -291.831846) (xy 98.156907 -291.784314)
			(xy 98.179597 -291.739782) (xy 98.208973 -291.699349) (xy 98.244313 -291.664009) (xy 98.284746 -291.634633)
			(xy 98.329278 -291.611943) (xy 98.37681 -291.596499) (xy 98.426173 -291.58868) (xy 98.476151 -291.58868)
			(xy 98.525514 -291.596499) (xy 98.573046 -291.611943) (xy 98.617578 -291.634633) (xy 98.658011 -291.664009)
			(xy 98.693351 -291.699349) (xy 98.722727 -291.739782) (xy 98.745417 -291.784314) (xy 98.760861 -291.831846)
			(xy 98.76868 -291.881209) (xy 98.76917 -291.906198) (xy 98.76868 -291.931187) (xy 100.013498 -291.931187)
			(xy 100.013498 -291.881209) (xy 100.021317 -291.831846) (xy 100.036761 -291.784314) (xy 100.059451 -291.739782)
			(xy 100.088827 -291.699349) (xy 100.124167 -291.664009) (xy 100.1646 -291.634633) (xy 100.209132 -291.611943)
			(xy 100.256664 -291.596499) (xy 100.306027 -291.58868) (xy 100.356005 -291.58868) (xy 100.405368 -291.596499)
			(xy 100.4529 -291.611943) (xy 100.497432 -291.634633) (xy 100.537865 -291.664009) (xy 100.573205 -291.699349)
			(xy 100.602581 -291.739782) (xy 100.625271 -291.784314) (xy 100.640715 -291.831846) (xy 100.648534 -291.881209)
			(xy 100.649024 -291.906198) (xy 100.648534 -291.931187) (xy 100.953552 -291.931187) (xy 100.953552 -291.881209)
			(xy 100.961371 -291.831846) (xy 100.976815 -291.784314) (xy 100.999505 -291.739782) (xy 101.028881 -291.699349)
			(xy 101.064221 -291.664009) (xy 101.104654 -291.634633) (xy 101.149186 -291.611943) (xy 101.196718 -291.596499)
			(xy 101.246081 -291.58868) (xy 101.296059 -291.58868) (xy 101.345422 -291.596499) (xy 101.392954 -291.611943)
			(xy 101.437486 -291.634633) (xy 101.477919 -291.664009) (xy 101.513259 -291.699349) (xy 101.542635 -291.739782)
			(xy 101.565325 -291.784314) (xy 101.580769 -291.831846) (xy 101.588588 -291.881209) (xy 101.589078 -291.906198)
			(xy 101.588588 -291.931187) (xy 102.83366 -291.931187) (xy 102.83366 -291.881209) (xy 102.841479 -291.831846)
			(xy 102.856923 -291.784314) (xy 102.879613 -291.739782) (xy 102.908989 -291.699349) (xy 102.944329 -291.664009)
			(xy 102.984762 -291.634633) (xy 103.029294 -291.611943) (xy 103.076826 -291.596499) (xy 103.126189 -291.58868)
			(xy 103.176167 -291.58868) (xy 103.22553 -291.596499) (xy 103.273062 -291.611943) (xy 103.317594 -291.634633)
			(xy 103.358027 -291.664009) (xy 103.393367 -291.699349) (xy 103.422743 -291.739782) (xy 103.445433 -291.784314)
			(xy 103.460877 -291.831846) (xy 103.468696 -291.881209) (xy 103.469186 -291.906198) (xy 103.468696 -291.931187)
			(xy 103.77346 -291.931187) (xy 103.77346 -291.881209) (xy 103.781279 -291.831846) (xy 103.796723 -291.784314)
			(xy 103.819413 -291.739782) (xy 103.848789 -291.699349) (xy 103.884129 -291.664009) (xy 103.924562 -291.634633)
			(xy 103.969094 -291.611943) (xy 104.016626 -291.596499) (xy 104.065989 -291.58868) (xy 104.115967 -291.58868)
			(xy 104.16533 -291.596499) (xy 104.212862 -291.611943) (xy 104.257394 -291.634633) (xy 104.297827 -291.664009)
			(xy 104.333167 -291.699349) (xy 104.362543 -291.739782) (xy 104.385233 -291.784314) (xy 104.400677 -291.831846)
			(xy 104.408496 -291.881209) (xy 104.408986 -291.906198) (xy 104.408496 -291.931187) (xy 105.653568 -291.931187)
			(xy 105.653568 -291.881209) (xy 105.661387 -291.831846) (xy 105.676831 -291.784314) (xy 105.699521 -291.739782)
			(xy 105.728897 -291.699349) (xy 105.764237 -291.664009) (xy 105.80467 -291.634633) (xy 105.849202 -291.611943)
			(xy 105.896734 -291.596499) (xy 105.946097 -291.58868) (xy 105.996075 -291.58868) (xy 106.045438 -291.596499)
			(xy 106.09297 -291.611943) (xy 106.137502 -291.634633) (xy 106.177935 -291.664009) (xy 106.213275 -291.699349)
			(xy 106.242651 -291.739782) (xy 106.265341 -291.784314) (xy 106.280785 -291.831846) (xy 106.288604 -291.881209)
			(xy 106.289094 -291.906198) (xy 106.288604 -291.931187) (xy 106.593622 -291.931187) (xy 106.593622 -291.881209)
			(xy 106.601441 -291.831846) (xy 106.616885 -291.784314) (xy 106.639575 -291.739782) (xy 106.668951 -291.699349)
			(xy 106.704291 -291.664009) (xy 106.744724 -291.634633) (xy 106.789256 -291.611943) (xy 106.836788 -291.596499)
			(xy 106.886151 -291.58868) (xy 106.936129 -291.58868) (xy 106.985492 -291.596499) (xy 107.033024 -291.611943)
			(xy 107.077556 -291.634633) (xy 107.117989 -291.664009) (xy 107.153329 -291.699349) (xy 107.182705 -291.739782)
			(xy 107.205395 -291.784314) (xy 107.220839 -291.831846) (xy 107.228658 -291.881209) (xy 107.229148 -291.906198)
			(xy 107.228658 -291.931187) (xy 108.473476 -291.931187) (xy 108.473476 -291.881209) (xy 108.481295 -291.831846)
			(xy 108.496739 -291.784314) (xy 108.519429 -291.739782) (xy 108.548805 -291.699349) (xy 108.584145 -291.664009)
			(xy 108.624578 -291.634633) (xy 108.66911 -291.611943) (xy 108.716642 -291.596499) (xy 108.766005 -291.58868)
			(xy 108.815983 -291.58868) (xy 108.865346 -291.596499) (xy 108.912878 -291.611943) (xy 108.95741 -291.634633)
			(xy 108.997843 -291.664009) (xy 109.033183 -291.699349) (xy 109.062559 -291.739782) (xy 109.085249 -291.784314)
			(xy 109.100693 -291.831846) (xy 109.108512 -291.881209) (xy 109.109002 -291.906198) (xy 109.108512 -291.931187)
			(xy 109.41353 -291.931187) (xy 109.41353 -291.881209) (xy 109.421349 -291.831846) (xy 109.436793 -291.784314)
			(xy 109.459483 -291.739782) (xy 109.488859 -291.699349) (xy 109.524199 -291.664009) (xy 109.564632 -291.634633)
			(xy 109.609164 -291.611943) (xy 109.656696 -291.596499) (xy 109.706059 -291.58868) (xy 109.756037 -291.58868)
			(xy 109.8054 -291.596499) (xy 109.852932 -291.611943) (xy 109.897464 -291.634633) (xy 109.937897 -291.664009)
			(xy 109.973237 -291.699349) (xy 110.002613 -291.739782) (xy 110.025303 -291.784314) (xy 110.040747 -291.831846)
			(xy 110.048566 -291.881209) (xy 110.049056 -291.906198) (xy 110.048566 -291.931187) (xy 110.353584 -291.931187)
			(xy 110.353584 -291.881209) (xy 110.361403 -291.831846) (xy 110.376847 -291.784314) (xy 110.399537 -291.739782)
			(xy 110.428913 -291.699349) (xy 110.464253 -291.664009) (xy 110.504686 -291.634633) (xy 110.549218 -291.611943)
			(xy 110.59675 -291.596499) (xy 110.646113 -291.58868) (xy 110.696091 -291.58868) (xy 110.745454 -291.596499)
			(xy 110.792986 -291.611943) (xy 110.837518 -291.634633) (xy 110.877951 -291.664009) (xy 110.913291 -291.699349)
			(xy 110.942667 -291.739782) (xy 110.965357 -291.784314) (xy 110.980801 -291.831846) (xy 110.98862 -291.881209)
			(xy 110.98911 -291.906198) (xy 110.98862 -291.931187) (xy 113.167142 -291.931187) (xy 113.167142 -291.881209)
			(xy 113.174961 -291.831846) (xy 113.190405 -291.784314) (xy 113.213095 -291.739782) (xy 113.242471 -291.699349)
			(xy 113.277811 -291.664009) (xy 113.318244 -291.634633) (xy 113.362776 -291.611943) (xy 113.410308 -291.596499)
			(xy 113.459671 -291.58868) (xy 113.509649 -291.58868) (xy 113.559012 -291.596499) (xy 113.606544 -291.611943)
			(xy 113.651076 -291.634633) (xy 113.691509 -291.664009) (xy 113.726849 -291.699349) (xy 113.756225 -291.739782)
			(xy 113.778915 -291.784314) (xy 113.794359 -291.831846) (xy 113.802178 -291.881209) (xy 113.802668 -291.906198)
			(xy 113.802178 -291.931187) (xy 114.107196 -291.931187) (xy 114.107196 -291.881209) (xy 114.115015 -291.831846)
			(xy 114.130459 -291.784314) (xy 114.153149 -291.739782) (xy 114.182525 -291.699349) (xy 114.217865 -291.664009)
			(xy 114.258298 -291.634633) (xy 114.30283 -291.611943) (xy 114.350362 -291.596499) (xy 114.399725 -291.58868)
			(xy 114.449703 -291.58868) (xy 114.499066 -291.596499) (xy 114.546598 -291.611943) (xy 114.59113 -291.634633)
			(xy 114.631563 -291.664009) (xy 114.666903 -291.699349) (xy 114.696279 -291.739782) (xy 114.718969 -291.784314)
			(xy 114.734413 -291.831846) (xy 114.742232 -291.881209) (xy 114.742722 -291.906198) (xy 114.742232 -291.931187)
			(xy 115.04725 -291.931187) (xy 115.04725 -291.881209) (xy 115.055069 -291.831846) (xy 115.070513 -291.784314)
			(xy 115.093203 -291.739782) (xy 115.122579 -291.699349) (xy 115.157919 -291.664009) (xy 115.198352 -291.634633)
			(xy 115.242884 -291.611943) (xy 115.290416 -291.596499) (xy 115.339779 -291.58868) (xy 115.389757 -291.58868)
			(xy 115.43912 -291.596499) (xy 115.486652 -291.611943) (xy 115.531184 -291.634633) (xy 115.571617 -291.664009)
			(xy 115.606957 -291.699349) (xy 115.636333 -291.739782) (xy 115.659023 -291.784314) (xy 115.674467 -291.831846)
			(xy 115.682286 -291.881209) (xy 115.682776 -291.906198) (xy 115.682286 -291.931187) (xy 115.674467 -291.98055)
			(xy 115.659023 -292.028082) (xy 115.636333 -292.072614) (xy 115.606957 -292.113047) (xy 115.571617 -292.148387)
			(xy 115.531184 -292.177763) (xy 115.486652 -292.200453) (xy 115.43912 -292.215897) (xy 115.389757 -292.223716)
			(xy 115.339779 -292.223716) (xy 115.290416 -292.215897) (xy 115.242884 -292.200453) (xy 115.198352 -292.177763)
			(xy 115.157919 -292.148387) (xy 115.122579 -292.113047) (xy 115.093203 -292.072614) (xy 115.070513 -292.028082)
			(xy 115.055069 -291.98055) (xy 115.04725 -291.931187) (xy 114.742232 -291.931187) (xy 114.734413 -291.98055)
			(xy 114.718969 -292.028082) (xy 114.696279 -292.072614) (xy 114.666903 -292.113047) (xy 114.631563 -292.148387)
			(xy 114.59113 -292.177763) (xy 114.546598 -292.200453) (xy 114.499066 -292.215897) (xy 114.449703 -292.223716)
			(xy 114.399725 -292.223716) (xy 114.350362 -292.215897) (xy 114.30283 -292.200453) (xy 114.258298 -292.177763)
			(xy 114.217865 -292.148387) (xy 114.182525 -292.113047) (xy 114.153149 -292.072614) (xy 114.130459 -292.028082)
			(xy 114.115015 -291.98055) (xy 114.107196 -291.931187) (xy 113.802178 -291.931187) (xy 113.794359 -291.98055)
			(xy 113.778915 -292.028082) (xy 113.756225 -292.072614) (xy 113.726849 -292.113047) (xy 113.691509 -292.148387)
			(xy 113.651076 -292.177763) (xy 113.606544 -292.200453) (xy 113.559012 -292.215897) (xy 113.509649 -292.223716)
			(xy 113.459671 -292.223716) (xy 113.410308 -292.215897) (xy 113.362776 -292.200453) (xy 113.318244 -292.177763)
			(xy 113.277811 -292.148387) (xy 113.242471 -292.113047) (xy 113.213095 -292.072614) (xy 113.190405 -292.028082)
			(xy 113.174961 -291.98055) (xy 113.167142 -291.931187) (xy 110.98862 -291.931187) (xy 110.980801 -291.98055)
			(xy 110.965357 -292.028082) (xy 110.942667 -292.072614) (xy 110.913291 -292.113047) (xy 110.877951 -292.148387)
			(xy 110.837518 -292.177763) (xy 110.792986 -292.200453) (xy 110.745454 -292.215897) (xy 110.696091 -292.223716)
			(xy 110.646113 -292.223716) (xy 110.59675 -292.215897) (xy 110.549218 -292.200453) (xy 110.504686 -292.177763)
			(xy 110.464253 -292.148387) (xy 110.428913 -292.113047) (xy 110.399537 -292.072614) (xy 110.376847 -292.028082)
			(xy 110.361403 -291.98055) (xy 110.353584 -291.931187) (xy 110.048566 -291.931187) (xy 110.040747 -291.98055)
			(xy 110.025303 -292.028082) (xy 110.002613 -292.072614) (xy 109.973237 -292.113047) (xy 109.937897 -292.148387)
			(xy 109.897464 -292.177763) (xy 109.852932 -292.200453) (xy 109.8054 -292.215897) (xy 109.756037 -292.223716)
			(xy 109.706059 -292.223716) (xy 109.656696 -292.215897) (xy 109.609164 -292.200453) (xy 109.564632 -292.177763)
			(xy 109.524199 -292.148387) (xy 109.488859 -292.113047) (xy 109.459483 -292.072614) (xy 109.436793 -292.028082)
			(xy 109.421349 -291.98055) (xy 109.41353 -291.931187) (xy 109.108512 -291.931187) (xy 109.100693 -291.98055)
			(xy 109.085249 -292.028082) (xy 109.062559 -292.072614) (xy 109.033183 -292.113047) (xy 108.997843 -292.148387)
			(xy 108.95741 -292.177763) (xy 108.912878 -292.200453) (xy 108.865346 -292.215897) (xy 108.815983 -292.223716)
			(xy 108.766005 -292.223716) (xy 108.716642 -292.215897) (xy 108.66911 -292.200453) (xy 108.624578 -292.177763)
			(xy 108.584145 -292.148387) (xy 108.548805 -292.113047) (xy 108.519429 -292.072614) (xy 108.496739 -292.028082)
			(xy 108.481295 -291.98055) (xy 108.473476 -291.931187) (xy 107.228658 -291.931187) (xy 107.220839 -291.98055)
			(xy 107.205395 -292.028082) (xy 107.182705 -292.072614) (xy 107.153329 -292.113047) (xy 107.117989 -292.148387)
			(xy 107.077556 -292.177763) (xy 107.033024 -292.200453) (xy 106.985492 -292.215897) (xy 106.936129 -292.223716)
			(xy 106.886151 -292.223716) (xy 106.836788 -292.215897) (xy 106.789256 -292.200453) (xy 106.744724 -292.177763)
			(xy 106.704291 -292.148387) (xy 106.668951 -292.113047) (xy 106.639575 -292.072614) (xy 106.616885 -292.028082)
			(xy 106.601441 -291.98055) (xy 106.593622 -291.931187) (xy 106.288604 -291.931187) (xy 106.280785 -291.98055)
			(xy 106.265341 -292.028082) (xy 106.242651 -292.072614) (xy 106.213275 -292.113047) (xy 106.177935 -292.148387)
			(xy 106.137502 -292.177763) (xy 106.09297 -292.200453) (xy 106.045438 -292.215897) (xy 105.996075 -292.223716)
			(xy 105.946097 -292.223716) (xy 105.896734 -292.215897) (xy 105.849202 -292.200453) (xy 105.80467 -292.177763)
			(xy 105.764237 -292.148387) (xy 105.728897 -292.113047) (xy 105.699521 -292.072614) (xy 105.676831 -292.028082)
			(xy 105.661387 -291.98055) (xy 105.653568 -291.931187) (xy 104.408496 -291.931187) (xy 104.400677 -291.98055)
			(xy 104.385233 -292.028082) (xy 104.362543 -292.072614) (xy 104.333167 -292.113047) (xy 104.297827 -292.148387)
			(xy 104.257394 -292.177763) (xy 104.212862 -292.200453) (xy 104.16533 -292.215897) (xy 104.115967 -292.223716)
			(xy 104.065989 -292.223716) (xy 104.016626 -292.215897) (xy 103.969094 -292.200453) (xy 103.924562 -292.177763)
			(xy 103.884129 -292.148387) (xy 103.848789 -292.113047) (xy 103.819413 -292.072614) (xy 103.796723 -292.028082)
			(xy 103.781279 -291.98055) (xy 103.77346 -291.931187) (xy 103.468696 -291.931187) (xy 103.460877 -291.98055)
			(xy 103.445433 -292.028082) (xy 103.422743 -292.072614) (xy 103.393367 -292.113047) (xy 103.358027 -292.148387)
			(xy 103.317594 -292.177763) (xy 103.273062 -292.200453) (xy 103.22553 -292.215897) (xy 103.176167 -292.223716)
			(xy 103.126189 -292.223716) (xy 103.076826 -292.215897) (xy 103.029294 -292.200453) (xy 102.984762 -292.177763)
			(xy 102.944329 -292.148387) (xy 102.908989 -292.113047) (xy 102.879613 -292.072614) (xy 102.856923 -292.028082)
			(xy 102.841479 -291.98055) (xy 102.83366 -291.931187) (xy 101.588588 -291.931187) (xy 101.580769 -291.98055)
			(xy 101.565325 -292.028082) (xy 101.542635 -292.072614) (xy 101.513259 -292.113047) (xy 101.477919 -292.148387)
			(xy 101.437486 -292.177763) (xy 101.392954 -292.200453) (xy 101.345422 -292.215897) (xy 101.296059 -292.223716)
			(xy 101.246081 -292.223716) (xy 101.196718 -292.215897) (xy 101.149186 -292.200453) (xy 101.104654 -292.177763)
			(xy 101.064221 -292.148387) (xy 101.028881 -292.113047) (xy 100.999505 -292.072614) (xy 100.976815 -292.028082)
			(xy 100.961371 -291.98055) (xy 100.953552 -291.931187) (xy 100.648534 -291.931187) (xy 100.640715 -291.98055)
			(xy 100.625271 -292.028082) (xy 100.602581 -292.072614) (xy 100.573205 -292.113047) (xy 100.537865 -292.148387)
			(xy 100.497432 -292.177763) (xy 100.4529 -292.200453) (xy 100.405368 -292.215897) (xy 100.356005 -292.223716)
			(xy 100.306027 -292.223716) (xy 100.256664 -292.215897) (xy 100.209132 -292.200453) (xy 100.1646 -292.177763)
			(xy 100.124167 -292.148387) (xy 100.088827 -292.113047) (xy 100.059451 -292.072614) (xy 100.036761 -292.028082)
			(xy 100.021317 -291.98055) (xy 100.013498 -291.931187) (xy 98.76868 -291.931187) (xy 98.760861 -291.98055)
			(xy 98.745417 -292.028082) (xy 98.722727 -292.072614) (xy 98.693351 -292.113047) (xy 98.658011 -292.148387)
			(xy 98.617578 -292.177763) (xy 98.573046 -292.200453) (xy 98.525514 -292.215897) (xy 98.476151 -292.223716)
			(xy 98.426173 -292.223716) (xy 98.37681 -292.215897) (xy 98.329278 -292.200453) (xy 98.284746 -292.177763)
			(xy 98.244313 -292.148387) (xy 98.208973 -292.113047) (xy 98.179597 -292.072614) (xy 98.156907 -292.028082)
			(xy 98.141463 -291.98055) (xy 98.133644 -291.931187) (xy 97.828626 -291.931187) (xy 97.820807 -291.98055)
			(xy 97.805363 -292.028082) (xy 97.782673 -292.072614) (xy 97.753297 -292.113047) (xy 97.717957 -292.148387)
			(xy 97.677524 -292.177763) (xy 97.632992 -292.200453) (xy 97.58546 -292.215897) (xy 97.536097 -292.223716)
			(xy 97.486119 -292.223716) (xy 97.436756 -292.215897) (xy 97.389224 -292.200453) (xy 97.344692 -292.177763)
			(xy 97.304259 -292.148387) (xy 97.268919 -292.113047) (xy 97.239543 -292.072614) (xy 97.216853 -292.028082)
			(xy 97.201409 -291.98055) (xy 97.19359 -291.931187) (xy 95.946219 -291.931187) (xy 95.94621 -291.931644)
			(xy 95.938046 -291.981878) (xy 95.92193 -292.030152) (xy 95.898279 -292.075215) (xy 95.867706 -292.115901)
			(xy 95.831002 -292.151156) (xy 95.789118 -292.180066) (xy 95.743139 -292.201883) (xy 95.694255 -292.216043)
			(xy 95.643734 -292.222177) (xy 95.592882 -292.220128) (xy 95.543018 -292.209948) (xy 95.495432 -292.191901)
			(xy 95.451358 -292.166455) (xy 95.411936 -292.134268) (xy 95.378188 -292.096174) (xy 95.350987 -292.05316)
			(xy 95.331039 -292.00634) (xy 95.31886 -291.956926) (xy 95.314765 -291.906198) (xy 95.006668 -291.906198)
			(xy 95.006156 -291.931644) (xy 94.997992 -291.981878) (xy 94.981876 -292.030152) (xy 94.958225 -292.075215)
			(xy 94.927652 -292.115901) (xy 94.890948 -292.151156) (xy 94.849064 -292.180066) (xy 94.803085 -292.201883)
			(xy 94.754201 -292.216043) (xy 94.70368 -292.222177) (xy 94.652828 -292.220128) (xy 94.602964 -292.209948)
			(xy 94.555378 -292.191901) (xy 94.511304 -292.166455) (xy 94.471882 -292.134268) (xy 94.438134 -292.096174)
			(xy 94.410933 -292.05316) (xy 94.390985 -292.00634) (xy 94.378806 -291.956926) (xy 94.374711 -291.906198)
			(xy 94.069154 -291.906198) (xy 94.068664 -291.931187) (xy 94.060845 -291.98055) (xy 94.045401 -292.028082)
			(xy 94.022711 -292.072614) (xy 93.993335 -292.113047) (xy 93.957995 -292.148387) (xy 93.917562 -292.177763)
			(xy 93.87303 -292.200453) (xy 93.825498 -292.215897) (xy 93.776135 -292.223716) (xy 93.726157 -292.223716)
			(xy 93.676794 -292.215897) (xy 93.629262 -292.200453) (xy 93.58473 -292.177763) (xy 93.544297 -292.148387)
			(xy 93.508957 -292.113047) (xy 93.479581 -292.072614) (xy 93.456891 -292.028082) (xy 93.441447 -291.98055)
			(xy 93.433628 -291.931187) (xy 93.126311 -291.931187) (xy 93.126302 -291.931644) (xy 93.118138 -291.981878)
			(xy 93.102022 -292.030152) (xy 93.078371 -292.075215) (xy 93.047798 -292.115901) (xy 93.011094 -292.151156)
			(xy 92.96921 -292.180066) (xy 92.923231 -292.201883) (xy 92.874347 -292.216043) (xy 92.823826 -292.222177)
			(xy 92.772974 -292.220128) (xy 92.72311 -292.209948) (xy 92.675524 -292.191901) (xy 92.63145 -292.166455)
			(xy 92.592028 -292.134268) (xy 92.55828 -292.096174) (xy 92.531079 -292.05316) (xy 92.511131 -292.00634)
			(xy 92.498952 -291.956926) (xy 92.494857 -291.906198) (xy 92.189794 -291.906198) (xy 92.189794 -291.906199)
			(xy 92.185779 -291.956637) (xy 92.173834 -292.005804) (xy 92.154261 -292.052463) (xy 92.127552 -292.095437)
			(xy 92.09438 -292.133644) (xy 92.055582 -292.166121) (xy 92.034106 -292.179502) (xy 92.030042 -292.181788)
			(xy 92.020898 -292.189916) (xy 92.014548 -292.19652) (xy 91.999054 -292.215824) (xy 91.99626 -292.225222)
			(xy 91.981434 -292.272904) (xy 91.944363 -292.365631) (xy 91.899128 -292.45466) (xy 91.87307 -292.497256)
			(xy 91.86926 -292.503352) (xy 91.863418 -292.523418) (xy 91.862472 -292.526898) (xy 91.861458 -292.534037)
			(xy 91.861386 -292.537642) (xy 91.861386 -292.716204) (xy 92.024703 -292.716204) (xy 92.028798 -292.665476)
			(xy 92.040977 -292.616062) (xy 92.060925 -292.569242) (xy 92.088126 -292.526228) (xy 92.121874 -292.488134)
			(xy 92.161296 -292.455947) (xy 92.20537 -292.430501) (xy 92.252956 -292.412454) (xy 92.30282 -292.402274)
			(xy 92.353672 -292.400225) (xy 92.404193 -292.406359) (xy 92.453077 -292.420519) (xy 92.499056 -292.442336)
			(xy 92.54094 -292.471246) (xy 92.577644 -292.506501) (xy 92.608217 -292.547187) (xy 92.631868 -292.59225)
			(xy 92.647984 -292.640524) (xy 92.656148 -292.690758) (xy 92.65666 -292.716204) (xy 92.656157 -292.741193)
			(xy 92.963474 -292.741193) (xy 92.963474 -292.691215) (xy 92.971293 -292.641852) (xy 92.986737 -292.59432)
			(xy 93.009427 -292.549788) (xy 93.038803 -292.509355) (xy 93.074143 -292.474015) (xy 93.114576 -292.444639)
			(xy 93.159108 -292.421949) (xy 93.20664 -292.406505) (xy 93.256003 -292.398686) (xy 93.305981 -292.398686)
			(xy 93.355344 -292.406505) (xy 93.402876 -292.421949) (xy 93.447408 -292.444639) (xy 93.487841 -292.474015)
			(xy 93.523181 -292.509355) (xy 93.552557 -292.549788) (xy 93.575247 -292.59432) (xy 93.590691 -292.641852)
			(xy 93.59851 -292.691215) (xy 93.599 -292.716204) (xy 93.904811 -292.716204) (xy 93.908906 -292.665476)
			(xy 93.921085 -292.616062) (xy 93.941033 -292.569242) (xy 93.968234 -292.526228) (xy 94.001982 -292.488134)
			(xy 94.041404 -292.455947) (xy 94.085478 -292.430501) (xy 94.133064 -292.412454) (xy 94.182928 -292.402274)
			(xy 94.23378 -292.400225) (xy 94.284301 -292.406359) (xy 94.333185 -292.420519) (xy 94.379164 -292.442336)
			(xy 94.421048 -292.471246) (xy 94.457752 -292.506501) (xy 94.488325 -292.547187) (xy 94.511976 -292.59225)
			(xy 94.528092 -292.640524) (xy 94.536256 -292.690758) (xy 94.536768 -292.716204) (xy 94.536265 -292.741193)
			(xy 94.843582 -292.741193) (xy 94.843582 -292.691215) (xy 94.851401 -292.641852) (xy 94.866845 -292.59432)
			(xy 94.889535 -292.549788) (xy 94.918911 -292.509355) (xy 94.954251 -292.474015) (xy 94.994684 -292.444639)
			(xy 95.039216 -292.421949) (xy 95.086748 -292.406505) (xy 95.136111 -292.398686) (xy 95.186089 -292.398686)
			(xy 95.235452 -292.406505) (xy 95.282984 -292.421949) (xy 95.327516 -292.444639) (xy 95.367949 -292.474015)
			(xy 95.403289 -292.509355) (xy 95.432665 -292.549788) (xy 95.455355 -292.59432) (xy 95.470799 -292.641852)
			(xy 95.478618 -292.691215) (xy 95.479108 -292.716204) (xy 95.784919 -292.716204) (xy 95.789014 -292.665476)
			(xy 95.801193 -292.616062) (xy 95.821141 -292.569242) (xy 95.848342 -292.526228) (xy 95.88209 -292.488134)
			(xy 95.921512 -292.455947) (xy 95.965586 -292.430501) (xy 96.013172 -292.412454) (xy 96.063036 -292.402274)
			(xy 96.113888 -292.400225) (xy 96.164409 -292.406359) (xy 96.213293 -292.420519) (xy 96.259272 -292.442336)
			(xy 96.301156 -292.471246) (xy 96.33786 -292.506501) (xy 96.368433 -292.547187) (xy 96.392084 -292.59225)
			(xy 96.4082 -292.640524) (xy 96.416364 -292.690758) (xy 96.416876 -292.716204) (xy 97.664773 -292.716204)
			(xy 97.668868 -292.665476) (xy 97.681047 -292.616062) (xy 97.700995 -292.569242) (xy 97.728196 -292.526228)
			(xy 97.761944 -292.488134) (xy 97.801366 -292.455947) (xy 97.84544 -292.430501) (xy 97.893026 -292.412454)
			(xy 97.94289 -292.402274) (xy 97.993742 -292.400225) (xy 98.044263 -292.406359) (xy 98.093147 -292.420519)
			(xy 98.139126 -292.442336) (xy 98.18101 -292.471246) (xy 98.217714 -292.506501) (xy 98.248287 -292.547187)
			(xy 98.271938 -292.59225) (xy 98.288054 -292.640524) (xy 98.296218 -292.690758) (xy 98.29673 -292.716204)
			(xy 98.604827 -292.716204) (xy 98.608922 -292.665476) (xy 98.621101 -292.616062) (xy 98.641049 -292.569242)
			(xy 98.66825 -292.526228) (xy 98.701998 -292.488134) (xy 98.74142 -292.455947) (xy 98.785494 -292.430501)
			(xy 98.83308 -292.412454) (xy 98.882944 -292.402274) (xy 98.933796 -292.400225) (xy 98.984317 -292.406359)
			(xy 99.033201 -292.420519) (xy 99.07918 -292.442336) (xy 99.121064 -292.471246) (xy 99.157768 -292.506501)
			(xy 99.188341 -292.547187) (xy 99.211992 -292.59225) (xy 99.228108 -292.640524) (xy 99.236272 -292.690758)
			(xy 99.236784 -292.716204) (xy 100.484935 -292.716204) (xy 100.48903 -292.665476) (xy 100.501209 -292.616062)
			(xy 100.521157 -292.569242) (xy 100.548358 -292.526228) (xy 100.582106 -292.488134) (xy 100.621528 -292.455947)
			(xy 100.665602 -292.430501) (xy 100.713188 -292.412454) (xy 100.763052 -292.402274) (xy 100.813904 -292.400225)
			(xy 100.864425 -292.406359) (xy 100.913309 -292.420519) (xy 100.959288 -292.442336) (xy 101.001172 -292.471246)
			(xy 101.037876 -292.506501) (xy 101.068449 -292.547187) (xy 101.0921 -292.59225) (xy 101.108216 -292.640524)
			(xy 101.11638 -292.690758) (xy 101.116892 -292.716204) (xy 101.424735 -292.716204) (xy 101.42883 -292.665476)
			(xy 101.441009 -292.616062) (xy 101.460957 -292.569242) (xy 101.488158 -292.526228) (xy 101.521906 -292.488134)
			(xy 101.561328 -292.455947) (xy 101.605402 -292.430501) (xy 101.652988 -292.412454) (xy 101.702852 -292.402274)
			(xy 101.753704 -292.400225) (xy 101.804225 -292.406359) (xy 101.853109 -292.420519) (xy 101.899088 -292.442336)
			(xy 101.940972 -292.471246) (xy 101.977676 -292.506501) (xy 102.008249 -292.547187) (xy 102.0319 -292.59225)
			(xy 102.048016 -292.640524) (xy 102.05618 -292.690758) (xy 102.056692 -292.716204) (xy 103.304843 -292.716204)
			(xy 103.308938 -292.665476) (xy 103.321117 -292.616062) (xy 103.341065 -292.569242) (xy 103.368266 -292.526228)
			(xy 103.402014 -292.488134) (xy 103.441436 -292.455947) (xy 103.48551 -292.430501) (xy 103.533096 -292.412454)
			(xy 103.58296 -292.402274) (xy 103.633812 -292.400225) (xy 103.684333 -292.406359) (xy 103.733217 -292.420519)
			(xy 103.779196 -292.442336) (xy 103.82108 -292.471246) (xy 103.857784 -292.506501) (xy 103.888357 -292.547187)
			(xy 103.912008 -292.59225) (xy 103.928124 -292.640524) (xy 103.936288 -292.690758) (xy 103.9368 -292.716204)
			(xy 104.244897 -292.716204) (xy 104.248992 -292.665476) (xy 104.261171 -292.616062) (xy 104.281119 -292.569242)
			(xy 104.30832 -292.526228) (xy 104.342068 -292.488134) (xy 104.38149 -292.455947) (xy 104.425564 -292.430501)
			(xy 104.47315 -292.412454) (xy 104.523014 -292.402274) (xy 104.573866 -292.400225) (xy 104.624387 -292.406359)
			(xy 104.673271 -292.420519) (xy 104.71925 -292.442336) (xy 104.761134 -292.471246) (xy 104.797838 -292.506501)
			(xy 104.828411 -292.547187) (xy 104.852062 -292.59225) (xy 104.868178 -292.640524) (xy 104.876342 -292.690758)
			(xy 104.876854 -292.716204) (xy 106.124751 -292.716204) (xy 106.128846 -292.665476) (xy 106.141025 -292.616062)
			(xy 106.160973 -292.569242) (xy 106.188174 -292.526228) (xy 106.221922 -292.488134) (xy 106.261344 -292.455947)
			(xy 106.305418 -292.430501) (xy 106.353004 -292.412454) (xy 106.402868 -292.402274) (xy 106.45372 -292.400225)
			(xy 106.504241 -292.406359) (xy 106.553125 -292.420519) (xy 106.599104 -292.442336) (xy 106.640988 -292.471246)
			(xy 106.677692 -292.506501) (xy 106.708265 -292.547187) (xy 106.731916 -292.59225) (xy 106.748032 -292.640524)
			(xy 106.756196 -292.690758) (xy 106.756708 -292.716204) (xy 107.064805 -292.716204) (xy 107.0689 -292.665476)
			(xy 107.081079 -292.616062) (xy 107.101027 -292.569242) (xy 107.128228 -292.526228) (xy 107.161976 -292.488134)
			(xy 107.201398 -292.455947) (xy 107.245472 -292.430501) (xy 107.293058 -292.412454) (xy 107.342922 -292.402274)
			(xy 107.393774 -292.400225) (xy 107.444295 -292.406359) (xy 107.493179 -292.420519) (xy 107.539158 -292.442336)
			(xy 107.581042 -292.471246) (xy 107.617746 -292.506501) (xy 107.648319 -292.547187) (xy 107.67197 -292.59225)
			(xy 107.688086 -292.640524) (xy 107.69625 -292.690758) (xy 107.696762 -292.716204) (xy 107.69625 -292.74165)
			(xy 107.688086 -292.791884) (xy 107.67197 -292.840158) (xy 107.648319 -292.885221) (xy 107.617746 -292.925907)
			(xy 107.581042 -292.961162) (xy 107.539158 -292.990072) (xy 107.493179 -293.011889) (xy 107.444295 -293.026049)
			(xy 107.393774 -293.032183) (xy 107.342922 -293.030134) (xy 107.293058 -293.019954) (xy 107.245472 -293.001907)
			(xy 107.201398 -292.976461) (xy 107.161976 -292.944274) (xy 107.128228 -292.90618) (xy 107.101027 -292.863166)
			(xy 107.081079 -292.816346) (xy 107.0689 -292.766932) (xy 107.064805 -292.716204) (xy 106.756708 -292.716204)
			(xy 106.756196 -292.74165) (xy 106.748032 -292.791884) (xy 106.731916 -292.840158) (xy 106.708265 -292.885221)
			(xy 106.677692 -292.925907) (xy 106.640988 -292.961162) (xy 106.599104 -292.990072) (xy 106.553125 -293.011889)
			(xy 106.504241 -293.026049) (xy 106.45372 -293.032183) (xy 106.402868 -293.030134) (xy 106.353004 -293.019954)
			(xy 106.305418 -293.001907) (xy 106.261344 -292.976461) (xy 106.221922 -292.944274) (xy 106.188174 -292.90618)
			(xy 106.160973 -292.863166) (xy 106.141025 -292.816346) (xy 106.128846 -292.766932) (xy 106.124751 -292.716204)
			(xy 104.876854 -292.716204) (xy 104.876342 -292.74165) (xy 104.868178 -292.791884) (xy 104.852062 -292.840158)
			(xy 104.828411 -292.885221) (xy 104.797838 -292.925907) (xy 104.761134 -292.961162) (xy 104.71925 -292.990072)
			(xy 104.673271 -293.011889) (xy 104.624387 -293.026049) (xy 104.573866 -293.032183) (xy 104.523014 -293.030134)
			(xy 104.47315 -293.019954) (xy 104.425564 -293.001907) (xy 104.38149 -292.976461) (xy 104.342068 -292.944274)
			(xy 104.30832 -292.90618) (xy 104.281119 -292.863166) (xy 104.261171 -292.816346) (xy 104.248992 -292.766932)
			(xy 104.244897 -292.716204) (xy 103.9368 -292.716204) (xy 103.936288 -292.74165) (xy 103.928124 -292.791884)
			(xy 103.912008 -292.840158) (xy 103.888357 -292.885221) (xy 103.857784 -292.925907) (xy 103.82108 -292.961162)
			(xy 103.779196 -292.990072) (xy 103.733217 -293.011889) (xy 103.684333 -293.026049) (xy 103.633812 -293.032183)
			(xy 103.58296 -293.030134) (xy 103.533096 -293.019954) (xy 103.48551 -293.001907) (xy 103.441436 -292.976461)
			(xy 103.402014 -292.944274) (xy 103.368266 -292.90618) (xy 103.341065 -292.863166) (xy 103.321117 -292.816346)
			(xy 103.308938 -292.766932) (xy 103.304843 -292.716204) (xy 102.056692 -292.716204) (xy 102.05618 -292.74165)
			(xy 102.048016 -292.791884) (xy 102.0319 -292.840158) (xy 102.008249 -292.885221) (xy 101.977676 -292.925907)
			(xy 101.940972 -292.961162) (xy 101.899088 -292.990072) (xy 101.853109 -293.011889) (xy 101.804225 -293.026049)
			(xy 101.753704 -293.032183) (xy 101.702852 -293.030134) (xy 101.652988 -293.019954) (xy 101.605402 -293.001907)
			(xy 101.561328 -292.976461) (xy 101.521906 -292.944274) (xy 101.488158 -292.90618) (xy 101.460957 -292.863166)
			(xy 101.441009 -292.816346) (xy 101.42883 -292.766932) (xy 101.424735 -292.716204) (xy 101.116892 -292.716204)
			(xy 101.11638 -292.74165) (xy 101.108216 -292.791884) (xy 101.0921 -292.840158) (xy 101.068449 -292.885221)
			(xy 101.037876 -292.925907) (xy 101.001172 -292.961162) (xy 100.959288 -292.990072) (xy 100.913309 -293.011889)
			(xy 100.864425 -293.026049) (xy 100.813904 -293.032183) (xy 100.763052 -293.030134) (xy 100.713188 -293.019954)
			(xy 100.665602 -293.001907) (xy 100.621528 -292.976461) (xy 100.582106 -292.944274) (xy 100.548358 -292.90618)
			(xy 100.521157 -292.863166) (xy 100.501209 -292.816346) (xy 100.48903 -292.766932) (xy 100.484935 -292.716204)
			(xy 99.236784 -292.716204) (xy 99.236272 -292.74165) (xy 99.228108 -292.791884) (xy 99.211992 -292.840158)
			(xy 99.188341 -292.885221) (xy 99.157768 -292.925907) (xy 99.121064 -292.961162) (xy 99.07918 -292.990072)
			(xy 99.033201 -293.011889) (xy 98.984317 -293.026049) (xy 98.933796 -293.032183) (xy 98.882944 -293.030134)
			(xy 98.83308 -293.019954) (xy 98.785494 -293.001907) (xy 98.74142 -292.976461) (xy 98.701998 -292.944274)
			(xy 98.66825 -292.90618) (xy 98.641049 -292.863166) (xy 98.621101 -292.816346) (xy 98.608922 -292.766932)
			(xy 98.604827 -292.716204) (xy 98.29673 -292.716204) (xy 98.296218 -292.74165) (xy 98.288054 -292.791884)
			(xy 98.271938 -292.840158) (xy 98.248287 -292.885221) (xy 98.217714 -292.925907) (xy 98.18101 -292.961162)
			(xy 98.139126 -292.990072) (xy 98.093147 -293.011889) (xy 98.044263 -293.026049) (xy 97.993742 -293.032183)
			(xy 97.94289 -293.030134) (xy 97.893026 -293.019954) (xy 97.84544 -293.001907) (xy 97.801366 -292.976461)
			(xy 97.761944 -292.944274) (xy 97.728196 -292.90618) (xy 97.700995 -292.863166) (xy 97.681047 -292.816346)
			(xy 97.668868 -292.766932) (xy 97.664773 -292.716204) (xy 96.416876 -292.716204) (xy 96.416364 -292.74165)
			(xy 96.4082 -292.791884) (xy 96.392084 -292.840158) (xy 96.368433 -292.885221) (xy 96.33786 -292.925907)
			(xy 96.301156 -292.961162) (xy 96.259272 -292.990072) (xy 96.213293 -293.011889) (xy 96.164409 -293.026049)
			(xy 96.113888 -293.032183) (xy 96.063036 -293.030134) (xy 96.013172 -293.019954) (xy 95.965586 -293.001907)
			(xy 95.921512 -292.976461) (xy 95.88209 -292.944274) (xy 95.848342 -292.90618) (xy 95.821141 -292.863166)
			(xy 95.801193 -292.816346) (xy 95.789014 -292.766932) (xy 95.784919 -292.716204) (xy 95.479108 -292.716204)
			(xy 95.478618 -292.741193) (xy 95.470799 -292.790556) (xy 95.455355 -292.838088) (xy 95.432665 -292.88262)
			(xy 95.403289 -292.923053) (xy 95.367949 -292.958393) (xy 95.327516 -292.987769) (xy 95.282984 -293.010459)
			(xy 95.235452 -293.025903) (xy 95.186089 -293.033722) (xy 95.136111 -293.033722) (xy 95.086748 -293.025903)
			(xy 95.039216 -293.010459) (xy 94.994684 -292.987769) (xy 94.954251 -292.958393) (xy 94.918911 -292.923053)
			(xy 94.889535 -292.88262) (xy 94.866845 -292.838088) (xy 94.851401 -292.790556) (xy 94.843582 -292.741193)
			(xy 94.536265 -292.741193) (xy 94.536256 -292.74165) (xy 94.528092 -292.791884) (xy 94.511976 -292.840158)
			(xy 94.488325 -292.885221) (xy 94.457752 -292.925907) (xy 94.421048 -292.961162) (xy 94.379164 -292.990072)
			(xy 94.333185 -293.011889) (xy 94.284301 -293.026049) (xy 94.23378 -293.032183) (xy 94.182928 -293.030134)
			(xy 94.133064 -293.019954) (xy 94.085478 -293.001907) (xy 94.041404 -292.976461) (xy 94.001982 -292.944274)
			(xy 93.968234 -292.90618) (xy 93.941033 -292.863166) (xy 93.921085 -292.816346) (xy 93.908906 -292.766932)
			(xy 93.904811 -292.716204) (xy 93.599 -292.716204) (xy 93.59851 -292.741193) (xy 93.590691 -292.790556)
			(xy 93.575247 -292.838088) (xy 93.552557 -292.88262) (xy 93.523181 -292.923053) (xy 93.487841 -292.958393)
			(xy 93.447408 -292.987769) (xy 93.402876 -293.010459) (xy 93.355344 -293.025903) (xy 93.305981 -293.033722)
			(xy 93.256003 -293.033722) (xy 93.20664 -293.025903) (xy 93.159108 -293.010459) (xy 93.114576 -292.987769)
			(xy 93.074143 -292.958393) (xy 93.038803 -292.923053) (xy 93.009427 -292.88262) (xy 92.986737 -292.838088)
			(xy 92.971293 -292.790556) (xy 92.963474 -292.741193) (xy 92.656157 -292.741193) (xy 92.656148 -292.74165)
			(xy 92.647984 -292.791884) (xy 92.631868 -292.840158) (xy 92.608217 -292.885221) (xy 92.577644 -292.925907)
			(xy 92.54094 -292.961162) (xy 92.499056 -292.990072) (xy 92.453077 -293.011889) (xy 92.404193 -293.026049)
			(xy 92.353672 -293.032183) (xy 92.30282 -293.030134) (xy 92.252956 -293.019954) (xy 92.20537 -293.001907)
			(xy 92.161296 -292.976461) (xy 92.121874 -292.944274) (xy 92.088126 -292.90618) (xy 92.060925 -292.863166)
			(xy 92.040977 -292.816346) (xy 92.028798 -292.766932) (xy 92.024703 -292.716204) (xy 91.861386 -292.716204)
			(xy 91.861386 -293.179246) (xy 91.88704 -293.207948) (xy 91.906598 -293.210234) (xy 91.932162 -293.213617)
			(xy 91.981798 -293.227583) (xy 92.028531 -293.249374) (xy 92.071135 -293.278421) (xy 92.108494 -293.313961)
			(xy 92.139628 -293.355064) (xy 92.163722 -293.400653) (xy 92.180145 -293.449531) (xy 92.188465 -293.500419)
			(xy 92.188465 -293.551199) (xy 92.493574 -293.551199) (xy 92.493574 -293.501221) (xy 92.501393 -293.451858)
			(xy 92.516837 -293.404326) (xy 92.539527 -293.359794) (xy 92.568903 -293.319361) (xy 92.604243 -293.284021)
			(xy 92.644676 -293.254645) (xy 92.689208 -293.231955) (xy 92.73674 -293.216511) (xy 92.786103 -293.208692)
			(xy 92.836081 -293.208692) (xy 92.885444 -293.216511) (xy 92.932976 -293.231955) (xy 92.977508 -293.254645)
			(xy 93.017941 -293.284021) (xy 93.053281 -293.319361) (xy 93.082657 -293.359794) (xy 93.105347 -293.404326)
			(xy 93.120791 -293.451858) (xy 93.12861 -293.501221) (xy 93.1291 -293.52621) (xy 93.12861 -293.551199)
			(xy 93.433628 -293.551199) (xy 93.433628 -293.501221) (xy 93.441447 -293.451858) (xy 93.456891 -293.404326)
			(xy 93.479581 -293.359794) (xy 93.508957 -293.319361) (xy 93.544297 -293.284021) (xy 93.58473 -293.254645)
			(xy 93.629262 -293.231955) (xy 93.676794 -293.216511) (xy 93.726157 -293.208692) (xy 93.776135 -293.208692)
			(xy 93.825498 -293.216511) (xy 93.87303 -293.231955) (xy 93.917562 -293.254645) (xy 93.957995 -293.284021)
			(xy 93.993335 -293.319361) (xy 94.022711 -293.359794) (xy 94.045401 -293.404326) (xy 94.060845 -293.451858)
			(xy 94.068664 -293.501221) (xy 94.069154 -293.52621) (xy 94.068664 -293.551199) (xy 94.373428 -293.551199)
			(xy 94.373428 -293.501221) (xy 94.381247 -293.451858) (xy 94.396691 -293.404326) (xy 94.419381 -293.359794)
			(xy 94.448757 -293.319361) (xy 94.484097 -293.284021) (xy 94.52453 -293.254645) (xy 94.569062 -293.231955)
			(xy 94.616594 -293.216511) (xy 94.665957 -293.208692) (xy 94.715935 -293.208692) (xy 94.765298 -293.216511)
			(xy 94.81283 -293.231955) (xy 94.857362 -293.254645) (xy 94.897795 -293.284021) (xy 94.933135 -293.319361)
			(xy 94.962511 -293.359794) (xy 94.985201 -293.404326) (xy 95.000645 -293.451858) (xy 95.008464 -293.501221)
			(xy 95.008954 -293.52621) (xy 95.314765 -293.52621) (xy 95.31886 -293.475482) (xy 95.331039 -293.426068)
			(xy 95.350987 -293.379248) (xy 95.378188 -293.336234) (xy 95.411936 -293.29814) (xy 95.451358 -293.265953)
			(xy 95.495432 -293.240507) (xy 95.543018 -293.22246) (xy 95.592882 -293.21228) (xy 95.643734 -293.210231)
			(xy 95.694255 -293.216365) (xy 95.743139 -293.230525) (xy 95.789118 -293.252342) (xy 95.831002 -293.281252)
			(xy 95.867706 -293.316507) (xy 95.898279 -293.357193) (xy 95.92193 -293.402256) (xy 95.938046 -293.45053)
			(xy 95.94621 -293.500764) (xy 95.946722 -293.52621) (xy 95.946219 -293.551199) (xy 96.253536 -293.551199)
			(xy 96.253536 -293.501221) (xy 96.261355 -293.451858) (xy 96.276799 -293.404326) (xy 96.299489 -293.359794)
			(xy 96.328865 -293.319361) (xy 96.364205 -293.284021) (xy 96.404638 -293.254645) (xy 96.44917 -293.231955)
			(xy 96.496702 -293.216511) (xy 96.546065 -293.208692) (xy 96.596043 -293.208692) (xy 96.645406 -293.216511)
			(xy 96.692938 -293.231955) (xy 96.73747 -293.254645) (xy 96.777903 -293.284021) (xy 96.813243 -293.319361)
			(xy 96.842619 -293.359794) (xy 96.865309 -293.404326) (xy 96.880753 -293.451858) (xy 96.888572 -293.501221)
			(xy 96.889062 -293.52621) (xy 96.888572 -293.551199) (xy 97.19359 -293.551199) (xy 97.19359 -293.501221)
			(xy 97.201409 -293.451858) (xy 97.216853 -293.404326) (xy 97.239543 -293.359794) (xy 97.268919 -293.319361)
			(xy 97.304259 -293.284021) (xy 97.344692 -293.254645) (xy 97.389224 -293.231955) (xy 97.436756 -293.216511)
			(xy 97.486119 -293.208692) (xy 97.536097 -293.208692) (xy 97.58546 -293.216511) (xy 97.632992 -293.231955)
			(xy 97.677524 -293.254645) (xy 97.717957 -293.284021) (xy 97.753297 -293.319361) (xy 97.782673 -293.359794)
			(xy 97.805363 -293.404326) (xy 97.820807 -293.451858) (xy 97.828626 -293.501221) (xy 97.829116 -293.52621)
			(xy 97.828626 -293.551199) (xy 98.133644 -293.551199) (xy 98.133644 -293.501221) (xy 98.141463 -293.451858)
			(xy 98.156907 -293.404326) (xy 98.179597 -293.359794) (xy 98.208973 -293.319361) (xy 98.244313 -293.284021)
			(xy 98.284746 -293.254645) (xy 98.329278 -293.231955) (xy 98.37681 -293.216511) (xy 98.426173 -293.208692)
			(xy 98.476151 -293.208692) (xy 98.525514 -293.216511) (xy 98.573046 -293.231955) (xy 98.617578 -293.254645)
			(xy 98.658011 -293.284021) (xy 98.693351 -293.319361) (xy 98.722727 -293.359794) (xy 98.745417 -293.404326)
			(xy 98.760861 -293.451858) (xy 98.76868 -293.501221) (xy 98.76917 -293.52621) (xy 98.76868 -293.551199)
			(xy 99.073444 -293.551199) (xy 99.073444 -293.501221) (xy 99.081263 -293.451858) (xy 99.096707 -293.404326)
			(xy 99.119397 -293.359794) (xy 99.148773 -293.319361) (xy 99.184113 -293.284021) (xy 99.224546 -293.254645)
			(xy 99.269078 -293.231955) (xy 99.31661 -293.216511) (xy 99.365973 -293.208692) (xy 99.415951 -293.208692)
			(xy 99.465314 -293.216511) (xy 99.512846 -293.231955) (xy 99.557378 -293.254645) (xy 99.597811 -293.284021)
			(xy 99.633151 -293.319361) (xy 99.662527 -293.359794) (xy 99.685217 -293.404326) (xy 99.700661 -293.451858)
			(xy 99.70848 -293.501221) (xy 99.70897 -293.52621) (xy 99.70848 -293.551199) (xy 100.013498 -293.551199)
			(xy 100.013498 -293.501221) (xy 100.021317 -293.451858) (xy 100.036761 -293.404326) (xy 100.059451 -293.359794)
			(xy 100.088827 -293.319361) (xy 100.124167 -293.284021) (xy 100.1646 -293.254645) (xy 100.209132 -293.231955)
			(xy 100.256664 -293.216511) (xy 100.306027 -293.208692) (xy 100.356005 -293.208692) (xy 100.405368 -293.216511)
			(xy 100.4529 -293.231955) (xy 100.497432 -293.254645) (xy 100.537865 -293.284021) (xy 100.573205 -293.319361)
			(xy 100.602581 -293.359794) (xy 100.625271 -293.404326) (xy 100.640715 -293.451858) (xy 100.648534 -293.501221)
			(xy 100.649024 -293.52621) (xy 100.648534 -293.551199) (xy 100.953552 -293.551199) (xy 100.953552 -293.501221)
			(xy 100.961371 -293.451858) (xy 100.976815 -293.404326) (xy 100.999505 -293.359794) (xy 101.028881 -293.319361)
			(xy 101.064221 -293.284021) (xy 101.104654 -293.254645) (xy 101.149186 -293.231955) (xy 101.196718 -293.216511)
			(xy 101.246081 -293.208692) (xy 101.296059 -293.208692) (xy 101.345422 -293.216511) (xy 101.392954 -293.231955)
			(xy 101.437486 -293.254645) (xy 101.477919 -293.284021) (xy 101.513259 -293.319361) (xy 101.542635 -293.359794)
			(xy 101.565325 -293.404326) (xy 101.580769 -293.451858) (xy 101.588588 -293.501221) (xy 101.589078 -293.52621)
			(xy 101.588588 -293.551199) (xy 101.893606 -293.551199) (xy 101.893606 -293.501221) (xy 101.901425 -293.451858)
			(xy 101.916869 -293.404326) (xy 101.939559 -293.359794) (xy 101.968935 -293.319361) (xy 102.004275 -293.284021)
			(xy 102.044708 -293.254645) (xy 102.08924 -293.231955) (xy 102.136772 -293.216511) (xy 102.186135 -293.208692)
			(xy 102.236113 -293.208692) (xy 102.285476 -293.216511) (xy 102.333008 -293.231955) (xy 102.37754 -293.254645)
			(xy 102.417973 -293.284021) (xy 102.453313 -293.319361) (xy 102.482689 -293.359794) (xy 102.505379 -293.404326)
			(xy 102.520823 -293.451858) (xy 102.528642 -293.501221) (xy 102.529132 -293.52621) (xy 102.528642 -293.551199)
			(xy 102.83366 -293.551199) (xy 102.83366 -293.501221) (xy 102.841479 -293.451858) (xy 102.856923 -293.404326)
			(xy 102.879613 -293.359794) (xy 102.908989 -293.319361) (xy 102.944329 -293.284021) (xy 102.984762 -293.254645)
			(xy 103.029294 -293.231955) (xy 103.076826 -293.216511) (xy 103.126189 -293.208692) (xy 103.176167 -293.208692)
			(xy 103.22553 -293.216511) (xy 103.273062 -293.231955) (xy 103.317594 -293.254645) (xy 103.358027 -293.284021)
			(xy 103.393367 -293.319361) (xy 103.422743 -293.359794) (xy 103.445433 -293.404326) (xy 103.460877 -293.451858)
			(xy 103.468696 -293.501221) (xy 103.469186 -293.52621) (xy 103.468696 -293.551199) (xy 103.77346 -293.551199)
			(xy 103.77346 -293.501221) (xy 103.781279 -293.451858) (xy 103.796723 -293.404326) (xy 103.819413 -293.359794)
			(xy 103.848789 -293.319361) (xy 103.884129 -293.284021) (xy 103.924562 -293.254645) (xy 103.969094 -293.231955)
			(xy 104.016626 -293.216511) (xy 104.065989 -293.208692) (xy 104.115967 -293.208692) (xy 104.16533 -293.216511)
			(xy 104.212862 -293.231955) (xy 104.257394 -293.254645) (xy 104.297827 -293.284021) (xy 104.333167 -293.319361)
			(xy 104.362543 -293.359794) (xy 104.385233 -293.404326) (xy 104.400677 -293.451858) (xy 104.408496 -293.501221)
			(xy 104.408986 -293.52621) (xy 104.408496 -293.551199) (xy 104.713514 -293.551199) (xy 104.713514 -293.501221)
			(xy 104.721333 -293.451858) (xy 104.736777 -293.404326) (xy 104.759467 -293.359794) (xy 104.788843 -293.319361)
			(xy 104.824183 -293.284021) (xy 104.864616 -293.254645) (xy 104.909148 -293.231955) (xy 104.95668 -293.216511)
			(xy 105.006043 -293.208692) (xy 105.056021 -293.208692) (xy 105.105384 -293.216511) (xy 105.152916 -293.231955)
			(xy 105.197448 -293.254645) (xy 105.237881 -293.284021) (xy 105.273221 -293.319361) (xy 105.302597 -293.359794)
			(xy 105.325287 -293.404326) (xy 105.340731 -293.451858) (xy 105.34855 -293.501221) (xy 105.34904 -293.52621)
			(xy 105.34855 -293.551199) (xy 105.653568 -293.551199) (xy 105.653568 -293.501221) (xy 105.661387 -293.451858)
			(xy 105.676831 -293.404326) (xy 105.699521 -293.359794) (xy 105.728897 -293.319361) (xy 105.764237 -293.284021)
			(xy 105.80467 -293.254645) (xy 105.849202 -293.231955) (xy 105.896734 -293.216511) (xy 105.946097 -293.208692)
			(xy 105.996075 -293.208692) (xy 106.045438 -293.216511) (xy 106.09297 -293.231955) (xy 106.137502 -293.254645)
			(xy 106.177935 -293.284021) (xy 106.213275 -293.319361) (xy 106.242651 -293.359794) (xy 106.265341 -293.404326)
			(xy 106.280785 -293.451858) (xy 106.288604 -293.501221) (xy 106.289094 -293.52621) (xy 106.288604 -293.551199)
			(xy 106.593622 -293.551199) (xy 106.593622 -293.501221) (xy 106.601441 -293.451858) (xy 106.616885 -293.404326)
			(xy 106.639575 -293.359794) (xy 106.668951 -293.319361) (xy 106.704291 -293.284021) (xy 106.744724 -293.254645)
			(xy 106.789256 -293.231955) (xy 106.836788 -293.216511) (xy 106.886151 -293.208692) (xy 106.936129 -293.208692)
			(xy 106.985492 -293.216511) (xy 107.033024 -293.231955) (xy 107.077556 -293.254645) (xy 107.117989 -293.284021)
			(xy 107.153329 -293.319361) (xy 107.182705 -293.359794) (xy 107.205395 -293.404326) (xy 107.220839 -293.451858)
			(xy 107.228658 -293.501221) (xy 107.229148 -293.52621) (xy 107.228658 -293.551199) (xy 107.533422 -293.551199)
			(xy 107.533422 -293.501221) (xy 107.541241 -293.451858) (xy 107.556685 -293.404326) (xy 107.579375 -293.359794)
			(xy 107.608751 -293.319361) (xy 107.644091 -293.284021) (xy 107.684524 -293.254645) (xy 107.729056 -293.231955)
			(xy 107.776588 -293.216511) (xy 107.825951 -293.208692) (xy 107.875929 -293.208692) (xy 107.925292 -293.216511)
			(xy 107.972824 -293.231955) (xy 108.017356 -293.254645) (xy 108.057789 -293.284021) (xy 108.093129 -293.319361)
			(xy 108.122505 -293.359794) (xy 108.145195 -293.404326) (xy 108.160639 -293.451858) (xy 108.168458 -293.501221)
			(xy 108.168948 -293.52621) (xy 108.168458 -293.551199) (xy 108.160639 -293.600562) (xy 108.145195 -293.648094)
			(xy 108.122505 -293.692626) (xy 108.093129 -293.733059) (xy 108.057789 -293.768399) (xy 108.017356 -293.797775)
			(xy 107.972824 -293.820465) (xy 107.925292 -293.835909) (xy 107.875929 -293.843728) (xy 107.825951 -293.843728)
			(xy 107.776588 -293.835909) (xy 107.729056 -293.820465) (xy 107.684524 -293.797775) (xy 107.644091 -293.768399)
			(xy 107.608751 -293.733059) (xy 107.579375 -293.692626) (xy 107.556685 -293.648094) (xy 107.541241 -293.600562)
			(xy 107.533422 -293.551199) (xy 107.228658 -293.551199) (xy 107.220839 -293.600562) (xy 107.205395 -293.648094)
			(xy 107.182705 -293.692626) (xy 107.153329 -293.733059) (xy 107.117989 -293.768399) (xy 107.077556 -293.797775)
			(xy 107.033024 -293.820465) (xy 106.985492 -293.835909) (xy 106.936129 -293.843728) (xy 106.886151 -293.843728)
			(xy 106.836788 -293.835909) (xy 106.789256 -293.820465) (xy 106.744724 -293.797775) (xy 106.704291 -293.768399)
			(xy 106.668951 -293.733059) (xy 106.639575 -293.692626) (xy 106.616885 -293.648094) (xy 106.601441 -293.600562)
			(xy 106.593622 -293.551199) (xy 106.288604 -293.551199) (xy 106.280785 -293.600562) (xy 106.265341 -293.648094)
			(xy 106.242651 -293.692626) (xy 106.213275 -293.733059) (xy 106.177935 -293.768399) (xy 106.137502 -293.797775)
			(xy 106.09297 -293.820465) (xy 106.045438 -293.835909) (xy 105.996075 -293.843728) (xy 105.946097 -293.843728)
			(xy 105.896734 -293.835909) (xy 105.849202 -293.820465) (xy 105.80467 -293.797775) (xy 105.764237 -293.768399)
			(xy 105.728897 -293.733059) (xy 105.699521 -293.692626) (xy 105.676831 -293.648094) (xy 105.661387 -293.600562)
			(xy 105.653568 -293.551199) (xy 105.34855 -293.551199) (xy 105.340731 -293.600562) (xy 105.325287 -293.648094)
			(xy 105.302597 -293.692626) (xy 105.273221 -293.733059) (xy 105.237881 -293.768399) (xy 105.197448 -293.797775)
			(xy 105.152916 -293.820465) (xy 105.105384 -293.835909) (xy 105.056021 -293.843728) (xy 105.006043 -293.843728)
			(xy 104.95668 -293.835909) (xy 104.909148 -293.820465) (xy 104.864616 -293.797775) (xy 104.824183 -293.768399)
			(xy 104.788843 -293.733059) (xy 104.759467 -293.692626) (xy 104.736777 -293.648094) (xy 104.721333 -293.600562)
			(xy 104.713514 -293.551199) (xy 104.408496 -293.551199) (xy 104.400677 -293.600562) (xy 104.385233 -293.648094)
			(xy 104.362543 -293.692626) (xy 104.333167 -293.733059) (xy 104.297827 -293.768399) (xy 104.257394 -293.797775)
			(xy 104.212862 -293.820465) (xy 104.16533 -293.835909) (xy 104.115967 -293.843728) (xy 104.065989 -293.843728)
			(xy 104.016626 -293.835909) (xy 103.969094 -293.820465) (xy 103.924562 -293.797775) (xy 103.884129 -293.768399)
			(xy 103.848789 -293.733059) (xy 103.819413 -293.692626) (xy 103.796723 -293.648094) (xy 103.781279 -293.600562)
			(xy 103.77346 -293.551199) (xy 103.468696 -293.551199) (xy 103.460877 -293.600562) (xy 103.445433 -293.648094)
			(xy 103.422743 -293.692626) (xy 103.393367 -293.733059) (xy 103.358027 -293.768399) (xy 103.317594 -293.797775)
			(xy 103.273062 -293.820465) (xy 103.22553 -293.835909) (xy 103.176167 -293.843728) (xy 103.126189 -293.843728)
			(xy 103.076826 -293.835909) (xy 103.029294 -293.820465) (xy 102.984762 -293.797775) (xy 102.944329 -293.768399)
			(xy 102.908989 -293.733059) (xy 102.879613 -293.692626) (xy 102.856923 -293.648094) (xy 102.841479 -293.600562)
			(xy 102.83366 -293.551199) (xy 102.528642 -293.551199) (xy 102.520823 -293.600562) (xy 102.505379 -293.648094)
			(xy 102.482689 -293.692626) (xy 102.453313 -293.733059) (xy 102.417973 -293.768399) (xy 102.37754 -293.797775)
			(xy 102.333008 -293.820465) (xy 102.285476 -293.835909) (xy 102.236113 -293.843728) (xy 102.186135 -293.843728)
			(xy 102.136772 -293.835909) (xy 102.08924 -293.820465) (xy 102.044708 -293.797775) (xy 102.004275 -293.768399)
			(xy 101.968935 -293.733059) (xy 101.939559 -293.692626) (xy 101.916869 -293.648094) (xy 101.901425 -293.600562)
			(xy 101.893606 -293.551199) (xy 101.588588 -293.551199) (xy 101.580769 -293.600562) (xy 101.565325 -293.648094)
			(xy 101.542635 -293.692626) (xy 101.513259 -293.733059) (xy 101.477919 -293.768399) (xy 101.437486 -293.797775)
			(xy 101.392954 -293.820465) (xy 101.345422 -293.835909) (xy 101.296059 -293.843728) (xy 101.246081 -293.843728)
			(xy 101.196718 -293.835909) (xy 101.149186 -293.820465) (xy 101.104654 -293.797775) (xy 101.064221 -293.768399)
			(xy 101.028881 -293.733059) (xy 100.999505 -293.692626) (xy 100.976815 -293.648094) (xy 100.961371 -293.600562)
			(xy 100.953552 -293.551199) (xy 100.648534 -293.551199) (xy 100.640715 -293.600562) (xy 100.625271 -293.648094)
			(xy 100.602581 -293.692626) (xy 100.573205 -293.733059) (xy 100.537865 -293.768399) (xy 100.497432 -293.797775)
			(xy 100.4529 -293.820465) (xy 100.405368 -293.835909) (xy 100.356005 -293.843728) (xy 100.306027 -293.843728)
			(xy 100.256664 -293.835909) (xy 100.209132 -293.820465) (xy 100.1646 -293.797775) (xy 100.124167 -293.768399)
			(xy 100.088827 -293.733059) (xy 100.059451 -293.692626) (xy 100.036761 -293.648094) (xy 100.021317 -293.600562)
			(xy 100.013498 -293.551199) (xy 99.70848 -293.551199) (xy 99.700661 -293.600562) (xy 99.685217 -293.648094)
			(xy 99.662527 -293.692626) (xy 99.633151 -293.733059) (xy 99.597811 -293.768399) (xy 99.557378 -293.797775)
			(xy 99.512846 -293.820465) (xy 99.465314 -293.835909) (xy 99.415951 -293.843728) (xy 99.365973 -293.843728)
			(xy 99.31661 -293.835909) (xy 99.269078 -293.820465) (xy 99.224546 -293.797775) (xy 99.184113 -293.768399)
			(xy 99.148773 -293.733059) (xy 99.119397 -293.692626) (xy 99.096707 -293.648094) (xy 99.081263 -293.600562)
			(xy 99.073444 -293.551199) (xy 98.76868 -293.551199) (xy 98.760861 -293.600562) (xy 98.745417 -293.648094)
			(xy 98.722727 -293.692626) (xy 98.693351 -293.733059) (xy 98.658011 -293.768399) (xy 98.617578 -293.797775)
			(xy 98.573046 -293.820465) (xy 98.525514 -293.835909) (xy 98.476151 -293.843728) (xy 98.426173 -293.843728)
			(xy 98.37681 -293.835909) (xy 98.329278 -293.820465) (xy 98.284746 -293.797775) (xy 98.244313 -293.768399)
			(xy 98.208973 -293.733059) (xy 98.179597 -293.692626) (xy 98.156907 -293.648094) (xy 98.141463 -293.600562)
			(xy 98.133644 -293.551199) (xy 97.828626 -293.551199) (xy 97.820807 -293.600562) (xy 97.805363 -293.648094)
			(xy 97.782673 -293.692626) (xy 97.753297 -293.733059) (xy 97.717957 -293.768399) (xy 97.677524 -293.797775)
			(xy 97.632992 -293.820465) (xy 97.58546 -293.835909) (xy 97.536097 -293.843728) (xy 97.486119 -293.843728)
			(xy 97.436756 -293.835909) (xy 97.389224 -293.820465) (xy 97.344692 -293.797775) (xy 97.304259 -293.768399)
			(xy 97.268919 -293.733059) (xy 97.239543 -293.692626) (xy 97.216853 -293.648094) (xy 97.201409 -293.600562)
			(xy 97.19359 -293.551199) (xy 96.888572 -293.551199) (xy 96.880753 -293.600562) (xy 96.865309 -293.648094)
			(xy 96.842619 -293.692626) (xy 96.813243 -293.733059) (xy 96.777903 -293.768399) (xy 96.73747 -293.797775)
			(xy 96.692938 -293.820465) (xy 96.645406 -293.835909) (xy 96.596043 -293.843728) (xy 96.546065 -293.843728)
			(xy 96.496702 -293.835909) (xy 96.44917 -293.820465) (xy 96.404638 -293.797775) (xy 96.364205 -293.768399)
			(xy 96.328865 -293.733059) (xy 96.299489 -293.692626) (xy 96.276799 -293.648094) (xy 96.261355 -293.600562)
			(xy 96.253536 -293.551199) (xy 95.946219 -293.551199) (xy 95.94621 -293.551656) (xy 95.938046 -293.60189)
			(xy 95.92193 -293.650164) (xy 95.898279 -293.695227) (xy 95.867706 -293.735913) (xy 95.831002 -293.771168)
			(xy 95.789118 -293.800078) (xy 95.743139 -293.821895) (xy 95.694255 -293.836055) (xy 95.643734 -293.842189)
			(xy 95.592882 -293.84014) (xy 95.543018 -293.82996) (xy 95.495432 -293.811913) (xy 95.451358 -293.786467)
			(xy 95.411936 -293.75428) (xy 95.378188 -293.716186) (xy 95.350987 -293.673172) (xy 95.331039 -293.626352)
			(xy 95.31886 -293.576938) (xy 95.314765 -293.52621) (xy 95.008954 -293.52621) (xy 95.008464 -293.551199)
			(xy 95.000645 -293.600562) (xy 94.985201 -293.648094) (xy 94.962511 -293.692626) (xy 94.933135 -293.733059)
			(xy 94.897795 -293.768399) (xy 94.857362 -293.797775) (xy 94.81283 -293.820465) (xy 94.765298 -293.835909)
			(xy 94.715935 -293.843728) (xy 94.665957 -293.843728) (xy 94.616594 -293.835909) (xy 94.569062 -293.820465)
			(xy 94.52453 -293.797775) (xy 94.484097 -293.768399) (xy 94.448757 -293.733059) (xy 94.419381 -293.692626)
			(xy 94.396691 -293.648094) (xy 94.381247 -293.600562) (xy 94.373428 -293.551199) (xy 94.068664 -293.551199)
			(xy 94.060845 -293.600562) (xy 94.045401 -293.648094) (xy 94.022711 -293.692626) (xy 93.993335 -293.733059)
			(xy 93.957995 -293.768399) (xy 93.917562 -293.797775) (xy 93.87303 -293.820465) (xy 93.825498 -293.835909)
			(xy 93.776135 -293.843728) (xy 93.726157 -293.843728) (xy 93.676794 -293.835909) (xy 93.629262 -293.820465)
			(xy 93.58473 -293.797775) (xy 93.544297 -293.768399) (xy 93.508957 -293.733059) (xy 93.479581 -293.692626)
			(xy 93.456891 -293.648094) (xy 93.441447 -293.600562) (xy 93.433628 -293.551199) (xy 93.12861 -293.551199)
			(xy 93.120791 -293.600562) (xy 93.105347 -293.648094) (xy 93.082657 -293.692626) (xy 93.053281 -293.733059)
			(xy 93.017941 -293.768399) (xy 92.977508 -293.797775) (xy 92.932976 -293.820465) (xy 92.885444 -293.835909)
			(xy 92.836081 -293.843728) (xy 92.786103 -293.843728) (xy 92.73674 -293.835909) (xy 92.689208 -293.820465)
			(xy 92.644676 -293.797775) (xy 92.604243 -293.768399) (xy 92.568903 -293.733059) (xy 92.539527 -293.692626)
			(xy 92.516837 -293.648094) (xy 92.501393 -293.600562) (xy 92.493574 -293.551199) (xy 92.188465 -293.551199)
			(xy 92.188465 -293.551983) (xy 92.180144 -293.602871) (xy 92.163722 -293.651749) (xy 92.139627 -293.697338)
			(xy 92.108492 -293.73844) (xy 92.071133 -293.773981) (xy 92.028529 -293.803027) (xy 91.981796 -293.824818)
			(xy 91.93216 -293.838783) (xy 91.906598 -293.842186) (xy 91.88704 -293.844472) (xy 91.861386 -293.873174)
			(xy 91.861386 -294.361205) (xy 92.02342 -294.361205) (xy 92.02342 -294.311227) (xy 92.031239 -294.261864)
			(xy 92.046683 -294.214332) (xy 92.069373 -294.1698) (xy 92.098749 -294.129367) (xy 92.134089 -294.094027)
			(xy 92.174522 -294.064651) (xy 92.219054 -294.041961) (xy 92.266586 -294.026517) (xy 92.315949 -294.018698)
			(xy 92.365927 -294.018698) (xy 92.41529 -294.026517) (xy 92.462822 -294.041961) (xy 92.507354 -294.064651)
			(xy 92.547787 -294.094027) (xy 92.583127 -294.129367) (xy 92.612503 -294.1698) (xy 92.635193 -294.214332)
			(xy 92.650637 -294.261864) (xy 92.658456 -294.311227) (xy 92.658946 -294.336216) (xy 92.658456 -294.361205)
			(xy 92.963474 -294.361205) (xy 92.963474 -294.311227) (xy 92.971293 -294.261864) (xy 92.986737 -294.214332)
			(xy 93.009427 -294.1698) (xy 93.038803 -294.129367) (xy 93.074143 -294.094027) (xy 93.114576 -294.064651)
			(xy 93.159108 -294.041961) (xy 93.20664 -294.026517) (xy 93.256003 -294.018698) (xy 93.305981 -294.018698)
			(xy 93.355344 -294.026517) (xy 93.402876 -294.041961) (xy 93.447408 -294.064651) (xy 93.487841 -294.094027)
			(xy 93.523181 -294.129367) (xy 93.552557 -294.1698) (xy 93.575247 -294.214332) (xy 93.590691 -294.261864)
			(xy 93.59851 -294.311227) (xy 93.599 -294.336216) (xy 93.59851 -294.361205) (xy 94.843582 -294.361205)
			(xy 94.843582 -294.311227) (xy 94.851401 -294.261864) (xy 94.866845 -294.214332) (xy 94.889535 -294.1698)
			(xy 94.918911 -294.129367) (xy 94.954251 -294.094027) (xy 94.994684 -294.064651) (xy 95.039216 -294.041961)
			(xy 95.086748 -294.026517) (xy 95.136111 -294.018698) (xy 95.186089 -294.018698) (xy 95.235452 -294.026517)
			(xy 95.282984 -294.041961) (xy 95.327516 -294.064651) (xy 95.367949 -294.094027) (xy 95.403289 -294.129367)
			(xy 95.432665 -294.1698) (xy 95.455355 -294.214332) (xy 95.470799 -294.261864) (xy 95.478618 -294.311227)
			(xy 95.479108 -294.336216) (xy 95.478618 -294.361205) (xy 95.783636 -294.361205) (xy 95.783636 -294.311227)
			(xy 95.791455 -294.261864) (xy 95.806899 -294.214332) (xy 95.829589 -294.1698) (xy 95.858965 -294.129367)
			(xy 95.894305 -294.094027) (xy 95.934738 -294.064651) (xy 95.97927 -294.041961) (xy 96.026802 -294.026517)
			(xy 96.076165 -294.018698) (xy 96.126143 -294.018698) (xy 96.175506 -294.026517) (xy 96.223038 -294.041961)
			(xy 96.26757 -294.064651) (xy 96.308003 -294.094027) (xy 96.343343 -294.129367) (xy 96.372719 -294.1698)
			(xy 96.395409 -294.214332) (xy 96.410853 -294.261864) (xy 96.418672 -294.311227) (xy 96.419162 -294.336216)
			(xy 96.724719 -294.336216) (xy 96.728814 -294.285488) (xy 96.740993 -294.236074) (xy 96.760941 -294.189254)
			(xy 96.788142 -294.14624) (xy 96.82189 -294.108146) (xy 96.861312 -294.075959) (xy 96.905386 -294.050513)
			(xy 96.952972 -294.032466) (xy 97.002836 -294.022286) (xy 97.053688 -294.020237) (xy 97.104209 -294.026371)
			(xy 97.153093 -294.040531) (xy 97.199072 -294.062348) (xy 97.240956 -294.091258) (xy 97.27766 -294.126513)
			(xy 97.308233 -294.167199) (xy 97.331884 -294.212262) (xy 97.348 -294.260536) (xy 97.356164 -294.31077)
			(xy 97.356676 -294.336216) (xy 97.664773 -294.336216) (xy 97.668868 -294.285488) (xy 97.681047 -294.236074)
			(xy 97.700995 -294.189254) (xy 97.728196 -294.14624) (xy 97.761944 -294.108146) (xy 97.801366 -294.075959)
			(xy 97.84544 -294.050513) (xy 97.893026 -294.032466) (xy 97.94289 -294.022286) (xy 97.993742 -294.020237)
			(xy 98.044263 -294.026371) (xy 98.093147 -294.040531) (xy 98.139126 -294.062348) (xy 98.18101 -294.091258)
			(xy 98.217714 -294.126513) (xy 98.248287 -294.167199) (xy 98.271938 -294.212262) (xy 98.288054 -294.260536)
			(xy 98.296218 -294.31077) (xy 98.29673 -294.336216) (xy 98.296227 -294.361205) (xy 98.603544 -294.361205)
			(xy 98.603544 -294.311227) (xy 98.611363 -294.261864) (xy 98.626807 -294.214332) (xy 98.649497 -294.1698)
			(xy 98.678873 -294.129367) (xy 98.714213 -294.094027) (xy 98.754646 -294.064651) (xy 98.799178 -294.041961)
			(xy 98.84671 -294.026517) (xy 98.896073 -294.018698) (xy 98.946051 -294.018698) (xy 98.995414 -294.026517)
			(xy 99.042946 -294.041961) (xy 99.087478 -294.064651) (xy 99.127911 -294.094027) (xy 99.163251 -294.129367)
			(xy 99.192627 -294.1698) (xy 99.215317 -294.214332) (xy 99.230761 -294.261864) (xy 99.23858 -294.311227)
			(xy 99.23907 -294.336216) (xy 99.544881 -294.336216) (xy 99.548976 -294.285488) (xy 99.561155 -294.236074)
			(xy 99.581103 -294.189254) (xy 99.608304 -294.14624) (xy 99.642052 -294.108146) (xy 99.681474 -294.075959)
			(xy 99.725548 -294.050513) (xy 99.773134 -294.032466) (xy 99.822998 -294.022286) (xy 99.87385 -294.020237)
			(xy 99.924371 -294.026371) (xy 99.973255 -294.040531) (xy 100.019234 -294.062348) (xy 100.061118 -294.091258)
			(xy 100.097822 -294.126513) (xy 100.128395 -294.167199) (xy 100.152046 -294.212262) (xy 100.168162 -294.260536)
			(xy 100.176326 -294.31077) (xy 100.176838 -294.336216) (xy 100.484935 -294.336216) (xy 100.48903 -294.285488)
			(xy 100.501209 -294.236074) (xy 100.521157 -294.189254) (xy 100.548358 -294.14624) (xy 100.582106 -294.108146)
			(xy 100.621528 -294.075959) (xy 100.665602 -294.050513) (xy 100.713188 -294.032466) (xy 100.763052 -294.022286)
			(xy 100.813904 -294.020237) (xy 100.864425 -294.026371) (xy 100.913309 -294.040531) (xy 100.959288 -294.062348)
			(xy 101.001172 -294.091258) (xy 101.037876 -294.126513) (xy 101.068449 -294.167199) (xy 101.0921 -294.212262)
			(xy 101.108216 -294.260536) (xy 101.11638 -294.31077) (xy 101.116892 -294.336216) (xy 101.116389 -294.361205)
			(xy 101.423452 -294.361205) (xy 101.423452 -294.311227) (xy 101.431271 -294.261864) (xy 101.446715 -294.214332)
			(xy 101.469405 -294.1698) (xy 101.498781 -294.129367) (xy 101.534121 -294.094027) (xy 101.574554 -294.064651)
			(xy 101.619086 -294.041961) (xy 101.666618 -294.026517) (xy 101.715981 -294.018698) (xy 101.765959 -294.018698)
			(xy 101.815322 -294.026517) (xy 101.862854 -294.041961) (xy 101.907386 -294.064651) (xy 101.947819 -294.094027)
			(xy 101.983159 -294.129367) (xy 102.012535 -294.1698) (xy 102.035225 -294.214332) (xy 102.050669 -294.261864)
			(xy 102.058488 -294.311227) (xy 102.058978 -294.336216) (xy 102.364789 -294.336216) (xy 102.368884 -294.285488)
			(xy 102.381063 -294.236074) (xy 102.401011 -294.189254) (xy 102.428212 -294.14624) (xy 102.46196 -294.108146)
			(xy 102.501382 -294.075959) (xy 102.545456 -294.050513) (xy 102.593042 -294.032466) (xy 102.642906 -294.022286)
			(xy 102.693758 -294.020237) (xy 102.744279 -294.026371) (xy 102.793163 -294.040531) (xy 102.839142 -294.062348)
			(xy 102.881026 -294.091258) (xy 102.91773 -294.126513) (xy 102.948303 -294.167199) (xy 102.971954 -294.212262)
			(xy 102.98807 -294.260536) (xy 102.996234 -294.31077) (xy 102.996746 -294.336216) (xy 103.304843 -294.336216)
			(xy 103.308938 -294.285488) (xy 103.321117 -294.236074) (xy 103.341065 -294.189254) (xy 103.368266 -294.14624)
			(xy 103.402014 -294.108146) (xy 103.441436 -294.075959) (xy 103.48551 -294.050513) (xy 103.533096 -294.032466)
			(xy 103.58296 -294.022286) (xy 103.633812 -294.020237) (xy 103.684333 -294.026371) (xy 103.733217 -294.040531)
			(xy 103.779196 -294.062348) (xy 103.82108 -294.091258) (xy 103.857784 -294.126513) (xy 103.888357 -294.167199)
			(xy 103.912008 -294.212262) (xy 103.928124 -294.260536) (xy 103.936288 -294.31077) (xy 103.9368 -294.336216)
			(xy 103.936297 -294.361205) (xy 104.243614 -294.361205) (xy 104.243614 -294.311227) (xy 104.251433 -294.261864)
			(xy 104.266877 -294.214332) (xy 104.289567 -294.1698) (xy 104.318943 -294.129367) (xy 104.354283 -294.094027)
			(xy 104.394716 -294.064651) (xy 104.439248 -294.041961) (xy 104.48678 -294.026517) (xy 104.536143 -294.018698)
			(xy 104.586121 -294.018698) (xy 104.635484 -294.026517) (xy 104.683016 -294.041961) (xy 104.727548 -294.064651)
			(xy 104.767981 -294.094027) (xy 104.803321 -294.129367) (xy 104.832697 -294.1698) (xy 104.855387 -294.214332)
			(xy 104.870831 -294.261864) (xy 104.87865 -294.311227) (xy 104.87914 -294.336216) (xy 105.184697 -294.336216)
			(xy 105.188792 -294.285488) (xy 105.200971 -294.236074) (xy 105.220919 -294.189254) (xy 105.24812 -294.14624)
			(xy 105.281868 -294.108146) (xy 105.32129 -294.075959) (xy 105.365364 -294.050513) (xy 105.41295 -294.032466)
			(xy 105.462814 -294.022286) (xy 105.513666 -294.020237) (xy 105.564187 -294.026371) (xy 105.613071 -294.040531)
			(xy 105.65905 -294.062348) (xy 105.700934 -294.091258) (xy 105.737638 -294.126513) (xy 105.768211 -294.167199)
			(xy 105.791862 -294.212262) (xy 105.807978 -294.260536) (xy 105.816142 -294.31077) (xy 105.816654 -294.336216)
			(xy 106.124751 -294.336216) (xy 106.128846 -294.285488) (xy 106.141025 -294.236074) (xy 106.160973 -294.189254)
			(xy 106.188174 -294.14624) (xy 106.221922 -294.108146) (xy 106.261344 -294.075959) (xy 106.305418 -294.050513)
			(xy 106.353004 -294.032466) (xy 106.402868 -294.022286) (xy 106.45372 -294.020237) (xy 106.504241 -294.026371)
			(xy 106.553125 -294.040531) (xy 106.599104 -294.062348) (xy 106.640988 -294.091258) (xy 106.677692 -294.126513)
			(xy 106.708265 -294.167199) (xy 106.731916 -294.212262) (xy 106.748032 -294.260536) (xy 106.756196 -294.31077)
			(xy 106.756708 -294.336216) (xy 106.756205 -294.361205) (xy 107.063522 -294.361205) (xy 107.063522 -294.311227)
			(xy 107.071341 -294.261864) (xy 107.086785 -294.214332) (xy 107.109475 -294.1698) (xy 107.138851 -294.129367)
			(xy 107.174191 -294.094027) (xy 107.214624 -294.064651) (xy 107.259156 -294.041961) (xy 107.306688 -294.026517)
			(xy 107.356051 -294.018698) (xy 107.406029 -294.018698) (xy 107.455392 -294.026517) (xy 107.502924 -294.041961)
			(xy 107.547456 -294.064651) (xy 107.587889 -294.094027) (xy 107.623229 -294.129367) (xy 107.652605 -294.1698)
			(xy 107.675295 -294.214332) (xy 107.690739 -294.261864) (xy 107.698558 -294.311227) (xy 107.699048 -294.336216)
			(xy 107.698558 -294.361205) (xy 108.003576 -294.361205) (xy 108.003576 -294.311227) (xy 108.011395 -294.261864)
			(xy 108.026839 -294.214332) (xy 108.049529 -294.1698) (xy 108.078905 -294.129367) (xy 108.114245 -294.094027)
			(xy 108.154678 -294.064651) (xy 108.19921 -294.041961) (xy 108.246742 -294.026517) (xy 108.296105 -294.018698)
			(xy 108.346083 -294.018698) (xy 108.395446 -294.026517) (xy 108.442978 -294.041961) (xy 108.48751 -294.064651)
			(xy 108.527943 -294.094027) (xy 108.563283 -294.129367) (xy 108.592659 -294.1698) (xy 108.615349 -294.214332)
			(xy 108.630793 -294.261864) (xy 108.638612 -294.311227) (xy 108.639102 -294.336216) (xy 108.638612 -294.361205)
			(xy 108.630793 -294.410568) (xy 108.615349 -294.4581) (xy 108.592659 -294.502632) (xy 108.563283 -294.543065)
			(xy 108.527943 -294.578405) (xy 108.48751 -294.607781) (xy 108.442978 -294.630471) (xy 108.395446 -294.645915)
			(xy 108.346083 -294.653734) (xy 108.296105 -294.653734) (xy 108.246742 -294.645915) (xy 108.19921 -294.630471)
			(xy 108.154678 -294.607781) (xy 108.114245 -294.578405) (xy 108.078905 -294.543065) (xy 108.049529 -294.502632)
			(xy 108.026839 -294.4581) (xy 108.011395 -294.410568) (xy 108.003576 -294.361205) (xy 107.698558 -294.361205)
			(xy 107.690739 -294.410568) (xy 107.675295 -294.4581) (xy 107.652605 -294.502632) (xy 107.623229 -294.543065)
			(xy 107.587889 -294.578405) (xy 107.547456 -294.607781) (xy 107.502924 -294.630471) (xy 107.455392 -294.645915)
			(xy 107.406029 -294.653734) (xy 107.356051 -294.653734) (xy 107.306688 -294.645915) (xy 107.259156 -294.630471)
			(xy 107.214624 -294.607781) (xy 107.174191 -294.578405) (xy 107.138851 -294.543065) (xy 107.109475 -294.502632)
			(xy 107.086785 -294.4581) (xy 107.071341 -294.410568) (xy 107.063522 -294.361205) (xy 106.756205 -294.361205)
			(xy 106.756196 -294.361662) (xy 106.748032 -294.411896) (xy 106.731916 -294.46017) (xy 106.708265 -294.505233)
			(xy 106.677692 -294.545919) (xy 106.640988 -294.581174) (xy 106.599104 -294.610084) (xy 106.553125 -294.631901)
			(xy 106.504241 -294.646061) (xy 106.45372 -294.652195) (xy 106.402868 -294.650146) (xy 106.353004 -294.639966)
			(xy 106.305418 -294.621919) (xy 106.261344 -294.596473) (xy 106.221922 -294.564286) (xy 106.188174 -294.526192)
			(xy 106.160973 -294.483178) (xy 106.141025 -294.436358) (xy 106.128846 -294.386944) (xy 106.124751 -294.336216)
			(xy 105.816654 -294.336216) (xy 105.816142 -294.361662) (xy 105.807978 -294.411896) (xy 105.791862 -294.46017)
			(xy 105.768211 -294.505233) (xy 105.737638 -294.545919) (xy 105.700934 -294.581174) (xy 105.65905 -294.610084)
			(xy 105.613071 -294.631901) (xy 105.564187 -294.646061) (xy 105.513666 -294.652195) (xy 105.462814 -294.650146)
			(xy 105.41295 -294.639966) (xy 105.365364 -294.621919) (xy 105.32129 -294.596473) (xy 105.281868 -294.564286)
			(xy 105.24812 -294.526192) (xy 105.220919 -294.483178) (xy 105.200971 -294.436358) (xy 105.188792 -294.386944)
			(xy 105.184697 -294.336216) (xy 104.87914 -294.336216) (xy 104.87865 -294.361205) (xy 104.870831 -294.410568)
			(xy 104.855387 -294.4581) (xy 104.832697 -294.502632) (xy 104.803321 -294.543065) (xy 104.767981 -294.578405)
			(xy 104.727548 -294.607781) (xy 104.683016 -294.630471) (xy 104.635484 -294.645915) (xy 104.586121 -294.653734)
			(xy 104.536143 -294.653734) (xy 104.48678 -294.645915) (xy 104.439248 -294.630471) (xy 104.394716 -294.607781)
			(xy 104.354283 -294.578405) (xy 104.318943 -294.543065) (xy 104.289567 -294.502632) (xy 104.266877 -294.4581)
			(xy 104.251433 -294.410568) (xy 104.243614 -294.361205) (xy 103.936297 -294.361205) (xy 103.936288 -294.361662)
			(xy 103.928124 -294.411896) (xy 103.912008 -294.46017) (xy 103.888357 -294.505233) (xy 103.857784 -294.545919)
			(xy 103.82108 -294.581174) (xy 103.779196 -294.610084) (xy 103.733217 -294.631901) (xy 103.684333 -294.646061)
			(xy 103.633812 -294.652195) (xy 103.58296 -294.650146) (xy 103.533096 -294.639966) (xy 103.48551 -294.621919)
			(xy 103.441436 -294.596473) (xy 103.402014 -294.564286) (xy 103.368266 -294.526192) (xy 103.341065 -294.483178)
			(xy 103.321117 -294.436358) (xy 103.308938 -294.386944) (xy 103.304843 -294.336216) (xy 102.996746 -294.336216)
			(xy 102.996234 -294.361662) (xy 102.98807 -294.411896) (xy 102.971954 -294.46017) (xy 102.948303 -294.505233)
			(xy 102.91773 -294.545919) (xy 102.881026 -294.581174) (xy 102.839142 -294.610084) (xy 102.793163 -294.631901)
			(xy 102.744279 -294.646061) (xy 102.693758 -294.652195) (xy 102.642906 -294.650146) (xy 102.593042 -294.639966)
			(xy 102.545456 -294.621919) (xy 102.501382 -294.596473) (xy 102.46196 -294.564286) (xy 102.428212 -294.526192)
			(xy 102.401011 -294.483178) (xy 102.381063 -294.436358) (xy 102.368884 -294.386944) (xy 102.364789 -294.336216)
			(xy 102.058978 -294.336216) (xy 102.058488 -294.361205) (xy 102.050669 -294.410568) (xy 102.035225 -294.4581)
			(xy 102.012535 -294.502632) (xy 101.983159 -294.543065) (xy 101.947819 -294.578405) (xy 101.907386 -294.607781)
			(xy 101.862854 -294.630471) (xy 101.815322 -294.645915) (xy 101.765959 -294.653734) (xy 101.715981 -294.653734)
			(xy 101.666618 -294.645915) (xy 101.619086 -294.630471) (xy 101.574554 -294.607781) (xy 101.534121 -294.578405)
			(xy 101.498781 -294.543065) (xy 101.469405 -294.502632) (xy 101.446715 -294.4581) (xy 101.431271 -294.410568)
			(xy 101.423452 -294.361205) (xy 101.116389 -294.361205) (xy 101.11638 -294.361662) (xy 101.108216 -294.411896)
			(xy 101.0921 -294.46017) (xy 101.068449 -294.505233) (xy 101.037876 -294.545919) (xy 101.001172 -294.581174)
			(xy 100.959288 -294.610084) (xy 100.913309 -294.631901) (xy 100.864425 -294.646061) (xy 100.813904 -294.652195)
			(xy 100.763052 -294.650146) (xy 100.713188 -294.639966) (xy 100.665602 -294.621919) (xy 100.621528 -294.596473)
			(xy 100.582106 -294.564286) (xy 100.548358 -294.526192) (xy 100.521157 -294.483178) (xy 100.501209 -294.436358)
			(xy 100.48903 -294.386944) (xy 100.484935 -294.336216) (xy 100.176838 -294.336216) (xy 100.176326 -294.361662)
			(xy 100.168162 -294.411896) (xy 100.152046 -294.46017) (xy 100.128395 -294.505233) (xy 100.097822 -294.545919)
			(xy 100.061118 -294.581174) (xy 100.019234 -294.610084) (xy 99.973255 -294.631901) (xy 99.924371 -294.646061)
			(xy 99.87385 -294.652195) (xy 99.822998 -294.650146) (xy 99.773134 -294.639966) (xy 99.725548 -294.621919)
			(xy 99.681474 -294.596473) (xy 99.642052 -294.564286) (xy 99.608304 -294.526192) (xy 99.581103 -294.483178)
			(xy 99.561155 -294.436358) (xy 99.548976 -294.386944) (xy 99.544881 -294.336216) (xy 99.23907 -294.336216)
			(xy 99.23858 -294.361205) (xy 99.230761 -294.410568) (xy 99.215317 -294.4581) (xy 99.192627 -294.502632)
			(xy 99.163251 -294.543065) (xy 99.127911 -294.578405) (xy 99.087478 -294.607781) (xy 99.042946 -294.630471)
			(xy 98.995414 -294.645915) (xy 98.946051 -294.653734) (xy 98.896073 -294.653734) (xy 98.84671 -294.645915)
			(xy 98.799178 -294.630471) (xy 98.754646 -294.607781) (xy 98.714213 -294.578405) (xy 98.678873 -294.543065)
			(xy 98.649497 -294.502632) (xy 98.626807 -294.4581) (xy 98.611363 -294.410568) (xy 98.603544 -294.361205)
			(xy 98.296227 -294.361205) (xy 98.296218 -294.361662) (xy 98.288054 -294.411896) (xy 98.271938 -294.46017)
			(xy 98.248287 -294.505233) (xy 98.217714 -294.545919) (xy 98.18101 -294.581174) (xy 98.139126 -294.610084)
			(xy 98.093147 -294.631901) (xy 98.044263 -294.646061) (xy 97.993742 -294.652195) (xy 97.94289 -294.650146)
			(xy 97.893026 -294.639966) (xy 97.84544 -294.621919) (xy 97.801366 -294.596473) (xy 97.761944 -294.564286)
			(xy 97.728196 -294.526192) (xy 97.700995 -294.483178) (xy 97.681047 -294.436358) (xy 97.668868 -294.386944)
			(xy 97.664773 -294.336216) (xy 97.356676 -294.336216) (xy 97.356164 -294.361662) (xy 97.348 -294.411896)
			(xy 97.331884 -294.46017) (xy 97.308233 -294.505233) (xy 97.27766 -294.545919) (xy 97.240956 -294.581174)
			(xy 97.199072 -294.610084) (xy 97.153093 -294.631901) (xy 97.104209 -294.646061) (xy 97.053688 -294.652195)
			(xy 97.002836 -294.650146) (xy 96.952972 -294.639966) (xy 96.905386 -294.621919) (xy 96.861312 -294.596473)
			(xy 96.82189 -294.564286) (xy 96.788142 -294.526192) (xy 96.760941 -294.483178) (xy 96.740993 -294.436358)
			(xy 96.728814 -294.386944) (xy 96.724719 -294.336216) (xy 96.419162 -294.336216) (xy 96.418672 -294.361205)
			(xy 96.410853 -294.410568) (xy 96.395409 -294.4581) (xy 96.372719 -294.502632) (xy 96.343343 -294.543065)
			(xy 96.308003 -294.578405) (xy 96.26757 -294.607781) (xy 96.223038 -294.630471) (xy 96.175506 -294.645915)
			(xy 96.126143 -294.653734) (xy 96.076165 -294.653734) (xy 96.026802 -294.645915) (xy 95.97927 -294.630471)
			(xy 95.934738 -294.607781) (xy 95.894305 -294.578405) (xy 95.858965 -294.543065) (xy 95.829589 -294.502632)
			(xy 95.806899 -294.4581) (xy 95.791455 -294.410568) (xy 95.783636 -294.361205) (xy 95.478618 -294.361205)
			(xy 95.470799 -294.410568) (xy 95.455355 -294.4581) (xy 95.432665 -294.502632) (xy 95.403289 -294.543065)
			(xy 95.367949 -294.578405) (xy 95.327516 -294.607781) (xy 95.282984 -294.630471) (xy 95.235452 -294.645915)
			(xy 95.186089 -294.653734) (xy 95.136111 -294.653734) (xy 95.086748 -294.645915) (xy 95.039216 -294.630471)
			(xy 94.994684 -294.607781) (xy 94.954251 -294.578405) (xy 94.918911 -294.543065) (xy 94.889535 -294.502632)
			(xy 94.866845 -294.4581) (xy 94.851401 -294.410568) (xy 94.843582 -294.361205) (xy 93.59851 -294.361205)
			(xy 93.590691 -294.410568) (xy 93.575247 -294.4581) (xy 93.552557 -294.502632) (xy 93.523181 -294.543065)
			(xy 93.487841 -294.578405) (xy 93.447408 -294.607781) (xy 93.402876 -294.630471) (xy 93.355344 -294.645915)
			(xy 93.305981 -294.653734) (xy 93.256003 -294.653734) (xy 93.20664 -294.645915) (xy 93.159108 -294.630471)
			(xy 93.114576 -294.607781) (xy 93.074143 -294.578405) (xy 93.038803 -294.543065) (xy 93.009427 -294.502632)
			(xy 92.986737 -294.4581) (xy 92.971293 -294.410568) (xy 92.963474 -294.361205) (xy 92.658456 -294.361205)
			(xy 92.650637 -294.410568) (xy 92.635193 -294.4581) (xy 92.612503 -294.502632) (xy 92.583127 -294.543065)
			(xy 92.547787 -294.578405) (xy 92.507354 -294.607781) (xy 92.462822 -294.630471) (xy 92.41529 -294.645915)
			(xy 92.365927 -294.653734) (xy 92.315949 -294.653734) (xy 92.266586 -294.645915) (xy 92.219054 -294.630471)
			(xy 92.174522 -294.607781) (xy 92.134089 -294.578405) (xy 92.098749 -294.543065) (xy 92.069373 -294.502632)
			(xy 92.046683 -294.4581) (xy 92.031239 -294.410568) (xy 92.02342 -294.361205) (xy 91.861386 -294.361205)
			(xy 91.861386 -294.799258) (xy 91.88704 -294.82796) (xy 91.906598 -294.830246) (xy 91.932161 -294.833629)
			(xy 91.981795 -294.847594) (xy 92.028526 -294.869385) (xy 92.071129 -294.898431) (xy 92.108486 -294.93397)
			(xy 92.139619 -294.975072) (xy 92.163712 -295.020659) (xy 92.180134 -295.069535) (xy 92.188453 -295.120422)
			(xy 92.188453 -295.171211) (xy 92.493574 -295.171211) (xy 92.493574 -295.121233) (xy 92.501393 -295.07187)
			(xy 92.516837 -295.024338) (xy 92.539527 -294.979806) (xy 92.568903 -294.939373) (xy 92.604243 -294.904033)
			(xy 92.644676 -294.874657) (xy 92.689208 -294.851967) (xy 92.73674 -294.836523) (xy 92.786103 -294.828704)
			(xy 92.836081 -294.828704) (xy 92.885444 -294.836523) (xy 92.932976 -294.851967) (xy 92.977508 -294.874657)
			(xy 93.017941 -294.904033) (xy 93.053281 -294.939373) (xy 93.082657 -294.979806) (xy 93.105347 -295.024338)
			(xy 93.120791 -295.07187) (xy 93.12861 -295.121233) (xy 93.1291 -295.146222) (xy 93.12861 -295.171211)
			(xy 95.313482 -295.171211) (xy 95.313482 -295.121233) (xy 95.321301 -295.07187) (xy 95.336745 -295.024338)
			(xy 95.359435 -294.979806) (xy 95.388811 -294.939373) (xy 95.424151 -294.904033) (xy 95.464584 -294.874657)
			(xy 95.509116 -294.851967) (xy 95.556648 -294.836523) (xy 95.606011 -294.828704) (xy 95.655989 -294.828704)
			(xy 95.705352 -294.836523) (xy 95.752884 -294.851967) (xy 95.797416 -294.874657) (xy 95.837849 -294.904033)
			(xy 95.873189 -294.939373) (xy 95.902565 -294.979806) (xy 95.925255 -295.024338) (xy 95.940699 -295.07187)
			(xy 95.948518 -295.121233) (xy 95.949008 -295.146222) (xy 95.948518 -295.171211) (xy 98.133644 -295.171211)
			(xy 98.133644 -295.121233) (xy 98.141463 -295.07187) (xy 98.156907 -295.024338) (xy 98.179597 -294.979806)
			(xy 98.208973 -294.939373) (xy 98.244313 -294.904033) (xy 98.284746 -294.874657) (xy 98.329278 -294.851967)
			(xy 98.37681 -294.836523) (xy 98.426173 -294.828704) (xy 98.476151 -294.828704) (xy 98.525514 -294.836523)
			(xy 98.573046 -294.851967) (xy 98.617578 -294.874657) (xy 98.658011 -294.904033) (xy 98.693351 -294.939373)
			(xy 98.722727 -294.979806) (xy 98.745417 -295.024338) (xy 98.760861 -295.07187) (xy 98.76868 -295.121233)
			(xy 98.76917 -295.146222) (xy 98.76868 -295.171211) (xy 100.953552 -295.171211) (xy 100.953552 -295.121233)
			(xy 100.961371 -295.07187) (xy 100.976815 -295.024338) (xy 100.999505 -294.979806) (xy 101.028881 -294.939373)
			(xy 101.064221 -294.904033) (xy 101.104654 -294.874657) (xy 101.149186 -294.851967) (xy 101.196718 -294.836523)
			(xy 101.246081 -294.828704) (xy 101.296059 -294.828704) (xy 101.345422 -294.836523) (xy 101.392954 -294.851967)
			(xy 101.437486 -294.874657) (xy 101.477919 -294.904033) (xy 101.513259 -294.939373) (xy 101.542635 -294.979806)
			(xy 101.565325 -295.024338) (xy 101.580769 -295.07187) (xy 101.588588 -295.121233) (xy 101.589078 -295.146222)
			(xy 101.588588 -295.171211) (xy 103.77346 -295.171211) (xy 103.77346 -295.121233) (xy 103.781279 -295.07187)
			(xy 103.796723 -295.024338) (xy 103.819413 -294.979806) (xy 103.848789 -294.939373) (xy 103.884129 -294.904033)
			(xy 103.924562 -294.874657) (xy 103.969094 -294.851967) (xy 104.016626 -294.836523) (xy 104.065989 -294.828704)
			(xy 104.115967 -294.828704) (xy 104.16533 -294.836523) (xy 104.212862 -294.851967) (xy 104.257394 -294.874657)
			(xy 104.297827 -294.904033) (xy 104.333167 -294.939373) (xy 104.362543 -294.979806) (xy 104.385233 -295.024338)
			(xy 104.400677 -295.07187) (xy 104.408496 -295.121233) (xy 104.408986 -295.146222) (xy 104.408496 -295.171211)
			(xy 106.593622 -295.171211) (xy 106.593622 -295.121233) (xy 106.601441 -295.07187) (xy 106.616885 -295.024338)
			(xy 106.639575 -294.979806) (xy 106.668951 -294.939373) (xy 106.704291 -294.904033) (xy 106.744724 -294.874657)
			(xy 106.789256 -294.851967) (xy 106.836788 -294.836523) (xy 106.886151 -294.828704) (xy 106.936129 -294.828704)
			(xy 106.985492 -294.836523) (xy 107.033024 -294.851967) (xy 107.077556 -294.874657) (xy 107.117989 -294.904033)
			(xy 107.153329 -294.939373) (xy 107.182705 -294.979806) (xy 107.205395 -295.024338) (xy 107.220839 -295.07187)
			(xy 107.228658 -295.121233) (xy 107.229148 -295.146222) (xy 107.228658 -295.171211) (xy 107.220839 -295.220574)
			(xy 107.205395 -295.268106) (xy 107.182705 -295.312638) (xy 107.153329 -295.353071) (xy 107.117989 -295.388411)
			(xy 107.077556 -295.417787) (xy 107.033024 -295.440477) (xy 106.985492 -295.455921) (xy 106.936129 -295.46374)
			(xy 106.886151 -295.46374) (xy 106.836788 -295.455921) (xy 106.789256 -295.440477) (xy 106.744724 -295.417787)
			(xy 106.704291 -295.388411) (xy 106.668951 -295.353071) (xy 106.639575 -295.312638) (xy 106.616885 -295.268106)
			(xy 106.601441 -295.220574) (xy 106.593622 -295.171211) (xy 104.408496 -295.171211) (xy 104.400677 -295.220574)
			(xy 104.385233 -295.268106) (xy 104.362543 -295.312638) (xy 104.333167 -295.353071) (xy 104.297827 -295.388411)
			(xy 104.257394 -295.417787) (xy 104.212862 -295.440477) (xy 104.16533 -295.455921) (xy 104.115967 -295.46374)
			(xy 104.065989 -295.46374) (xy 104.016626 -295.455921) (xy 103.969094 -295.440477) (xy 103.924562 -295.417787)
			(xy 103.884129 -295.388411) (xy 103.848789 -295.353071) (xy 103.819413 -295.312638) (xy 103.796723 -295.268106)
			(xy 103.781279 -295.220574) (xy 103.77346 -295.171211) (xy 101.588588 -295.171211) (xy 101.580769 -295.220574)
			(xy 101.565325 -295.268106) (xy 101.542635 -295.312638) (xy 101.513259 -295.353071) (xy 101.477919 -295.388411)
			(xy 101.437486 -295.417787) (xy 101.392954 -295.440477) (xy 101.345422 -295.455921) (xy 101.296059 -295.46374)
			(xy 101.246081 -295.46374) (xy 101.196718 -295.455921) (xy 101.149186 -295.440477) (xy 101.104654 -295.417787)
			(xy 101.064221 -295.388411) (xy 101.028881 -295.353071) (xy 100.999505 -295.312638) (xy 100.976815 -295.268106)
			(xy 100.961371 -295.220574) (xy 100.953552 -295.171211) (xy 98.76868 -295.171211) (xy 98.760861 -295.220574)
			(xy 98.745417 -295.268106) (xy 98.722727 -295.312638) (xy 98.693351 -295.353071) (xy 98.658011 -295.388411)
			(xy 98.617578 -295.417787) (xy 98.573046 -295.440477) (xy 98.525514 -295.455921) (xy 98.476151 -295.46374)
			(xy 98.426173 -295.46374) (xy 98.37681 -295.455921) (xy 98.329278 -295.440477) (xy 98.284746 -295.417787)
			(xy 98.244313 -295.388411) (xy 98.208973 -295.353071) (xy 98.179597 -295.312638) (xy 98.156907 -295.268106)
			(xy 98.141463 -295.220574) (xy 98.133644 -295.171211) (xy 95.948518 -295.171211) (xy 95.940699 -295.220574)
			(xy 95.925255 -295.268106) (xy 95.902565 -295.312638) (xy 95.873189 -295.353071) (xy 95.837849 -295.388411)
			(xy 95.797416 -295.417787) (xy 95.752884 -295.440477) (xy 95.705352 -295.455921) (xy 95.655989 -295.46374)
			(xy 95.606011 -295.46374) (xy 95.556648 -295.455921) (xy 95.509116 -295.440477) (xy 95.464584 -295.417787)
			(xy 95.424151 -295.388411) (xy 95.388811 -295.353071) (xy 95.359435 -295.312638) (xy 95.336745 -295.268106)
			(xy 95.321301 -295.220574) (xy 95.313482 -295.171211) (xy 93.12861 -295.171211) (xy 93.120791 -295.220574)
			(xy 93.105347 -295.268106) (xy 93.082657 -295.312638) (xy 93.053281 -295.353071) (xy 93.017941 -295.388411)
			(xy 92.977508 -295.417787) (xy 92.932976 -295.440477) (xy 92.885444 -295.455921) (xy 92.836081 -295.46374)
			(xy 92.786103 -295.46374) (xy 92.73674 -295.455921) (xy 92.689208 -295.440477) (xy 92.644676 -295.417787)
			(xy 92.604243 -295.388411) (xy 92.568903 -295.353071) (xy 92.539527 -295.312638) (xy 92.516837 -295.268106)
			(xy 92.501393 -295.220574) (xy 92.493574 -295.171211) (xy 92.188453 -295.171211) (xy 92.188453 -295.171983)
			(xy 92.180132 -295.222869) (xy 92.16371 -295.271746) (xy 92.139616 -295.317332) (xy 92.108483 -295.358433)
			(xy 92.071125 -295.393972) (xy 92.028522 -295.423017) (xy 91.981791 -295.444807) (xy 91.932156 -295.458772)
			(xy 91.906598 -295.462198) (xy 91.88704 -295.464484) (xy 91.861386 -295.493186) (xy 91.861386 -295.702482)
			(xy 91.861824 -295.712546) (xy 91.869557 -295.73113) (xy 91.876372 -295.73855) (xy 91.92641 -295.788588)
			(xy 91.934672 -295.796107) (xy 91.955633 -295.803754) (xy 91.966796 -295.80332) (xy 92.009976 -295.79951)
			(xy 92.040964 -295.796716) (xy 92.048761 -295.795723) (xy 92.063252 -295.789658) (xy 92.069412 -295.784778)
			(xy 92.070936 -295.783508) (xy 92.079826 -295.774618) (xy 92.082366 -295.771316) (xy 92.097394 -295.751098)
			(xy 92.132769 -295.715234) (xy 92.173358 -295.685399) (xy 92.218145 -295.662342) (xy 92.266009 -295.646638)
			(xy 92.315751 -295.638681) (xy 92.340938 -295.63822) (xy 92.365924 -295.638713) (xy 92.415281 -295.646536)
			(xy 92.462807 -295.661984) (xy 92.50733 -295.684676) (xy 92.547756 -295.714054) (xy 92.583089 -295.749394)
			(xy 92.612458 -295.789826) (xy 92.635141 -295.834354) (xy 92.650579 -295.881883) (xy 92.658392 -295.931241)
			(xy 92.658946 -295.956228) (xy 92.658434 -295.981779) (xy 92.650253 -296.032221) (xy 92.634108 -296.080705)
			(xy 92.610413 -296.125981) (xy 92.579779 -296.166883) (xy 92.542996 -296.202356) (xy 92.522294 -296.21734)
			(xy 92.515182 -296.22242) (xy 92.505276 -296.236136) (xy 92.502736 -296.244772) (xy 92.500704 -296.254678)
			(xy 92.497656 -296.286936) (xy 92.497656 -296.287444) (xy 92.493846 -296.33037) (xy 92.493476 -296.341521)
			(xy 92.501123 -296.362454) (xy 92.508578 -296.370756) (xy 92.6084 -296.470578) (xy 92.615798 -296.477427)
			(xy 92.634396 -296.485165) (xy 92.644468 -296.485564)
		)
		(stroke
			(width 0)
			(type solid)
		)
		(fill yes)
		(layer "B.Cu")
		(net "PVDDCR_CPU1_P1")
	)
	(gr_poly
		(pts
			(xy 88.62695 -294.765984) (xy 88.634195 -294.764357) (xy 88.647365 -294.757518) (xy 88.652858 -294.752522)
			(xy 88.66759 -294.73779) (xy 88.674069 -294.73072) (xy 88.68168 -294.713134) (xy 88.68231 -294.693981)
			(xy 88.675871 -294.675933) (xy 88.669876 -294.668448) (xy 88.668098 -294.666416) (xy 88.663609 -294.662004)
			(xy 88.652943 -294.655328) (xy 88.647016 -294.653208) (xy 88.636856 -294.649906) (xy 88.624664 -294.65143)
			(xy 88.613798 -294.652851) (xy 88.591934 -294.654377) (xy 88.580976 -294.654478) (xy 88.555967 -294.653986)
			(xy 88.506565 -294.646158) (xy 88.458995 -294.630698) (xy 88.41443 -294.607988) (xy 88.373965 -294.578586)
			(xy 88.338598 -294.543216) (xy 88.309199 -294.50275) (xy 88.286493 -294.458182) (xy 88.271037 -294.410612)
			(xy 88.263213 -294.361209) (xy 88.263213 -294.311191) (xy 88.271037 -294.261788) (xy 88.286493 -294.214218)
			(xy 88.309199 -294.16965) (xy 88.338598 -294.129184) (xy 88.373965 -294.093814) (xy 88.41443 -294.064412)
			(xy 88.458995 -294.041702) (xy 88.506565 -294.026242) (xy 88.555967 -294.018414) (xy 88.580976 -294.017954)
			(xy 88.605816 -294.018436) (xy 88.65489 -294.026163) (xy 88.70217 -294.041416) (xy 88.746508 -294.063827)
			(xy 88.786827 -294.092851) (xy 88.82215 -294.127785) (xy 88.851619 -294.16778) (xy 88.87452 -294.211866)
			(xy 88.890298 -294.258973) (xy 88.89492 -294.283384) (xy 88.897658 -294.297038) (xy 88.909526 -294.322218)
			(xy 88.927753 -294.343259) (xy 88.950985 -294.358594) (xy 88.977495 -294.367086) (xy 89.005314 -294.368103)
			(xy 89.032374 -294.361569) (xy 89.056664 -294.347971) (xy 89.066878 -294.338502) (xy 89.390982 -294.014398)
			(xy 89.398094 -294.005254) (xy 89.400888 -294.000936) (xy 89.40292 -293.994332) (xy 89.415857 -293.955729)
			(xy 89.446625 -293.880344) (xy 89.464388 -293.84371) (xy 89.477334 -293.817936) (xy 89.505542 -293.767618)
			(xy 89.520776 -293.743126) (xy 89.526364 -293.73068) (xy 89.530428 -293.717218) (xy 89.531392 -293.713677)
			(xy 89.53241 -293.70641) (xy 89.53246 -293.70274) (xy 89.53246 -293.102792) (xy 89.532156 -293.093433)
			(xy 89.525511 -293.07594) (xy 89.519506 -293.068756) (xy 89.49944 -293.046658) (xy 89.493458 -293.040474)
			(xy 89.478396 -293.032179) (xy 89.469976 -293.030402) (xy 89.445432 -293.025924) (xy 89.398038 -293.010343)
			(xy 89.353656 -292.987559) (xy 89.313371 -292.95813) (xy 89.278171 -292.922777) (xy 89.248917 -292.882365)
			(xy 89.226326 -292.837884) (xy 89.21095 -292.790423) (xy 89.203167 -292.741145) (xy 89.203167 -292.691256)
			(xy 89.21095 -292.641978) (xy 89.226325 -292.594517) (xy 89.248917 -292.550036) (xy 89.27817 -292.509624)
			(xy 89.31337 -292.474271) (xy 89.353655 -292.444842) (xy 89.398037 -292.422057) (xy 89.445431 -292.406476)
			(xy 89.469976 -292.402006) (xy 89.478402 -292.400252) (xy 89.493462 -292.391942) (xy 89.49944 -292.38575)
			(xy 89.519506 -292.363652) (xy 89.525405 -292.356404) (xy 89.532044 -292.338952) (xy 89.53246 -292.329616)
			(xy 89.53246 -291.48278) (xy 89.532154 -291.473422) (xy 89.525506 -291.455931) (xy 89.519506 -291.448744)
			(xy 89.49944 -291.426646) (xy 89.493457 -291.420463) (xy 89.478395 -291.41217) (xy 89.469976 -291.41039)
			(xy 89.445433 -291.405913) (xy 89.398041 -291.390332) (xy 89.353661 -291.367548) (xy 89.313378 -291.33812)
			(xy 89.278179 -291.302768) (xy 89.248926 -291.262357) (xy 89.226336 -291.217878) (xy 89.210962 -291.170419)
			(xy 89.203179 -291.121142) (xy 89.203179 -291.071255) (xy 89.210962 -291.021979) (xy 89.226337 -290.97452)
			(xy 89.248928 -290.930041) (xy 89.278181 -290.88963) (xy 89.31338 -290.854278) (xy 89.353663 -290.824851)
			(xy 89.398044 -290.802067) (xy 89.445435 -290.786487) (xy 89.469976 -290.781994) (xy 89.478402 -290.780239)
			(xy 89.49346 -290.771928) (xy 89.49944 -290.765738) (xy 89.519506 -290.74364) (xy 89.525404 -290.736392)
			(xy 89.532038 -290.718939) (xy 89.53246 -290.709604) (xy 89.53246 -289.862768) (xy 89.532151 -289.853411)
			(xy 89.5255 -289.835923) (xy 89.519506 -289.828732) (xy 89.49944 -289.806634) (xy 89.493462 -289.800442)
			(xy 89.478402 -289.792135) (xy 89.469976 -289.790378) (xy 89.445434 -289.785901) (xy 89.398044 -289.77032)
			(xy 89.353665 -289.747537) (xy 89.313384 -289.71811) (xy 89.278187 -289.682758) (xy 89.248935 -289.642349)
			(xy 89.226346 -289.597871) (xy 89.210973 -289.550414) (xy 89.203191 -289.501139) (xy 89.203191 -289.451254)
			(xy 89.210974 -289.40198) (xy 89.226349 -289.354523) (xy 89.248939 -289.310045) (xy 89.278191 -289.269637)
			(xy 89.313389 -289.234286) (xy 89.353671 -289.20486) (xy 89.39805 -289.182078) (xy 89.44544 -289.166498)
			(xy 89.469976 -289.161982) (xy 89.478401 -289.160227) (xy 89.493459 -289.151915) (xy 89.49944 -289.145726)
			(xy 89.519506 -289.123628) (xy 89.525402 -289.116379) (xy 89.532033 -289.098927) (xy 89.53246 -289.089592)
			(xy 89.53246 -288.24301) (xy 89.532141 -288.233657) (xy 89.525475 -288.216183) (xy 89.519506 -288.208974)
			(xy 89.49944 -288.186876) (xy 89.493459 -288.18069) (xy 89.478397 -288.172392) (xy 89.469976 -288.17062)
			(xy 89.44543 -288.166142) (xy 89.398034 -288.150561) (xy 89.353649 -288.127776) (xy 89.313362 -288.098345)
			(xy 89.278159 -288.06299) (xy 89.248904 -288.022577) (xy 89.226311 -287.978093) (xy 89.210934 -287.93063)
			(xy 89.20315 -287.881349) (xy 89.203149 -287.831458) (xy 89.210932 -287.782177) (xy 89.226308 -287.734713)
			(xy 89.2489 -287.690229) (xy 89.278155 -287.649815) (xy 89.313357 -287.614459) (xy 89.353643 -287.585028)
			(xy 89.398028 -287.562242) (xy 89.445424 -287.546659) (xy 89.469976 -287.542224) (xy 89.478403 -287.540471)
			(xy 89.493465 -287.532163) (xy 89.49944 -287.525968) (xy 89.519506 -287.50387) (xy 89.525408 -287.496623)
			(xy 89.532053 -287.479171) (xy 89.53246 -287.469834) (xy 89.53246 -286.622998) (xy 89.532157 -286.613639)
			(xy 89.525513 -286.596144) (xy 89.519506 -286.588962) (xy 89.49944 -286.566864) (xy 89.493458 -286.560679)
			(xy 89.478396 -286.552383) (xy 89.469976 -286.550608) (xy 89.445431 -286.54613) (xy 89.398037 -286.530549)
			(xy 89.353654 -286.507765) (xy 89.313368 -286.478335) (xy 89.278167 -286.442981) (xy 89.248913 -286.402569)
			(xy 89.226321 -286.358087) (xy 89.210945 -286.310626) (xy 89.203162 -286.261347) (xy 89.203161 -286.211457)
			(xy 89.210944 -286.162177) (xy 89.22632 -286.114716) (xy 89.248911 -286.070234) (xy 89.278165 -286.029821)
			(xy 89.313366 -285.994467) (xy 89.353651 -285.965037) (xy 89.398034 -285.942252) (xy 89.445428 -285.92667)
			(xy 89.469976 -285.922212) (xy 89.478402 -285.920458) (xy 89.493463 -285.912149) (xy 89.49944 -285.905956)
			(xy 89.519506 -285.883858) (xy 89.525406 -285.876611) (xy 89.532047 -285.859158) (xy 89.53246 -285.849822)
			(xy 89.53246 -285.002986) (xy 89.532155 -284.993627) (xy 89.525508 -284.976136) (xy 89.519506 -284.96895)
			(xy 89.49944 -284.946852) (xy 89.493458 -284.940668) (xy 89.478395 -284.932374) (xy 89.469976 -284.930596)
			(xy 89.445432 -284.926119) (xy 89.39804 -284.910537) (xy 89.353658 -284.887754) (xy 89.313375 -284.858325)
			(xy 89.278175 -284.822972) (xy 89.248922 -284.782561) (xy 89.226331 -284.738081) (xy 89.210956 -284.690621)
			(xy 89.203173 -284.641344) (xy 89.203173 -284.591456) (xy 89.210956 -284.542178) (xy 89.226331 -284.494719)
			(xy 89.248922 -284.450239) (xy 89.278175 -284.409827) (xy 89.313375 -284.374475) (xy 89.353659 -284.345046)
			(xy 89.39804 -284.322262) (xy 89.445433 -284.306681) (xy 89.469976 -284.3022) (xy 89.478402 -284.300446)
			(xy 89.493461 -284.292135) (xy 89.49944 -284.285944) (xy 89.519506 -284.263846) (xy 89.525405 -284.256598)
			(xy 89.532041 -284.239146) (xy 89.53246 -284.22981) (xy 89.53246 -283.382974) (xy 89.532152 -283.373616)
			(xy 89.525503 -283.356127) (xy 89.519506 -283.348938) (xy 89.49944 -283.32684) (xy 89.493457 -283.320657)
			(xy 89.478394 -283.312366) (xy 89.469976 -283.310584) (xy 89.445433 -283.306107) (xy 89.398043 -283.290526)
			(xy 89.353663 -283.267742) (xy 89.313381 -283.238315) (xy 89.278183 -283.202963) (xy 89.248931 -283.162553)
			(xy 89.226341 -283.118075) (xy 89.210967 -283.070616) (xy 89.203185 -283.021341) (xy 89.203185 -282.971455)
			(xy 89.210968 -282.922179) (xy 89.226343 -282.874721) (xy 89.248933 -282.830243) (xy 89.278186 -282.789834)
			(xy 89.313384 -282.754482) (xy 89.353667 -282.725055) (xy 89.398047 -282.702273) (xy 89.445438 -282.686692)
			(xy 89.469976 -282.682188) (xy 89.478402 -282.680433) (xy 89.493459 -282.672121) (xy 89.49944 -282.665932)
			(xy 89.519506 -282.643834) (xy 89.525403 -282.636586) (xy 89.532036 -282.619133) (xy 89.53246 -282.609798)
			(xy 89.53246 -281.84348) (xy 89.535 -281.838654) (xy 89.541289 -281.826384) (xy 89.547725 -281.799584)
			(xy 89.546746 -281.772041) (xy 89.538424 -281.745766) (xy 89.523367 -281.722681) (xy 89.502676 -281.704474)
			(xy 89.477864 -281.692475) (xy 89.464388 -281.689556) (xy 89.440239 -281.684722) (xy 89.393705 -281.6686)
			(xy 89.35021 -281.645501) (xy 89.310792 -281.615978) (xy 89.276394 -281.580735) (xy 89.247835 -281.540613)
			(xy 89.225798 -281.49657) (xy 89.210809 -281.449659) (xy 89.203227 -281.400998) (xy 89.202768 -281.376374)
			(xy 89.203235 -281.351365) (xy 89.211064 -281.301964) (xy 89.226524 -281.254395) (xy 89.249236 -281.20983)
			(xy 89.278639 -281.169368) (xy 89.31401 -281.134003) (xy 89.354478 -281.104606) (xy 89.399047 -281.081903)
			(xy 89.446618 -281.066451) (xy 89.496021 -281.058631) (xy 89.52103 -281.058112) (xy 89.547519 -281.058634)
			(xy 89.599766 -281.067396) (xy 89.64984 -281.084691) (xy 89.696359 -281.11004) (xy 89.738036 -281.142744)
			(xy 89.756234 -281.161998) (xy 89.765857 -281.171916) (xy 89.789226 -281.18664) (xy 89.815691 -281.194553)
			(xy 89.843308 -281.195073) (xy 89.870051 -281.188161) (xy 89.893958 -281.174326) (xy 89.913275 -281.154582)
			(xy 89.920318 -281.142694) (xy 89.985596 -281.024584) (xy 89.991705 -281.012626) (xy 89.998064 -280.986545)
			(xy 89.997408 -280.959708) (xy 89.989783 -280.933969) (xy 89.975717 -280.911105) (xy 89.95618 -280.892695)
			(xy 89.932521 -280.88001) (xy 89.919556 -280.876502) (xy 89.893602 -280.869961) (xy 89.84419 -280.849396)
			(xy 89.798913 -280.820856) (xy 89.759047 -280.785147) (xy 89.725714 -280.743274) (xy 89.699854 -280.696416)
			(xy 89.682194 -280.645893) (xy 89.673232 -280.593128) (xy 89.672668 -280.566368) (xy 89.673161 -280.541361)
			(xy 89.68099 -280.491964) (xy 89.696449 -280.4444) (xy 89.719159 -280.39984) (xy 89.748561 -280.359382)
			(xy 89.783929 -280.32402) (xy 89.824393 -280.294627) (xy 89.868958 -280.271926) (xy 89.916525 -280.256475)
			(xy 89.965923 -280.248656) (xy 89.99093 -280.248106) (xy 90.015903 -280.248596) (xy 90.065234 -280.256402)
			(xy 90.112741 -280.271817) (xy 90.157257 -280.294463) (xy 90.19769 -280.323784) (xy 90.21572 -280.34107)
			(xy 90.225527 -280.350295) (xy 90.248869 -280.363695) (xy 90.274902 -280.370532) (xy 90.301816 -280.37033)
			(xy 90.327743 -280.363104) (xy 90.350882 -280.349355) (xy 90.369625 -280.330039) (xy 90.376502 -280.318464)
			(xy 90.436446 -280.209752) (xy 90.443419 -280.196114) (xy 90.449673 -280.166143) (xy 90.446764 -280.135666)
			(xy 90.434952 -280.10742) (xy 90.415298 -280.083944) (xy 90.38957 -280.067348) (xy 90.374978 -280.062686)
			(xy 90.350272 -280.055216) (xy 90.303493 -280.033408) (xy 90.260845 -280.00434) (xy 90.223444 -279.968774)
			(xy 90.192269 -279.927641) (xy 90.168138 -279.882018) (xy 90.151681 -279.8331) (xy 90.14333 -279.782168)
			(xy 90.142822 -279.756362) (xy 90.143315 -279.731354) (xy 90.151145 -279.681956) (xy 90.166604 -279.634389)
			(xy 90.189314 -279.589827) (xy 90.218714 -279.549365) (xy 90.254082 -279.514) (xy 90.294546 -279.484602)
			(xy 90.33911 -279.461896) (xy 90.386677 -279.446439) (xy 90.436076 -279.438614) (xy 90.461084 -279.4381)
			(xy 90.484548 -279.438517) (xy 90.530968 -279.445403) (xy 90.575875 -279.459028) (xy 90.618295 -279.479096)
			(xy 90.657311 -279.505175) (xy 90.674952 -279.52065) (xy 90.686623 -279.530553) (xy 90.714341 -279.543505)
			(xy 90.74465 -279.547681) (xy 90.774838 -279.542707) (xy 90.802205 -279.529027) (xy 90.824301 -279.507866)
			(xy 90.832178 -279.494742) (xy 90.888058 -279.394158) (xy 90.894794 -279.380857) (xy 90.901036 -279.351718)
			(xy 90.89861 -279.322017) (xy 90.887724 -279.294276) (xy 90.869302 -279.270853) (xy 90.844909 -279.253736)
			(xy 90.830908 -279.248616) (xy 90.807429 -279.240313) (xy 90.763185 -279.217455) (xy 90.723037 -279.18799)
			(xy 90.687963 -279.152637) (xy 90.658819 -279.112256) (xy 90.636313 -279.067832) (xy 90.620994 -279.020447)
			(xy 90.613236 -278.971256) (xy 90.612722 -278.946356) (xy 90.613216 -278.921349) (xy 90.621046 -278.871951)
			(xy 90.636506 -278.824385) (xy 90.659216 -278.779823) (xy 90.688616 -278.739362) (xy 90.723984 -278.703998)
			(xy 90.764447 -278.674601) (xy 90.809011 -278.651895) (xy 90.856578 -278.636439) (xy 90.905977 -278.628614)
			(xy 90.930984 -278.628094) (xy 90.958515 -278.628676) (xy 91.012756 -278.638147) (xy 91.064558 -278.65681)
			(xy 91.112377 -278.684108) (xy 91.13393 -278.701246) (xy 91.145746 -278.710361) (xy 91.173234 -278.721944)
			(xy 91.202896 -278.725085) (xy 91.2322 -278.719517) (xy 91.258643 -278.705716) (xy 91.279968 -278.684859)
			(xy 91.2876 -278.672036) (xy 91.339924 -278.577548) (xy 91.346461 -278.564603) (xy 91.352742 -278.536305)
			(xy 91.350837 -278.507381) (xy 91.340899 -278.480151) (xy 91.323725 -278.4568) (xy 91.300692 -278.439201)
			(xy 91.287346 -278.43353) (xy 91.265108 -278.424546) (xy 91.223401 -278.400865) (xy 91.18572 -278.371194)
			(xy 91.152917 -278.336206) (xy 91.125734 -278.296692) (xy 91.104788 -278.253546) (xy 91.090552 -278.207747)
			(xy 91.083349 -278.16033) (xy 91.082876 -278.13635) (xy 91.08337 -278.111345) (xy 91.091201 -278.06195)
			(xy 91.106663 -278.014389) (xy 91.129374 -277.969832) (xy 91.158775 -277.929377) (xy 91.194144 -277.894018)
			(xy 91.234607 -277.864628) (xy 91.279171 -277.841929) (xy 91.326736 -277.826481) (xy 91.376132 -277.818663)
			(xy 91.401138 -277.818088) (xy 91.426803 -277.81863) (xy 91.477461 -277.826911) (xy 91.526138 -277.843204)
			(xy 91.571573 -277.867088) (xy 91.5924 -277.882096) (xy 91.604306 -277.890435) (xy 91.631486 -277.900697)
			(xy 91.660456 -277.902889) (xy 91.688871 -277.896835) (xy 91.714431 -277.883024) (xy 91.735068 -277.862574)
			(xy 91.742514 -277.850092) (xy 91.792044 -277.76043) (xy 91.798501 -277.747839) (xy 91.804917 -277.72029)
			(xy 91.803538 -277.692038) (xy 91.79447 -277.665246) (xy 91.778408 -277.641963) (xy 91.75658 -277.623973)
			(xy 91.743784 -277.617936) (xy 91.719811 -277.606934) (xy 91.675589 -277.57819) (xy 91.636715 -277.542543)
			(xy 91.604257 -277.500971) (xy 91.579103 -277.454612) (xy 91.561944 -277.404738) (xy 91.55325 -277.352716)
			(xy 91.552776 -277.326344) (xy 91.553238 -277.301332) (xy 91.561058 -277.251922) (xy 91.576512 -277.204345)
			(xy 91.59922 -277.159771) (xy 91.628622 -277.119299) (xy 91.663995 -277.083926) (xy 91.704466 -277.054523)
			(xy 91.749039 -277.031815) (xy 91.796616 -277.016359) (xy 91.846026 -277.008538) (xy 91.871038 -277.008082)
			(xy 91.894904 -277.008532) (xy 91.942096 -277.0157) (xy 91.987692 -277.029826) (xy 92.03067 -277.050594)
			(xy 92.050616 -277.063708) (xy 92.062541 -277.071322) (xy 92.089363 -277.080294) (xy 92.117617 -277.081556)
			(xy 92.145132 -277.075013) (xy 92.169793 -277.061166) (xy 92.189703 -277.04108) (xy 92.19692 -277.02891)
			(xy 92.244672 -276.942296) (xy 92.250894 -276.930073) (xy 92.257262 -276.903406) (xy 92.256317 -276.876006)
			(xy 92.248127 -276.849841) (xy 92.23328 -276.826792) (xy 92.212844 -276.808516) (xy 92.20073 -276.802088)
			(xy 92.178184 -276.790477) (xy 92.136776 -276.761203) (xy 92.100536 -276.725732) (xy 92.070379 -276.684963)
			(xy 92.04707 -276.639927) (xy 92.031198 -276.591764) (xy 92.023166 -276.541693) (xy 92.022676 -276.516338)
			(xy 92.023138 -276.491326) (xy 92.030959 -276.441917) (xy 92.046414 -276.39434) (xy 92.069122 -276.349768)
			(xy 92.098525 -276.309297) (xy 92.133897 -276.273925) (xy 92.174368 -276.244522) (xy 92.21894 -276.221814)
			(xy 92.266517 -276.206359) (xy 92.315926 -276.198538) (xy 92.340938 -276.198076) (xy 92.370392 -276.19871)
			(xy 92.428295 -276.209539) (xy 92.483217 -276.230838) (xy 92.508578 -276.245828) (xy 92.520495 -276.252652)
			(xy 92.546854 -276.260315) (xy 92.574302 -276.260674) (xy 92.600852 -276.253703) (xy 92.624583 -276.239905)
			(xy 92.643777 -276.220281) (xy 92.650818 -276.20849) (xy 92.697808 -276.123654) (xy 92.703922 -276.111772)
			(xy 92.710351 -276.085845) (xy 92.709848 -276.059137) (xy 92.702447 -276.03347) (xy 92.688654 -276.010594)
			(xy 92.669408 -275.992069) (xy 92.65793 -275.985224) (xy 92.63684 -275.973138) (xy 92.59827 -275.943559)
			(xy 92.564654 -275.908452) (xy 92.536775 -275.868636) (xy 92.515282 -275.825039) (xy 92.500678 -275.778679)
			(xy 92.493303 -275.730635) (xy 92.49283 -275.706332) (xy 92.493293 -275.681319) (xy 92.501114 -275.631908)
			(xy 92.516569 -275.584329) (xy 92.539277 -275.539754) (xy 92.568678 -275.49928) (xy 92.60405 -275.463904)
			(xy 92.64452 -275.434498) (xy 92.689092 -275.411784) (xy 92.736669 -275.396323) (xy 92.786079 -275.388496)
			(xy 92.811092 -275.38807) (xy 92.838083 -275.388662) (xy 92.891286 -275.397811) (xy 92.942186 -275.415797)
			(xy 92.966032 -275.428456) (xy 92.977893 -275.434633) (xy 93.003814 -275.441178) (xy 93.030545 -275.440761)
			(xy 93.056249 -275.433409) (xy 93.079158 -275.419628) (xy 93.097697 -275.400367) (xy 93.104462 -275.388832)
			(xy 93.151452 -275.303996) (xy 93.158472 -275.290099) (xy 93.164604 -275.259589) (xy 93.161289 -275.228646)
			(xy 93.148833 -275.200128) (xy 93.128388 -275.176667) (xy 93.115384 -275.168106) (xy 93.092472 -275.1535)
			(xy 93.051548 -275.117764) (xy 93.017284 -275.0756) (xy 92.990675 -275.028231) (xy 92.972493 -274.977033)
			(xy 92.963266 -274.923491) (xy 92.96273 -274.896326) (xy 92.963193 -274.871313) (xy 92.971015 -274.821903)
			(xy 92.986471 -274.774325) (xy 93.009179 -274.729751) (xy 93.03858 -274.689278) (xy 93.073952 -274.653903)
			(xy 93.114422 -274.624496) (xy 93.158994 -274.601784) (xy 93.20657 -274.586323) (xy 93.255979 -274.578496)
			(xy 93.280992 -274.578064) (xy 93.305581 -274.57852) (xy 93.354174 -274.586079) (xy 93.401027 -274.601019)
			(xy 93.423232 -274.611592) (xy 93.43741 -274.618059) (xy 93.468169 -274.622962) (xy 93.498978 -274.618379)
			(xy 93.526977 -274.604733) (xy 93.54957 -274.583293) (xy 93.557598 -274.569936) (xy 93.60535 -274.483576)
			(xy 93.612202 -274.470117) (xy 93.618503 -274.440595) (xy 93.615887 -274.410522) (xy 93.604584 -274.382532)
			(xy 93.585583 -274.359076) (xy 93.573346 -274.350226) (xy 93.552115 -274.335299) (xy 93.514355 -274.299699)
			(xy 93.482867 -274.258447) (xy 93.458487 -274.212634) (xy 93.441859 -274.163474) (xy 93.433423 -274.112268)
			(xy 93.432884 -274.08632) (xy 93.433348 -274.061309) (xy 93.441171 -274.011903) (xy 93.456627 -273.964329)
			(xy 93.479337 -273.91976) (xy 93.508739 -273.879292) (xy 93.544112 -273.843923) (xy 93.584582 -273.814523)
			(xy 93.629153 -273.791817) (xy 93.676728 -273.776365) (xy 93.726135 -273.768546) (xy 93.751146 -273.768058)
			(xy 93.773301 -273.768457) (xy 93.81718 -273.774634) (xy 93.859779 -273.786836) (xy 93.880178 -273.79549)
			(xy 93.894215 -273.801157) (xy 93.924244 -273.804864) (xy 93.95404 -273.799607) (xy 93.980987 -273.785849)
			(xy 94.002719 -273.764798) (xy 94.01048 -273.751802) (xy 94.082616 -273.6215) (xy 94.086966 -273.612564)
			(xy 94.089172 -273.592831) (xy 94.086934 -273.583146) (xy 94.086934 -273.582892) (xy 94.083863 -273.573541)
			(xy 94.071853 -273.557971) (xy 94.063566 -273.552666) (xy 94.063312 -273.552666) (xy 94.042745 -273.540429)
			(xy 94.005201 -273.51075) (xy 93.972521 -273.475787) (xy 93.945441 -273.436328) (xy 93.92457 -273.393261)
			(xy 93.910379 -273.347556) (xy 93.903186 -273.300243) (xy 93.902784 -273.276314) (xy 93.903248 -273.251303)
			(xy 93.911072 -273.201898) (xy 93.926529 -273.154325) (xy 93.949239 -273.109756) (xy 93.978642 -273.069289)
			(xy 94.014014 -273.033921) (xy 94.054484 -273.004522) (xy 94.099055 -272.981817) (xy 94.146629 -272.966364)
			(xy 94.196035 -272.958546) (xy 94.221046 -272.958052) (xy 94.247165 -272.958603) (xy 94.298698 -272.967169)
			(xy 94.348147 -272.984016) (xy 94.371414 -272.995898) (xy 94.380451 -273.000168) (xy 94.400321 -273.002119)
			(xy 94.410022 -272.999708) (xy 94.419674 -272.996914) (xy 94.434914 -272.984468) (xy 94.446344 -272.963894)
			(xy 94.53626 -272.801588) (xy 94.54054 -272.793046) (xy 94.543014 -272.774116) (xy 94.541086 -272.764758)
			(xy 94.5388 -272.75536) (xy 94.52737 -272.739612) (xy 94.519242 -272.734278) (xy 94.49716 -272.7195)
			(xy 94.457802 -272.68381) (xy 94.424917 -272.642079) (xy 94.399419 -272.595466) (xy 94.382015 -272.545266)
			(xy 94.373191 -272.492873) (xy 94.372684 -272.466308) (xy 94.373149 -272.441298) (xy 94.380973 -272.391893)
			(xy 94.396431 -272.344321) (xy 94.419141 -272.299753) (xy 94.448544 -272.259287) (xy 94.483916 -272.223919)
			(xy 94.524385 -272.194521) (xy 94.568956 -272.171816) (xy 94.61653 -272.156364) (xy 94.665936 -272.148546)
			(xy 94.690946 -272.148046) (xy 94.714385 -272.148465) (xy 94.760756 -272.155345) (xy 94.805617 -272.168947)
			(xy 94.847999 -272.18898) (xy 94.86773 -272.20164) (xy 94.875228 -272.206202) (xy 94.892239 -272.210482)
			(xy 94.901004 -272.210022) (xy 94.90964 -272.20926) (xy 94.925134 -272.201894) (xy 95.033084 -272.093944)
			(xy 95.040377 -272.085443) (xy 95.047489 -272.06423) (xy 95.0468 -272.05305) (xy 95.046546 -272.05178)
			(xy 95.044006 -272.034) (xy 95.044006 -272.033492) (xy 95.034862 -271.972532) (xy 95.033798 -271.966816)
			(xy 95.029437 -271.956042) (xy 95.026226 -271.951196) (xy 95.023178 -271.946624) (xy 95.014796 -271.939004)
			(xy 95.009208 -271.935956) (xy 94.987971 -271.923913) (xy 94.949133 -271.89433) (xy 94.915266 -271.859166)
			(xy 94.887165 -271.819244) (xy 94.865487 -271.775499) (xy 94.850741 -271.728959) (xy 94.843273 -271.680712)
			(xy 94.842838 -271.656302) (xy 94.843303 -271.631291) (xy 94.851128 -271.581884) (xy 94.866586 -271.53431)
			(xy 94.889295 -271.489739) (xy 94.918697 -271.44927) (xy 94.954069 -271.413899) (xy 94.994538 -271.384496)
			(xy 95.039108 -271.361786) (xy 95.086682 -271.346328) (xy 95.136089 -271.338503) (xy 95.1611 -271.33804)
			(xy 95.18551 -271.338484) (xy 95.233758 -271.345942) (xy 95.280299 -271.360683) (xy 95.324043 -271.38236)
			(xy 95.363963 -271.410465) (xy 95.39912 -271.444338) (xy 95.42869 -271.483184) (xy 95.440754 -271.50441)
			(xy 95.440754 -271.504664) (xy 95.443753 -271.509753) (xy 95.451713 -271.518478) (xy 95.456502 -271.521936)
			(xy 95.46082 -271.524984) (xy 95.471488 -271.529048) (xy 95.53829 -271.539208) (xy 95.538798 -271.539208)
			(xy 95.556578 -271.541748) (xy 95.557848 -271.542002) (xy 95.56903 -271.542715) (xy 95.590244 -271.53559)
			(xy 95.598742 -271.528286) (xy 96.15043 -270.976598) (xy 96.152462 -270.973804) (xy 96.163247 -270.95996)
			(xy 96.185605 -270.932904) (xy 96.197166 -270.919702) (xy 96.228154 -270.886174) (xy 96.231258 -270.882421)
			(xy 96.23611 -270.873976) (xy 96.237806 -270.86941) (xy 96.239037 -270.865461) (xy 96.240311 -270.85729)
			(xy 96.240346 -270.853154) (xy 96.240346 -270.8275) (xy 96.240259 -270.822825) (xy 96.23859 -270.813625)
			(xy 96.237044 -270.809212) (xy 96.233488 -270.800322) (xy 96.226376 -270.792956) (xy 96.19222 -270.755326)
			(xy 96.13016 -270.67484) (xy 96.075699 -270.58903) (xy 96.029291 -270.49861) (xy 95.991322 -270.404335)
			(xy 95.976186 -270.355822) (xy 95.97517 -270.352774) (xy 95.973138 -270.34617) (xy 95.949262 -270.316198)
			(xy 95.941134 -270.311372) (xy 95.919292 -270.298072) (xy 95.879776 -270.265618) (xy 95.845958 -270.227263)
			(xy 95.818708 -270.183994) (xy 95.798727 -270.136924) (xy 95.786529 -270.087265) (xy 95.782428 -270.036295)
			(xy 95.78653 -269.985325) (xy 95.79873 -269.935666) (xy 95.818712 -269.888597) (xy 95.845964 -269.845329)
			(xy 95.879783 -269.806975) (xy 95.9193 -269.774522) (xy 95.941134 -269.761208) (xy 95.949262 -269.756382)
			(xy 95.973138 -269.726664) (xy 95.976186 -269.717012) (xy 95.991577 -269.66767) (xy 96.0303 -269.571832)
			(xy 96.077763 -269.480007) (xy 96.133555 -269.392991) (xy 96.197192 -269.311537) (xy 96.232218 -269.273528)
			(xy 96.232472 -269.273274) (xy 96.238822 -269.266416) (xy 96.252792 -269.23238) (xy 96.252792 -269.222728)
			(xy 96.253549 -269.197544) (xy 96.262043 -269.147884) (xy 96.278268 -269.100186) (xy 96.289622 -269.077694)
			(xy 96.292416 -269.072106) (xy 96.295464 -269.060168) (xy 96.295464 -268.823694) (xy 96.295394 -268.819561)
			(xy 96.294113 -268.811397) (xy 96.292924 -268.807438) (xy 96.290564 -268.801191) (xy 96.2831 -268.790122)
			(xy 96.278192 -268.785594) (xy 96.215962 -268.73581) (xy 96.211416 -268.732402) (xy 96.201156 -268.727529)
			(xy 96.195642 -268.726158) (xy 96.18472 -268.723618) (xy 96.173036 -268.726412) (xy 96.155311 -268.730225)
			(xy 96.119283 -268.734297) (xy 96.101154 -268.73454) (xy 96.076149 -268.734046) (xy 96.026755 -268.726216)
			(xy 95.979195 -268.710757) (xy 95.934637 -268.688048) (xy 95.894181 -268.658649) (xy 95.858821 -268.623284)
			(xy 95.829428 -268.582823) (xy 95.806726 -268.538263) (xy 95.791273 -268.4907) (xy 95.78345 -268.441305)
			(xy 95.78345 -268.391295) (xy 95.791273 -268.3419) (xy 95.806726 -268.294337) (xy 95.829428 -268.249777)
			(xy 95.858821 -268.209316) (xy 95.894181 -268.173951) (xy 95.934637 -268.144552) (xy 95.979195 -268.121843)
			(xy 96.026755 -268.106384) (xy 96.076149 -268.098554) (xy 96.101154 -268.098016) (xy 96.129556 -268.098643)
			(xy 96.185461 -268.10872) (xy 96.238693 -268.128547) (xy 96.26346 -268.142466) (xy 96.263968 -268.14272)
			(xy 96.27139 -268.146668) (xy 96.287849 -268.150029) (xy 96.296226 -268.149324) (xy 96.303846 -268.148308)
			(xy 96.319086 -268.140942) (xy 96.425004 -268.035024) (xy 96.432164 -268.027001) (xy 96.439778 -268.006916)
			(xy 96.439736 -267.996162) (xy 96.430338 -267.916152) (xy 96.429494 -267.910348) (xy 96.425518 -267.899316)
			(xy 96.422464 -267.894308) (xy 96.41967 -267.889482) (xy 96.411288 -267.881608) (xy 96.406208 -267.87856)
			(xy 96.383189 -267.863977) (xy 96.342058 -267.828239) (xy 96.307615 -267.786017) (xy 96.280867 -267.738546)
			(xy 96.262597 -267.687212) (xy 96.253337 -267.633516) (xy 96.252792 -267.606272) (xy 96.253285 -267.581263)
			(xy 96.261112 -267.531861) (xy 96.276571 -267.484292) (xy 96.299279 -267.439726) (xy 96.328679 -267.39926)
			(xy 96.364046 -267.363891) (xy 96.40451 -267.334489) (xy 96.449075 -267.311778) (xy 96.496644 -267.296317)
			(xy 96.546045 -267.288486) (xy 96.571054 -267.28801) (xy 96.598295 -267.288572) (xy 96.65198 -267.297852)
			(xy 96.703303 -267.316132) (xy 96.750767 -267.342878) (xy 96.792987 -267.377312) (xy 96.828732 -267.418427)
			(xy 96.843342 -267.441426) (xy 96.846471 -267.446319) (xy 96.854545 -267.454666) (xy 96.859344 -267.457936)
			(xy 96.86417 -267.460984) (xy 96.874838 -267.465048) (xy 96.96069 -267.474954) (xy 96.971529 -267.475158)
			(xy 96.9918 -267.467531) (xy 96.999806 -267.460222) (xy 97.423732 -267.036296) (xy 97.430444 -267.029057)
			(xy 97.438038 -267.010853) (xy 97.438464 -267.00099) (xy 97.438464 -266.788138) (xy 97.438998 -266.778299)
			(xy 97.446579 -266.760133) (xy 97.453196 -266.752832) (xy 97.696782 -266.509246) (xy 97.701768 -266.503747)
			(xy 97.708607 -266.490579) (xy 97.710244 -266.483338) (xy 97.71126 -266.473686) (xy 97.71126 -266.386564)
			(xy 97.711752 -266.371537) (xy 97.719527 -266.342504) (xy 97.734538 -266.316466) (xy 97.755767 -266.295191)
			(xy 97.781772 -266.280123) (xy 97.810788 -266.272285) (xy 97.825814 -266.271756) (xy 97.917762 -266.271756)
			(xy 97.922923 -266.271662) (xy 97.933037 -266.269611) (xy 97.937828 -266.267692) (xy 97.947734 -266.263374)
			(xy 97.952362 -266.261603) (xy 97.962084 -266.259689) (xy 97.967038 -266.259564) (xy 98.070162 -266.259564)
			(xy 98.082257 -266.258825) (xy 98.103739 -266.247689) (xy 98.11131 -266.238228) (xy 98.13925 -266.195302)
			(xy 98.139758 -266.194794) (xy 98.1583 -266.165838) (xy 98.161563 -266.160375) (xy 98.165552 -266.148295)
			(xy 98.166174 -266.141962) (xy 98.166936 -266.12977) (xy 98.161856 -266.117832) (xy 98.161348 -266.117324)
			(xy 98.152455 -266.096674) (xy 98.139907 -266.053501) (xy 98.133547 -266.008994) (xy 98.133154 -265.986514)
			(xy 98.133154 -265.98626) (xy 98.133644 -265.961271) (xy 98.141463 -265.911908) (xy 98.156907 -265.864376)
			(xy 98.179597 -265.819844) (xy 98.208973 -265.779411) (xy 98.244313 -265.744071) (xy 98.284746 -265.714695)
			(xy 98.329278 -265.692005) (xy 98.37681 -265.676561) (xy 98.426173 -265.668742) (xy 98.476151 -265.668742)
			(xy 98.525514 -265.676561) (xy 98.573046 -265.692005) (xy 98.617578 -265.714695) (xy 98.658011 -265.744071)
			(xy 98.693351 -265.779411) (xy 98.722727 -265.819844) (xy 98.745417 -265.864376) (xy 98.760861 -265.911908)
			(xy 98.76868 -265.961271) (xy 98.76917 -265.98626) (xy 98.76917 -265.986514) (xy 98.768784 -266.008995)
			(xy 98.762445 -266.053507) (xy 98.74988 -266.096678) (xy 98.740976 -266.117324) (xy 98.740468 -266.117832)
			(xy 98.740468 -266.11834) (xy 98.738113 -266.124007) (xy 98.735938 -266.136082) (xy 98.73615 -266.142216)
			(xy 98.737166 -266.154916) (xy 98.762566 -266.194794) (xy 98.763074 -266.195302) (xy 98.791014 -266.238228)
			(xy 98.798582 -266.247696) (xy 98.820064 -266.258844) (xy 98.832162 -266.259564) (xy 99.57689 -266.259564)
			(xy 99.586727 -266.259026) (xy 99.604889 -266.251441) (xy 99.612196 -266.244832) (xy 100.344732 -265.512296)
			(xy 100.351971 -265.505585) (xy 100.370176 -265.497997) (xy 100.380038 -265.497564) (xy 100.97389 -265.497564)
			(xy 100.983727 -265.497026) (xy 101.001889 -265.489441) (xy 101.009196 -265.482832) (xy 101.106732 -265.385296)
			(xy 101.113444 -265.378057) (xy 101.121038 -265.359853) (xy 101.121464 -265.34999) (xy 101.121464 -264.688066)
			(xy 101.121298 -264.682056) (xy 101.118476 -264.670373) (xy 101.115876 -264.664952) (xy 101.106732 -264.648442)
			(xy 101.1047 -264.644886) (xy 101.101398 -264.639044) (xy 101.094794 -264.63117) (xy 101.090476 -264.628122)
			(xy 101.089206 -264.62736) (xy 101.06761 -264.611633) (xy 101.029511 -264.574185) (xy 100.998202 -264.5309)
			(xy 100.974562 -264.482994) (xy 100.959256 -264.431812) (xy 100.952712 -264.378793) (xy 100.955116 -264.325426)
			(xy 100.960174 -264.299192) (xy 100.965607 -264.275981) (xy 100.982481 -264.231398) (xy 101.005816 -264.189831)
			(xy 101.035089 -264.152209) (xy 101.069646 -264.119373) (xy 101.088952 -264.10539) (xy 101.093778 -264.102088)
			(xy 101.101398 -264.093706) (xy 101.1047 -264.087864) (xy 101.1047 -264.08761) (xy 101.115114 -264.068814)
			(xy 101.118073 -264.06309) (xy 101.12129 -264.050617) (xy 101.121464 -264.044176) (xy 101.121464 -263.068054)
			(xy 101.121297 -263.062044) (xy 101.118472 -263.050362) (xy 101.115876 -263.04494) (xy 101.106732 -263.02843)
			(xy 101.1047 -263.024874) (xy 101.101398 -263.019032) (xy 101.094794 -263.011158) (xy 101.090476 -263.00811)
			(xy 101.089206 -263.007348) (xy 101.067604 -262.991622) (xy 101.029494 -262.954176) (xy 100.998172 -262.910892)
			(xy 100.974519 -262.862984) (xy 100.959199 -262.811799) (xy 100.952643 -262.758775) (xy 100.955033 -262.7054)
			(xy 100.960174 -262.67918) (xy 100.965607 -262.655969) (xy 100.982483 -262.611388) (xy 101.005819 -262.569822)
			(xy 101.035093 -262.532201) (xy 101.06965 -262.499366) (xy 101.088952 -262.485378) (xy 101.093778 -262.482076)
			(xy 101.101398 -262.473694) (xy 101.1047 -262.467852) (xy 101.1047 -262.467598) (xy 101.115114 -262.448802)
			(xy 101.118072 -262.443078) (xy 101.121286 -262.430605) (xy 101.121464 -262.424164) (xy 101.121464 -261.962646)
			(xy 101.121296 -261.956637) (xy 101.11847 -261.944956) (xy 101.115876 -261.939532) (xy 101.114038 -261.936056)
			(xy 101.109448 -261.929674) (xy 101.106732 -261.926832) (xy 100.574856 -261.394956) (xy 100.568415 -261.388984)
			(xy 100.552566 -261.381444) (xy 100.543868 -261.380224) (xy 100.534978 -261.379462) (xy 100.517706 -261.38378)
			(xy 100.512372 -261.387336) (xy 100.492327 -261.400739) (xy 100.449039 -261.42198) (xy 100.403037 -261.436433)
			(xy 100.355379 -261.443764) (xy 100.33127 -261.444232) (xy 100.324158 -261.444232) (xy 100.299525 -261.443238)
			(xy 100.250995 -261.434582) (xy 100.204382 -261.418538) (xy 100.160804 -261.395491) (xy 100.121306 -261.365994)
			(xy 100.086835 -261.330753) (xy 100.058217 -261.290614) (xy 100.036138 -261.246538) (xy 100.021127 -261.199583)
			(xy 100.013545 -261.150873) (xy 100.013008 -261.126224) (xy 100.013471 -261.101232) (xy 100.021287 -261.051863)
			(xy 100.03673 -261.004325) (xy 100.059421 -260.959788) (xy 100.0888 -260.919349) (xy 100.124143 -260.884005)
			(xy 100.164581 -260.854625) (xy 100.209117 -260.831933) (xy 100.256655 -260.816489) (xy 100.306024 -260.808671)
			(xy 100.331016 -260.808216) (xy 100.33127 -260.808216) (xy 100.341779 -260.808312) (xy 100.362751 -260.809711)
			(xy 100.37318 -260.81101) (xy 100.384356 -260.812534) (xy 100.394516 -260.809486) (xy 100.399598 -260.807772)
			(xy 100.408942 -260.802512) (xy 100.413058 -260.799072) (xy 100.432108 -260.782308) (xy 100.469192 -260.749542)
			(xy 100.476982 -260.742003) (xy 100.485911 -260.72227) (xy 100.486464 -260.711442) (xy 100.486464 -256.501646)
			(xy 100.486296 -256.495637) (xy 100.48347 -256.483956) (xy 100.480876 -256.478532) (xy 100.479038 -256.475056)
			(xy 100.474448 -256.468674) (xy 100.471732 -256.465832) (xy 100.247196 -256.241296) (xy 100.244344 -256.238592)
			(xy 100.237964 -256.234003) (xy 100.234496 -256.232152) (xy 100.229071 -256.229562) (xy 100.217391 -256.226727)
			(xy 100.211382 -256.226564) (xy 99.374198 -256.226564) (xy 99.36988 -256.226818) (xy 99.35746 -256.228529)
			(xy 99.336421 -256.242112) (xy 99.329748 -256.252726) (xy 99.326954 -256.258822) (xy 99.30257 -256.321306)
			(xy 99.294188 -256.342896) (xy 99.291696 -256.350057) (xy 99.290669 -256.365178) (xy 99.292156 -256.372614)
			(xy 99.295458 -256.3876) (xy 99.313292 -256.402902) (xy 99.34472 -256.437837) (xy 99.37071 -256.476987)
			(xy 99.390702 -256.519513) (xy 99.404269 -256.564503) (xy 99.411119 -256.610992) (xy 99.411536 -256.634488)
			(xy 99.411025 -256.660609) (xy 99.402542 -256.712156) (xy 99.385786 -256.761636) (xy 99.361201 -256.807731)
			(xy 99.34575 -256.828798) (xy 99.343249 -256.832171) (xy 99.339292 -256.839577) (xy 99.337876 -256.84353)
			(xy 99.335844 -256.849626) (xy 99.335844 -256.879852) (xy 99.335844 -256.880868) (xy 99.335807 -256.902151)
			(xy 99.328322 -256.944043) (xy 99.312706 -256.983628) (xy 99.289573 -257.019346) (xy 99.259838 -257.049788)
			(xy 99.224673 -257.073752) (xy 99.185465 -257.090294) (xy 99.143761 -257.09876) (xy 99.122484 -257.099308)
			(xy 98.897186 -257.099308) (xy 98.867468 -257.06959) (xy 98.867468 -257.05943) (xy 98.86569 -257.05562)
			(xy 98.853498 -257.047746) (xy 98.84717 -257.043876) (xy 98.832971 -257.039607) (xy 98.825558 -257.039364)
			(xy 98.632518 -257.039364) (xy 98.6028 -257.009646) (xy 98.6028 -256.99466) (xy 98.602546 -256.99212)
			(xy 98.602546 -256.477008) (xy 98.6028 -256.474468) (xy 98.6028 -256.459482) (xy 98.632518 -256.429764)
			(xy 98.815398 -256.429764) (xy 98.820566 -256.429577) (xy 98.830674 -256.427397) (xy 98.835464 -256.425446)
			(xy 98.845878 -256.421128) (xy 98.852482 -256.414524) (xy 98.859318 -256.407122) (xy 98.867028 -256.388524)
			(xy 98.867468 -256.378456) (xy 98.867468 -256.36982) (xy 98.895408 -256.36982) (xy 98.902448 -256.369598)
			(xy 98.915986 -256.365734) (xy 98.922078 -256.3622) (xy 98.945213 -256.348444) (xy 98.995009 -256.328022)
			(xy 99.021138 -256.32156) (xy 99.021392 -256.32156) (xy 99.031552 -256.308352) (xy 99.035056 -256.30351)
			(xy 99.039926 -256.2926) (xy 99.041204 -256.286762) (xy 99.041966 -256.28219) (xy 99.041966 -256.277364)
			(xy 99.041471 -256.267364) (xy 99.033804 -256.24889) (xy 99.019651 -256.234756) (xy 99.001167 -256.227115)
			(xy 98.991166 -256.226564) (xy 97.494598 -256.226564) (xy 97.484754 -256.227008) (xy 97.466518 -256.234425)
			(xy 97.452446 -256.248192) (xy 97.448116 -256.257044) (xy 97.434654 -256.291334) (xy 97.413826 -256.344674)
			(xy 97.411227 -256.351941) (xy 97.410074 -256.367323) (xy 97.41154 -256.3749) (xy 97.413318 -256.382012)
			(xy 97.420938 -256.394966) (xy 97.42678 -256.4003) (xy 97.44577 -256.418541) (xy 97.478088 -256.460108)
			(xy 97.50313 -256.506424) (xy 97.520214 -256.556227) (xy 97.528875 -256.608162) (xy 97.529396 -256.634488)
			(xy 97.528905 -256.659497) (xy 97.521081 -256.7089) (xy 97.505624 -256.75647) (xy 97.482916 -256.801037)
			(xy 97.453516 -256.841502) (xy 97.418148 -256.87687) (xy 97.377683 -256.90627) (xy 97.333116 -256.928978)
			(xy 97.285546 -256.944435) (xy 97.236143 -256.952259) (xy 97.186125 -256.952259) (xy 97.136722 -256.944435)
			(xy 97.089152 -256.928978) (xy 97.044585 -256.90627) (xy 97.00412 -256.87687) (xy 96.968752 -256.841502)
			(xy 96.939352 -256.801037) (xy 96.916644 -256.75647) (xy 96.901187 -256.7089) (xy 96.893363 -256.659497)
			(xy 96.892872 -256.634488) (xy 96.893415 -256.608163) (xy 96.902075 -256.556231) (xy 96.919156 -256.50643)
			(xy 96.944195 -256.460116) (xy 96.976509 -256.41855) (xy 96.995488 -256.4003) (xy 97.000956 -256.394952)
			(xy 97.008694 -256.381766) (xy 97.010728 -256.374392) (xy 97.012506 -256.367026) (xy 97.01149 -256.35204)
			(xy 96.987614 -256.291334) (xy 96.974152 -256.257044) (xy 96.969791 -256.248218) (xy 96.955709 -256.234486)
			(xy 96.937503 -256.227043) (xy 96.92767 -256.226564) (xy 96.316038 -256.226564) (xy 96.306198 -256.226031)
			(xy 96.288029 -256.218454) (xy 96.280732 -256.211832) (xy 96.183196 -256.114296) (xy 96.176481 -256.107059)
			(xy 96.168883 -256.088854) (xy 96.168464 -256.07899) (xy 96.168464 -256.013966) (xy 96.168038 -256.003952)
			(xy 96.160361 -255.985453) (xy 96.146188 -255.9713) (xy 96.127679 -255.963648) (xy 96.117664 -255.963166)
			(xy 96.104202 -255.963166) (xy 96.092772 -255.969516) (xy 96.087165 -255.972907) (xy 96.077773 -255.982038)
			(xy 96.07423 -255.98755) (xy 96.073976 -255.987804) (xy 96.073976 -255.988058) (xy 96.061568 -256.007965)
			(xy 96.031822 -256.044236) (xy 95.997073 -256.075745) (xy 95.958074 -256.101812) (xy 95.91567 -256.12187)
			(xy 95.870781 -256.135484) (xy 95.82438 -256.142361) (xy 95.800926 -256.142744) (xy 95.775915 -256.142281)
			(xy 95.726508 -256.134459) (xy 95.678933 -256.119005) (xy 95.634362 -256.096298) (xy 95.593892 -256.066897)
			(xy 95.558519 -256.031528) (xy 95.529116 -255.99106) (xy 95.506405 -255.946491) (xy 95.490947 -255.898917)
			(xy 95.483121 -255.849511) (xy 95.483121 -255.799489) (xy 95.490947 -255.750083) (xy 95.506405 -255.702509)
			(xy 95.529116 -255.65794) (xy 95.558519 -255.617472) (xy 95.593892 -255.582103) (xy 95.634362 -255.552702)
			(xy 95.678933 -255.529995) (xy 95.726508 -255.514541) (xy 95.775915 -255.506719) (xy 95.800926 -255.50622)
			(xy 95.80118 -255.50622) (xy 95.828749 -255.506835) (xy 95.883056 -255.516378) (xy 95.934914 -255.535113)
			(xy 95.982781 -255.562483) (xy 96.00438 -255.579626) (xy 96.004634 -255.57988) (xy 96.010376 -255.584267)
			(xy 96.023656 -255.589948) (xy 96.030796 -255.591056) (xy 96.0374 -255.591818) (xy 96.05137 -255.589786)
			(xy 96.141032 -255.547876) (xy 96.148676 -255.543514) (xy 96.160652 -255.530636) (xy 96.167568 -255.514467)
			(xy 96.168464 -255.505712) (xy 96.168464 -255.349756) (xy 96.168213 -255.342576) (xy 96.164207 -255.328786)
			(xy 96.16059 -255.322578) (xy 96.15678 -255.316736) (xy 96.145858 -255.307338) (xy 96.138746 -255.304036)
			(xy 96.115338 -255.292754) (xy 96.072233 -255.263742) (xy 96.03441 -255.228118) (xy 96.002872 -255.186825)
			(xy 95.978457 -255.14096) (xy 95.961811 -255.091739) (xy 95.953377 -255.040469) (xy 95.953379 -254.988511)
			(xy 95.961816 -254.937241) (xy 95.978464 -254.888022) (xy 96.002883 -254.842158) (xy 96.034423 -254.800867)
			(xy 96.072249 -254.765245) (xy 96.115356 -254.736236) (xy 96.138746 -254.724916) (xy 96.139 -254.724662)
			(xy 96.145572 -254.721431) (xy 96.156664 -254.711879) (xy 96.160844 -254.705866) (xy 96.1644 -254.700024)
			(xy 96.168464 -254.686562) (xy 96.168464 -254.526288) (xy 96.168464 -254.52324) (xy 96.167569 -254.514487)
			(xy 96.160642 -254.498328) (xy 96.148661 -254.485461) (xy 96.141032 -254.481076) (xy 96.057974 -254.442214)
			(xy 96.051421 -254.439446) (xy 96.037372 -254.437247) (xy 96.030288 -254.437896) (xy 96.02343 -254.438658)
			(xy 96.010476 -254.444246) (xy 96.00438 -254.449326) (xy 95.982801 -254.466502) (xy 95.934946 -254.493912)
			(xy 95.883078 -254.512648) (xy 95.828754 -254.522148) (xy 95.80118 -254.522732) (xy 95.800926 -254.522732)
			(xy 95.775916 -254.522269) (xy 95.726511 -254.514448) (xy 95.678938 -254.498994) (xy 95.634368 -254.476287)
			(xy 95.5939 -254.446888) (xy 95.558529 -254.41152) (xy 95.529126 -254.371054) (xy 95.506416 -254.326486)
			(xy 95.490958 -254.278914) (xy 95.483133 -254.22951) (xy 95.483133 -254.17949) (xy 95.490958 -254.130086)
			(xy 95.506416 -254.082514) (xy 95.529126 -254.037946) (xy 95.558529 -253.99748) (xy 95.5939 -253.962112)
			(xy 95.634368 -253.932713) (xy 95.678938 -253.910006) (xy 95.726511 -253.894552) (xy 95.775916 -253.886731)
			(xy 95.800926 -253.886208) (xy 95.80118 -253.886208) (xy 95.828749 -253.886823) (xy 95.883056 -253.896365)
			(xy 95.934915 -253.9151) (xy 95.982782 -253.942469) (xy 96.00438 -253.959614) (xy 96.004634 -253.959868)
			(xy 96.010379 -253.964248) (xy 96.023659 -253.96992) (xy 96.030796 -253.971044) (xy 96.0374 -253.971806)
			(xy 96.05137 -253.969774) (xy 96.141032 -253.927864) (xy 96.148674 -253.923501) (xy 96.160648 -253.910623)
			(xy 96.16756 -253.894454) (xy 96.168464 -253.8857) (xy 96.168464 -253.729744) (xy 96.168211 -253.722565)
			(xy 96.164203 -253.708776) (xy 96.16059 -253.702566) (xy 96.15678 -253.696724) (xy 96.145858 -253.687326)
			(xy 96.138746 -253.684024) (xy 96.115339 -253.672742) (xy 96.072236 -253.643731) (xy 96.034415 -253.608107)
			(xy 96.002879 -253.566815) (xy 95.978465 -253.520951) (xy 95.96182 -253.471732) (xy 95.953388 -253.420464)
			(xy 95.95339 -253.368506) (xy 95.961828 -253.317239) (xy 95.978476 -253.268022) (xy 96.002895 -253.22216)
			(xy 96.034435 -253.180871) (xy 96.07226 -253.14525) (xy 96.115366 -253.116243) (xy 96.138746 -253.104904)
			(xy 96.139 -253.10465) (xy 96.145571 -253.101419) (xy 96.156661 -253.091865) (xy 96.160844 -253.085854)
			(xy 96.1644 -253.080012) (xy 96.168464 -253.06655) (xy 96.168464 -252.906276) (xy 96.168464 -252.903228)
			(xy 96.167567 -252.894477) (xy 96.160638 -252.87832) (xy 96.148656 -252.865456) (xy 96.141032 -252.861064)
			(xy 96.057974 -252.822202) (xy 96.051421 -252.819434) (xy 96.037372 -252.817235) (xy 96.030288 -252.817884)
			(xy 96.02343 -252.818646) (xy 96.010476 -252.824234) (xy 96.00438 -252.829314) (xy 95.982801 -252.846491)
			(xy 95.934947 -252.873901) (xy 95.883079 -252.892638) (xy 95.828755 -252.902139) (xy 95.80118 -252.90272)
			(xy 95.800926 -252.90272) (xy 95.775917 -252.902257) (xy 95.726514 -252.894436) (xy 95.678942 -252.878983)
			(xy 95.634375 -252.856277) (xy 95.593907 -252.826879) (xy 95.558538 -252.791512) (xy 95.529136 -252.751048)
			(xy 95.506427 -252.706482) (xy 95.49097 -252.658912) (xy 95.483145 -252.609509) (xy 95.483145 -252.559491)
			(xy 95.49097 -252.510088) (xy 95.506427 -252.462518) (xy 95.529136 -252.417952) (xy 95.558538 -252.377488)
			(xy 95.593907 -252.342121) (xy 95.634375 -252.312723) (xy 95.678942 -252.290017) (xy 95.726514 -252.274564)
			(xy 95.775917 -252.266743) (xy 95.800926 -252.266196) (xy 95.80118 -252.266196) (xy 95.828749 -252.266811)
			(xy 95.883057 -252.276352) (xy 95.934916 -252.295086) (xy 95.982784 -252.322455) (xy 96.00438 -252.339602)
			(xy 96.004634 -252.339856) (xy 96.010379 -252.344237) (xy 96.023659 -252.34991) (xy 96.030796 -252.351032)
			(xy 96.0374 -252.351794) (xy 96.05137 -252.349762) (xy 96.141032 -252.307852) (xy 96.148683 -252.303494)
			(xy 96.160678 -252.29062) (xy 96.167618 -252.274451) (xy 96.168464 -252.265688) (xy 96.168464 -252.109732)
			(xy 96.168223 -252.102549) (xy 96.164235 -252.088748) (xy 96.16059 -252.082554) (xy 96.15678 -252.076712)
			(xy 96.145858 -252.067314) (xy 96.138746 -252.064012) (xy 96.11534 -252.05273) (xy 96.072239 -252.023719)
			(xy 96.03442 -251.988096) (xy 96.002885 -251.946805) (xy 95.978473 -251.900942) (xy 95.96183 -251.851724)
			(xy 95.953398 -251.800458) (xy 95.953401 -251.748502) (xy 95.961839 -251.697237) (xy 95.978488 -251.648021)
			(xy 96.002907 -251.602162) (xy 96.034446 -251.560875) (xy 96.07227 -251.525256) (xy 96.115375 -251.49625)
			(xy 96.138746 -251.484892) (xy 96.139 -251.484638) (xy 96.145576 -251.481412) (xy 96.15668 -251.471867)
			(xy 96.160844 -251.465842) (xy 96.1644 -251.46) (xy 96.168464 -251.446538) (xy 96.168464 -251.286264)
			(xy 96.168464 -251.283216) (xy 96.167565 -251.274466) (xy 96.160633 -251.258313) (xy 96.148652 -251.245452)
			(xy 96.141032 -251.241052) (xy 96.057974 -251.20219) (xy 96.051421 -251.199422) (xy 96.037372 -251.197225)
			(xy 96.030288 -251.197872) (xy 96.02343 -251.198634) (xy 96.010476 -251.204222) (xy 96.00438 -251.209302)
			(xy 95.982801 -251.226479) (xy 95.934947 -251.253891) (xy 95.883079 -251.272629) (xy 95.828755 -251.28213)
			(xy 95.80118 -251.282708) (xy 95.800926 -251.282708) (xy 95.77591 -251.282245) (xy 95.726493 -251.274422)
			(xy 95.678909 -251.258964) (xy 95.634328 -251.236253) (xy 95.59385 -251.206846) (xy 95.55847 -251.17147)
			(xy 95.529061 -251.130994) (xy 95.506346 -251.086415) (xy 95.490884 -251.038832) (xy 95.483057 -250.989416)
			(xy 95.483057 -250.939384) (xy 95.490884 -250.889968) (xy 95.506346 -250.842385) (xy 95.529061 -250.797806)
			(xy 95.55847 -250.75733) (xy 95.59385 -250.721954) (xy 95.634328 -250.692547) (xy 95.678909 -250.669836)
			(xy 95.726493 -250.654378) (xy 95.77591 -250.646555) (xy 95.800926 -250.646184) (xy 95.80118 -250.646184)
			(xy 95.828749 -250.646799) (xy 95.883057 -250.65634) (xy 95.934917 -250.675074) (xy 95.982785 -250.702441)
			(xy 96.00438 -250.71959) (xy 96.004634 -250.719844) (xy 96.010379 -250.724226) (xy 96.023658 -250.7299)
			(xy 96.030796 -250.73102) (xy 96.0374 -250.731782) (xy 96.05137 -250.72975) (xy 96.141032 -250.68784)
			(xy 96.148682 -250.683481) (xy 96.160674 -250.670607) (xy 96.16761 -250.654437) (xy 96.168464 -250.645676)
			(xy 96.168464 -250.48972) (xy 96.168221 -250.482537) (xy 96.164231 -250.468738) (xy 96.16059 -250.462542)
			(xy 96.15678 -250.4567) (xy 96.145858 -250.447302) (xy 96.138746 -250.444) (xy 96.115333 -250.432718)
			(xy 96.072217 -250.403705) (xy 96.034384 -250.368077) (xy 96.002837 -250.326779) (xy 95.978413 -250.280908)
			(xy 95.96176 -250.231679) (xy 95.953321 -250.180401) (xy 95.953318 -250.128432) (xy 95.961752 -250.077153)
			(xy 95.9784 -250.027923) (xy 96.002819 -249.982049) (xy 96.034362 -249.940748) (xy 96.072191 -249.905116)
			(xy 96.115304 -249.876098) (xy 96.138746 -249.86488) (xy 96.139 -249.864626) (xy 96.145575 -249.861399)
			(xy 96.156677 -249.851853) (xy 96.160844 -249.84583) (xy 96.1644 -249.839988) (xy 96.168464 -249.826526)
			(xy 96.168464 -249.666252) (xy 96.168464 -249.663204) (xy 96.167563 -249.654455) (xy 96.160629 -249.638305)
			(xy 96.148647 -249.625447) (xy 96.141032 -249.62104) (xy 96.057974 -249.582178) (xy 96.051421 -249.579411)
			(xy 96.037372 -249.577214) (xy 96.030288 -249.57786) (xy 96.02343 -249.578622) (xy 96.010476 -249.58421)
			(xy 96.00438 -249.58929) (xy 95.982801 -249.606468) (xy 95.934948 -249.63388) (xy 95.883079 -249.652619)
			(xy 95.828755 -249.662121) (xy 95.80118 -249.662696) (xy 95.800926 -249.662696) (xy 95.775911 -249.662233)
			(xy 95.726496 -249.65441) (xy 95.678913 -249.638953) (xy 95.634335 -249.616242) (xy 95.593858 -249.586837)
			(xy 95.55848 -249.551462) (xy 95.529072 -249.510987) (xy 95.506357 -249.466411) (xy 95.490896 -249.418829)
			(xy 95.483069 -249.369415) (xy 95.483069 -249.319385) (xy 95.490896 -249.269971) (xy 95.506357 -249.222389)
			(xy 95.529072 -249.177813) (xy 95.55848 -249.137338) (xy 95.593858 -249.101963) (xy 95.634335 -249.072558)
			(xy 95.678913 -249.049847) (xy 95.726496 -249.03439) (xy 95.775911 -249.026567) (xy 95.800926 -249.026172)
			(xy 95.80118 -249.026172) (xy 95.828749 -249.026787) (xy 95.883057 -249.036328) (xy 95.934917 -249.055061)
			(xy 95.982786 -249.082428) (xy 96.00438 -249.099578) (xy 96.004634 -249.099832) (xy 96.010378 -249.104215)
			(xy 96.023658 -249.109891) (xy 96.030796 -249.111008) (xy 96.0374 -249.11177) (xy 96.05137 -249.109738)
			(xy 96.141032 -249.067828) (xy 96.148681 -249.063469) (xy 96.16067 -249.050594) (xy 96.167602 -249.034424)
			(xy 96.168464 -249.025664) (xy 96.168464 -248.869708) (xy 96.16822 -248.862526) (xy 96.164226 -248.848728)
			(xy 96.16059 -248.84253) (xy 96.15678 -248.836688) (xy 96.145858 -248.82729) (xy 96.138746 -248.823988)
			(xy 96.115336 -248.812704) (xy 96.072227 -248.783688) (xy 96.034397 -248.748062) (xy 96.00285 -248.706769)
			(xy 95.978422 -248.660904) (xy 95.961761 -248.611683) (xy 95.953308 -248.56041) (xy 95.952818 -248.534428)
			(xy 95.953281 -248.509415) (xy 95.961103 -248.460004) (xy 95.976558 -248.412425) (xy 95.999266 -248.367849)
			(xy 96.028667 -248.327375) (xy 96.064038 -248.291998) (xy 96.104508 -248.262591) (xy 96.14908 -248.239876)
			(xy 96.196657 -248.224414) (xy 96.246067 -248.216585) (xy 96.27108 -248.216166) (xy 96.29931 -248.216781)
			(xy 96.354885 -248.226747) (xy 96.407834 -248.246352) (xy 96.456497 -248.274983) (xy 96.478344 -248.292874)
			(xy 96.485964 -248.299224) (xy 96.494092 -248.302018) (xy 96.498637 -248.303538) (xy 96.508096 -248.305077)
			(xy 96.512888 -248.305066) (xy 96.582484 -248.302526) (xy 96.591371 -248.301368) (xy 96.60762 -248.293841)
			(xy 96.614234 -248.287794) (xy 96.702626 -248.199402) (xy 96.708704 -248.192897) (xy 96.71626 -248.17679)
			(xy 96.7178 -248.159064) (xy 96.715834 -248.15038) (xy 96.701356 -248.096278) (xy 96.693736 -248.067576)
			(xy 96.691783 -248.061179) (xy 96.685098 -248.049599) (xy 96.680528 -248.044716) (xy 96.675956 -248.040144)
			(xy 96.664526 -248.03354) (xy 96.657922 -248.031762) (xy 96.632955 -248.024452) (xy 96.585631 -248.002853)
			(xy 96.542443 -247.973854) (xy 96.504538 -247.938227) (xy 96.472922 -247.896916) (xy 96.448436 -247.85102)
			(xy 96.431729 -247.801755) (xy 96.423244 -247.750432) (xy 96.422718 -247.724422) (xy 96.423182 -247.699409)
			(xy 96.431004 -247.649999) (xy 96.446459 -247.602421) (xy 96.469168 -247.557846) (xy 96.498569 -247.517372)
			(xy 96.53394 -247.481997) (xy 96.57441 -247.45259) (xy 96.618982 -247.429876) (xy 96.666558 -247.414414)
			(xy 96.715967 -247.406585) (xy 96.74098 -247.40616) (xy 96.758071 -247.406401) (xy 96.792053 -247.410095)
			(xy 96.808798 -247.413526) (xy 96.819974 -247.415812) (xy 96.830896 -247.413272) (xy 96.836484 -247.411849)
			(xy 96.846866 -247.406839) (xy 96.85147 -247.403366) (xy 96.911414 -247.355614) (xy 96.914716 -247.35282)
			(xy 96.919593 -247.347774) (xy 96.926685 -247.33567) (xy 96.928686 -247.328944) (xy 96.930464 -247.31599)
			(xy 96.930464 -247.07088) (xy 96.927924 -247.059704) (xy 96.925384 -247.05437) (xy 96.915139 -247.032476)
			(xy 96.900659 -246.986361) (xy 96.893333 -246.938584) (xy 96.892872 -246.914416) (xy 96.89334 -246.890249)
			(xy 96.900676 -246.842474) (xy 96.915137 -246.796354) (xy 96.925384 -246.774462) (xy 96.927924 -246.769128)
			(xy 96.930464 -246.757952) (xy 96.930464 -246.518176) (xy 96.929448 -246.508016) (xy 96.9264 -246.49303)
			(xy 96.924623 -246.489012) (xy 96.919889 -246.481611) (xy 96.917002 -246.478298) (xy 96.911414 -246.473218)
			(xy 96.85147 -246.425466) (xy 96.846875 -246.42198) (xy 96.836487 -246.416975) (xy 96.830896 -246.41556)
			(xy 96.819974 -246.41302) (xy 96.808798 -246.415306) (xy 96.792054 -246.418743) (xy 96.758071 -246.422436)
			(xy 96.74098 -246.422672) (xy 96.715971 -246.42218) (xy 96.666569 -246.414353) (xy 96.619 -246.398894)
			(xy 96.574435 -246.376184) (xy 96.533971 -246.346783) (xy 96.498604 -246.311414) (xy 96.469205 -246.270948)
			(xy 96.446499 -246.226381) (xy 96.431043 -246.178811) (xy 96.423219 -246.129409) (xy 96.423219 -246.079391)
			(xy 96.431043 -246.029989) (xy 96.446499 -245.982419) (xy 96.469205 -245.937852) (xy 96.498604 -245.897386)
			(xy 96.533971 -245.862017) (xy 96.574435 -245.832616) (xy 96.619 -245.809906) (xy 96.666569 -245.794447)
			(xy 96.715971 -245.78662) (xy 96.74098 -245.786148) (xy 96.758071 -245.786389) (xy 96.792053 -245.790083)
			(xy 96.808798 -245.793514) (xy 96.819974 -245.7958) (xy 96.830896 -245.79326) (xy 96.836485 -245.791839)
			(xy 96.846873 -245.786837) (xy 96.85147 -245.783354) (xy 96.911414 -245.735602) (xy 96.914716 -245.732808)
			(xy 96.919592 -245.727761) (xy 96.926681 -245.715657) (xy 96.928686 -245.708932) (xy 96.930464 -245.695978)
			(xy 96.930464 -245.450868) (xy 96.927924 -245.439692) (xy 96.925384 -245.434358) (xy 96.91514 -245.412464)
			(xy 96.900661 -245.366349) (xy 96.893337 -245.318572) (xy 96.892872 -245.294404) (xy 96.893341 -245.270237)
			(xy 96.900678 -245.222463) (xy 96.915141 -245.176343) (xy 96.925384 -245.15445) (xy 96.927924 -245.149116)
			(xy 96.930464 -245.13794) (xy 96.930464 -244.898164) (xy 96.929448 -244.888004) (xy 96.9264 -244.873018)
			(xy 96.924629 -244.868996) (xy 96.919905 -244.861586) (xy 96.917002 -244.858286) (xy 96.911414 -244.853206)
			(xy 96.85147 -244.805454) (xy 96.846875 -244.801969) (xy 96.836486 -244.796965) (xy 96.830896 -244.795548)
			(xy 96.819974 -244.793008) (xy 96.808798 -244.795294) (xy 96.792054 -244.798731) (xy 96.758071 -244.802424)
			(xy 96.74098 -244.80266) (xy 96.715972 -244.802168) (xy 96.666572 -244.794341) (xy 96.619005 -244.778883)
			(xy 96.574441 -244.756174) (xy 96.533979 -244.726774) (xy 96.498613 -244.691406) (xy 96.469216 -244.650941)
			(xy 96.44651 -244.606376) (xy 96.431054 -244.558808) (xy 96.423231 -244.509408) (xy 96.423231 -244.459392)
			(xy 96.431054 -244.409992) (xy 96.44651 -244.362424) (xy 96.469216 -244.317859) (xy 96.498613 -244.277394)
			(xy 96.533979 -244.242026) (xy 96.574441 -244.212626) (xy 96.619005 -244.189917) (xy 96.666572 -244.174459)
			(xy 96.715972 -244.166632) (xy 96.74098 -244.166136) (xy 96.758071 -244.166377) (xy 96.792053 -244.170071)
			(xy 96.808798 -244.173502) (xy 96.819974 -244.175788) (xy 96.830896 -244.173248) (xy 96.836485 -244.171827)
			(xy 96.846872 -244.166823) (xy 96.85147 -244.163342) (xy 96.911414 -244.11559) (xy 96.914716 -244.112796)
			(xy 96.919591 -244.107749) (xy 96.926678 -244.095644) (xy 96.928686 -244.08892) (xy 96.930464 -244.075966)
			(xy 96.930464 -243.830856) (xy 96.927924 -243.81968) (xy 96.925384 -243.814346) (xy 96.915134 -243.792453)
			(xy 96.900643 -243.746339) (xy 96.893305 -243.698561) (xy 96.892872 -243.674392) (xy 96.893341 -243.650225)
			(xy 96.900681 -243.602452) (xy 96.915145 -243.556333) (xy 96.925384 -243.534438) (xy 96.927924 -243.529104)
			(xy 96.930464 -243.517928) (xy 96.930464 -243.278152) (xy 96.929448 -243.267992) (xy 96.9264 -243.253006)
			(xy 96.924628 -243.248984) (xy 96.919902 -243.241576) (xy 96.917002 -243.238274) (xy 96.911414 -243.233194)
			(xy 96.85147 -243.185442) (xy 96.846874 -243.181958) (xy 96.836486 -243.176955) (xy 96.830896 -243.175536)
			(xy 96.819974 -243.172996) (xy 96.808798 -243.175282) (xy 96.792054 -243.178718) (xy 96.758071 -243.182411)
			(xy 96.74098 -243.182648) (xy 96.715973 -243.182156) (xy 96.666575 -243.174329) (xy 96.61901 -243.158872)
			(xy 96.574448 -243.136164) (xy 96.533987 -243.106765) (xy 96.498622 -243.071398) (xy 96.469226 -243.030935)
			(xy 96.446521 -242.986372) (xy 96.431066 -242.938805) (xy 96.423242 -242.889407) (xy 96.423242 -242.839393)
			(xy 96.431066 -242.789995) (xy 96.446521 -242.742428) (xy 96.469226 -242.697865) (xy 96.498622 -242.657402)
			(xy 96.533987 -242.622035) (xy 96.574448 -242.592636) (xy 96.61901 -242.569928) (xy 96.666575 -242.554471)
			(xy 96.715973 -242.546644) (xy 96.74098 -242.546124) (xy 96.758071 -242.546365) (xy 96.792053 -242.550059)
			(xy 96.808798 -242.55349) (xy 96.819974 -242.555776) (xy 96.830896 -242.553236) (xy 96.836485 -242.551815)
			(xy 96.846871 -242.54681) (xy 96.85147 -242.54333) (xy 96.911414 -242.495578) (xy 96.914716 -242.492784)
			(xy 96.91959 -242.487736) (xy 96.926674 -242.47563) (xy 96.928686 -242.468908) (xy 96.930464 -242.455954)
			(xy 96.930464 -242.210844) (xy 96.927924 -242.199668) (xy 96.925384 -242.194334) (xy 96.915135 -242.172441)
			(xy 96.900645 -242.126326) (xy 96.893309 -242.078549) (xy 96.892872 -242.05438) (xy 96.893342 -242.030214)
			(xy 96.900683 -241.982441) (xy 96.915149 -241.936323) (xy 96.925384 -241.914426) (xy 96.927924 -241.909092)
			(xy 96.930464 -241.897916) (xy 96.930464 -241.65814) (xy 96.929448 -241.64798) (xy 96.9264 -241.632994)
			(xy 96.924627 -241.628973) (xy 96.9199 -241.621565) (xy 96.917002 -241.618262) (xy 96.911414 -241.613182)
			(xy 96.85147 -241.56543) (xy 96.846877 -241.561941) (xy 96.83649 -241.55693) (xy 96.830896 -241.555524)
			(xy 96.819974 -241.552984) (xy 96.808798 -241.55527) (xy 96.792054 -241.558707) (xy 96.758071 -241.562399)
			(xy 96.74098 -241.562636) (xy 96.715974 -241.562144) (xy 96.666578 -241.554318) (xy 96.619014 -241.538861)
			(xy 96.574454 -241.516153) (xy 96.533994 -241.486756) (xy 96.498631 -241.45139) (xy 96.469236 -241.410929)
			(xy 96.446532 -241.366367) (xy 96.431078 -241.318803) (xy 96.423254 -241.269406) (xy 96.423254 -241.219394)
			(xy 96.431078 -241.169997) (xy 96.446532 -241.122433) (xy 96.469236 -241.077871) (xy 96.498631 -241.03741)
			(xy 96.533994 -241.002044) (xy 96.574454 -240.972647) (xy 96.619014 -240.949939) (xy 96.666578 -240.934482)
			(xy 96.715974 -240.926656) (xy 96.74098 -240.926112) (xy 96.758071 -240.926353) (xy 96.792053 -240.930048)
			(xy 96.808798 -240.933478) (xy 96.819974 -240.935764) (xy 96.830896 -240.933224) (xy 96.836485 -240.931802)
			(xy 96.846871 -240.926797) (xy 96.85147 -240.923318) (xy 96.911414 -240.875566) (xy 96.914716 -240.872772)
			(xy 96.919589 -240.867723) (xy 96.92667 -240.855617) (xy 96.928686 -240.848896) (xy 96.930464 -240.835942)
			(xy 96.930464 -240.590832) (xy 96.927924 -240.579656) (xy 96.925384 -240.574322) (xy 96.915136 -240.552429)
			(xy 96.900648 -240.506314) (xy 96.893314 -240.458537) (xy 96.892872 -240.434368) (xy 96.893343 -240.410202)
			(xy 96.900686 -240.36243) (xy 96.915153 -240.316313) (xy 96.925384 -240.294414) (xy 96.927924 -240.28908)
			(xy 96.930464 -240.277904) (xy 96.930464 -240.038128) (xy 96.929448 -240.027968) (xy 96.9264 -240.012982)
			(xy 96.924626 -240.008962) (xy 96.919898 -240.001555) (xy 96.917002 -239.99825) (xy 96.911414 -239.99317)
			(xy 96.85147 -239.945418) (xy 96.846877 -239.941929) (xy 96.836489 -239.936919) (xy 96.830896 -239.935512)
			(xy 96.819974 -239.932972) (xy 96.808798 -239.935258) (xy 96.792054 -239.938695) (xy 96.758071 -239.942387)
			(xy 96.74098 -239.942624) (xy 96.715975 -239.942132) (xy 96.666581 -239.934306) (xy 96.619019 -239.918849)
			(xy 96.57446 -239.896143) (xy 96.534002 -239.866746) (xy 96.498641 -239.831383) (xy 96.469246 -239.790923)
			(xy 96.446543 -239.746363) (xy 96.431089 -239.6988) (xy 96.423266 -239.649405) (xy 96.423266 -239.599395)
			(xy 96.431089 -239.55) (xy 96.446543 -239.502437) (xy 96.469246 -239.457877) (xy 96.498641 -239.417417)
			(xy 96.534002 -239.382054) (xy 96.57446 -239.352657) (xy 96.619019 -239.329951) (xy 96.666581 -239.314494)
			(xy 96.715975 -239.306668) (xy 96.74098 -239.3061) (xy 96.758071 -239.306341) (xy 96.792053 -239.310036)
			(xy 96.808798 -239.313466) (xy 96.819974 -239.315752) (xy 96.830896 -239.313212) (xy 96.836485 -239.31179)
			(xy 96.84687 -239.306784) (xy 96.85147 -239.303306) (xy 96.911414 -239.255554) (xy 96.914716 -239.25276)
			(xy 96.919588 -239.247711) (xy 96.926666 -239.235604) (xy 96.928686 -239.228884) (xy 96.930464 -239.21593)
			(xy 96.930464 -238.97082) (xy 96.927924 -238.959644) (xy 96.925384 -238.95431) (xy 96.915137 -238.932417)
			(xy 96.90065 -238.886302) (xy 96.893318 -238.838524) (xy 96.892872 -238.814356) (xy 96.893344 -238.79019)
			(xy 96.900689 -238.742419) (xy 96.915157 -238.696302) (xy 96.925384 -238.674402) (xy 96.927924 -238.669068)
			(xy 96.930464 -238.657892) (xy 96.930464 -237.350808) (xy 96.927924 -237.339632) (xy 96.925384 -237.334298)
			(xy 96.915137 -237.312405) (xy 96.900653 -237.26629) (xy 96.893323 -237.218512) (xy 96.892872 -237.194344)
			(xy 96.893345 -237.170178) (xy 96.900691 -237.122408) (xy 96.915161 -237.076292) (xy 96.925384 -237.05439)
			(xy 96.927924 -237.049056) (xy 96.930464 -237.03788) (xy 96.930464 -236.798104) (xy 96.929448 -236.787944)
			(xy 96.9264 -236.772958) (xy 96.924625 -236.768939) (xy 96.919894 -236.761535) (xy 96.917002 -236.758226)
			(xy 96.911414 -236.753146) (xy 96.85147 -236.705394) (xy 96.846876 -236.701907) (xy 96.836488 -236.696899)
			(xy 96.830896 -236.695488) (xy 96.819974 -236.692948) (xy 96.808798 -236.695234) (xy 96.792054 -236.698671)
			(xy 96.758071 -236.702364) (xy 96.74098 -236.7026) (xy 96.715969 -236.702108) (xy 96.666563 -236.69428)
			(xy 96.61899 -236.67882) (xy 96.574421 -236.656108) (xy 96.533953 -236.626704) (xy 96.498583 -236.591332)
			(xy 96.469181 -236.550862) (xy 96.446473 -236.506292) (xy 96.431016 -236.458718) (xy 96.423191 -236.409311)
			(xy 96.423191 -236.359289) (xy 96.431016 -236.309882) (xy 96.446473 -236.262308) (xy 96.469181 -236.217738)
			(xy 96.498583 -236.177268) (xy 96.533953 -236.141896) (xy 96.574421 -236.112492) (xy 96.61899 -236.08978)
			(xy 96.666563 -236.07432) (xy 96.715969 -236.066492) (xy 96.74098 -236.066076) (xy 96.758071 -236.066317)
			(xy 96.792053 -236.070011) (xy 96.808798 -236.073442) (xy 96.819974 -236.075728) (xy 96.830896 -236.073188)
			(xy 96.836484 -236.071765) (xy 96.846868 -236.066757) (xy 96.85147 -236.063282) (xy 96.911414 -236.01553)
			(xy 96.914716 -236.012736) (xy 96.919595 -236.00769) (xy 96.92669 -235.995588) (xy 96.928686 -235.98886)
			(xy 96.930464 -235.975906) (xy 96.930464 -235.730796) (xy 96.927924 -235.71962) (xy 96.925384 -235.714286)
			(xy 96.915138 -235.692393) (xy 96.900655 -235.646277) (xy 96.893327 -235.5985) (xy 96.892872 -235.574332)
			(xy 96.893346 -235.550167) (xy 96.900694 -235.502396) (xy 96.915165 -235.456282) (xy 96.925384 -235.434378)
			(xy 96.927924 -235.429044) (xy 96.930464 -235.417868) (xy 96.930464 -235.178092) (xy 96.929448 -235.167932)
			(xy 96.9264 -235.152946) (xy 96.924624 -235.148927) (xy 96.919892 -235.141524) (xy 96.917002 -235.138214)
			(xy 96.911414 -235.133134) (xy 96.85147 -235.085382) (xy 96.846875 -235.081895) (xy 96.836488 -235.076889)
			(xy 96.830896 -235.075476) (xy 96.819974 -235.072936) (xy 96.808798 -235.075222) (xy 96.792054 -235.078659)
			(xy 96.758071 -235.082352) (xy 96.74098 -235.082588) (xy 96.71597 -235.082096) (xy 96.666566 -235.074268)
			(xy 96.618994 -235.058809) (xy 96.574427 -235.036098) (xy 96.533961 -235.006695) (xy 96.498592 -234.971324)
			(xy 96.469192 -234.930856) (xy 96.446484 -234.886287) (xy 96.431027 -234.838715) (xy 96.423203 -234.78931)
			(xy 96.423203 -234.73929) (xy 96.431027 -234.689885) (xy 96.446484 -234.642313) (xy 96.469192 -234.597744)
			(xy 96.498592 -234.557276) (xy 96.533961 -234.521905) (xy 96.574427 -234.492502) (xy 96.618994 -234.469791)
			(xy 96.666566 -234.454332) (xy 96.71597 -234.446504) (xy 96.74098 -234.446064) (xy 96.758071 -234.446305)
			(xy 96.792053 -234.449999) (xy 96.808798 -234.45343) (xy 96.819974 -234.455716) (xy 96.830896 -234.453176)
			(xy 96.836484 -234.451753) (xy 96.846867 -234.446743) (xy 96.85147 -234.44327) (xy 96.911414 -234.395518)
			(xy 96.914716 -234.392724) (xy 96.919594 -234.387678) (xy 96.926687 -234.375575) (xy 96.928686 -234.368848)
			(xy 96.930464 -234.355894) (xy 96.930464 -234.110784) (xy 96.927924 -234.099608) (xy 96.925384 -234.094274)
			(xy 96.915139 -234.07238) (xy 96.900658 -234.026265) (xy 96.893331 -233.978488) (xy 96.892872 -233.95432)
			(xy 96.893339 -233.930153) (xy 96.900675 -233.882378) (xy 96.915136 -233.836257) (xy 96.925384 -233.814366)
			(xy 96.927924 -233.809032) (xy 96.930464 -233.797856) (xy 96.930464 -233.55808) (xy 96.929448 -233.54792)
			(xy 96.9264 -233.532934) (xy 96.924623 -233.528916) (xy 96.91989 -233.521514) (xy 96.917002 -233.518202)
			(xy 96.911414 -233.513122) (xy 96.85147 -233.46537) (xy 96.846875 -233.461884) (xy 96.836487 -233.456879)
			(xy 96.830896 -233.455464) (xy 96.819974 -233.452924) (xy 96.808798 -233.45521) (xy 96.792054 -233.458647)
			(xy 96.758071 -233.46234) (xy 96.74098 -233.462576) (xy 96.715971 -233.462084) (xy 96.666569 -233.454256)
			(xy 96.618999 -233.438797) (xy 96.574433 -233.416088) (xy 96.533968 -233.386686) (xy 96.498601 -233.351316)
			(xy 96.469202 -233.31085) (xy 96.446495 -233.266283) (xy 96.431039 -233.218712) (xy 96.423215 -233.169309)
			(xy 96.423215 -233.119291) (xy 96.431039 -233.069888) (xy 96.446495 -233.022317) (xy 96.469202 -232.97775)
			(xy 96.498601 -232.937284) (xy 96.533968 -232.901914) (xy 96.574433 -232.872512) (xy 96.618999 -232.849803)
			(xy 96.666569 -232.834344) (xy 96.715971 -232.826516) (xy 96.74098 -232.826052) (xy 96.758071 -232.826293)
			(xy 96.792053 -232.829987) (xy 96.808798 -232.833418) (xy 96.819974 -232.835704) (xy 96.830896 -232.833164)
			(xy 96.836485 -232.831744) (xy 96.846874 -232.826741) (xy 96.85147 -232.823258) (xy 96.911414 -232.775506)
			(xy 96.914716 -232.772712) (xy 96.919593 -232.767665) (xy 96.926683 -232.755561) (xy 96.928686 -232.748836)
			(xy 96.930464 -232.735882) (xy 96.930464 -232.490772) (xy 96.927924 -232.479596) (xy 96.925384 -232.474262)
			(xy 96.91514 -232.452368) (xy 96.900661 -232.406253) (xy 96.893336 -232.358476) (xy 96.892872 -232.334308)
			(xy 96.89334 -232.310141) (xy 96.900677 -232.262367) (xy 96.91514 -232.216247) (xy 96.925384 -232.194354)
			(xy 96.927924 -232.18902) (xy 96.930464 -232.177844) (xy 96.930464 -231.938068) (xy 96.929448 -231.927908)
			(xy 96.9264 -231.912922) (xy 96.924622 -231.908904) (xy 96.919888 -231.901504) (xy 96.917002 -231.89819)
			(xy 96.911414 -231.89311) (xy 96.85147 -231.845358) (xy 96.846875 -231.841873) (xy 96.836487 -231.836869)
			(xy 96.830896 -231.835452) (xy 96.819974 -231.832912) (xy 96.808798 -231.835198) (xy 96.792054 -231.838635)
			(xy 96.758071 -231.842328) (xy 96.74098 -231.842564) (xy 96.715972 -231.842072) (xy 96.666571 -231.834245)
			(xy 96.619003 -231.818786) (xy 96.574439 -231.796077) (xy 96.533976 -231.766677) (xy 96.49861 -231.731309)
			(xy 96.469212 -231.690844) (xy 96.446506 -231.646278) (xy 96.431051 -231.598709) (xy 96.423227 -231.549308)
			(xy 96.423227 -231.499292) (xy 96.431051 -231.449891) (xy 96.446506 -231.402322) (xy 96.469212 -231.357756)
			(xy 96.49861 -231.317291) (xy 96.533976 -231.281923) (xy 96.574439 -231.252523) (xy 96.619003 -231.229814)
			(xy 96.666571 -231.214355) (xy 96.715972 -231.206528) (xy 96.74098 -231.20604) (xy 96.758071 -231.206281)
			(xy 96.792053 -231.209975) (xy 96.808798 -231.213406) (xy 96.819974 -231.215692) (xy 96.830896 -231.213152)
			(xy 96.836485 -231.211731) (xy 96.846873 -231.206728) (xy 96.85147 -231.203246) (xy 96.911414 -231.155494)
			(xy 96.914716 -231.1527) (xy 96.919591 -231.147653) (xy 96.926679 -231.135548) (xy 96.928686 -231.128824)
			(xy 96.930464 -231.11587) (xy 96.930464 -230.871014) (xy 96.927924 -230.859838) (xy 96.925384 -230.854504)
			(xy 96.915137 -230.832611) (xy 96.900652 -230.786496) (xy 96.89332 -230.738718) (xy 96.892872 -230.71455)
			(xy 96.893345 -230.690384) (xy 96.90069 -230.642613) (xy 96.915159 -230.596497) (xy 96.925384 -230.574596)
			(xy 96.927924 -230.569262) (xy 96.930464 -230.558086) (xy 96.930464 -230.318056) (xy 96.929448 -230.307896)
			(xy 96.9264 -230.29291) (xy 96.924628 -230.288888) (xy 96.919903 -230.281479) (xy 96.917002 -230.278178)
			(xy 96.911414 -230.273098) (xy 96.85147 -230.225346) (xy 96.846874 -230.221861) (xy 96.836486 -230.216858)
			(xy 96.830896 -230.21544) (xy 96.819974 -230.2129) (xy 96.808798 -230.215186) (xy 96.792054 -230.218622)
			(xy 96.758071 -230.222315) (xy 96.74098 -230.222552) (xy 96.715973 -230.22206) (xy 96.666574 -230.214233)
			(xy 96.619008 -230.198775) (xy 96.574446 -230.176067) (xy 96.533984 -230.146668) (xy 96.498619 -230.111301)
			(xy 96.469222 -230.070837) (xy 96.446517 -230.026273) (xy 96.431062 -229.978706) (xy 96.423239 -229.929307)
			(xy 96.423239 -229.879293) (xy 96.431062 -229.829894) (xy 96.446517 -229.782327) (xy 96.469222 -229.737763)
			(xy 96.498619 -229.697299) (xy 96.533984 -229.661932) (xy 96.574446 -229.632533) (xy 96.619008 -229.609825)
			(xy 96.666574 -229.594367) (xy 96.715973 -229.58654) (xy 96.74098 -229.586028) (xy 96.758071 -229.586269)
			(xy 96.792053 -229.589963) (xy 96.808798 -229.593394) (xy 96.819974 -229.59568) (xy 96.830896 -229.59314)
			(xy 96.836485 -229.591719) (xy 96.846872 -229.586715) (xy 96.85147 -229.583234) (xy 96.911414 -229.535482)
			(xy 96.914716 -229.532688) (xy 96.91959 -229.52764) (xy 96.926675 -229.515535) (xy 96.928686 -229.508812)
			(xy 96.930464 -229.495858) (xy 96.930464 -229.251002) (xy 96.927924 -229.239826) (xy 96.925384 -229.234492)
			(xy 96.915138 -229.212599) (xy 96.900654 -229.166483) (xy 96.893325 -229.118706) (xy 96.892872 -229.094538)
			(xy 96.893345 -229.070372) (xy 96.900692 -229.022602) (xy 96.915163 -228.976487) (xy 96.925384 -228.954584)
			(xy 96.927924 -228.94925) (xy 96.930464 -228.938074) (xy 96.930464 -228.698298) (xy 96.929448 -228.688138)
			(xy 96.9264 -228.673152) (xy 96.924624 -228.669133) (xy 96.919893 -228.661729) (xy 96.917002 -228.65842)
			(xy 96.911414 -228.65334) (xy 96.85147 -228.605588) (xy 96.846876 -228.602101) (xy 96.836488 -228.597094)
			(xy 96.830896 -228.595682) (xy 96.819974 -228.593142) (xy 96.808798 -228.595428) (xy 96.792054 -228.598864)
			(xy 96.758071 -228.602557) (xy 96.74098 -228.602794) (xy 96.715969 -228.602302) (xy 96.666564 -228.594474)
			(xy 96.618992 -228.579014) (xy 96.574424 -228.556303) (xy 96.533957 -228.5269) (xy 96.498587 -228.491528)
			(xy 96.469187 -228.451059) (xy 96.446478 -228.406489) (xy 96.431021 -228.358916) (xy 96.423197 -228.309511)
			(xy 96.423197 -228.259489) (xy 96.431021 -228.210084) (xy 96.446478 -228.162511) (xy 96.469187 -228.117941)
			(xy 96.498587 -228.077472) (xy 96.533957 -228.0421) (xy 96.574424 -228.012697) (xy 96.618992 -227.989986)
			(xy 96.666564 -227.974526) (xy 96.715969 -227.966698) (xy 96.74098 -227.96627) (xy 96.758071 -227.966511)
			(xy 96.792053 -227.970205) (xy 96.808798 -227.973636) (xy 96.819974 -227.975922) (xy 96.830896 -227.973382)
			(xy 96.836484 -227.971959) (xy 96.846867 -227.96695) (xy 96.85147 -227.963476) (xy 96.911414 -227.915724)
			(xy 96.914716 -227.91293) (xy 96.919594 -227.907884) (xy 96.926688 -227.895781) (xy 96.928686 -227.889054)
			(xy 96.930464 -227.8761) (xy 96.930464 -227.799646) (xy 96.930296 -227.793637) (xy 96.92747 -227.781956)
			(xy 96.924876 -227.776532) (xy 96.923038 -227.773056) (xy 96.918448 -227.766674) (xy 96.915732 -227.763832)
			(xy 96.724724 -227.572824) (xy 96.716112 -227.565018) (xy 96.694151 -227.557476) (xy 96.68256 -227.558346)
			(xy 96.6343 -227.567236) (xy 96.599248 -227.57384) (xy 96.593322 -227.575134) (xy 96.582275 -227.580133)
			(xy 96.577404 -227.583746) (xy 96.572324 -227.58781) (xy 96.564704 -227.597462) (xy 96.562164 -227.603304)
			(xy 96.55105 -227.627099) (xy 96.522209 -227.670983) (xy 96.486553 -227.709536) (xy 96.445051 -227.74171)
			(xy 96.398828 -227.766632) (xy 96.349141 -227.783626) (xy 96.297337 -227.79223) (xy 96.27108 -227.792788)
			(xy 96.246071 -227.792296) (xy 96.19667 -227.784469) (xy 96.1491 -227.769011) (xy 96.104535 -227.746303)
			(xy 96.064069 -227.716903) (xy 96.028701 -227.681535) (xy 95.999301 -227.641071) (xy 95.976591 -227.596505)
			(xy 95.961132 -227.548936) (xy 95.953305 -227.499535) (xy 95.952818 -227.474526) (xy 95.952818 -227.474018)
			(xy 95.953135 -227.454183) (xy 95.9581 -227.414823) (xy 95.962724 -227.395532) (xy 95.965772 -227.383848)
			(xy 95.963486 -227.372672) (xy 95.96214 -227.367091) (xy 95.957267 -227.356699) (xy 95.953834 -227.352098)
			(xy 95.909892 -227.295456) (xy 95.903796 -227.287836) (xy 95.896262 -227.280034) (xy 95.876529 -227.271079)
			(xy 95.865696 -227.270564) (xy 95.73641 -227.270564) (xy 95.72497 -227.271094) (xy 95.704356 -227.281019)
			(xy 95.696786 -227.289614) (xy 95.695516 -227.291138) (xy 95.648272 -227.352098) (xy 95.644885 -227.356726)
			(xy 95.640023 -227.367111) (xy 95.63862 -227.372672) (xy 95.636334 -227.383848) (xy 95.639382 -227.395532)
			(xy 95.643994 -227.414826) (xy 95.64896 -227.454183) (xy 95.649288 -227.474018) (xy 95.649288 -227.474526)
			(xy 95.648797 -227.499535) (xy 95.640973 -227.548938) (xy 95.625516 -227.596508) (xy 95.602808 -227.641075)
			(xy 95.573408 -227.68154) (xy 95.53804 -227.716908) (xy 95.497575 -227.746308) (xy 95.453008 -227.769016)
			(xy 95.405438 -227.784473) (xy 95.356035 -227.792297) (xy 95.306017 -227.792297) (xy 95.256614 -227.784473)
			(xy 95.209044 -227.769016) (xy 95.164477 -227.746308) (xy 95.124012 -227.716908) (xy 95.088644 -227.68154)
			(xy 95.059244 -227.641075) (xy 95.036536 -227.596508) (xy 95.021079 -227.548938) (xy 95.013255 -227.499535)
			(xy 95.012764 -227.474526) (xy 95.012764 -227.474018) (xy 95.013081 -227.454183) (xy 95.018045 -227.414823)
			(xy 95.02267 -227.395532) (xy 95.025718 -227.383848) (xy 95.023432 -227.372672) (xy 95.022085 -227.367092)
			(xy 95.017207 -227.356703) (xy 95.01378 -227.352098) (xy 94.969838 -227.295456) (xy 94.963742 -227.287836)
			(xy 94.956205 -227.280042) (xy 94.936471 -227.271108) (xy 94.925642 -227.270564) (xy 94.796356 -227.270564)
			(xy 94.784912 -227.271084) (xy 94.764282 -227.280998) (xy 94.756732 -227.289614) (xy 94.755462 -227.291138)
			(xy 94.708218 -227.352098) (xy 94.704828 -227.356725) (xy 94.699962 -227.367108) (xy 94.698566 -227.372672)
			(xy 94.69628 -227.383848) (xy 94.699328 -227.395532) (xy 94.70394 -227.414826) (xy 94.708905 -227.454183)
			(xy 94.709234 -227.474018) (xy 94.709234 -227.474526) (xy 94.708743 -227.499535) (xy 94.700919 -227.548938)
			(xy 94.685462 -227.596508) (xy 94.662754 -227.641075) (xy 94.633354 -227.68154) (xy 94.597986 -227.716908)
			(xy 94.557521 -227.746308) (xy 94.512954 -227.769016) (xy 94.465384 -227.784473) (xy 94.415981 -227.792297)
			(xy 94.365963 -227.792297) (xy 94.31656 -227.784473) (xy 94.26899 -227.769016) (xy 94.224423 -227.746308)
			(xy 94.183958 -227.716908) (xy 94.14859 -227.68154) (xy 94.11919 -227.641075) (xy 94.096482 -227.596508)
			(xy 94.081025 -227.548938) (xy 94.073201 -227.499535) (xy 94.07271 -227.474526) (xy 94.07271 -227.474018)
			(xy 94.073027 -227.454183) (xy 94.077992 -227.414823) (xy 94.082616 -227.395532) (xy 94.085664 -227.383848)
			(xy 94.083378 -227.372672) (xy 94.082032 -227.367091) (xy 94.077158 -227.3567) (xy 94.073726 -227.352098)
			(xy 94.029784 -227.295456) (xy 94.023688 -227.287836) (xy 94.016154 -227.280035) (xy 93.996421 -227.271083)
			(xy 93.985588 -227.270564) (xy 92.916502 -227.270564) (xy 92.905063 -227.271095) (xy 92.884452 -227.281023)
			(xy 92.876878 -227.289614) (xy 92.875608 -227.291138) (xy 92.828364 -227.352098) (xy 92.824972 -227.356724)
			(xy 92.820101 -227.367106) (xy 92.818712 -227.372672) (xy 92.816426 -227.383848) (xy 92.819474 -227.395532)
			(xy 92.824085 -227.414826) (xy 92.82905 -227.454184) (xy 92.82938 -227.474018) (xy 92.82938 -227.474526)
			(xy 92.828889 -227.499535) (xy 92.821065 -227.548938) (xy 92.805608 -227.596508) (xy 92.7829 -227.641075)
			(xy 92.7535 -227.68154) (xy 92.718132 -227.716908) (xy 92.677667 -227.746308) (xy 92.6331 -227.769016)
			(xy 92.58553 -227.784473) (xy 92.536127 -227.792297) (xy 92.486109 -227.792297) (xy 92.436706 -227.784473)
			(xy 92.389136 -227.769016) (xy 92.344569 -227.746308) (xy 92.304104 -227.716908) (xy 92.268736 -227.68154)
			(xy 92.239336 -227.641075) (xy 92.216628 -227.596508) (xy 92.201171 -227.548938) (xy 92.193347 -227.499535)
			(xy 92.192856 -227.474526) (xy 92.192856 -227.474018) (xy 92.193173 -227.454183) (xy 92.198137 -227.414823)
			(xy 92.202762 -227.395532) (xy 92.20581 -227.383848) (xy 92.203524 -227.372672) (xy 92.202177 -227.367092)
			(xy 92.197299 -227.356704) (xy 92.193872 -227.352098) (xy 92.14993 -227.295456) (xy 92.143834 -227.287836)
			(xy 92.136296 -227.280044) (xy 92.116563 -227.271112) (xy 92.105734 -227.270564) (xy 91.976448 -227.270564)
			(xy 91.965004 -227.271086) (xy 91.944378 -227.281002) (xy 91.936824 -227.289614) (xy 91.935554 -227.291138)
			(xy 91.88831 -227.352098) (xy 91.884921 -227.356725) (xy 91.880055 -227.367109) (xy 91.878658 -227.372672)
			(xy 91.876372 -227.383848) (xy 91.87942 -227.395532) (xy 91.884032 -227.414826) (xy 91.888997 -227.454183)
			(xy 91.889326 -227.474018) (xy 91.889326 -227.474526) (xy 91.888835 -227.499535) (xy 91.881011 -227.548938)
			(xy 91.865554 -227.596508) (xy 91.842846 -227.641075) (xy 91.813446 -227.68154) (xy 91.778078 -227.716908)
			(xy 91.737613 -227.746308) (xy 91.693046 -227.769016) (xy 91.645476 -227.784473) (xy 91.596073 -227.792297)
			(xy 91.546055 -227.792297) (xy 91.496652 -227.784473) (xy 91.449082 -227.769016) (xy 91.404515 -227.746308)
			(xy 91.36405 -227.716908) (xy 91.328682 -227.68154) (xy 91.299282 -227.641075) (xy 91.276574 -227.596508)
			(xy 91.261117 -227.548938) (xy 91.253293 -227.499535) (xy 91.252802 -227.474526) (xy 91.252802 -227.474018)
			(xy 91.253119 -227.454183) (xy 91.258084 -227.414823) (xy 91.262708 -227.395532) (xy 91.265756 -227.383848)
			(xy 91.26347 -227.372672) (xy 91.262124 -227.367091) (xy 91.257249 -227.356701) (xy 91.253818 -227.352098)
			(xy 91.209876 -227.295456) (xy 91.20378 -227.287836) (xy 91.196245 -227.280036) (xy 91.176512 -227.271087)
			(xy 91.16568 -227.270564) (xy 91.036394 -227.270564) (xy 91.024956 -227.271097) (xy 91.004347 -227.281027)
			(xy 90.99677 -227.289614) (xy 90.9955 -227.291138) (xy 90.948256 -227.352098) (xy 90.944864 -227.356724)
			(xy 90.939994 -227.367107) (xy 90.938604 -227.372672) (xy 90.936318 -227.383848) (xy 90.939366 -227.395532)
			(xy 90.943977 -227.414826) (xy 90.948942 -227.454184) (xy 90.949272 -227.474018) (xy 90.949272 -227.474526)
			(xy 90.948781 -227.499535) (xy 90.940957 -227.548938) (xy 90.9255 -227.596508) (xy 90.902792 -227.641075)
			(xy 90.873392 -227.68154) (xy 90.838024 -227.716908) (xy 90.797559 -227.746308) (xy 90.752992 -227.769016)
			(xy 90.705422 -227.784473) (xy 90.656019 -227.792297) (xy 90.606001 -227.792297) (xy 90.556598 -227.784473)
			(xy 90.509028 -227.769016) (xy 90.464461 -227.746308) (xy 90.423996 -227.716908) (xy 90.388628 -227.68154)
			(xy 90.359228 -227.641075) (xy 90.33652 -227.596508) (xy 90.321063 -227.548938) (xy 90.313239 -227.499535)
			(xy 90.312748 -227.474526) (xy 90.31344 -227.443975) (xy 90.325073 -227.383991) (xy 90.335862 -227.3554)
			(xy 90.340753 -227.34206) (xy 90.343741 -227.313817) (xy 90.338834 -227.285843) (xy 90.326411 -227.260304)
			(xy 90.307433 -227.239174) (xy 90.283369 -227.22409) (xy 90.256082 -227.216217) (xy 90.241882 -227.2157)
			(xy 90.080084 -227.2157) (xy 90.065888 -227.216212) (xy 90.038612 -227.224108) (xy 90.014561 -227.239203)
			(xy 89.99559 -227.260331) (xy 89.983163 -227.285863) (xy 89.978239 -227.313829) (xy 89.981198 -227.34207)
			(xy 89.986104 -227.3554) (xy 89.996883 -227.383994) (xy 90.008518 -227.443976) (xy 90.009218 -227.474526)
			(xy 90.008727 -227.499535) (xy 90.000903 -227.548938) (xy 89.985446 -227.596508) (xy 89.962738 -227.641075)
			(xy 89.933338 -227.68154) (xy 89.89797 -227.716908) (xy 89.857505 -227.746308) (xy 89.812938 -227.769016)
			(xy 89.765368 -227.784473) (xy 89.715965 -227.792297) (xy 89.665947 -227.792297) (xy 89.616544 -227.784473)
			(xy 89.568974 -227.769016) (xy 89.524407 -227.746308) (xy 89.483942 -227.716908) (xy 89.448574 -227.68154)
			(xy 89.419174 -227.641075) (xy 89.396466 -227.596508) (xy 89.381009 -227.548938) (xy 89.373185 -227.499535)
			(xy 89.372694 -227.474526) (xy 89.373386 -227.443975) (xy 89.385021 -227.383991) (xy 89.395808 -227.3554)
			(xy 89.400697 -227.342058) (xy 89.403684 -227.313812) (xy 89.398776 -227.285835) (xy 89.386354 -227.260292)
			(xy 89.367379 -227.239157) (xy 89.343317 -227.224064) (xy 89.316029 -227.216181) (xy 89.301828 -227.2157)
			(xy 89.140284 -227.2157) (xy 89.126088 -227.216212) (xy 89.098812 -227.224108) (xy 89.074761 -227.239203)
			(xy 89.05579 -227.260331) (xy 89.043363 -227.285863) (xy 89.038439 -227.313829) (xy 89.041398 -227.34207)
			(xy 89.046304 -227.3554) (xy 89.057083 -227.383994) (xy 89.068718 -227.443976) (xy 89.069418 -227.474526)
			(xy 89.068927 -227.499535) (xy 89.061103 -227.548938) (xy 89.045646 -227.596508) (xy 89.022938 -227.641075)
			(xy 88.993538 -227.68154) (xy 88.95817 -227.716908) (xy 88.917705 -227.746308) (xy 88.873138 -227.769016)
			(xy 88.825568 -227.784473) (xy 88.776165 -227.792297) (xy 88.726147 -227.792297) (xy 88.676744 -227.784473)
			(xy 88.629174 -227.769016) (xy 88.584607 -227.746308) (xy 88.544142 -227.716908) (xy 88.508774 -227.68154)
			(xy 88.479374 -227.641075) (xy 88.456666 -227.596508) (xy 88.441209 -227.548938) (xy 88.433385 -227.499535)
			(xy 88.432894 -227.474526) (xy 88.433586 -227.443975) (xy 88.445221 -227.383991) (xy 88.456008 -227.3554)
			(xy 88.460897 -227.342058) (xy 88.463884 -227.313812) (xy 88.458976 -227.285835) (xy 88.446554 -227.260292)
			(xy 88.427579 -227.239157) (xy 88.403517 -227.224064) (xy 88.376229 -227.216181) (xy 88.362028 -227.2157)
			(xy 88.20023 -227.2157) (xy 88.186029 -227.216206) (xy 88.158742 -227.224095) (xy 88.134679 -227.239188)
			(xy 88.115698 -227.260319) (xy 88.103265 -227.285858) (xy 88.098339 -227.313832) (xy 88.101301 -227.342082)
			(xy 88.10625 -227.3554) (xy 88.117031 -227.383993) (xy 88.128667 -227.443976) (xy 88.129364 -227.474526)
			(xy 88.128873 -227.499535) (xy 88.121049 -227.548938) (xy 88.105592 -227.596508) (xy 88.082884 -227.641075)
			(xy 88.053484 -227.68154) (xy 88.018116 -227.716908) (xy 87.977651 -227.746308) (xy 87.933084 -227.769016)
			(xy 87.885514 -227.784473) (xy 87.836111 -227.792297) (xy 87.786093 -227.792297) (xy 87.73669 -227.784473)
			(xy 87.68912 -227.769016) (xy 87.644553 -227.746308) (xy 87.604088 -227.716908) (xy 87.56872 -227.68154)
			(xy 87.53932 -227.641075) (xy 87.516612 -227.596508) (xy 87.501155 -227.548938) (xy 87.493331 -227.499535)
			(xy 87.49284 -227.474526) (xy 87.493532 -227.443975) (xy 87.505165 -227.383991) (xy 87.515954 -227.3554)
			(xy 87.520845 -227.34206) (xy 87.523833 -227.313818) (xy 87.518926 -227.285845) (xy 87.506503 -227.260306)
			(xy 87.487525 -227.239178) (xy 87.463461 -227.224095) (xy 87.436173 -227.216224) (xy 87.421974 -227.2157)
			(xy 86.320122 -227.2157) (xy 86.305922 -227.216207) (xy 86.278637 -227.224097) (xy 86.254576 -227.23919)
			(xy 86.235596 -227.260321) (xy 86.223164 -227.285859) (xy 86.218239 -227.313832) (xy 86.221201 -227.34208)
			(xy 86.226142 -227.3554) (xy 86.236923 -227.383993) (xy 86.24856 -227.443976) (xy 86.249256 -227.474526)
			(xy 86.248765 -227.499535) (xy 86.240941 -227.548938) (xy 86.225484 -227.596508) (xy 86.202776 -227.641075)
			(xy 86.173376 -227.68154) (xy 86.138008 -227.716908) (xy 86.097543 -227.746308) (xy 86.052976 -227.769016)
			(xy 86.005406 -227.784473) (xy 85.956003 -227.792297) (xy 85.905985 -227.792297) (xy 85.856582 -227.784473)
			(xy 85.809012 -227.769016) (xy 85.764445 -227.746308) (xy 85.72398 -227.716908) (xy 85.688612 -227.68154)
			(xy 85.659212 -227.641075) (xy 85.636504 -227.596508) (xy 85.621047 -227.548938) (xy 85.613223 -227.499535)
			(xy 85.612732 -227.474526) (xy 85.613424 -227.443975) (xy 85.625056 -227.38399) (xy 85.635846 -227.3554)
			(xy 85.640737 -227.342061) (xy 85.643726 -227.313819) (xy 85.638819 -227.285846) (xy 85.626395 -227.260308)
			(xy 85.607417 -227.239181) (xy 85.583353 -227.224099) (xy 85.556065 -227.216231) (xy 85.541866 -227.2157)
			(xy 85.380068 -227.2157) (xy 85.365873 -227.216214) (xy 85.338602 -227.224113) (xy 85.314554 -227.239208)
			(xy 85.295587 -227.260335) (xy 85.283162 -227.285865) (xy 85.278239 -227.313827) (xy 85.281197 -227.342065)
			(xy 85.286088 -227.3554) (xy 85.296868 -227.383993) (xy 85.308503 -227.443976) (xy 85.309202 -227.474526)
			(xy 85.308711 -227.499535) (xy 85.300887 -227.548938) (xy 85.28543 -227.596508) (xy 85.262722 -227.641075)
			(xy 85.233322 -227.68154) (xy 85.197954 -227.716908) (xy 85.157489 -227.746308) (xy 85.112922 -227.769016)
			(xy 85.065352 -227.784473) (xy 85.015949 -227.792297) (xy 84.965931 -227.792297) (xy 84.916528 -227.784473)
			(xy 84.868958 -227.769016) (xy 84.824391 -227.746308) (xy 84.783926 -227.716908) (xy 84.748558 -227.68154)
			(xy 84.719158 -227.641075) (xy 84.69645 -227.596508) (xy 84.680993 -227.548938) (xy 84.673169 -227.499535)
			(xy 84.672678 -227.474526) (xy 84.67337 -227.443975) (xy 84.685004 -227.383991) (xy 84.695792 -227.3554)
			(xy 84.700682 -227.342059) (xy 84.703669 -227.313814) (xy 84.698761 -227.285838) (xy 84.686339 -227.260296)
			(xy 84.667363 -227.239163) (xy 84.6433 -227.224073) (xy 84.616012 -227.216194) (xy 84.601812 -227.2157)
			(xy 84.440268 -227.2157) (xy 84.426073 -227.216214) (xy 84.398802 -227.224113) (xy 84.374754 -227.239208)
			(xy 84.355787 -227.260335) (xy 84.343362 -227.285865) (xy 84.338439 -227.313827) (xy 84.341397 -227.342065)
			(xy 84.346288 -227.3554) (xy 84.357068 -227.383993) (xy 84.368703 -227.443976) (xy 84.369402 -227.474526)
			(xy 84.368911 -227.499535) (xy 84.361087 -227.548938) (xy 84.34563 -227.596508) (xy 84.322922 -227.641075)
			(xy 84.293522 -227.68154) (xy 84.258154 -227.716908) (xy 84.217689 -227.746308) (xy 84.173122 -227.769016)
			(xy 84.125552 -227.784473) (xy 84.076149 -227.792297) (xy 84.026131 -227.792297) (xy 83.976728 -227.784473)
			(xy 83.929158 -227.769016) (xy 83.884591 -227.746308) (xy 83.844126 -227.716908) (xy 83.808758 -227.68154)
			(xy 83.779358 -227.641075) (xy 83.75665 -227.596508) (xy 83.741193 -227.548938) (xy 83.733369 -227.499535)
			(xy 83.732878 -227.474526) (xy 83.73357 -227.443975) (xy 83.745204 -227.383991) (xy 83.755992 -227.3554)
			(xy 83.760882 -227.342059) (xy 83.763869 -227.313814) (xy 83.758961 -227.285838) (xy 83.746539 -227.260296)
			(xy 83.727563 -227.239163) (xy 83.7035 -227.224073) (xy 83.676212 -227.216194) (xy 83.662012 -227.2157)
			(xy 83.500214 -227.2157) (xy 83.486015 -227.216208) (xy 83.458731 -227.224099) (xy 83.434672 -227.239193)
			(xy 83.415695 -227.260323) (xy 83.403264 -227.28586) (xy 83.398339 -227.313831) (xy 83.4013 -227.342078)
			(xy 83.406234 -227.3554) (xy 83.417016 -227.383993) (xy 83.428652 -227.443976) (xy 83.429348 -227.474526)
			(xy 83.428857 -227.499535) (xy 83.421033 -227.548938) (xy 83.405576 -227.596508) (xy 83.382868 -227.641075)
			(xy 83.353468 -227.68154) (xy 83.3181 -227.716908) (xy 83.277635 -227.746308) (xy 83.233068 -227.769016)
			(xy 83.185498 -227.784473) (xy 83.136095 -227.792297) (xy 83.086077 -227.792297) (xy 83.036674 -227.784473)
			(xy 82.989104 -227.769016) (xy 82.944537 -227.746308) (xy 82.904072 -227.716908) (xy 82.868704 -227.68154)
			(xy 82.839304 -227.641075) (xy 82.816596 -227.596508) (xy 82.801139 -227.548938) (xy 82.793315 -227.499535)
			(xy 82.792824 -227.474526) (xy 82.793516 -227.443975) (xy 82.805148 -227.38399) (xy 82.815938 -227.3554)
			(xy 82.820829 -227.342061) (xy 82.823818 -227.31382) (xy 82.818911 -227.285848) (xy 82.806488 -227.26031)
			(xy 82.787509 -227.239184) (xy 82.763445 -227.224103) (xy 82.736157 -227.216237) (xy 82.721958 -227.2157)
			(xy 82.56016 -227.2157) (xy 82.545956 -227.216202) (xy 82.518661 -227.224086) (xy 82.494591 -227.239178)
			(xy 82.475603 -227.260311) (xy 82.463166 -227.285855) (xy 82.458239 -227.313835) (xy 82.461203 -227.34209)
			(xy 82.46618 -227.3554) (xy 82.47696 -227.383993) (xy 82.488595 -227.443976) (xy 82.489294 -227.474526)
			(xy 82.488803 -227.499535) (xy 82.480979 -227.548938) (xy 82.465522 -227.596508) (xy 82.442814 -227.641075)
			(xy 82.413414 -227.68154) (xy 82.378046 -227.716908) (xy 82.337581 -227.746308) (xy 82.293014 -227.769016)
			(xy 82.245444 -227.784473) (xy 82.196041 -227.792297) (xy 82.146023 -227.792297) (xy 82.09662 -227.784473)
			(xy 82.04905 -227.769016) (xy 82.004483 -227.746308) (xy 81.964018 -227.716908) (xy 81.92865 -227.68154)
			(xy 81.89925 -227.641075) (xy 81.876542 -227.596508) (xy 81.861085 -227.548938) (xy 81.853261 -227.499535)
			(xy 81.85277 -227.474526) (xy 81.853462 -227.443975) (xy 81.865096 -227.383991) (xy 81.875884 -227.3554)
			(xy 81.880774 -227.342059) (xy 81.883761 -227.313814) (xy 81.878854 -227.285839) (xy 81.866432 -227.260298)
			(xy 81.847455 -227.239166) (xy 81.823392 -227.224077) (xy 81.796104 -227.2162) (xy 81.781904 -227.2157)
			(xy 81.620106 -227.2157) (xy 81.605907 -227.216209) (xy 81.578626 -227.224102) (xy 81.554569 -227.239195)
			(xy 81.535594 -227.260325) (xy 81.523164 -227.285861) (xy 81.518239 -227.31383) (xy 81.521199 -227.342076)
			(xy 81.526126 -227.3554) (xy 81.536908 -227.383993) (xy 81.548545 -227.443976) (xy 81.54924 -227.474526)
			(xy 81.548749 -227.499535) (xy 81.540925 -227.548938) (xy 81.525468 -227.596508) (xy 81.50276 -227.641075)
			(xy 81.47336 -227.68154) (xy 81.437992 -227.716908) (xy 81.397527 -227.746308) (xy 81.35296 -227.769016)
			(xy 81.30539 -227.784473) (xy 81.255987 -227.792297) (xy 81.205969 -227.792297) (xy 81.156566 -227.784473)
			(xy 81.108996 -227.769016) (xy 81.064429 -227.746308) (xy 81.023964 -227.716908) (xy 80.988596 -227.68154)
			(xy 80.959196 -227.641075) (xy 80.936488 -227.596508) (xy 80.921031 -227.548938) (xy 80.913207 -227.499535)
			(xy 80.912716 -227.474526) (xy 80.913408 -227.443975) (xy 80.92504 -227.38399) (xy 80.93583 -227.3554)
			(xy 80.940721 -227.342061) (xy 80.943711 -227.313821) (xy 80.938804 -227.285849) (xy 80.92638 -227.260312)
			(xy 80.907401 -227.239187) (xy 80.883336 -227.224108) (xy 80.856049 -227.216243) (xy 80.84185 -227.2157)
			(xy 79.827882 -227.2157) (xy 79.821871 -227.215864) (xy 79.810186 -227.218681) (xy 79.804768 -227.221288)
			(xy 79.801294 -227.223128) (xy 79.794916 -227.227722) (xy 79.792068 -227.230432) (xy 79.547212 -227.475288)
			(xy 79.544507 -227.478139) (xy 79.539914 -227.484518) (xy 79.538068 -227.487988) (xy 79.535491 -227.493416)
			(xy 79.532679 -227.505096) (xy 79.53248 -227.511102) (xy 79.53248 -227.908612) (xy 79.532983 -227.923383)
			(xy 79.541445 -227.951689) (xy 79.557657 -227.976386) (xy 79.580263 -227.995407) (xy 79.607368 -228.007159)
			(xy 79.636703 -228.010658) (xy 79.665811 -228.005611) (xy 79.679292 -227.999544) (xy 79.701428 -227.989049)
			(xy 79.74812 -227.974229) (xy 79.79653 -227.966732) (xy 79.821024 -227.96627) (xy 79.846029 -227.966762)
			(xy 79.895424 -227.974589) (xy 79.942986 -227.990046) (xy 79.987545 -228.012753) (xy 80.028003 -228.04215)
			(xy 80.063365 -228.077515) (xy 80.09276 -228.117975) (xy 80.115463 -228.162536) (xy 80.130917 -228.210099)
			(xy 80.13874 -228.259495) (xy 80.13874 -228.284532) (xy 80.444843 -228.284532) (xy 80.448938 -228.233804)
			(xy 80.461117 -228.18439) (xy 80.481065 -228.13757) (xy 80.508266 -228.094556) (xy 80.542014 -228.056462)
			(xy 80.581436 -228.024275) (xy 80.62551 -227.998829) (xy 80.673096 -227.980782) (xy 80.72296 -227.970602)
			(xy 80.773812 -227.968553) (xy 80.824333 -227.974687) (xy 80.873217 -227.988847) (xy 80.919196 -228.010664)
			(xy 80.96108 -228.039574) (xy 80.997784 -228.074829) (xy 81.028357 -228.115515) (xy 81.052008 -228.160578)
			(xy 81.068124 -228.208852) (xy 81.076288 -228.259086) (xy 81.0768 -228.284532) (xy 81.076297 -228.309521)
			(xy 81.383614 -228.309521) (xy 81.383614 -228.259543) (xy 81.391433 -228.21018) (xy 81.406877 -228.162648)
			(xy 81.429567 -228.118116) (xy 81.458943 -228.077683) (xy 81.494283 -228.042343) (xy 81.534716 -228.012967)
			(xy 81.579248 -227.990277) (xy 81.62678 -227.974833) (xy 81.676143 -227.967014) (xy 81.726121 -227.967014)
			(xy 81.775484 -227.974833) (xy 81.823016 -227.990277) (xy 81.867548 -228.012967) (xy 81.907981 -228.042343)
			(xy 81.943321 -228.077683) (xy 81.972697 -228.118116) (xy 81.995387 -228.162648) (xy 82.010831 -228.21018)
			(xy 82.01865 -228.259543) (xy 82.01914 -228.284532) (xy 82.324697 -228.284532) (xy 82.328792 -228.233804)
			(xy 82.340971 -228.18439) (xy 82.360919 -228.13757) (xy 82.38812 -228.094556) (xy 82.421868 -228.056462)
			(xy 82.46129 -228.024275) (xy 82.505364 -227.998829) (xy 82.55295 -227.980782) (xy 82.602814 -227.970602)
			(xy 82.653666 -227.968553) (xy 82.704187 -227.974687) (xy 82.753071 -227.988847) (xy 82.79905 -228.010664)
			(xy 82.840934 -228.039574) (xy 82.877638 -228.074829) (xy 82.908211 -228.115515) (xy 82.931862 -228.160578)
			(xy 82.947978 -228.208852) (xy 82.956142 -228.259086) (xy 82.956654 -228.284532) (xy 82.956151 -228.309521)
			(xy 83.263468 -228.309521) (xy 83.263468 -228.259543) (xy 83.271287 -228.21018) (xy 83.286731 -228.162648)
			(xy 83.309421 -228.118116) (xy 83.338797 -228.077683) (xy 83.374137 -228.042343) (xy 83.41457 -228.012967)
			(xy 83.459102 -227.990277) (xy 83.506634 -227.974833) (xy 83.555997 -227.967014) (xy 83.605975 -227.967014)
			(xy 83.655338 -227.974833) (xy 83.70287 -227.990277) (xy 83.747402 -228.012967) (xy 83.787835 -228.042343)
			(xy 83.823175 -228.077683) (xy 83.852551 -228.118116) (xy 83.875241 -228.162648) (xy 83.890685 -228.21018)
			(xy 83.898504 -228.259543) (xy 83.898994 -228.284532) (xy 84.204805 -228.284532) (xy 84.2089 -228.233804)
			(xy 84.221079 -228.18439) (xy 84.241027 -228.13757) (xy 84.268228 -228.094556) (xy 84.301976 -228.056462)
			(xy 84.341398 -228.024275) (xy 84.385472 -227.998829) (xy 84.433058 -227.980782) (xy 84.482922 -227.970602)
			(xy 84.533774 -227.968553) (xy 84.584295 -227.974687) (xy 84.633179 -227.988847) (xy 84.679158 -228.010664)
			(xy 84.721042 -228.039574) (xy 84.757746 -228.074829) (xy 84.788319 -228.115515) (xy 84.81197 -228.160578)
			(xy 84.828086 -228.208852) (xy 84.83625 -228.259086) (xy 84.836762 -228.284532) (xy 85.144859 -228.284532)
			(xy 85.148954 -228.233804) (xy 85.161133 -228.18439) (xy 85.181081 -228.13757) (xy 85.208282 -228.094556)
			(xy 85.24203 -228.056462) (xy 85.281452 -228.024275) (xy 85.325526 -227.998829) (xy 85.373112 -227.980782)
			(xy 85.422976 -227.970602) (xy 85.473828 -227.968553) (xy 85.524349 -227.974687) (xy 85.573233 -227.988847)
			(xy 85.619212 -228.010664) (xy 85.661096 -228.039574) (xy 85.6978 -228.074829) (xy 85.728373 -228.115515)
			(xy 85.752024 -228.160578) (xy 85.76814 -228.208852) (xy 85.776304 -228.259086) (xy 85.776816 -228.284532)
			(xy 85.776313 -228.309521) (xy 86.08363 -228.309521) (xy 86.08363 -228.259543) (xy 86.091449 -228.21018)
			(xy 86.106893 -228.162648) (xy 86.129583 -228.118116) (xy 86.158959 -228.077683) (xy 86.194299 -228.042343)
			(xy 86.234732 -228.012967) (xy 86.279264 -227.990277) (xy 86.326796 -227.974833) (xy 86.376159 -227.967014)
			(xy 86.426137 -227.967014) (xy 86.4755 -227.974833) (xy 86.523032 -227.990277) (xy 86.567564 -228.012967)
			(xy 86.607997 -228.042343) (xy 86.643337 -228.077683) (xy 86.672713 -228.118116) (xy 86.695403 -228.162648)
			(xy 86.710847 -228.21018) (xy 86.718666 -228.259543) (xy 86.719156 -228.284532) (xy 87.024713 -228.284532)
			(xy 87.028808 -228.233804) (xy 87.040987 -228.18439) (xy 87.060935 -228.13757) (xy 87.088136 -228.094556)
			(xy 87.121884 -228.056462) (xy 87.161306 -228.024275) (xy 87.20538 -227.998829) (xy 87.252966 -227.980782)
			(xy 87.30283 -227.970602) (xy 87.353682 -227.968553) (xy 87.404203 -227.974687) (xy 87.453087 -227.988847)
			(xy 87.499066 -228.010664) (xy 87.54095 -228.039574) (xy 87.577654 -228.074829) (xy 87.608227 -228.115515)
			(xy 87.631878 -228.160578) (xy 87.647994 -228.208852) (xy 87.656158 -228.259086) (xy 87.65667 -228.284532)
			(xy 87.656167 -228.309521) (xy 87.963484 -228.309521) (xy 87.963484 -228.259543) (xy 87.971303 -228.21018)
			(xy 87.986747 -228.162648) (xy 88.009437 -228.118116) (xy 88.038813 -228.077683) (xy 88.074153 -228.042343)
			(xy 88.114586 -228.012967) (xy 88.159118 -227.990277) (xy 88.20665 -227.974833) (xy 88.256013 -227.967014)
			(xy 88.305991 -227.967014) (xy 88.355354 -227.974833) (xy 88.402886 -227.990277) (xy 88.447418 -228.012967)
			(xy 88.487851 -228.042343) (xy 88.523191 -228.077683) (xy 88.552567 -228.118116) (xy 88.575257 -228.162648)
			(xy 88.590701 -228.21018) (xy 88.59852 -228.259543) (xy 88.59901 -228.284532) (xy 88.904821 -228.284532)
			(xy 88.908916 -228.233804) (xy 88.921095 -228.18439) (xy 88.941043 -228.13757) (xy 88.968244 -228.094556)
			(xy 89.001992 -228.056462) (xy 89.041414 -228.024275) (xy 89.085488 -227.998829) (xy 89.133074 -227.980782)
			(xy 89.182938 -227.970602) (xy 89.23379 -227.968553) (xy 89.284311 -227.974687) (xy 89.333195 -227.988847)
			(xy 89.379174 -228.010664) (xy 89.421058 -228.039574) (xy 89.457762 -228.074829) (xy 89.488335 -228.115515)
			(xy 89.511986 -228.160578) (xy 89.528102 -228.208852) (xy 89.536266 -228.259086) (xy 89.536778 -228.284532)
			(xy 89.536275 -228.309521) (xy 89.843592 -228.309521) (xy 89.843592 -228.259543) (xy 89.851411 -228.21018)
			(xy 89.866855 -228.162648) (xy 89.889545 -228.118116) (xy 89.918921 -228.077683) (xy 89.954261 -228.042343)
			(xy 89.994694 -228.012967) (xy 90.039226 -227.990277) (xy 90.086758 -227.974833) (xy 90.136121 -227.967014)
			(xy 90.186099 -227.967014) (xy 90.235462 -227.974833) (xy 90.282994 -227.990277) (xy 90.327526 -228.012967)
			(xy 90.367959 -228.042343) (xy 90.403299 -228.077683) (xy 90.432675 -228.118116) (xy 90.455365 -228.162648)
			(xy 90.470809 -228.21018) (xy 90.478628 -228.259543) (xy 90.479118 -228.284532) (xy 90.784675 -228.284532)
			(xy 90.78877 -228.233804) (xy 90.800949 -228.18439) (xy 90.820897 -228.13757) (xy 90.848098 -228.094556)
			(xy 90.881846 -228.056462) (xy 90.921268 -228.024275) (xy 90.965342 -227.998829) (xy 91.012928 -227.980782)
			(xy 91.062792 -227.970602) (xy 91.113644 -227.968553) (xy 91.164165 -227.974687) (xy 91.213049 -227.988847)
			(xy 91.259028 -228.010664) (xy 91.300912 -228.039574) (xy 91.337616 -228.074829) (xy 91.368189 -228.115515)
			(xy 91.39184 -228.160578) (xy 91.407956 -228.208852) (xy 91.41612 -228.259086) (xy 91.416632 -228.284532)
			(xy 91.724729 -228.284532) (xy 91.728824 -228.233804) (xy 91.741003 -228.18439) (xy 91.760951 -228.13757)
			(xy 91.788152 -228.094556) (xy 91.8219 -228.056462) (xy 91.861322 -228.024275) (xy 91.905396 -227.998829)
			(xy 91.952982 -227.980782) (xy 92.002846 -227.970602) (xy 92.053698 -227.968553) (xy 92.104219 -227.974687)
			(xy 92.153103 -227.988847) (xy 92.199082 -228.010664) (xy 92.240966 -228.039574) (xy 92.27767 -228.074829)
			(xy 92.308243 -228.115515) (xy 92.331894 -228.160578) (xy 92.34801 -228.208852) (xy 92.356174 -228.259086)
			(xy 92.356686 -228.284532) (xy 92.356183 -228.309521) (xy 92.6635 -228.309521) (xy 92.6635 -228.259543)
			(xy 92.671319 -228.21018) (xy 92.686763 -228.162648) (xy 92.709453 -228.118116) (xy 92.738829 -228.077683)
			(xy 92.774169 -228.042343) (xy 92.814602 -228.012967) (xy 92.859134 -227.990277) (xy 92.906666 -227.974833)
			(xy 92.956029 -227.967014) (xy 93.006007 -227.967014) (xy 93.05537 -227.974833) (xy 93.102902 -227.990277)
			(xy 93.147434 -228.012967) (xy 93.187867 -228.042343) (xy 93.223207 -228.077683) (xy 93.252583 -228.118116)
			(xy 93.275273 -228.162648) (xy 93.290717 -228.21018) (xy 93.298536 -228.259543) (xy 93.299026 -228.284532)
			(xy 93.604837 -228.284532) (xy 93.608932 -228.233804) (xy 93.621111 -228.18439) (xy 93.641059 -228.13757)
			(xy 93.66826 -228.094556) (xy 93.702008 -228.056462) (xy 93.74143 -228.024275) (xy 93.785504 -227.998829)
			(xy 93.83309 -227.980782) (xy 93.882954 -227.970602) (xy 93.933806 -227.968553) (xy 93.984327 -227.974687)
			(xy 94.033211 -227.988847) (xy 94.07919 -228.010664) (xy 94.121074 -228.039574) (xy 94.157778 -228.074829)
			(xy 94.188351 -228.115515) (xy 94.212002 -228.160578) (xy 94.228118 -228.208852) (xy 94.236282 -228.259086)
			(xy 94.236794 -228.284532) (xy 94.236291 -228.309521) (xy 94.543608 -228.309521) (xy 94.543608 -228.259543)
			(xy 94.551427 -228.21018) (xy 94.566871 -228.162648) (xy 94.589561 -228.118116) (xy 94.618937 -228.077683)
			(xy 94.654277 -228.042343) (xy 94.69471 -228.012967) (xy 94.739242 -227.990277) (xy 94.786774 -227.974833)
			(xy 94.836137 -227.967014) (xy 94.886115 -227.967014) (xy 94.935478 -227.974833) (xy 94.98301 -227.990277)
			(xy 95.027542 -228.012967) (xy 95.067975 -228.042343) (xy 95.103315 -228.077683) (xy 95.132691 -228.118116)
			(xy 95.155381 -228.162648) (xy 95.170825 -228.21018) (xy 95.178644 -228.259543) (xy 95.179134 -228.284532)
			(xy 95.484691 -228.284532) (xy 95.488786 -228.233804) (xy 95.500965 -228.18439) (xy 95.520913 -228.13757)
			(xy 95.548114 -228.094556) (xy 95.581862 -228.056462) (xy 95.621284 -228.024275) (xy 95.665358 -227.998829)
			(xy 95.712944 -227.980782) (xy 95.762808 -227.970602) (xy 95.81366 -227.968553) (xy 95.864181 -227.974687)
			(xy 95.913065 -227.988847) (xy 95.959044 -228.010664) (xy 96.000928 -228.039574) (xy 96.037632 -228.074829)
			(xy 96.068205 -228.115515) (xy 96.091856 -228.160578) (xy 96.107972 -228.208852) (xy 96.116136 -228.259086)
			(xy 96.116648 -228.284532) (xy 96.116136 -228.309978) (xy 96.107972 -228.360212) (xy 96.091856 -228.408486)
			(xy 96.068205 -228.453549) (xy 96.037632 -228.494235) (xy 96.000928 -228.52949) (xy 95.959044 -228.5584)
			(xy 95.913065 -228.580217) (xy 95.864181 -228.594377) (xy 95.81366 -228.600511) (xy 95.762808 -228.598462)
			(xy 95.712944 -228.588282) (xy 95.665358 -228.570235) (xy 95.621284 -228.544789) (xy 95.581862 -228.512602)
			(xy 95.548114 -228.474508) (xy 95.520913 -228.431494) (xy 95.500965 -228.384674) (xy 95.488786 -228.33526)
			(xy 95.484691 -228.284532) (xy 95.179134 -228.284532) (xy 95.178644 -228.309521) (xy 95.170825 -228.358884)
			(xy 95.155381 -228.406416) (xy 95.132691 -228.450948) (xy 95.103315 -228.491381) (xy 95.067975 -228.526721)
			(xy 95.027542 -228.556097) (xy 94.98301 -228.578787) (xy 94.935478 -228.594231) (xy 94.886115 -228.60205)
			(xy 94.836137 -228.60205) (xy 94.786774 -228.594231) (xy 94.739242 -228.578787) (xy 94.69471 -228.556097)
			(xy 94.654277 -228.526721) (xy 94.618937 -228.491381) (xy 94.589561 -228.450948) (xy 94.566871 -228.406416)
			(xy 94.551427 -228.358884) (xy 94.543608 -228.309521) (xy 94.236291 -228.309521) (xy 94.236282 -228.309978)
			(xy 94.228118 -228.360212) (xy 94.212002 -228.408486) (xy 94.188351 -228.453549) (xy 94.157778 -228.494235)
			(xy 94.121074 -228.52949) (xy 94.07919 -228.5584) (xy 94.033211 -228.580217) (xy 93.984327 -228.594377)
			(xy 93.933806 -228.600511) (xy 93.882954 -228.598462) (xy 93.83309 -228.588282) (xy 93.785504 -228.570235)
			(xy 93.74143 -228.544789) (xy 93.702008 -228.512602) (xy 93.66826 -228.474508) (xy 93.641059 -228.431494)
			(xy 93.621111 -228.384674) (xy 93.608932 -228.33526) (xy 93.604837 -228.284532) (xy 93.299026 -228.284532)
			(xy 93.298536 -228.309521) (xy 93.290717 -228.358884) (xy 93.275273 -228.406416) (xy 93.252583 -228.450948)
			(xy 93.223207 -228.491381) (xy 93.187867 -228.526721) (xy 93.147434 -228.556097) (xy 93.102902 -228.578787)
			(xy 93.05537 -228.594231) (xy 93.006007 -228.60205) (xy 92.956029 -228.60205) (xy 92.906666 -228.594231)
			(xy 92.859134 -228.578787) (xy 92.814602 -228.556097) (xy 92.774169 -228.526721) (xy 92.738829 -228.491381)
			(xy 92.709453 -228.450948) (xy 92.686763 -228.406416) (xy 92.671319 -228.358884) (xy 92.6635 -228.309521)
			(xy 92.356183 -228.309521) (xy 92.356174 -228.309978) (xy 92.34801 -228.360212) (xy 92.331894 -228.408486)
			(xy 92.308243 -228.453549) (xy 92.27767 -228.494235) (xy 92.240966 -228.52949) (xy 92.199082 -228.5584)
			(xy 92.153103 -228.580217) (xy 92.104219 -228.594377) (xy 92.053698 -228.600511) (xy 92.002846 -228.598462)
			(xy 91.952982 -228.588282) (xy 91.905396 -228.570235) (xy 91.861322 -228.544789) (xy 91.8219 -228.512602)
			(xy 91.788152 -228.474508) (xy 91.760951 -228.431494) (xy 91.741003 -228.384674) (xy 91.728824 -228.33526)
			(xy 91.724729 -228.284532) (xy 91.416632 -228.284532) (xy 91.41612 -228.309978) (xy 91.407956 -228.360212)
			(xy 91.39184 -228.408486) (xy 91.368189 -228.453549) (xy 91.337616 -228.494235) (xy 91.300912 -228.52949)
			(xy 91.259028 -228.5584) (xy 91.213049 -228.580217) (xy 91.164165 -228.594377) (xy 91.113644 -228.600511)
			(xy 91.062792 -228.598462) (xy 91.012928 -228.588282) (xy 90.965342 -228.570235) (xy 90.921268 -228.544789)
			(xy 90.881846 -228.512602) (xy 90.848098 -228.474508) (xy 90.820897 -228.431494) (xy 90.800949 -228.384674)
			(xy 90.78877 -228.33526) (xy 90.784675 -228.284532) (xy 90.479118 -228.284532) (xy 90.478628 -228.309521)
			(xy 90.470809 -228.358884) (xy 90.455365 -228.406416) (xy 90.432675 -228.450948) (xy 90.403299 -228.491381)
			(xy 90.367959 -228.526721) (xy 90.327526 -228.556097) (xy 90.282994 -228.578787) (xy 90.235462 -228.594231)
			(xy 90.186099 -228.60205) (xy 90.136121 -228.60205) (xy 90.086758 -228.594231) (xy 90.039226 -228.578787)
			(xy 89.994694 -228.556097) (xy 89.954261 -228.526721) (xy 89.918921 -228.491381) (xy 89.889545 -228.450948)
			(xy 89.866855 -228.406416) (xy 89.851411 -228.358884) (xy 89.843592 -228.309521) (xy 89.536275 -228.309521)
			(xy 89.536266 -228.309978) (xy 89.528102 -228.360212) (xy 89.511986 -228.408486) (xy 89.488335 -228.453549)
			(xy 89.457762 -228.494235) (xy 89.421058 -228.52949) (xy 89.379174 -228.5584) (xy 89.333195 -228.580217)
			(xy 89.284311 -228.594377) (xy 89.23379 -228.600511) (xy 89.182938 -228.598462) (xy 89.133074 -228.588282)
			(xy 89.085488 -228.570235) (xy 89.041414 -228.544789) (xy 89.001992 -228.512602) (xy 88.968244 -228.474508)
			(xy 88.941043 -228.431494) (xy 88.921095 -228.384674) (xy 88.908916 -228.33526) (xy 88.904821 -228.284532)
			(xy 88.59901 -228.284532) (xy 88.59852 -228.309521) (xy 88.590701 -228.358884) (xy 88.575257 -228.406416)
			(xy 88.552567 -228.450948) (xy 88.523191 -228.491381) (xy 88.487851 -228.526721) (xy 88.447418 -228.556097)
			(xy 88.402886 -228.578787) (xy 88.355354 -228.594231) (xy 88.305991 -228.60205) (xy 88.256013 -228.60205)
			(xy 88.20665 -228.594231) (xy 88.159118 -228.578787) (xy 88.114586 -228.556097) (xy 88.074153 -228.526721)
			(xy 88.038813 -228.491381) (xy 88.009437 -228.450948) (xy 87.986747 -228.406416) (xy 87.971303 -228.358884)
			(xy 87.963484 -228.309521) (xy 87.656167 -228.309521) (xy 87.656158 -228.309978) (xy 87.647994 -228.360212)
			(xy 87.631878 -228.408486) (xy 87.608227 -228.453549) (xy 87.577654 -228.494235) (xy 87.54095 -228.52949)
			(xy 87.499066 -228.5584) (xy 87.453087 -228.580217) (xy 87.404203 -228.594377) (xy 87.353682 -228.600511)
			(xy 87.30283 -228.598462) (xy 87.252966 -228.588282) (xy 87.20538 -228.570235) (xy 87.161306 -228.544789)
			(xy 87.121884 -228.512602) (xy 87.088136 -228.474508) (xy 87.060935 -228.431494) (xy 87.040987 -228.384674)
			(xy 87.028808 -228.33526) (xy 87.024713 -228.284532) (xy 86.719156 -228.284532) (xy 86.718666 -228.309521)
			(xy 86.710847 -228.358884) (xy 86.695403 -228.406416) (xy 86.672713 -228.450948) (xy 86.643337 -228.491381)
			(xy 86.607997 -228.526721) (xy 86.567564 -228.556097) (xy 86.523032 -228.578787) (xy 86.4755 -228.594231)
			(xy 86.426137 -228.60205) (xy 86.376159 -228.60205) (xy 86.326796 -228.594231) (xy 86.279264 -228.578787)
			(xy 86.234732 -228.556097) (xy 86.194299 -228.526721) (xy 86.158959 -228.491381) (xy 86.129583 -228.450948)
			(xy 86.106893 -228.406416) (xy 86.091449 -228.358884) (xy 86.08363 -228.309521) (xy 85.776313 -228.309521)
			(xy 85.776304 -228.309978) (xy 85.76814 -228.360212) (xy 85.752024 -228.408486) (xy 85.728373 -228.453549)
			(xy 85.6978 -228.494235) (xy 85.661096 -228.52949) (xy 85.619212 -228.5584) (xy 85.573233 -228.580217)
			(xy 85.524349 -228.594377) (xy 85.473828 -228.600511) (xy 85.422976 -228.598462) (xy 85.373112 -228.588282)
			(xy 85.325526 -228.570235) (xy 85.281452 -228.544789) (xy 85.24203 -228.512602) (xy 85.208282 -228.474508)
			(xy 85.181081 -228.431494) (xy 85.161133 -228.384674) (xy 85.148954 -228.33526) (xy 85.144859 -228.284532)
			(xy 84.836762 -228.284532) (xy 84.83625 -228.309978) (xy 84.828086 -228.360212) (xy 84.81197 -228.408486)
			(xy 84.788319 -228.453549) (xy 84.757746 -228.494235) (xy 84.721042 -228.52949) (xy 84.679158 -228.5584)
			(xy 84.633179 -228.580217) (xy 84.584295 -228.594377) (xy 84.533774 -228.600511) (xy 84.482922 -228.598462)
			(xy 84.433058 -228.588282) (xy 84.385472 -228.570235) (xy 84.341398 -228.544789) (xy 84.301976 -228.512602)
			(xy 84.268228 -228.474508) (xy 84.241027 -228.431494) (xy 84.221079 -228.384674) (xy 84.2089 -228.33526)
			(xy 84.204805 -228.284532) (xy 83.898994 -228.284532) (xy 83.898504 -228.309521) (xy 83.890685 -228.358884)
			(xy 83.875241 -228.406416) (xy 83.852551 -228.450948) (xy 83.823175 -228.491381) (xy 83.787835 -228.526721)
			(xy 83.747402 -228.556097) (xy 83.70287 -228.578787) (xy 83.655338 -228.594231) (xy 83.605975 -228.60205)
			(xy 83.555997 -228.60205) (xy 83.506634 -228.594231) (xy 83.459102 -228.578787) (xy 83.41457 -228.556097)
			(xy 83.374137 -228.526721) (xy 83.338797 -228.491381) (xy 83.309421 -228.450948) (xy 83.286731 -228.406416)
			(xy 83.271287 -228.358884) (xy 83.263468 -228.309521) (xy 82.956151 -228.309521) (xy 82.956142 -228.309978)
			(xy 82.947978 -228.360212) (xy 82.931862 -228.408486) (xy 82.908211 -228.453549) (xy 82.877638 -228.494235)
			(xy 82.840934 -228.52949) (xy 82.79905 -228.5584) (xy 82.753071 -228.580217) (xy 82.704187 -228.594377)
			(xy 82.653666 -228.600511) (xy 82.602814 -228.598462) (xy 82.55295 -228.588282) (xy 82.505364 -228.570235)
			(xy 82.46129 -228.544789) (xy 82.421868 -228.512602) (xy 82.38812 -228.474508) (xy 82.360919 -228.431494)
			(xy 82.340971 -228.384674) (xy 82.328792 -228.33526) (xy 82.324697 -228.284532) (xy 82.01914 -228.284532)
			(xy 82.01865 -228.309521) (xy 82.010831 -228.358884) (xy 81.995387 -228.406416) (xy 81.972697 -228.450948)
			(xy 81.943321 -228.491381) (xy 81.907981 -228.526721) (xy 81.867548 -228.556097) (xy 81.823016 -228.578787)
			(xy 81.775484 -228.594231) (xy 81.726121 -228.60205) (xy 81.676143 -228.60205) (xy 81.62678 -228.594231)
			(xy 81.579248 -228.578787) (xy 81.534716 -228.556097) (xy 81.494283 -228.526721) (xy 81.458943 -228.491381)
			(xy 81.429567 -228.450948) (xy 81.406877 -228.406416) (xy 81.391433 -228.358884) (xy 81.383614 -228.309521)
			(xy 81.076297 -228.309521) (xy 81.076288 -228.309978) (xy 81.068124 -228.360212) (xy 81.052008 -228.408486)
			(xy 81.028357 -228.453549) (xy 80.997784 -228.494235) (xy 80.96108 -228.52949) (xy 80.919196 -228.5584)
			(xy 80.873217 -228.580217) (xy 80.824333 -228.594377) (xy 80.773812 -228.600511) (xy 80.72296 -228.598462)
			(xy 80.673096 -228.588282) (xy 80.62551 -228.570235) (xy 80.581436 -228.544789) (xy 80.542014 -228.512602)
			(xy 80.508266 -228.474508) (xy 80.481065 -228.431494) (xy 80.461117 -228.384674) (xy 80.448938 -228.33526)
			(xy 80.444843 -228.284532) (xy 80.13874 -228.284532) (xy 80.13874 -228.309505) (xy 80.130917 -228.358901)
			(xy 80.115463 -228.406464) (xy 80.09276 -228.451025) (xy 80.063365 -228.491485) (xy 80.028003 -228.52685)
			(xy 79.987545 -228.556247) (xy 79.942986 -228.578954) (xy 79.895424 -228.594411) (xy 79.846029 -228.602238)
			(xy 79.821024 -228.602794) (xy 79.796529 -228.602346) (xy 79.748117 -228.594849) (xy 79.701424 -228.580026)
			(xy 79.679292 -228.56952) (xy 79.665841 -228.563397) (xy 79.636729 -228.558375) (xy 79.607397 -228.561892)
			(xy 79.580298 -228.573656) (xy 79.557698 -228.592682) (xy 79.541488 -228.617378) (xy 79.533021 -228.645681)
			(xy 79.53248 -228.660452) (xy 79.53248 -229.119527) (xy 79.97366 -229.119527) (xy 79.97366 -229.069549)
			(xy 79.981479 -229.020186) (xy 79.996923 -228.972654) (xy 80.019613 -228.928122) (xy 80.048989 -228.887689)
			(xy 80.084329 -228.852349) (xy 80.124762 -228.822973) (xy 80.169294 -228.800283) (xy 80.216826 -228.784839)
			(xy 80.266189 -228.77702) (xy 80.316167 -228.77702) (xy 80.36553 -228.784839) (xy 80.413062 -228.800283)
			(xy 80.457594 -228.822973) (xy 80.498027 -228.852349) (xy 80.533367 -228.887689) (xy 80.562743 -228.928122)
			(xy 80.585433 -228.972654) (xy 80.600877 -229.020186) (xy 80.608696 -229.069549) (xy 80.609186 -229.094538)
			(xy 80.914743 -229.094538) (xy 80.918838 -229.04381) (xy 80.931017 -228.994396) (xy 80.950965 -228.947576)
			(xy 80.978166 -228.904562) (xy 81.011914 -228.866468) (xy 81.051336 -228.834281) (xy 81.09541 -228.808835)
			(xy 81.142996 -228.790788) (xy 81.19286 -228.780608) (xy 81.243712 -228.778559) (xy 81.294233 -228.784693)
			(xy 81.343117 -228.798853) (xy 81.389096 -228.82067) (xy 81.43098 -228.84958) (xy 81.467684 -228.884835)
			(xy 81.498257 -228.925521) (xy 81.521908 -228.970584) (xy 81.538024 -229.018858) (xy 81.546188 -229.069092)
			(xy 81.5467 -229.094538) (xy 81.854797 -229.094538) (xy 81.858892 -229.04381) (xy 81.871071 -228.994396)
			(xy 81.891019 -228.947576) (xy 81.91822 -228.904562) (xy 81.951968 -228.866468) (xy 81.99139 -228.834281)
			(xy 82.035464 -228.808835) (xy 82.08305 -228.790788) (xy 82.132914 -228.780608) (xy 82.183766 -228.778559)
			(xy 82.234287 -228.784693) (xy 82.283171 -228.798853) (xy 82.32915 -228.82067) (xy 82.371034 -228.84958)
			(xy 82.407738 -228.884835) (xy 82.438311 -228.925521) (xy 82.461962 -228.970584) (xy 82.478078 -229.018858)
			(xy 82.486242 -229.069092) (xy 82.486754 -229.094538) (xy 82.486251 -229.119527) (xy 82.793568 -229.119527)
			(xy 82.793568 -229.069549) (xy 82.801387 -229.020186) (xy 82.816831 -228.972654) (xy 82.839521 -228.928122)
			(xy 82.868897 -228.887689) (xy 82.904237 -228.852349) (xy 82.94467 -228.822973) (xy 82.989202 -228.800283)
			(xy 83.036734 -228.784839) (xy 83.086097 -228.77702) (xy 83.136075 -228.77702) (xy 83.185438 -228.784839)
			(xy 83.23297 -228.800283) (xy 83.277502 -228.822973) (xy 83.317935 -228.852349) (xy 83.353275 -228.887689)
			(xy 83.382651 -228.928122) (xy 83.405341 -228.972654) (xy 83.420785 -229.020186) (xy 83.428604 -229.069549)
			(xy 83.429094 -229.094538) (xy 83.734905 -229.094538) (xy 83.739 -229.04381) (xy 83.751179 -228.994396)
			(xy 83.771127 -228.947576) (xy 83.798328 -228.904562) (xy 83.832076 -228.866468) (xy 83.871498 -228.834281)
			(xy 83.915572 -228.808835) (xy 83.963158 -228.790788) (xy 84.013022 -228.780608) (xy 84.063874 -228.778559)
			(xy 84.114395 -228.784693) (xy 84.163279 -228.798853) (xy 84.209258 -228.82067) (xy 84.251142 -228.84958)
			(xy 84.287846 -228.884835) (xy 84.318419 -228.925521) (xy 84.34207 -228.970584) (xy 84.358186 -229.018858)
			(xy 84.36635 -229.069092) (xy 84.366862 -229.094538) (xy 84.366359 -229.119527) (xy 84.673422 -229.119527)
			(xy 84.673422 -229.069549) (xy 84.681241 -229.020186) (xy 84.696685 -228.972654) (xy 84.719375 -228.928122)
			(xy 84.748751 -228.887689) (xy 84.784091 -228.852349) (xy 84.824524 -228.822973) (xy 84.869056 -228.800283)
			(xy 84.916588 -228.784839) (xy 84.965951 -228.77702) (xy 85.015929 -228.77702) (xy 85.065292 -228.784839)
			(xy 85.112824 -228.800283) (xy 85.157356 -228.822973) (xy 85.197789 -228.852349) (xy 85.233129 -228.887689)
			(xy 85.262505 -228.928122) (xy 85.285195 -228.972654) (xy 85.300639 -229.020186) (xy 85.308458 -229.069549)
			(xy 85.308948 -229.094538) (xy 85.614759 -229.094538) (xy 85.618854 -229.04381) (xy 85.631033 -228.994396)
			(xy 85.650981 -228.947576) (xy 85.678182 -228.904562) (xy 85.71193 -228.866468) (xy 85.751352 -228.834281)
			(xy 85.795426 -228.808835) (xy 85.843012 -228.790788) (xy 85.892876 -228.780608) (xy 85.943728 -228.778559)
			(xy 85.994249 -228.784693) (xy 86.043133 -228.798853) (xy 86.089112 -228.82067) (xy 86.130996 -228.84958)
			(xy 86.1677 -228.884835) (xy 86.198273 -228.925521) (xy 86.221924 -228.970584) (xy 86.23804 -229.018858)
			(xy 86.246204 -229.069092) (xy 86.246716 -229.094538) (xy 86.246213 -229.119527) (xy 86.55353 -229.119527)
			(xy 86.55353 -229.069549) (xy 86.561349 -229.020186) (xy 86.576793 -228.972654) (xy 86.599483 -228.928122)
			(xy 86.628859 -228.887689) (xy 86.664199 -228.852349) (xy 86.704632 -228.822973) (xy 86.749164 -228.800283)
			(xy 86.796696 -228.784839) (xy 86.846059 -228.77702) (xy 86.896037 -228.77702) (xy 86.9454 -228.784839)
			(xy 86.992932 -228.800283) (xy 87.037464 -228.822973) (xy 87.077897 -228.852349) (xy 87.113237 -228.887689)
			(xy 87.142613 -228.928122) (xy 87.165303 -228.972654) (xy 87.180747 -229.020186) (xy 87.188566 -229.069549)
			(xy 87.189056 -229.094538) (xy 87.494867 -229.094538) (xy 87.498962 -229.04381) (xy 87.511141 -228.994396)
			(xy 87.531089 -228.947576) (xy 87.55829 -228.904562) (xy 87.592038 -228.866468) (xy 87.63146 -228.834281)
			(xy 87.675534 -228.808835) (xy 87.72312 -228.790788) (xy 87.772984 -228.780608) (xy 87.823836 -228.778559)
			(xy 87.874357 -228.784693) (xy 87.923241 -228.798853) (xy 87.96922 -228.82067) (xy 88.011104 -228.84958)
			(xy 88.047808 -228.884835) (xy 88.078381 -228.925521) (xy 88.102032 -228.970584) (xy 88.118148 -229.018858)
			(xy 88.126312 -229.069092) (xy 88.126824 -229.094538) (xy 88.434921 -229.094538) (xy 88.439016 -229.04381)
			(xy 88.451195 -228.994396) (xy 88.471143 -228.947576) (xy 88.498344 -228.904562) (xy 88.532092 -228.866468)
			(xy 88.571514 -228.834281) (xy 88.615588 -228.808835) (xy 88.663174 -228.790788) (xy 88.713038 -228.780608)
			(xy 88.76389 -228.778559) (xy 88.814411 -228.784693) (xy 88.863295 -228.798853) (xy 88.909274 -228.82067)
			(xy 88.951158 -228.84958) (xy 88.987862 -228.884835) (xy 89.018435 -228.925521) (xy 89.042086 -228.970584)
			(xy 89.058202 -229.018858) (xy 89.066366 -229.069092) (xy 89.066878 -229.094538) (xy 89.066375 -229.119527)
			(xy 89.373438 -229.119527) (xy 89.373438 -229.069549) (xy 89.381257 -229.020186) (xy 89.396701 -228.972654)
			(xy 89.419391 -228.928122) (xy 89.448767 -228.887689) (xy 89.484107 -228.852349) (xy 89.52454 -228.822973)
			(xy 89.569072 -228.800283) (xy 89.616604 -228.784839) (xy 89.665967 -228.77702) (xy 89.715945 -228.77702)
			(xy 89.765308 -228.784839) (xy 89.81284 -228.800283) (xy 89.857372 -228.822973) (xy 89.897805 -228.852349)
			(xy 89.933145 -228.887689) (xy 89.962521 -228.928122) (xy 89.985211 -228.972654) (xy 90.000655 -229.020186)
			(xy 90.008474 -229.069549) (xy 90.008964 -229.094538) (xy 90.314775 -229.094538) (xy 90.31887 -229.04381)
			(xy 90.331049 -228.994396) (xy 90.350997 -228.947576) (xy 90.378198 -228.904562) (xy 90.411946 -228.866468)
			(xy 90.451368 -228.834281) (xy 90.495442 -228.808835) (xy 90.543028 -228.790788) (xy 90.592892 -228.780608)
			(xy 90.643744 -228.778559) (xy 90.694265 -228.784693) (xy 90.743149 -228.798853) (xy 90.789128 -228.82067)
			(xy 90.831012 -228.84958) (xy 90.867716 -228.884835) (xy 90.898289 -228.925521) (xy 90.92194 -228.970584)
			(xy 90.938056 -229.018858) (xy 90.94622 -229.069092) (xy 90.946732 -229.094538) (xy 90.946229 -229.119527)
			(xy 91.253546 -229.119527) (xy 91.253546 -229.069549) (xy 91.261365 -229.020186) (xy 91.276809 -228.972654)
			(xy 91.299499 -228.928122) (xy 91.328875 -228.887689) (xy 91.364215 -228.852349) (xy 91.404648 -228.822973)
			(xy 91.44918 -228.800283) (xy 91.496712 -228.784839) (xy 91.546075 -228.77702) (xy 91.596053 -228.77702)
			(xy 91.645416 -228.784839) (xy 91.692948 -228.800283) (xy 91.73748 -228.822973) (xy 91.777913 -228.852349)
			(xy 91.813253 -228.887689) (xy 91.842629 -228.928122) (xy 91.865319 -228.972654) (xy 91.880763 -229.020186)
			(xy 91.888582 -229.069549) (xy 91.889072 -229.094538) (xy 92.194883 -229.094538) (xy 92.198978 -229.04381)
			(xy 92.211157 -228.994396) (xy 92.231105 -228.947576) (xy 92.258306 -228.904562) (xy 92.292054 -228.866468)
			(xy 92.331476 -228.834281) (xy 92.37555 -228.808835) (xy 92.423136 -228.790788) (xy 92.473 -228.780608)
			(xy 92.523852 -228.778559) (xy 92.574373 -228.784693) (xy 92.623257 -228.798853) (xy 92.669236 -228.82067)
			(xy 92.71112 -228.84958) (xy 92.747824 -228.884835) (xy 92.778397 -228.925521) (xy 92.802048 -228.970584)
			(xy 92.818164 -229.018858) (xy 92.826328 -229.069092) (xy 92.82684 -229.094538) (xy 92.826337 -229.119527)
			(xy 93.1334 -229.119527) (xy 93.1334 -229.069549) (xy 93.141219 -229.020186) (xy 93.156663 -228.972654)
			(xy 93.179353 -228.928122) (xy 93.208729 -228.887689) (xy 93.244069 -228.852349) (xy 93.284502 -228.822973)
			(xy 93.329034 -228.800283) (xy 93.376566 -228.784839) (xy 93.425929 -228.77702) (xy 93.475907 -228.77702)
			(xy 93.52527 -228.784839) (xy 93.572802 -228.800283) (xy 93.617334 -228.822973) (xy 93.657767 -228.852349)
			(xy 93.693107 -228.887689) (xy 93.722483 -228.928122) (xy 93.745173 -228.972654) (xy 93.760617 -229.020186)
			(xy 93.768436 -229.069549) (xy 93.768926 -229.094538) (xy 94.074737 -229.094538) (xy 94.078832 -229.04381)
			(xy 94.091011 -228.994396) (xy 94.110959 -228.947576) (xy 94.13816 -228.904562) (xy 94.171908 -228.866468)
			(xy 94.21133 -228.834281) (xy 94.255404 -228.808835) (xy 94.30299 -228.790788) (xy 94.352854 -228.780608)
			(xy 94.403706 -228.778559) (xy 94.454227 -228.784693) (xy 94.503111 -228.798853) (xy 94.54909 -228.82067)
			(xy 94.590974 -228.84958) (xy 94.627678 -228.884835) (xy 94.658251 -228.925521) (xy 94.681902 -228.970584)
			(xy 94.698018 -229.018858) (xy 94.706182 -229.069092) (xy 94.706694 -229.094538) (xy 95.014791 -229.094538)
			(xy 95.018886 -229.04381) (xy 95.031065 -228.994396) (xy 95.051013 -228.947576) (xy 95.078214 -228.904562)
			(xy 95.111962 -228.866468) (xy 95.151384 -228.834281) (xy 95.195458 -228.808835) (xy 95.243044 -228.790788)
			(xy 95.292908 -228.780608) (xy 95.34376 -228.778559) (xy 95.394281 -228.784693) (xy 95.443165 -228.798853)
			(xy 95.489144 -228.82067) (xy 95.531028 -228.84958) (xy 95.567732 -228.884835) (xy 95.598305 -228.925521)
			(xy 95.621956 -228.970584) (xy 95.638072 -229.018858) (xy 95.646236 -229.069092) (xy 95.646748 -229.094538)
			(xy 95.646236 -229.119984) (xy 95.638072 -229.170218) (xy 95.621956 -229.218492) (xy 95.598305 -229.263555)
			(xy 95.567732 -229.304241) (xy 95.531028 -229.339496) (xy 95.489144 -229.368406) (xy 95.443165 -229.390223)
			(xy 95.394281 -229.404383) (xy 95.34376 -229.410517) (xy 95.292908 -229.408468) (xy 95.243044 -229.398288)
			(xy 95.195458 -229.380241) (xy 95.151384 -229.354795) (xy 95.111962 -229.322608) (xy 95.078214 -229.284514)
			(xy 95.051013 -229.2415) (xy 95.031065 -229.19468) (xy 95.018886 -229.145266) (xy 95.014791 -229.094538)
			(xy 94.706694 -229.094538) (xy 94.706182 -229.119984) (xy 94.698018 -229.170218) (xy 94.681902 -229.218492)
			(xy 94.658251 -229.263555) (xy 94.627678 -229.304241) (xy 94.590974 -229.339496) (xy 94.54909 -229.368406)
			(xy 94.503111 -229.390223) (xy 94.454227 -229.404383) (xy 94.403706 -229.410517) (xy 94.352854 -229.408468)
			(xy 94.30299 -229.398288) (xy 94.255404 -229.380241) (xy 94.21133 -229.354795) (xy 94.171908 -229.322608)
			(xy 94.13816 -229.284514) (xy 94.110959 -229.2415) (xy 94.091011 -229.19468) (xy 94.078832 -229.145266)
			(xy 94.074737 -229.094538) (xy 93.768926 -229.094538) (xy 93.768436 -229.119527) (xy 93.760617 -229.16889)
			(xy 93.745173 -229.216422) (xy 93.722483 -229.260954) (xy 93.693107 -229.301387) (xy 93.657767 -229.336727)
			(xy 93.617334 -229.366103) (xy 93.572802 -229.388793) (xy 93.52527 -229.404237) (xy 93.475907 -229.412056)
			(xy 93.425929 -229.412056) (xy 93.376566 -229.404237) (xy 93.329034 -229.388793) (xy 93.284502 -229.366103)
			(xy 93.244069 -229.336727) (xy 93.208729 -229.301387) (xy 93.179353 -229.260954) (xy 93.156663 -229.216422)
			(xy 93.141219 -229.16889) (xy 93.1334 -229.119527) (xy 92.826337 -229.119527) (xy 92.826328 -229.119984)
			(xy 92.818164 -229.170218) (xy 92.802048 -229.218492) (xy 92.778397 -229.263555) (xy 92.747824 -229.304241)
			(xy 92.71112 -229.339496) (xy 92.669236 -229.368406) (xy 92.623257 -229.390223) (xy 92.574373 -229.404383)
			(xy 92.523852 -229.410517) (xy 92.473 -229.408468) (xy 92.423136 -229.398288) (xy 92.37555 -229.380241)
			(xy 92.331476 -229.354795) (xy 92.292054 -229.322608) (xy 92.258306 -229.284514) (xy 92.231105 -229.2415)
			(xy 92.211157 -229.19468) (xy 92.198978 -229.145266) (xy 92.194883 -229.094538) (xy 91.889072 -229.094538)
			(xy 91.888582 -229.119527) (xy 91.880763 -229.16889) (xy 91.865319 -229.216422) (xy 91.842629 -229.260954)
			(xy 91.813253 -229.301387) (xy 91.777913 -229.336727) (xy 91.73748 -229.366103) (xy 91.692948 -229.388793)
			(xy 91.645416 -229.404237) (xy 91.596053 -229.412056) (xy 91.546075 -229.412056) (xy 91.496712 -229.404237)
			(xy 91.44918 -229.388793) (xy 91.404648 -229.366103) (xy 91.364215 -229.336727) (xy 91.328875 -229.301387)
			(xy 91.299499 -229.260954) (xy 91.276809 -229.216422) (xy 91.261365 -229.16889) (xy 91.253546 -229.119527)
			(xy 90.946229 -229.119527) (xy 90.94622 -229.119984) (xy 90.938056 -229.170218) (xy 90.92194 -229.218492)
			(xy 90.898289 -229.263555) (xy 90.867716 -229.304241) (xy 90.831012 -229.339496) (xy 90.789128 -229.368406)
			(xy 90.743149 -229.390223) (xy 90.694265 -229.404383) (xy 90.643744 -229.410517) (xy 90.592892 -229.408468)
			(xy 90.543028 -229.398288) (xy 90.495442 -229.380241) (xy 90.451368 -229.354795) (xy 90.411946 -229.322608)
			(xy 90.378198 -229.284514) (xy 90.350997 -229.2415) (xy 90.331049 -229.19468) (xy 90.31887 -229.145266)
			(xy 90.314775 -229.094538) (xy 90.008964 -229.094538) (xy 90.008474 -229.119527) (xy 90.000655 -229.16889)
			(xy 89.985211 -229.216422) (xy 89.962521 -229.260954) (xy 89.933145 -229.301387) (xy 89.897805 -229.336727)
			(xy 89.857372 -229.366103) (xy 89.81284 -229.388793) (xy 89.765308 -229.404237) (xy 89.715945 -229.412056)
			(xy 89.665967 -229.412056) (xy 89.616604 -229.404237) (xy 89.569072 -229.388793) (xy 89.52454 -229.366103)
			(xy 89.484107 -229.336727) (xy 89.448767 -229.301387) (xy 89.419391 -229.260954) (xy 89.396701 -229.216422)
			(xy 89.381257 -229.16889) (xy 89.373438 -229.119527) (xy 89.066375 -229.119527) (xy 89.066366 -229.119984)
			(xy 89.058202 -229.170218) (xy 89.042086 -229.218492) (xy 89.018435 -229.263555) (xy 88.987862 -229.304241)
			(xy 88.951158 -229.339496) (xy 88.909274 -229.368406) (xy 88.863295 -229.390223) (xy 88.814411 -229.404383)
			(xy 88.76389 -229.410517) (xy 88.713038 -229.408468) (xy 88.663174 -229.398288) (xy 88.615588 -229.380241)
			(xy 88.571514 -229.354795) (xy 88.532092 -229.322608) (xy 88.498344 -229.284514) (xy 88.471143 -229.2415)
			(xy 88.451195 -229.19468) (xy 88.439016 -229.145266) (xy 88.434921 -229.094538) (xy 88.126824 -229.094538)
			(xy 88.126312 -229.119984) (xy 88.118148 -229.170218) (xy 88.102032 -229.218492) (xy 88.078381 -229.263555)
			(xy 88.047808 -229.304241) (xy 88.011104 -229.339496) (xy 87.96922 -229.368406) (xy 87.923241 -229.390223)
			(xy 87.874357 -229.404383) (xy 87.823836 -229.410517) (xy 87.772984 -229.408468) (xy 87.72312 -229.398288)
			(xy 87.675534 -229.380241) (xy 87.63146 -229.354795) (xy 87.592038 -229.322608) (xy 87.55829 -229.284514)
			(xy 87.531089 -229.2415) (xy 87.511141 -229.19468) (xy 87.498962 -229.145266) (xy 87.494867 -229.094538)
			(xy 87.189056 -229.094538) (xy 87.188566 -229.119527) (xy 87.180747 -229.16889) (xy 87.165303 -229.216422)
			(xy 87.142613 -229.260954) (xy 87.113237 -229.301387) (xy 87.077897 -229.336727) (xy 87.037464 -229.366103)
			(xy 86.992932 -229.388793) (xy 86.9454 -229.404237) (xy 86.896037 -229.412056) (xy 86.846059 -229.412056)
			(xy 86.796696 -229.404237) (xy 86.749164 -229.388793) (xy 86.704632 -229.366103) (xy 86.664199 -229.336727)
			(xy 86.628859 -229.301387) (xy 86.599483 -229.260954) (xy 86.576793 -229.216422) (xy 86.561349 -229.16889)
			(xy 86.55353 -229.119527) (xy 86.246213 -229.119527) (xy 86.246204 -229.119984) (xy 86.23804 -229.170218)
			(xy 86.221924 -229.218492) (xy 86.198273 -229.263555) (xy 86.1677 -229.304241) (xy 86.130996 -229.339496)
			(xy 86.089112 -229.368406) (xy 86.043133 -229.390223) (xy 85.994249 -229.404383) (xy 85.943728 -229.410517)
			(xy 85.892876 -229.408468) (xy 85.843012 -229.398288) (xy 85.795426 -229.380241) (xy 85.751352 -229.354795)
			(xy 85.71193 -229.322608) (xy 85.678182 -229.284514) (xy 85.650981 -229.2415) (xy 85.631033 -229.19468)
			(xy 85.618854 -229.145266) (xy 85.614759 -229.094538) (xy 85.308948 -229.094538) (xy 85.308458 -229.119527)
			(xy 85.300639 -229.16889) (xy 85.285195 -229.216422) (xy 85.262505 -229.260954) (xy 85.233129 -229.301387)
			(xy 85.197789 -229.336727) (xy 85.157356 -229.366103) (xy 85.112824 -229.388793) (xy 85.065292 -229.404237)
			(xy 85.015929 -229.412056) (xy 84.965951 -229.412056) (xy 84.916588 -229.404237) (xy 84.869056 -229.388793)
			(xy 84.824524 -229.366103) (xy 84.784091 -229.336727) (xy 84.748751 -229.301387) (xy 84.719375 -229.260954)
			(xy 84.696685 -229.216422) (xy 84.681241 -229.16889) (xy 84.673422 -229.119527) (xy 84.366359 -229.119527)
			(xy 84.36635 -229.119984) (xy 84.358186 -229.170218) (xy 84.34207 -229.218492) (xy 84.318419 -229.263555)
			(xy 84.287846 -229.304241) (xy 84.251142 -229.339496) (xy 84.209258 -229.368406) (xy 84.163279 -229.390223)
			(xy 84.114395 -229.404383) (xy 84.063874 -229.410517) (xy 84.013022 -229.408468) (xy 83.963158 -229.398288)
			(xy 83.915572 -229.380241) (xy 83.871498 -229.354795) (xy 83.832076 -229.322608) (xy 83.798328 -229.284514)
			(xy 83.771127 -229.2415) (xy 83.751179 -229.19468) (xy 83.739 -229.145266) (xy 83.734905 -229.094538)
			(xy 83.429094 -229.094538) (xy 83.428604 -229.119527) (xy 83.420785 -229.16889) (xy 83.405341 -229.216422)
			(xy 83.382651 -229.260954) (xy 83.353275 -229.301387) (xy 83.317935 -229.336727) (xy 83.277502 -229.366103)
			(xy 83.23297 -229.388793) (xy 83.185438 -229.404237) (xy 83.136075 -229.412056) (xy 83.086097 -229.412056)
			(xy 83.036734 -229.404237) (xy 82.989202 -229.388793) (xy 82.94467 -229.366103) (xy 82.904237 -229.336727)
			(xy 82.868897 -229.301387) (xy 82.839521 -229.260954) (xy 82.816831 -229.216422) (xy 82.801387 -229.16889)
			(xy 82.793568 -229.119527) (xy 82.486251 -229.119527) (xy 82.486242 -229.119984) (xy 82.478078 -229.170218)
			(xy 82.461962 -229.218492) (xy 82.438311 -229.263555) (xy 82.407738 -229.304241) (xy 82.371034 -229.339496)
			(xy 82.32915 -229.368406) (xy 82.283171 -229.390223) (xy 82.234287 -229.404383) (xy 82.183766 -229.410517)
			(xy 82.132914 -229.408468) (xy 82.08305 -229.398288) (xy 82.035464 -229.380241) (xy 81.99139 -229.354795)
			(xy 81.951968 -229.322608) (xy 81.91822 -229.284514) (xy 81.891019 -229.2415) (xy 81.871071 -229.19468)
			(xy 81.858892 -229.145266) (xy 81.854797 -229.094538) (xy 81.5467 -229.094538) (xy 81.546188 -229.119984)
			(xy 81.538024 -229.170218) (xy 81.521908 -229.218492) (xy 81.498257 -229.263555) (xy 81.467684 -229.304241)
			(xy 81.43098 -229.339496) (xy 81.389096 -229.368406) (xy 81.343117 -229.390223) (xy 81.294233 -229.404383)
			(xy 81.243712 -229.410517) (xy 81.19286 -229.408468) (xy 81.142996 -229.398288) (xy 81.09541 -229.380241)
			(xy 81.051336 -229.354795) (xy 81.011914 -229.322608) (xy 80.978166 -229.284514) (xy 80.950965 -229.2415)
			(xy 80.931017 -229.19468) (xy 80.918838 -229.145266) (xy 80.914743 -229.094538) (xy 80.609186 -229.094538)
			(xy 80.608696 -229.119527) (xy 80.600877 -229.16889) (xy 80.585433 -229.216422) (xy 80.562743 -229.260954)
			(xy 80.533367 -229.301387) (xy 80.498027 -229.336727) (xy 80.457594 -229.366103) (xy 80.413062 -229.388793)
			(xy 80.36553 -229.404237) (xy 80.316167 -229.412056) (xy 80.266189 -229.412056) (xy 80.216826 -229.404237)
			(xy 80.169294 -229.388793) (xy 80.124762 -229.366103) (xy 80.084329 -229.336727) (xy 80.048989 -229.301387)
			(xy 80.019613 -229.260954) (xy 79.996923 -229.216422) (xy 79.981479 -229.16889) (xy 79.97366 -229.119527)
			(xy 79.53248 -229.119527) (xy 79.53248 -229.90429) (xy 80.444843 -229.90429) (xy 80.448938 -229.853562)
			(xy 80.461117 -229.804148) (xy 80.481065 -229.757328) (xy 80.508266 -229.714314) (xy 80.542014 -229.67622)
			(xy 80.581436 -229.644033) (xy 80.62551 -229.618587) (xy 80.673096 -229.60054) (xy 80.72296 -229.59036)
			(xy 80.773812 -229.588311) (xy 80.824333 -229.594445) (xy 80.873217 -229.608605) (xy 80.919196 -229.630422)
			(xy 80.96108 -229.659332) (xy 80.997784 -229.694587) (xy 81.028357 -229.735273) (xy 81.052008 -229.780336)
			(xy 81.068124 -229.82861) (xy 81.076288 -229.878844) (xy 81.0768 -229.90429) (xy 81.076297 -229.929279)
			(xy 81.383614 -229.929279) (xy 81.383614 -229.879301) (xy 81.391433 -229.829938) (xy 81.406877 -229.782406)
			(xy 81.429567 -229.737874) (xy 81.458943 -229.697441) (xy 81.494283 -229.662101) (xy 81.534716 -229.632725)
			(xy 81.579248 -229.610035) (xy 81.62678 -229.594591) (xy 81.676143 -229.586772) (xy 81.726121 -229.586772)
			(xy 81.775484 -229.594591) (xy 81.823016 -229.610035) (xy 81.867548 -229.632725) (xy 81.907981 -229.662101)
			(xy 81.943321 -229.697441) (xy 81.972697 -229.737874) (xy 81.995387 -229.782406) (xy 82.010831 -229.829938)
			(xy 82.01865 -229.879301) (xy 82.01914 -229.90429) (xy 82.324697 -229.90429) (xy 82.328792 -229.853562)
			(xy 82.340971 -229.804148) (xy 82.360919 -229.757328) (xy 82.38812 -229.714314) (xy 82.421868 -229.67622)
			(xy 82.46129 -229.644033) (xy 82.505364 -229.618587) (xy 82.55295 -229.60054) (xy 82.602814 -229.59036)
			(xy 82.653666 -229.588311) (xy 82.704187 -229.594445) (xy 82.753071 -229.608605) (xy 82.79905 -229.630422)
			(xy 82.840934 -229.659332) (xy 82.877638 -229.694587) (xy 82.908211 -229.735273) (xy 82.931862 -229.780336)
			(xy 82.947978 -229.82861) (xy 82.956142 -229.878844) (xy 82.956654 -229.90429) (xy 82.956151 -229.929279)
			(xy 83.263468 -229.929279) (xy 83.263468 -229.879301) (xy 83.271287 -229.829938) (xy 83.286731 -229.782406)
			(xy 83.309421 -229.737874) (xy 83.338797 -229.697441) (xy 83.374137 -229.662101) (xy 83.41457 -229.632725)
			(xy 83.459102 -229.610035) (xy 83.506634 -229.594591) (xy 83.555997 -229.586772) (xy 83.605975 -229.586772)
			(xy 83.655338 -229.594591) (xy 83.70287 -229.610035) (xy 83.747402 -229.632725) (xy 83.787835 -229.662101)
			(xy 83.823175 -229.697441) (xy 83.852551 -229.737874) (xy 83.875241 -229.782406) (xy 83.890685 -229.829938)
			(xy 83.898504 -229.879301) (xy 83.898994 -229.90429) (xy 84.204805 -229.90429) (xy 84.2089 -229.853562)
			(xy 84.221079 -229.804148) (xy 84.241027 -229.757328) (xy 84.268228 -229.714314) (xy 84.301976 -229.67622)
			(xy 84.341398 -229.644033) (xy 84.385472 -229.618587) (xy 84.433058 -229.60054) (xy 84.482922 -229.59036)
			(xy 84.533774 -229.588311) (xy 84.584295 -229.594445) (xy 84.633179 -229.608605) (xy 84.679158 -229.630422)
			(xy 84.721042 -229.659332) (xy 84.757746 -229.694587) (xy 84.788319 -229.735273) (xy 84.81197 -229.780336)
			(xy 84.828086 -229.82861) (xy 84.83625 -229.878844) (xy 84.836762 -229.90429) (xy 85.144859 -229.90429)
			(xy 85.148954 -229.853562) (xy 85.161133 -229.804148) (xy 85.181081 -229.757328) (xy 85.208282 -229.714314)
			(xy 85.24203 -229.67622) (xy 85.281452 -229.644033) (xy 85.325526 -229.618587) (xy 85.373112 -229.60054)
			(xy 85.422976 -229.59036) (xy 85.473828 -229.588311) (xy 85.524349 -229.594445) (xy 85.573233 -229.608605)
			(xy 85.619212 -229.630422) (xy 85.661096 -229.659332) (xy 85.6978 -229.694587) (xy 85.728373 -229.735273)
			(xy 85.752024 -229.780336) (xy 85.76814 -229.82861) (xy 85.776304 -229.878844) (xy 85.776816 -229.90429)
			(xy 87.024713 -229.90429) (xy 87.028808 -229.853562) (xy 87.040987 -229.804148) (xy 87.060935 -229.757328)
			(xy 87.088136 -229.714314) (xy 87.121884 -229.67622) (xy 87.161306 -229.644033) (xy 87.20538 -229.618587)
			(xy 87.252966 -229.60054) (xy 87.30283 -229.59036) (xy 87.353682 -229.588311) (xy 87.404203 -229.594445)
			(xy 87.453087 -229.608605) (xy 87.499066 -229.630422) (xy 87.54095 -229.659332) (xy 87.577654 -229.694587)
			(xy 87.608227 -229.735273) (xy 87.631878 -229.780336) (xy 87.647994 -229.82861) (xy 87.656158 -229.878844)
			(xy 87.65667 -229.90429) (xy 87.656167 -229.929279) (xy 87.963484 -229.929279) (xy 87.963484 -229.879301)
			(xy 87.971303 -229.829938) (xy 87.986747 -229.782406) (xy 88.009437 -229.737874) (xy 88.038813 -229.697441)
			(xy 88.074153 -229.662101) (xy 88.114586 -229.632725) (xy 88.159118 -229.610035) (xy 88.20665 -229.594591)
			(xy 88.256013 -229.586772) (xy 88.305991 -229.586772) (xy 88.355354 -229.594591) (xy 88.402886 -229.610035)
			(xy 88.447418 -229.632725) (xy 88.487851 -229.662101) (xy 88.523191 -229.697441) (xy 88.552567 -229.737874)
			(xy 88.575257 -229.782406) (xy 88.590701 -229.829938) (xy 88.59852 -229.879301) (xy 88.59901 -229.90429)
			(xy 88.904821 -229.90429) (xy 88.908916 -229.853562) (xy 88.921095 -229.804148) (xy 88.941043 -229.757328)
			(xy 88.968244 -229.714314) (xy 89.001992 -229.67622) (xy 89.041414 -229.644033) (xy 89.085488 -229.618587)
			(xy 89.133074 -229.60054) (xy 89.182938 -229.59036) (xy 89.23379 -229.588311) (xy 89.284311 -229.594445)
			(xy 89.333195 -229.608605) (xy 89.379174 -229.630422) (xy 89.421058 -229.659332) (xy 89.457762 -229.694587)
			(xy 89.488335 -229.735273) (xy 89.511986 -229.780336) (xy 89.528102 -229.82861) (xy 89.536266 -229.878844)
			(xy 89.536778 -229.90429) (xy 89.536275 -229.929279) (xy 89.843592 -229.929279) (xy 89.843592 -229.879301)
			(xy 89.851411 -229.829938) (xy 89.866855 -229.782406) (xy 89.889545 -229.737874) (xy 89.918921 -229.697441)
			(xy 89.954261 -229.662101) (xy 89.994694 -229.632725) (xy 90.039226 -229.610035) (xy 90.086758 -229.594591)
			(xy 90.136121 -229.586772) (xy 90.186099 -229.586772) (xy 90.235462 -229.594591) (xy 90.282994 -229.610035)
			(xy 90.327526 -229.632725) (xy 90.367959 -229.662101) (xy 90.403299 -229.697441) (xy 90.432675 -229.737874)
			(xy 90.455365 -229.782406) (xy 90.470809 -229.829938) (xy 90.478628 -229.879301) (xy 90.479118 -229.90429)
			(xy 90.784675 -229.90429) (xy 90.78877 -229.853562) (xy 90.800949 -229.804148) (xy 90.820897 -229.757328)
			(xy 90.848098 -229.714314) (xy 90.881846 -229.67622) (xy 90.921268 -229.644033) (xy 90.965342 -229.618587)
			(xy 91.012928 -229.60054) (xy 91.062792 -229.59036) (xy 91.113644 -229.588311) (xy 91.164165 -229.594445)
			(xy 91.213049 -229.608605) (xy 91.259028 -229.630422) (xy 91.300912 -229.659332) (xy 91.337616 -229.694587)
			(xy 91.368189 -229.735273) (xy 91.39184 -229.780336) (xy 91.407956 -229.82861) (xy 91.41612 -229.878844)
			(xy 91.416632 -229.90429) (xy 91.724729 -229.90429) (xy 91.728824 -229.853562) (xy 91.741003 -229.804148)
			(xy 91.760951 -229.757328) (xy 91.788152 -229.714314) (xy 91.8219 -229.67622) (xy 91.861322 -229.644033)
			(xy 91.905396 -229.618587) (xy 91.952982 -229.60054) (xy 92.002846 -229.59036) (xy 92.053698 -229.588311)
			(xy 92.104219 -229.594445) (xy 92.153103 -229.608605) (xy 92.199082 -229.630422) (xy 92.240966 -229.659332)
			(xy 92.27767 -229.694587) (xy 92.308243 -229.735273) (xy 92.331894 -229.780336) (xy 92.34801 -229.82861)
			(xy 92.356174 -229.878844) (xy 92.356686 -229.90429) (xy 93.604837 -229.90429) (xy 93.608932 -229.853562)
			(xy 93.621111 -229.804148) (xy 93.641059 -229.757328) (xy 93.66826 -229.714314) (xy 93.702008 -229.67622)
			(xy 93.74143 -229.644033) (xy 93.785504 -229.618587) (xy 93.83309 -229.60054) (xy 93.882954 -229.59036)
			(xy 93.933806 -229.588311) (xy 93.984327 -229.594445) (xy 94.033211 -229.608605) (xy 94.07919 -229.630422)
			(xy 94.121074 -229.659332) (xy 94.157778 -229.694587) (xy 94.188351 -229.735273) (xy 94.212002 -229.780336)
			(xy 94.228118 -229.82861) (xy 94.236282 -229.878844) (xy 94.236794 -229.90429) (xy 94.236291 -229.929279)
			(xy 94.543608 -229.929279) (xy 94.543608 -229.879301) (xy 94.551427 -229.829938) (xy 94.566871 -229.782406)
			(xy 94.589561 -229.737874) (xy 94.618937 -229.697441) (xy 94.654277 -229.662101) (xy 94.69471 -229.632725)
			(xy 94.739242 -229.610035) (xy 94.786774 -229.594591) (xy 94.836137 -229.586772) (xy 94.886115 -229.586772)
			(xy 94.935478 -229.594591) (xy 94.98301 -229.610035) (xy 95.027542 -229.632725) (xy 95.067975 -229.662101)
			(xy 95.103315 -229.697441) (xy 95.132691 -229.737874) (xy 95.155381 -229.782406) (xy 95.170825 -229.829938)
			(xy 95.178644 -229.879301) (xy 95.179134 -229.90429) (xy 95.484691 -229.90429) (xy 95.488786 -229.853562)
			(xy 95.500965 -229.804148) (xy 95.520913 -229.757328) (xy 95.548114 -229.714314) (xy 95.581862 -229.67622)
			(xy 95.621284 -229.644033) (xy 95.665358 -229.618587) (xy 95.712944 -229.60054) (xy 95.762808 -229.59036)
			(xy 95.81366 -229.588311) (xy 95.864181 -229.594445) (xy 95.913065 -229.608605) (xy 95.959044 -229.630422)
			(xy 96.000928 -229.659332) (xy 96.037632 -229.694587) (xy 96.068205 -229.735273) (xy 96.091856 -229.780336)
			(xy 96.107972 -229.82861) (xy 96.116136 -229.878844) (xy 96.116648 -229.90429) (xy 96.116136 -229.929736)
			(xy 96.107972 -229.97997) (xy 96.091856 -230.028244) (xy 96.068205 -230.073307) (xy 96.037632 -230.113993)
			(xy 96.000928 -230.149248) (xy 95.959044 -230.178158) (xy 95.913065 -230.199975) (xy 95.864181 -230.214135)
			(xy 95.81366 -230.220269) (xy 95.762808 -230.21822) (xy 95.712944 -230.20804) (xy 95.665358 -230.189993)
			(xy 95.621284 -230.164547) (xy 95.581862 -230.13236) (xy 95.548114 -230.094266) (xy 95.520913 -230.051252)
			(xy 95.500965 -230.004432) (xy 95.488786 -229.955018) (xy 95.484691 -229.90429) (xy 95.179134 -229.90429)
			(xy 95.178644 -229.929279) (xy 95.170825 -229.978642) (xy 95.155381 -230.026174) (xy 95.132691 -230.070706)
			(xy 95.103315 -230.111139) (xy 95.067975 -230.146479) (xy 95.027542 -230.175855) (xy 94.98301 -230.198545)
			(xy 94.935478 -230.213989) (xy 94.886115 -230.221808) (xy 94.836137 -230.221808) (xy 94.786774 -230.213989)
			(xy 94.739242 -230.198545) (xy 94.69471 -230.175855) (xy 94.654277 -230.146479) (xy 94.618937 -230.111139)
			(xy 94.589561 -230.070706) (xy 94.566871 -230.026174) (xy 94.551427 -229.978642) (xy 94.543608 -229.929279)
			(xy 94.236291 -229.929279) (xy 94.236282 -229.929736) (xy 94.228118 -229.97997) (xy 94.212002 -230.028244)
			(xy 94.188351 -230.073307) (xy 94.157778 -230.113993) (xy 94.121074 -230.149248) (xy 94.07919 -230.178158)
			(xy 94.033211 -230.199975) (xy 93.984327 -230.214135) (xy 93.933806 -230.220269) (xy 93.882954 -230.21822)
			(xy 93.83309 -230.20804) (xy 93.785504 -230.189993) (xy 93.74143 -230.164547) (xy 93.702008 -230.13236)
			(xy 93.66826 -230.094266) (xy 93.641059 -230.051252) (xy 93.621111 -230.004432) (xy 93.608932 -229.955018)
			(xy 93.604837 -229.90429) (xy 92.356686 -229.90429) (xy 92.356174 -229.929736) (xy 92.34801 -229.97997)
			(xy 92.331894 -230.028244) (xy 92.308243 -230.073307) (xy 92.27767 -230.113993) (xy 92.240966 -230.149248)
			(xy 92.199082 -230.178158) (xy 92.153103 -230.199975) (xy 92.104219 -230.214135) (xy 92.053698 -230.220269)
			(xy 92.002846 -230.21822) (xy 91.952982 -230.20804) (xy 91.905396 -230.189993) (xy 91.861322 -230.164547)
			(xy 91.8219 -230.13236) (xy 91.788152 -230.094266) (xy 91.760951 -230.051252) (xy 91.741003 -230.004432)
			(xy 91.728824 -229.955018) (xy 91.724729 -229.90429) (xy 91.416632 -229.90429) (xy 91.41612 -229.929736)
			(xy 91.407956 -229.97997) (xy 91.39184 -230.028244) (xy 91.368189 -230.073307) (xy 91.337616 -230.113993)
			(xy 91.300912 -230.149248) (xy 91.259028 -230.178158) (xy 91.213049 -230.199975) (xy 91.164165 -230.214135)
			(xy 91.113644 -230.220269) (xy 91.062792 -230.21822) (xy 91.012928 -230.20804) (xy 90.965342 -230.189993)
			(xy 90.921268 -230.164547) (xy 90.881846 -230.13236) (xy 90.848098 -230.094266) (xy 90.820897 -230.051252)
			(xy 90.800949 -230.004432) (xy 90.78877 -229.955018) (xy 90.784675 -229.90429) (xy 90.479118 -229.90429)
			(xy 90.478628 -229.929279) (xy 90.470809 -229.978642) (xy 90.455365 -230.026174) (xy 90.432675 -230.070706)
			(xy 90.403299 -230.111139) (xy 90.367959 -230.146479) (xy 90.327526 -230.175855) (xy 90.282994 -230.198545)
			(xy 90.235462 -230.213989) (xy 90.186099 -230.221808) (xy 90.136121 -230.221808) (xy 90.086758 -230.213989)
			(xy 90.039226 -230.198545) (xy 89.994694 -230.175855) (xy 89.954261 -230.146479) (xy 89.918921 -230.111139)
			(xy 89.889545 -230.070706) (xy 89.866855 -230.026174) (xy 89.851411 -229.978642) (xy 89.843592 -229.929279)
			(xy 89.536275 -229.929279) (xy 89.536266 -229.929736) (xy 89.528102 -229.97997) (xy 89.511986 -230.028244)
			(xy 89.488335 -230.073307) (xy 89.457762 -230.113993) (xy 89.421058 -230.149248) (xy 89.379174 -230.178158)
			(xy 89.333195 -230.199975) (xy 89.284311 -230.214135) (xy 89.23379 -230.220269) (xy 89.182938 -230.21822)
			(xy 89.133074 -230.20804) (xy 89.085488 -230.189993) (xy 89.041414 -230.164547) (xy 89.001992 -230.13236)
			(xy 88.968244 -230.094266) (xy 88.941043 -230.051252) (xy 88.921095 -230.004432) (xy 88.908916 -229.955018)
			(xy 88.904821 -229.90429) (xy 88.59901 -229.90429) (xy 88.59852 -229.929279) (xy 88.590701 -229.978642)
			(xy 88.575257 -230.026174) (xy 88.552567 -230.070706) (xy 88.523191 -230.111139) (xy 88.487851 -230.146479)
			(xy 88.447418 -230.175855) (xy 88.402886 -230.198545) (xy 88.355354 -230.213989) (xy 88.305991 -230.221808)
			(xy 88.256013 -230.221808) (xy 88.20665 -230.213989) (xy 88.159118 -230.198545) (xy 88.114586 -230.175855)
			(xy 88.074153 -230.146479) (xy 88.038813 -230.111139) (xy 88.009437 -230.070706) (xy 87.986747 -230.026174)
			(xy 87.971303 -229.978642) (xy 87.963484 -229.929279) (xy 87.656167 -229.929279) (xy 87.656158 -229.929736)
			(xy 87.647994 -229.97997) (xy 87.631878 -230.028244) (xy 87.608227 -230.073307) (xy 87.577654 -230.113993)
			(xy 87.54095 -230.149248) (xy 87.499066 -230.178158) (xy 87.453087 -230.199975) (xy 87.404203 -230.214135)
			(xy 87.353682 -230.220269) (xy 87.30283 -230.21822) (xy 87.252966 -230.20804) (xy 87.20538 -230.189993)
			(xy 87.161306 -230.164547) (xy 87.121884 -230.13236) (xy 87.088136 -230.094266) (xy 87.060935 -230.051252)
			(xy 87.040987 -230.004432) (xy 87.028808 -229.955018) (xy 87.024713 -229.90429) (xy 85.776816 -229.90429)
			(xy 85.776304 -229.929736) (xy 85.76814 -229.97997) (xy 85.752024 -230.028244) (xy 85.728373 -230.073307)
			(xy 85.6978 -230.113993) (xy 85.661096 -230.149248) (xy 85.619212 -230.178158) (xy 85.573233 -230.199975)
			(xy 85.524349 -230.214135) (xy 85.473828 -230.220269) (xy 85.422976 -230.21822) (xy 85.373112 -230.20804)
			(xy 85.325526 -230.189993) (xy 85.281452 -230.164547) (xy 85.24203 -230.13236) (xy 85.208282 -230.094266)
			(xy 85.181081 -230.051252) (xy 85.161133 -230.004432) (xy 85.148954 -229.955018) (xy 85.144859 -229.90429)
			(xy 84.836762 -229.90429) (xy 84.83625 -229.929736) (xy 84.828086 -229.97997) (xy 84.81197 -230.028244)
			(xy 84.788319 -230.073307) (xy 84.757746 -230.113993) (xy 84.721042 -230.149248) (xy 84.679158 -230.178158)
			(xy 84.633179 -230.199975) (xy 84.584295 -230.214135) (xy 84.533774 -230.220269) (xy 84.482922 -230.21822)
			(xy 84.433058 -230.20804) (xy 84.385472 -230.189993) (xy 84.341398 -230.164547) (xy 84.301976 -230.13236)
			(xy 84.268228 -230.094266) (xy 84.241027 -230.051252) (xy 84.221079 -230.004432) (xy 84.2089 -229.955018)
			(xy 84.204805 -229.90429) (xy 83.898994 -229.90429) (xy 83.898504 -229.929279) (xy 83.890685 -229.978642)
			(xy 83.875241 -230.026174) (xy 83.852551 -230.070706) (xy 83.823175 -230.111139) (xy 83.787835 -230.146479)
			(xy 83.747402 -230.175855) (xy 83.70287 -230.198545) (xy 83.655338 -230.213989) (xy 83.605975 -230.221808)
			(xy 83.555997 -230.221808) (xy 83.506634 -230.213989) (xy 83.459102 -230.198545) (xy 83.41457 -230.175855)
			(xy 83.374137 -230.146479) (xy 83.338797 -230.111139) (xy 83.309421 -230.070706) (xy 83.286731 -230.026174)
			(xy 83.271287 -229.978642) (xy 83.263468 -229.929279) (xy 82.956151 -229.929279) (xy 82.956142 -229.929736)
			(xy 82.947978 -229.97997) (xy 82.931862 -230.028244) (xy 82.908211 -230.073307) (xy 82.877638 -230.113993)
			(xy 82.840934 -230.149248) (xy 82.79905 -230.178158) (xy 82.753071 -230.199975) (xy 82.704187 -230.214135)
			(xy 82.653666 -230.220269) (xy 82.602814 -230.21822) (xy 82.55295 -230.20804) (xy 82.505364 -230.189993)
			(xy 82.46129 -230.164547) (xy 82.421868 -230.13236) (xy 82.38812 -230.094266) (xy 82.360919 -230.051252)
			(xy 82.340971 -230.004432) (xy 82.328792 -229.955018) (xy 82.324697 -229.90429) (xy 82.01914 -229.90429)
			(xy 82.01865 -229.929279) (xy 82.010831 -229.978642) (xy 81.995387 -230.026174) (xy 81.972697 -230.070706)
			(xy 81.943321 -230.111139) (xy 81.907981 -230.146479) (xy 81.867548 -230.175855) (xy 81.823016 -230.198545)
			(xy 81.775484 -230.213989) (xy 81.726121 -230.221808) (xy 81.676143 -230.221808) (xy 81.62678 -230.213989)
			(xy 81.579248 -230.198545) (xy 81.534716 -230.175855) (xy 81.494283 -230.146479) (xy 81.458943 -230.111139)
			(xy 81.429567 -230.070706) (xy 81.406877 -230.026174) (xy 81.391433 -229.978642) (xy 81.383614 -229.929279)
			(xy 81.076297 -229.929279) (xy 81.076288 -229.929736) (xy 81.068124 -229.97997) (xy 81.052008 -230.028244)
			(xy 81.028357 -230.073307) (xy 80.997784 -230.113993) (xy 80.96108 -230.149248) (xy 80.919196 -230.178158)
			(xy 80.873217 -230.199975) (xy 80.824333 -230.214135) (xy 80.773812 -230.220269) (xy 80.72296 -230.21822)
			(xy 80.673096 -230.20804) (xy 80.62551 -230.189993) (xy 80.581436 -230.164547) (xy 80.542014 -230.13236)
			(xy 80.508266 -230.094266) (xy 80.481065 -230.051252) (xy 80.461117 -230.004432) (xy 80.448938 -229.955018)
			(xy 80.444843 -229.90429) (xy 79.53248 -229.90429) (xy 79.53248 -230.739539) (xy 79.97366 -230.739539)
			(xy 79.97366 -230.689561) (xy 79.981479 -230.640198) (xy 79.996923 -230.592666) (xy 80.019613 -230.548134)
			(xy 80.048989 -230.507701) (xy 80.084329 -230.472361) (xy 80.124762 -230.442985) (xy 80.169294 -230.420295)
			(xy 80.216826 -230.404851) (xy 80.266189 -230.397032) (xy 80.316167 -230.397032) (xy 80.36553 -230.404851)
			(xy 80.413062 -230.420295) (xy 80.457594 -230.442985) (xy 80.498027 -230.472361) (xy 80.533367 -230.507701)
			(xy 80.562743 -230.548134) (xy 80.585433 -230.592666) (xy 80.600877 -230.640198) (xy 80.608696 -230.689561)
			(xy 80.609186 -230.71455) (xy 80.914743 -230.71455) (xy 80.918838 -230.663822) (xy 80.931017 -230.614408)
			(xy 80.950965 -230.567588) (xy 80.978166 -230.524574) (xy 81.011914 -230.48648) (xy 81.051336 -230.454293)
			(xy 81.09541 -230.428847) (xy 81.142996 -230.4108) (xy 81.19286 -230.40062) (xy 81.243712 -230.398571)
			(xy 81.294233 -230.404705) (xy 81.343117 -230.418865) (xy 81.389096 -230.440682) (xy 81.43098 -230.469592)
			(xy 81.467684 -230.504847) (xy 81.498257 -230.545533) (xy 81.521908 -230.590596) (xy 81.538024 -230.63887)
			(xy 81.546188 -230.689104) (xy 81.5467 -230.71455) (xy 81.854797 -230.71455) (xy 81.858892 -230.663822)
			(xy 81.871071 -230.614408) (xy 81.891019 -230.567588) (xy 81.91822 -230.524574) (xy 81.951968 -230.48648)
			(xy 81.99139 -230.454293) (xy 82.035464 -230.428847) (xy 82.08305 -230.4108) (xy 82.132914 -230.40062)
			(xy 82.183766 -230.398571) (xy 82.234287 -230.404705) (xy 82.283171 -230.418865) (xy 82.32915 -230.440682)
			(xy 82.371034 -230.469592) (xy 82.407738 -230.504847) (xy 82.438311 -230.545533) (xy 82.461962 -230.590596)
			(xy 82.478078 -230.63887) (xy 82.486242 -230.689104) (xy 82.486754 -230.71455) (xy 82.486251 -230.739539)
			(xy 82.793568 -230.739539) (xy 82.793568 -230.689561) (xy 82.801387 -230.640198) (xy 82.816831 -230.592666)
			(xy 82.839521 -230.548134) (xy 82.868897 -230.507701) (xy 82.904237 -230.472361) (xy 82.94467 -230.442985)
			(xy 82.989202 -230.420295) (xy 83.036734 -230.404851) (xy 83.086097 -230.397032) (xy 83.136075 -230.397032)
			(xy 83.185438 -230.404851) (xy 83.23297 -230.420295) (xy 83.277502 -230.442985) (xy 83.317935 -230.472361)
			(xy 83.353275 -230.507701) (xy 83.382651 -230.548134) (xy 83.405341 -230.592666) (xy 83.420785 -230.640198)
			(xy 83.428604 -230.689561) (xy 83.429094 -230.71455) (xy 83.734905 -230.71455) (xy 83.739 -230.663822)
			(xy 83.751179 -230.614408) (xy 83.771127 -230.567588) (xy 83.798328 -230.524574) (xy 83.832076 -230.48648)
			(xy 83.871498 -230.454293) (xy 83.915572 -230.428847) (xy 83.963158 -230.4108) (xy 84.013022 -230.40062)
			(xy 84.063874 -230.398571) (xy 84.114395 -230.404705) (xy 84.163279 -230.418865) (xy 84.209258 -230.440682)
			(xy 84.251142 -230.469592) (xy 84.287846 -230.504847) (xy 84.318419 -230.545533) (xy 84.34207 -230.590596)
			(xy 84.358186 -230.63887) (xy 84.36635 -230.689104) (xy 84.366862 -230.71455) (xy 84.366364 -230.739285)
			(xy 84.673422 -230.739285) (xy 84.673422 -230.689307) (xy 84.681241 -230.639944) (xy 84.696685 -230.592412)
			(xy 84.719375 -230.54788) (xy 84.748751 -230.507447) (xy 84.784091 -230.472107) (xy 84.824524 -230.442731)
			(xy 84.869056 -230.420041) (xy 84.916588 -230.404597) (xy 84.965951 -230.396778) (xy 85.015929 -230.396778)
			(xy 85.065292 -230.404597) (xy 85.112824 -230.420041) (xy 85.157356 -230.442731) (xy 85.197789 -230.472107)
			(xy 85.233129 -230.507447) (xy 85.262505 -230.54788) (xy 85.285195 -230.592412) (xy 85.300639 -230.639944)
			(xy 85.308458 -230.689307) (xy 85.308948 -230.714296) (xy 85.308943 -230.71455) (xy 85.614759 -230.71455)
			(xy 85.618854 -230.663822) (xy 85.631033 -230.614408) (xy 85.650981 -230.567588) (xy 85.678182 -230.524574)
			(xy 85.71193 -230.48648) (xy 85.751352 -230.454293) (xy 85.795426 -230.428847) (xy 85.843012 -230.4108)
			(xy 85.892876 -230.40062) (xy 85.943728 -230.398571) (xy 85.994249 -230.404705) (xy 86.043133 -230.418865)
			(xy 86.089112 -230.440682) (xy 86.130996 -230.469592) (xy 86.1677 -230.504847) (xy 86.198273 -230.545533)
			(xy 86.221924 -230.590596) (xy 86.23804 -230.63887) (xy 86.246204 -230.689104) (xy 86.246716 -230.71455)
			(xy 86.246213 -230.739539) (xy 86.55353 -230.739539) (xy 86.55353 -230.689561) (xy 86.561349 -230.640198)
			(xy 86.576793 -230.592666) (xy 86.599483 -230.548134) (xy 86.628859 -230.507701) (xy 86.664199 -230.472361)
			(xy 86.704632 -230.442985) (xy 86.749164 -230.420295) (xy 86.796696 -230.404851) (xy 86.846059 -230.397032)
			(xy 86.896037 -230.397032) (xy 86.9454 -230.404851) (xy 86.992932 -230.420295) (xy 87.037464 -230.442985)
			(xy 87.077897 -230.472361) (xy 87.113237 -230.507701) (xy 87.142613 -230.548134) (xy 87.165303 -230.592666)
			(xy 87.180747 -230.640198) (xy 87.188566 -230.689561) (xy 87.189056 -230.71455) (xy 87.494867 -230.71455)
			(xy 87.498962 -230.663822) (xy 87.511141 -230.614408) (xy 87.531089 -230.567588) (xy 87.55829 -230.524574)
			(xy 87.592038 -230.48648) (xy 87.63146 -230.454293) (xy 87.675534 -230.428847) (xy 87.72312 -230.4108)
			(xy 87.772984 -230.40062) (xy 87.823836 -230.398571) (xy 87.874357 -230.404705) (xy 87.923241 -230.418865)
			(xy 87.96922 -230.440682) (xy 88.011104 -230.469592) (xy 88.047808 -230.504847) (xy 88.078381 -230.545533)
			(xy 88.102032 -230.590596) (xy 88.118148 -230.63887) (xy 88.126312 -230.689104) (xy 88.126824 -230.71455)
			(xy 88.434921 -230.71455) (xy 88.439016 -230.663822) (xy 88.451195 -230.614408) (xy 88.471143 -230.567588)
			(xy 88.498344 -230.524574) (xy 88.532092 -230.48648) (xy 88.571514 -230.454293) (xy 88.615588 -230.428847)
			(xy 88.663174 -230.4108) (xy 88.713038 -230.40062) (xy 88.76389 -230.398571) (xy 88.814411 -230.404705)
			(xy 88.863295 -230.418865) (xy 88.909274 -230.440682) (xy 88.951158 -230.469592) (xy 88.987862 -230.504847)
			(xy 89.018435 -230.545533) (xy 89.042086 -230.590596) (xy 89.058202 -230.63887) (xy 89.066366 -230.689104)
			(xy 89.066878 -230.71455) (xy 89.06638 -230.739285) (xy 89.373438 -230.739285) (xy 89.373438 -230.689307)
			(xy 89.381257 -230.639944) (xy 89.396701 -230.592412) (xy 89.419391 -230.54788) (xy 89.448767 -230.507447)
			(xy 89.484107 -230.472107) (xy 89.52454 -230.442731) (xy 89.569072 -230.420041) (xy 89.616604 -230.404597)
			(xy 89.665967 -230.396778) (xy 89.715945 -230.396778) (xy 89.765308 -230.404597) (xy 89.81284 -230.420041)
			(xy 89.857372 -230.442731) (xy 89.897805 -230.472107) (xy 89.933145 -230.507447) (xy 89.962521 -230.54788)
			(xy 89.985211 -230.592412) (xy 90.000655 -230.639944) (xy 90.008474 -230.689307) (xy 90.008964 -230.714296)
			(xy 90.008959 -230.71455) (xy 90.314775 -230.71455) (xy 90.31887 -230.663822) (xy 90.331049 -230.614408)
			(xy 90.350997 -230.567588) (xy 90.378198 -230.524574) (xy 90.411946 -230.48648) (xy 90.451368 -230.454293)
			(xy 90.495442 -230.428847) (xy 90.543028 -230.4108) (xy 90.592892 -230.40062) (xy 90.643744 -230.398571)
			(xy 90.694265 -230.404705) (xy 90.743149 -230.418865) (xy 90.789128 -230.440682) (xy 90.831012 -230.469592)
			(xy 90.867716 -230.504847) (xy 90.898289 -230.545533) (xy 90.92194 -230.590596) (xy 90.938056 -230.63887)
			(xy 90.94622 -230.689104) (xy 90.946732 -230.71455) (xy 90.946229 -230.739539) (xy 91.253546 -230.739539)
			(xy 91.253546 -230.689561) (xy 91.261365 -230.640198) (xy 91.276809 -230.592666) (xy 91.299499 -230.548134)
			(xy 91.328875 -230.507701) (xy 91.364215 -230.472361) (xy 91.404648 -230.442985) (xy 91.44918 -230.420295)
			(xy 91.496712 -230.404851) (xy 91.546075 -230.397032) (xy 91.596053 -230.397032) (xy 91.645416 -230.404851)
			(xy 91.692948 -230.420295) (xy 91.73748 -230.442985) (xy 91.777913 -230.472361) (xy 91.813253 -230.507701)
			(xy 91.842629 -230.548134) (xy 91.865319 -230.592666) (xy 91.880763 -230.640198) (xy 91.888582 -230.689561)
			(xy 91.889072 -230.71455) (xy 92.194883 -230.71455) (xy 92.198978 -230.663822) (xy 92.211157 -230.614408)
			(xy 92.231105 -230.567588) (xy 92.258306 -230.524574) (xy 92.292054 -230.48648) (xy 92.331476 -230.454293)
			(xy 92.37555 -230.428847) (xy 92.423136 -230.4108) (xy 92.473 -230.40062) (xy 92.523852 -230.398571)
			(xy 92.574373 -230.404705) (xy 92.623257 -230.418865) (xy 92.669236 -230.440682) (xy 92.71112 -230.469592)
			(xy 92.747824 -230.504847) (xy 92.778397 -230.545533) (xy 92.802048 -230.590596) (xy 92.818164 -230.63887)
			(xy 92.826328 -230.689104) (xy 92.82684 -230.71455) (xy 92.826342 -230.739285) (xy 93.1334 -230.739285)
			(xy 93.1334 -230.689307) (xy 93.141219 -230.639944) (xy 93.156663 -230.592412) (xy 93.179353 -230.54788)
			(xy 93.208729 -230.507447) (xy 93.244069 -230.472107) (xy 93.284502 -230.442731) (xy 93.329034 -230.420041)
			(xy 93.376566 -230.404597) (xy 93.425929 -230.396778) (xy 93.475907 -230.396778) (xy 93.52527 -230.404597)
			(xy 93.572802 -230.420041) (xy 93.617334 -230.442731) (xy 93.657767 -230.472107) (xy 93.693107 -230.507447)
			(xy 93.722483 -230.54788) (xy 93.745173 -230.592412) (xy 93.760617 -230.639944) (xy 93.768436 -230.689307)
			(xy 93.768926 -230.714296) (xy 93.768921 -230.71455) (xy 94.074737 -230.71455) (xy 94.078832 -230.663822)
			(xy 94.091011 -230.614408) (xy 94.110959 -230.567588) (xy 94.13816 -230.524574) (xy 94.171908 -230.48648)
			(xy 94.21133 -230.454293) (xy 94.255404 -230.428847) (xy 94.30299 -230.4108) (xy 94.352854 -230.40062)
			(xy 94.403706 -230.398571) (xy 94.454227 -230.404705) (xy 94.503111 -230.418865) (xy 94.54909 -230.440682)
			(xy 94.590974 -230.469592) (xy 94.627678 -230.504847) (xy 94.658251 -230.545533) (xy 94.681902 -230.590596)
			(xy 94.698018 -230.63887) (xy 94.706182 -230.689104) (xy 94.706694 -230.71455) (xy 95.014791 -230.71455)
			(xy 95.018886 -230.663822) (xy 95.031065 -230.614408) (xy 95.051013 -230.567588) (xy 95.078214 -230.524574)
			(xy 95.111962 -230.48648) (xy 95.151384 -230.454293) (xy 95.195458 -230.428847) (xy 95.243044 -230.4108)
			(xy 95.292908 -230.40062) (xy 95.34376 -230.398571) (xy 95.394281 -230.404705) (xy 95.443165 -230.418865)
			(xy 95.489144 -230.440682) (xy 95.531028 -230.469592) (xy 95.567732 -230.504847) (xy 95.598305 -230.545533)
			(xy 95.621956 -230.590596) (xy 95.638072 -230.63887) (xy 95.646236 -230.689104) (xy 95.646748 -230.71455)
			(xy 95.646245 -230.739539) (xy 95.953562 -230.739539) (xy 95.953562 -230.689561) (xy 95.961381 -230.640198)
			(xy 95.976825 -230.592666) (xy 95.999515 -230.548134) (xy 96.028891 -230.507701) (xy 96.064231 -230.472361)
			(xy 96.104664 -230.442985) (xy 96.149196 -230.420295) (xy 96.196728 -230.404851) (xy 96.246091 -230.397032)
			(xy 96.296069 -230.397032) (xy 96.345432 -230.404851) (xy 96.392964 -230.420295) (xy 96.437496 -230.442985)
			(xy 96.477929 -230.472361) (xy 96.513269 -230.507701) (xy 96.542645 -230.548134) (xy 96.565335 -230.592666)
			(xy 96.580779 -230.640198) (xy 96.588598 -230.689561) (xy 96.589088 -230.71455) (xy 96.588598 -230.739539)
			(xy 96.580779 -230.788902) (xy 96.565335 -230.836434) (xy 96.542645 -230.880966) (xy 96.513269 -230.921399)
			(xy 96.477929 -230.956739) (xy 96.437496 -230.986115) (xy 96.392964 -231.008805) (xy 96.345432 -231.024249)
			(xy 96.296069 -231.032068) (xy 96.246091 -231.032068) (xy 96.196728 -231.024249) (xy 96.149196 -231.008805)
			(xy 96.104664 -230.986115) (xy 96.064231 -230.956739) (xy 96.028891 -230.921399) (xy 95.999515 -230.880966)
			(xy 95.976825 -230.836434) (xy 95.961381 -230.788902) (xy 95.953562 -230.739539) (xy 95.646245 -230.739539)
			(xy 95.646236 -230.739996) (xy 95.638072 -230.79023) (xy 95.621956 -230.838504) (xy 95.598305 -230.883567)
			(xy 95.567732 -230.924253) (xy 95.531028 -230.959508) (xy 95.489144 -230.988418) (xy 95.443165 -231.010235)
			(xy 95.394281 -231.024395) (xy 95.34376 -231.030529) (xy 95.292908 -231.02848) (xy 95.243044 -231.0183)
			(xy 95.195458 -231.000253) (xy 95.151384 -230.974807) (xy 95.111962 -230.94262) (xy 95.078214 -230.904526)
			(xy 95.051013 -230.861512) (xy 95.031065 -230.814692) (xy 95.018886 -230.765278) (xy 95.014791 -230.71455)
			(xy 94.706694 -230.71455) (xy 94.706182 -230.739996) (xy 94.698018 -230.79023) (xy 94.681902 -230.838504)
			(xy 94.658251 -230.883567) (xy 94.627678 -230.924253) (xy 94.590974 -230.959508) (xy 94.54909 -230.988418)
			(xy 94.503111 -231.010235) (xy 94.454227 -231.024395) (xy 94.403706 -231.030529) (xy 94.352854 -231.02848)
			(xy 94.30299 -231.0183) (xy 94.255404 -231.000253) (xy 94.21133 -230.974807) (xy 94.171908 -230.94262)
			(xy 94.13816 -230.904526) (xy 94.110959 -230.861512) (xy 94.091011 -230.814692) (xy 94.078832 -230.765278)
			(xy 94.074737 -230.71455) (xy 93.768921 -230.71455) (xy 93.768436 -230.739285) (xy 93.760617 -230.788648)
			(xy 93.745173 -230.83618) (xy 93.722483 -230.880712) (xy 93.693107 -230.921145) (xy 93.657767 -230.956485)
			(xy 93.617334 -230.985861) (xy 93.572802 -231.008551) (xy 93.52527 -231.023995) (xy 93.475907 -231.031814)
			(xy 93.425929 -231.031814) (xy 93.376566 -231.023995) (xy 93.329034 -231.008551) (xy 93.284502 -230.985861)
			(xy 93.244069 -230.956485) (xy 93.208729 -230.921145) (xy 93.179353 -230.880712) (xy 93.156663 -230.83618)
			(xy 93.141219 -230.788648) (xy 93.1334 -230.739285) (xy 92.826342 -230.739285) (xy 92.826328 -230.739996)
			(xy 92.818164 -230.79023) (xy 92.802048 -230.838504) (xy 92.778397 -230.883567) (xy 92.747824 -230.924253)
			(xy 92.71112 -230.959508) (xy 92.669236 -230.988418) (xy 92.623257 -231.010235) (xy 92.574373 -231.024395)
			(xy 92.523852 -231.030529) (xy 92.473 -231.02848) (xy 92.423136 -231.0183) (xy 92.37555 -231.000253)
			(xy 92.331476 -230.974807) (xy 92.292054 -230.94262) (xy 92.258306 -230.904526) (xy 92.231105 -230.861512)
			(xy 92.211157 -230.814692) (xy 92.198978 -230.765278) (xy 92.194883 -230.71455) (xy 91.889072 -230.71455)
			(xy 91.888582 -230.739539) (xy 91.880763 -230.788902) (xy 91.865319 -230.836434) (xy 91.842629 -230.880966)
			(xy 91.813253 -230.921399) (xy 91.777913 -230.956739) (xy 91.73748 -230.986115) (xy 91.692948 -231.008805)
			(xy 91.645416 -231.024249) (xy 91.596053 -231.032068) (xy 91.546075 -231.032068) (xy 91.496712 -231.024249)
			(xy 91.44918 -231.008805) (xy 91.404648 -230.986115) (xy 91.364215 -230.956739) (xy 91.328875 -230.921399)
			(xy 91.299499 -230.880966) (xy 91.276809 -230.836434) (xy 91.261365 -230.788902) (xy 91.253546 -230.739539)
			(xy 90.946229 -230.739539) (xy 90.94622 -230.739996) (xy 90.938056 -230.79023) (xy 90.92194 -230.838504)
			(xy 90.898289 -230.883567) (xy 90.867716 -230.924253) (xy 90.831012 -230.959508) (xy 90.789128 -230.988418)
			(xy 90.743149 -231.010235) (xy 90.694265 -231.024395) (xy 90.643744 -231.030529) (xy 90.592892 -231.02848)
			(xy 90.543028 -231.0183) (xy 90.495442 -231.000253) (xy 90.451368 -230.974807) (xy 90.411946 -230.94262)
			(xy 90.378198 -230.904526) (xy 90.350997 -230.861512) (xy 90.331049 -230.814692) (xy 90.31887 -230.765278)
			(xy 90.314775 -230.71455) (xy 90.008959 -230.71455) (xy 90.008474 -230.739285) (xy 90.000655 -230.788648)
			(xy 89.985211 -230.83618) (xy 89.962521 -230.880712) (xy 89.933145 -230.921145) (xy 89.897805 -230.956485)
			(xy 89.857372 -230.985861) (xy 89.81284 -231.008551) (xy 89.765308 -231.023995) (xy 89.715945 -231.031814)
			(xy 89.665967 -231.031814) (xy 89.616604 -231.023995) (xy 89.569072 -231.008551) (xy 89.52454 -230.985861)
			(xy 89.484107 -230.956485) (xy 89.448767 -230.921145) (xy 89.419391 -230.880712) (xy 89.396701 -230.83618)
			(xy 89.381257 -230.788648) (xy 89.373438 -230.739285) (xy 89.06638 -230.739285) (xy 89.066366 -230.739996)
			(xy 89.058202 -230.79023) (xy 89.042086 -230.838504) (xy 89.018435 -230.883567) (xy 88.987862 -230.924253)
			(xy 88.951158 -230.959508) (xy 88.909274 -230.988418) (xy 88.863295 -231.010235) (xy 88.814411 -231.024395)
			(xy 88.76389 -231.030529) (xy 88.713038 -231.02848) (xy 88.663174 -231.0183) (xy 88.615588 -231.000253)
			(xy 88.571514 -230.974807) (xy 88.532092 -230.94262) (xy 88.498344 -230.904526) (xy 88.471143 -230.861512)
			(xy 88.451195 -230.814692) (xy 88.439016 -230.765278) (xy 88.434921 -230.71455) (xy 88.126824 -230.71455)
			(xy 88.126312 -230.739996) (xy 88.118148 -230.79023) (xy 88.102032 -230.838504) (xy 88.078381 -230.883567)
			(xy 88.047808 -230.924253) (xy 88.011104 -230.959508) (xy 87.96922 -230.988418) (xy 87.923241 -231.010235)
			(xy 87.874357 -231.024395) (xy 87.823836 -231.030529) (xy 87.772984 -231.02848) (xy 87.72312 -231.0183)
			(xy 87.675534 -231.000253) (xy 87.63146 -230.974807) (xy 87.592038 -230.94262) (xy 87.55829 -230.904526)
			(xy 87.531089 -230.861512) (xy 87.511141 -230.814692) (xy 87.498962 -230.765278) (xy 87.494867 -230.71455)
			(xy 87.189056 -230.71455) (xy 87.188566 -230.739539) (xy 87.180747 -230.788902) (xy 87.165303 -230.836434)
			(xy 87.142613 -230.880966) (xy 87.113237 -230.921399) (xy 87.077897 -230.956739) (xy 87.037464 -230.986115)
			(xy 86.992932 -231.008805) (xy 86.9454 -231.024249) (xy 86.896037 -231.032068) (xy 86.846059 -231.032068)
			(xy 86.796696 -231.024249) (xy 86.749164 -231.008805) (xy 86.704632 -230.986115) (xy 86.664199 -230.956739)
			(xy 86.628859 -230.921399) (xy 86.599483 -230.880966) (xy 86.576793 -230.836434) (xy 86.561349 -230.788902)
			(xy 86.55353 -230.739539) (xy 86.246213 -230.739539) (xy 86.246204 -230.739996) (xy 86.23804 -230.79023)
			(xy 86.221924 -230.838504) (xy 86.198273 -230.883567) (xy 86.1677 -230.924253) (xy 86.130996 -230.959508)
			(xy 86.089112 -230.988418) (xy 86.043133 -231.010235) (xy 85.994249 -231.024395) (xy 85.943728 -231.030529)
			(xy 85.892876 -231.02848) (xy 85.843012 -231.0183) (xy 85.795426 -231.000253) (xy 85.751352 -230.974807)
			(xy 85.71193 -230.94262) (xy 85.678182 -230.904526) (xy 85.650981 -230.861512) (xy 85.631033 -230.814692)
			(xy 85.618854 -230.765278) (xy 85.614759 -230.71455) (xy 85.308943 -230.71455) (xy 85.308458 -230.739285)
			(xy 85.300639 -230.788648) (xy 85.285195 -230.83618) (xy 85.262505 -230.880712) (xy 85.233129 -230.921145)
			(xy 85.197789 -230.956485) (xy 85.157356 -230.985861) (xy 85.112824 -231.008551) (xy 85.065292 -231.023995)
			(xy 85.015929 -231.031814) (xy 84.965951 -231.031814) (xy 84.916588 -231.023995) (xy 84.869056 -231.008551)
			(xy 84.824524 -230.985861) (xy 84.784091 -230.956485) (xy 84.748751 -230.921145) (xy 84.719375 -230.880712)
			(xy 84.696685 -230.83618) (xy 84.681241 -230.788648) (xy 84.673422 -230.739285) (xy 84.366364 -230.739285)
			(xy 84.36635 -230.739996) (xy 84.358186 -230.79023) (xy 84.34207 -230.838504) (xy 84.318419 -230.883567)
			(xy 84.287846 -230.924253) (xy 84.251142 -230.959508) (xy 84.209258 -230.988418) (xy 84.163279 -231.010235)
			(xy 84.114395 -231.024395) (xy 84.063874 -231.030529) (xy 84.013022 -231.02848) (xy 83.963158 -231.0183)
			(xy 83.915572 -231.000253) (xy 83.871498 -230.974807) (xy 83.832076 -230.94262) (xy 83.798328 -230.904526)
			(xy 83.771127 -230.861512) (xy 83.751179 -230.814692) (xy 83.739 -230.765278) (xy 83.734905 -230.71455)
			(xy 83.429094 -230.71455) (xy 83.428604 -230.739539) (xy 83.420785 -230.788902) (xy 83.405341 -230.836434)
			(xy 83.382651 -230.880966) (xy 83.353275 -230.921399) (xy 83.317935 -230.956739) (xy 83.277502 -230.986115)
			(xy 83.23297 -231.008805) (xy 83.185438 -231.024249) (xy 83.136075 -231.032068) (xy 83.086097 -231.032068)
			(xy 83.036734 -231.024249) (xy 82.989202 -231.008805) (xy 82.94467 -230.986115) (xy 82.904237 -230.956739)
			(xy 82.868897 -230.921399) (xy 82.839521 -230.880966) (xy 82.816831 -230.836434) (xy 82.801387 -230.788902)
			(xy 82.793568 -230.739539) (xy 82.486251 -230.739539) (xy 82.486242 -230.739996) (xy 82.478078 -230.79023)
			(xy 82.461962 -230.838504) (xy 82.438311 -230.883567) (xy 82.407738 -230.924253) (xy 82.371034 -230.959508)
			(xy 82.32915 -230.988418) (xy 82.283171 -231.010235) (xy 82.234287 -231.024395) (xy 82.183766 -231.030529)
			(xy 82.132914 -231.02848) (xy 82.08305 -231.0183) (xy 82.035464 -231.000253) (xy 81.99139 -230.974807)
			(xy 81.951968 -230.94262) (xy 81.91822 -230.904526) (xy 81.891019 -230.861512) (xy 81.871071 -230.814692)
			(xy 81.858892 -230.765278) (xy 81.854797 -230.71455) (xy 81.5467 -230.71455) (xy 81.546188 -230.739996)
			(xy 81.538024 -230.79023) (xy 81.521908 -230.838504) (xy 81.498257 -230.883567) (xy 81.467684 -230.924253)
			(xy 81.43098 -230.959508) (xy 81.389096 -230.988418) (xy 81.343117 -231.010235) (xy 81.294233 -231.024395)
			(xy 81.243712 -231.030529) (xy 81.19286 -231.02848) (xy 81.142996 -231.0183) (xy 81.09541 -231.000253)
			(xy 81.051336 -230.974807) (xy 81.011914 -230.94262) (xy 80.978166 -230.904526) (xy 80.950965 -230.861512)
			(xy 80.931017 -230.814692) (xy 80.918838 -230.765278) (xy 80.914743 -230.71455) (xy 80.609186 -230.71455)
			(xy 80.608696 -230.739539) (xy 80.600877 -230.788902) (xy 80.585433 -230.836434) (xy 80.562743 -230.880966)
			(xy 80.533367 -230.921399) (xy 80.498027 -230.956739) (xy 80.457594 -230.986115) (xy 80.413062 -231.008805)
			(xy 80.36553 -231.024249) (xy 80.316167 -231.032068) (xy 80.266189 -231.032068) (xy 80.216826 -231.024249)
			(xy 80.169294 -231.008805) (xy 80.124762 -230.986115) (xy 80.084329 -230.956739) (xy 80.048989 -230.921399)
			(xy 80.019613 -230.880966) (xy 79.996923 -230.836434) (xy 79.981479 -230.788902) (xy 79.97366 -230.739539)
			(xy 79.53248 -230.739539) (xy 79.53248 -231.148382) (xy 79.532979 -231.163157) (xy 79.541436 -231.19147)
			(xy 79.557648 -231.216175) (xy 79.580255 -231.235202) (xy 79.607366 -231.246958) (xy 79.636707 -231.250458)
			(xy 79.665821 -231.245408) (xy 79.679292 -231.239314) (xy 79.701428 -231.22882) (xy 79.74812 -231.214001)
			(xy 79.79653 -231.206505) (xy 79.821024 -231.20604) (xy 79.846032 -231.206532) (xy 79.895431 -231.21436)
			(xy 79.942998 -231.229818) (xy 79.987561 -231.252527) (xy 80.028023 -231.281928) (xy 80.063388 -231.317295)
			(xy 80.092785 -231.35776) (xy 80.115491 -231.402324) (xy 80.130946 -231.449892) (xy 80.138769 -231.499292)
			(xy 80.138769 -231.524302) (xy 80.444843 -231.524302) (xy 80.448938 -231.473574) (xy 80.461117 -231.42416)
			(xy 80.481065 -231.37734) (xy 80.508266 -231.334326) (xy 80.542014 -231.296232) (xy 80.581436 -231.264045)
			(xy 80.62551 -231.238599) (xy 80.673096 -231.220552) (xy 80.72296 -231.210372) (xy 80.773812 -231.208323)
			(xy 80.824333 -231.214457) (xy 80.873217 -231.228617) (xy 80.919196 -231.250434) (xy 80.96108 -231.279344)
			(xy 80.997784 -231.314599) (xy 81.028357 -231.355285) (xy 81.052008 -231.400348) (xy 81.068124 -231.448622)
			(xy 81.076288 -231.498856) (xy 81.0768 -231.524302) (xy 81.076297 -231.549291) (xy 81.383614 -231.549291)
			(xy 81.383614 -231.499313) (xy 81.391433 -231.44995) (xy 81.406877 -231.402418) (xy 81.429567 -231.357886)
			(xy 81.458943 -231.317453) (xy 81.494283 -231.282113) (xy 81.534716 -231.252737) (xy 81.579248 -231.230047)
			(xy 81.62678 -231.214603) (xy 81.676143 -231.206784) (xy 81.726121 -231.206784) (xy 81.775484 -231.214603)
			(xy 81.823016 -231.230047) (xy 81.867548 -231.252737) (xy 81.907981 -231.282113) (xy 81.943321 -231.317453)
			(xy 81.972697 -231.357886) (xy 81.995387 -231.402418) (xy 82.010831 -231.44995) (xy 82.01865 -231.499313)
			(xy 82.01914 -231.524302) (xy 82.324697 -231.524302) (xy 82.328792 -231.473574) (xy 82.340971 -231.42416)
			(xy 82.360919 -231.37734) (xy 82.38812 -231.334326) (xy 82.421868 -231.296232) (xy 82.46129 -231.264045)
			(xy 82.505364 -231.238599) (xy 82.55295 -231.220552) (xy 82.602814 -231.210372) (xy 82.653666 -231.208323)
			(xy 82.704187 -231.214457) (xy 82.753071 -231.228617) (xy 82.79905 -231.250434) (xy 82.840934 -231.279344)
			(xy 82.877638 -231.314599) (xy 82.908211 -231.355285) (xy 82.931862 -231.400348) (xy 82.947978 -231.448622)
			(xy 82.956142 -231.498856) (xy 82.956654 -231.524302) (xy 82.956151 -231.549291) (xy 83.263468 -231.549291)
			(xy 83.263468 -231.499313) (xy 83.271287 -231.44995) (xy 83.286731 -231.402418) (xy 83.309421 -231.357886)
			(xy 83.338797 -231.317453) (xy 83.374137 -231.282113) (xy 83.41457 -231.252737) (xy 83.459102 -231.230047)
			(xy 83.506634 -231.214603) (xy 83.555997 -231.206784) (xy 83.605975 -231.206784) (xy 83.655338 -231.214603)
			(xy 83.70287 -231.230047) (xy 83.747402 -231.252737) (xy 83.787835 -231.282113) (xy 83.823175 -231.317453)
			(xy 83.852551 -231.357886) (xy 83.875241 -231.402418) (xy 83.890685 -231.44995) (xy 83.898504 -231.499313)
			(xy 83.898994 -231.524302) (xy 84.204805 -231.524302) (xy 84.2089 -231.473574) (xy 84.221079 -231.42416)
			(xy 84.241027 -231.37734) (xy 84.268228 -231.334326) (xy 84.301976 -231.296232) (xy 84.341398 -231.264045)
			(xy 84.385472 -231.238599) (xy 84.433058 -231.220552) (xy 84.482922 -231.210372) (xy 84.533774 -231.208323)
			(xy 84.584295 -231.214457) (xy 84.633179 -231.228617) (xy 84.679158 -231.250434) (xy 84.721042 -231.279344)
			(xy 84.757746 -231.314599) (xy 84.788319 -231.355285) (xy 84.81197 -231.400348) (xy 84.828086 -231.448622)
			(xy 84.83625 -231.498856) (xy 84.836762 -231.524302) (xy 85.144859 -231.524302) (xy 85.148954 -231.473574)
			(xy 85.161133 -231.42416) (xy 85.181081 -231.37734) (xy 85.208282 -231.334326) (xy 85.24203 -231.296232)
			(xy 85.281452 -231.264045) (xy 85.325526 -231.238599) (xy 85.373112 -231.220552) (xy 85.422976 -231.210372)
			(xy 85.473828 -231.208323) (xy 85.524349 -231.214457) (xy 85.573233 -231.228617) (xy 85.619212 -231.250434)
			(xy 85.661096 -231.279344) (xy 85.6978 -231.314599) (xy 85.728373 -231.355285) (xy 85.752024 -231.400348)
			(xy 85.76814 -231.448622) (xy 85.776304 -231.498856) (xy 85.776816 -231.524302) (xy 85.776313 -231.549291)
			(xy 86.08363 -231.549291) (xy 86.08363 -231.499313) (xy 86.091449 -231.44995) (xy 86.106893 -231.402418)
			(xy 86.129583 -231.357886) (xy 86.158959 -231.317453) (xy 86.194299 -231.282113) (xy 86.234732 -231.252737)
			(xy 86.279264 -231.230047) (xy 86.326796 -231.214603) (xy 86.376159 -231.206784) (xy 86.426137 -231.206784)
			(xy 86.4755 -231.214603) (xy 86.523032 -231.230047) (xy 86.567564 -231.252737) (xy 86.607997 -231.282113)
			(xy 86.643337 -231.317453) (xy 86.672713 -231.357886) (xy 86.695403 -231.402418) (xy 86.710847 -231.44995)
			(xy 86.718666 -231.499313) (xy 86.719156 -231.524302) (xy 87.024713 -231.524302) (xy 87.028808 -231.473574)
			(xy 87.040987 -231.42416) (xy 87.060935 -231.37734) (xy 87.088136 -231.334326) (xy 87.121884 -231.296232)
			(xy 87.161306 -231.264045) (xy 87.20538 -231.238599) (xy 87.252966 -231.220552) (xy 87.30283 -231.210372)
			(xy 87.353682 -231.208323) (xy 87.404203 -231.214457) (xy 87.453087 -231.228617) (xy 87.499066 -231.250434)
			(xy 87.54095 -231.279344) (xy 87.577654 -231.314599) (xy 87.608227 -231.355285) (xy 87.631878 -231.400348)
			(xy 87.647994 -231.448622) (xy 87.656158 -231.498856) (xy 87.65667 -231.524302) (xy 87.656167 -231.549291)
			(xy 87.963484 -231.549291) (xy 87.963484 -231.499313) (xy 87.971303 -231.44995) (xy 87.986747 -231.402418)
			(xy 88.009437 -231.357886) (xy 88.038813 -231.317453) (xy 88.074153 -231.282113) (xy 88.114586 -231.252737)
			(xy 88.159118 -231.230047) (xy 88.20665 -231.214603) (xy 88.256013 -231.206784) (xy 88.305991 -231.206784)
			(xy 88.355354 -231.214603) (xy 88.402886 -231.230047) (xy 88.447418 -231.252737) (xy 88.487851 -231.282113)
			(xy 88.523191 -231.317453) (xy 88.552567 -231.357886) (xy 88.575257 -231.402418) (xy 88.590701 -231.44995)
			(xy 88.59852 -231.499313) (xy 88.59901 -231.524302) (xy 88.904821 -231.524302) (xy 88.908916 -231.473574)
			(xy 88.921095 -231.42416) (xy 88.941043 -231.37734) (xy 88.968244 -231.334326) (xy 89.001992 -231.296232)
			(xy 89.041414 -231.264045) (xy 89.085488 -231.238599) (xy 89.133074 -231.220552) (xy 89.182938 -231.210372)
			(xy 89.23379 -231.208323) (xy 89.284311 -231.214457) (xy 89.333195 -231.228617) (xy 89.379174 -231.250434)
			(xy 89.421058 -231.279344) (xy 89.457762 -231.314599) (xy 89.488335 -231.355285) (xy 89.511986 -231.400348)
			(xy 89.528102 -231.448622) (xy 89.536266 -231.498856) (xy 89.536778 -231.524302) (xy 89.536275 -231.549291)
			(xy 89.843592 -231.549291) (xy 89.843592 -231.499313) (xy 89.851411 -231.44995) (xy 89.866855 -231.402418)
			(xy 89.889545 -231.357886) (xy 89.918921 -231.317453) (xy 89.954261 -231.282113) (xy 89.994694 -231.252737)
			(xy 90.039226 -231.230047) (xy 90.086758 -231.214603) (xy 90.136121 -231.206784) (xy 90.186099 -231.206784)
			(xy 90.235462 -231.214603) (xy 90.282994 -231.230047) (xy 90.327526 -231.252737) (xy 90.367959 -231.282113)
			(xy 90.403299 -231.317453) (xy 90.432675 -231.357886) (xy 90.455365 -231.402418) (xy 90.470809 -231.44995)
			(xy 90.478628 -231.499313) (xy 90.479118 -231.524302) (xy 90.784675 -231.524302) (xy 90.78877 -231.473574)
			(xy 90.800949 -231.42416) (xy 90.820897 -231.37734) (xy 90.848098 -231.334326) (xy 90.881846 -231.296232)
			(xy 90.921268 -231.264045) (xy 90.965342 -231.238599) (xy 91.012928 -231.220552) (xy 91.062792 -231.210372)
			(xy 91.113644 -231.208323) (xy 91.164165 -231.214457) (xy 91.213049 -231.228617) (xy 91.259028 -231.250434)
			(xy 91.300912 -231.279344) (xy 91.337616 -231.314599) (xy 91.368189 -231.355285) (xy 91.39184 -231.400348)
			(xy 91.407956 -231.448622) (xy 91.41612 -231.498856) (xy 91.416632 -231.524302) (xy 91.724729 -231.524302)
			(xy 91.728824 -231.473574) (xy 91.741003 -231.42416) (xy 91.760951 -231.37734) (xy 91.788152 -231.334326)
			(xy 91.8219 -231.296232) (xy 91.861322 -231.264045) (xy 91.905396 -231.238599) (xy 91.952982 -231.220552)
			(xy 92.002846 -231.210372) (xy 92.053698 -231.208323) (xy 92.104219 -231.214457) (xy 92.153103 -231.228617)
			(xy 92.199082 -231.250434) (xy 92.240966 -231.279344) (xy 92.27767 -231.314599) (xy 92.308243 -231.355285)
			(xy 92.331894 -231.400348) (xy 92.34801 -231.448622) (xy 92.356174 -231.498856) (xy 92.356686 -231.524302)
			(xy 92.356183 -231.549291) (xy 92.6635 -231.549291) (xy 92.6635 -231.499313) (xy 92.671319 -231.44995)
			(xy 92.686763 -231.402418) (xy 92.709453 -231.357886) (xy 92.738829 -231.317453) (xy 92.774169 -231.282113)
			(xy 92.814602 -231.252737) (xy 92.859134 -231.230047) (xy 92.906666 -231.214603) (xy 92.956029 -231.206784)
			(xy 93.006007 -231.206784) (xy 93.05537 -231.214603) (xy 93.102902 -231.230047) (xy 93.147434 -231.252737)
			(xy 93.187867 -231.282113) (xy 93.223207 -231.317453) (xy 93.252583 -231.357886) (xy 93.275273 -231.402418)
			(xy 93.290717 -231.44995) (xy 93.298536 -231.499313) (xy 93.299026 -231.524302) (xy 93.604837 -231.524302)
			(xy 93.608932 -231.473574) (xy 93.621111 -231.42416) (xy 93.641059 -231.37734) (xy 93.66826 -231.334326)
			(xy 93.702008 -231.296232) (xy 93.74143 -231.264045) (xy 93.785504 -231.238599) (xy 93.83309 -231.220552)
			(xy 93.882954 -231.210372) (xy 93.933806 -231.208323) (xy 93.984327 -231.214457) (xy 94.033211 -231.228617)
			(xy 94.07919 -231.250434) (xy 94.121074 -231.279344) (xy 94.157778 -231.314599) (xy 94.188351 -231.355285)
			(xy 94.212002 -231.400348) (xy 94.228118 -231.448622) (xy 94.236282 -231.498856) (xy 94.236794 -231.524302)
			(xy 94.236291 -231.549291) (xy 94.543608 -231.549291) (xy 94.543608 -231.499313) (xy 94.551427 -231.44995)
			(xy 94.566871 -231.402418) (xy 94.589561 -231.357886) (xy 94.618937 -231.317453) (xy 94.654277 -231.282113)
			(xy 94.69471 -231.252737) (xy 94.739242 -231.230047) (xy 94.786774 -231.214603) (xy 94.836137 -231.206784)
			(xy 94.886115 -231.206784) (xy 94.935478 -231.214603) (xy 94.98301 -231.230047) (xy 95.027542 -231.252737)
			(xy 95.067975 -231.282113) (xy 95.103315 -231.317453) (xy 95.132691 -231.357886) (xy 95.155381 -231.402418)
			(xy 95.170825 -231.44995) (xy 95.178644 -231.499313) (xy 95.179134 -231.524302) (xy 95.484691 -231.524302)
			(xy 95.488786 -231.473574) (xy 95.500965 -231.42416) (xy 95.520913 -231.37734) (xy 95.548114 -231.334326)
			(xy 95.581862 -231.296232) (xy 95.621284 -231.264045) (xy 95.665358 -231.238599) (xy 95.712944 -231.220552)
			(xy 95.762808 -231.210372) (xy 95.81366 -231.208323) (xy 95.864181 -231.214457) (xy 95.913065 -231.228617)
			(xy 95.959044 -231.250434) (xy 96.000928 -231.279344) (xy 96.037632 -231.314599) (xy 96.068205 -231.355285)
			(xy 96.091856 -231.400348) (xy 96.107972 -231.448622) (xy 96.116136 -231.498856) (xy 96.116648 -231.524302)
			(xy 96.116136 -231.549748) (xy 96.107972 -231.599982) (xy 96.091856 -231.648256) (xy 96.068205 -231.693319)
			(xy 96.037632 -231.734005) (xy 96.000928 -231.76926) (xy 95.959044 -231.79817) (xy 95.913065 -231.819987)
			(xy 95.864181 -231.834147) (xy 95.81366 -231.840281) (xy 95.762808 -231.838232) (xy 95.712944 -231.828052)
			(xy 95.665358 -231.810005) (xy 95.621284 -231.784559) (xy 95.581862 -231.752372) (xy 95.548114 -231.714278)
			(xy 95.520913 -231.671264) (xy 95.500965 -231.624444) (xy 95.488786 -231.57503) (xy 95.484691 -231.524302)
			(xy 95.179134 -231.524302) (xy 95.178644 -231.549291) (xy 95.170825 -231.598654) (xy 95.155381 -231.646186)
			(xy 95.132691 -231.690718) (xy 95.103315 -231.731151) (xy 95.067975 -231.766491) (xy 95.027542 -231.795867)
			(xy 94.98301 -231.818557) (xy 94.935478 -231.834001) (xy 94.886115 -231.84182) (xy 94.836137 -231.84182)
			(xy 94.786774 -231.834001) (xy 94.739242 -231.818557) (xy 94.69471 -231.795867) (xy 94.654277 -231.766491)
			(xy 94.618937 -231.731151) (xy 94.589561 -231.690718) (xy 94.566871 -231.646186) (xy 94.551427 -231.598654)
			(xy 94.543608 -231.549291) (xy 94.236291 -231.549291) (xy 94.236282 -231.549748) (xy 94.228118 -231.599982)
			(xy 94.212002 -231.648256) (xy 94.188351 -231.693319) (xy 94.157778 -231.734005) (xy 94.121074 -231.76926)
			(xy 94.07919 -231.79817) (xy 94.033211 -231.819987) (xy 93.984327 -231.834147) (xy 93.933806 -231.840281)
			(xy 93.882954 -231.838232) (xy 93.83309 -231.828052) (xy 93.785504 -231.810005) (xy 93.74143 -231.784559)
			(xy 93.702008 -231.752372) (xy 93.66826 -231.714278) (xy 93.641059 -231.671264) (xy 93.621111 -231.624444)
			(xy 93.608932 -231.57503) (xy 93.604837 -231.524302) (xy 93.299026 -231.524302) (xy 93.298536 -231.549291)
			(xy 93.290717 -231.598654) (xy 93.275273 -231.646186) (xy 93.252583 -231.690718) (xy 93.223207 -231.731151)
			(xy 93.187867 -231.766491) (xy 93.147434 -231.795867) (xy 93.102902 -231.818557) (xy 93.05537 -231.834001)
			(xy 93.006007 -231.84182) (xy 92.956029 -231.84182) (xy 92.906666 -231.834001) (xy 92.859134 -231.818557)
			(xy 92.814602 -231.795867) (xy 92.774169 -231.766491) (xy 92.738829 -231.731151) (xy 92.709453 -231.690718)
			(xy 92.686763 -231.646186) (xy 92.671319 -231.598654) (xy 92.6635 -231.549291) (xy 92.356183 -231.549291)
			(xy 92.356174 -231.549748) (xy 92.34801 -231.599982) (xy 92.331894 -231.648256) (xy 92.308243 -231.693319)
			(xy 92.27767 -231.734005) (xy 92.240966 -231.76926) (xy 92.199082 -231.79817) (xy 92.153103 -231.819987)
			(xy 92.104219 -231.834147) (xy 92.053698 -231.840281) (xy 92.002846 -231.838232) (xy 91.952982 -231.828052)
			(xy 91.905396 -231.810005) (xy 91.861322 -231.784559) (xy 91.8219 -231.752372) (xy 91.788152 -231.714278)
			(xy 91.760951 -231.671264) (xy 91.741003 -231.624444) (xy 91.728824 -231.57503) (xy 91.724729 -231.524302)
			(xy 91.416632 -231.524302) (xy 91.41612 -231.549748) (xy 91.407956 -231.599982) (xy 91.39184 -231.648256)
			(xy 91.368189 -231.693319) (xy 91.337616 -231.734005) (xy 91.300912 -231.76926) (xy 91.259028 -231.79817)
			(xy 91.213049 -231.819987) (xy 91.164165 -231.834147) (xy 91.113644 -231.840281) (xy 91.062792 -231.838232)
			(xy 91.012928 -231.828052) (xy 90.965342 -231.810005) (xy 90.921268 -231.784559) (xy 90.881846 -231.752372)
			(xy 90.848098 -231.714278) (xy 90.820897 -231.671264) (xy 90.800949 -231.624444) (xy 90.78877 -231.57503)
			(xy 90.784675 -231.524302) (xy 90.479118 -231.524302) (xy 90.478628 -231.549291) (xy 90.470809 -231.598654)
			(xy 90.455365 -231.646186) (xy 90.432675 -231.690718) (xy 90.403299 -231.731151) (xy 90.367959 -231.766491)
			(xy 90.327526 -231.795867) (xy 90.282994 -231.818557) (xy 90.235462 -231.834001) (xy 90.186099 -231.84182)
			(xy 90.136121 -231.84182) (xy 90.086758 -231.834001) (xy 90.039226 -231.818557) (xy 89.994694 -231.795867)
			(xy 89.954261 -231.766491) (xy 89.918921 -231.731151) (xy 89.889545 -231.690718) (xy 89.866855 -231.646186)
			(xy 89.851411 -231.598654) (xy 89.843592 -231.549291) (xy 89.536275 -231.549291) (xy 89.536266 -231.549748)
			(xy 89.528102 -231.599982) (xy 89.511986 -231.648256) (xy 89.488335 -231.693319) (xy 89.457762 -231.734005)
			(xy 89.421058 -231.76926) (xy 89.379174 -231.79817) (xy 89.333195 -231.819987) (xy 89.284311 -231.834147)
			(xy 89.23379 -231.840281) (xy 89.182938 -231.838232) (xy 89.133074 -231.828052) (xy 89.085488 -231.810005)
			(xy 89.041414 -231.784559) (xy 89.001992 -231.752372) (xy 88.968244 -231.714278) (xy 88.941043 -231.671264)
			(xy 88.921095 -231.624444) (xy 88.908916 -231.57503) (xy 88.904821 -231.524302) (xy 88.59901 -231.524302)
			(xy 88.59852 -231.549291) (xy 88.590701 -231.598654) (xy 88.575257 -231.646186) (xy 88.552567 -231.690718)
			(xy 88.523191 -231.731151) (xy 88.487851 -231.766491) (xy 88.447418 -231.795867) (xy 88.402886 -231.818557)
			(xy 88.355354 -231.834001) (xy 88.305991 -231.84182) (xy 88.256013 -231.84182) (xy 88.20665 -231.834001)
			(xy 88.159118 -231.818557) (xy 88.114586 -231.795867) (xy 88.074153 -231.766491) (xy 88.038813 -231.731151)
			(xy 88.009437 -231.690718) (xy 87.986747 -231.646186) (xy 87.971303 -231.598654) (xy 87.963484 -231.549291)
			(xy 87.656167 -231.549291) (xy 87.656158 -231.549748) (xy 87.647994 -231.599982) (xy 87.631878 -231.648256)
			(xy 87.608227 -231.693319) (xy 87.577654 -231.734005) (xy 87.54095 -231.76926) (xy 87.499066 -231.79817)
			(xy 87.453087 -231.819987) (xy 87.404203 -231.834147) (xy 87.353682 -231.840281) (xy 87.30283 -231.838232)
			(xy 87.252966 -231.828052) (xy 87.20538 -231.810005) (xy 87.161306 -231.784559) (xy 87.121884 -231.752372)
			(xy 87.088136 -231.714278) (xy 87.060935 -231.671264) (xy 87.040987 -231.624444) (xy 87.028808 -231.57503)
			(xy 87.024713 -231.524302) (xy 86.719156 -231.524302) (xy 86.718666 -231.549291) (xy 86.710847 -231.598654)
			(xy 86.695403 -231.646186) (xy 86.672713 -231.690718) (xy 86.643337 -231.731151) (xy 86.607997 -231.766491)
			(xy 86.567564 -231.795867) (xy 86.523032 -231.818557) (xy 86.4755 -231.834001) (xy 86.426137 -231.84182)
			(xy 86.376159 -231.84182) (xy 86.326796 -231.834001) (xy 86.279264 -231.818557) (xy 86.234732 -231.795867)
			(xy 86.194299 -231.766491) (xy 86.158959 -231.731151) (xy 86.129583 -231.690718) (xy 86.106893 -231.646186)
			(xy 86.091449 -231.598654) (xy 86.08363 -231.549291) (xy 85.776313 -231.549291) (xy 85.776304 -231.549748)
			(xy 85.76814 -231.599982) (xy 85.752024 -231.648256) (xy 85.728373 -231.693319) (xy 85.6978 -231.734005)
			(xy 85.661096 -231.76926) (xy 85.619212 -231.79817) (xy 85.573233 -231.819987) (xy 85.524349 -231.834147)
			(xy 85.473828 -231.840281) (xy 85.422976 -231.838232) (xy 85.373112 -231.828052) (xy 85.325526 -231.810005)
			(xy 85.281452 -231.784559) (xy 85.24203 -231.752372) (xy 85.208282 -231.714278) (xy 85.181081 -231.671264)
			(xy 85.161133 -231.624444) (xy 85.148954 -231.57503) (xy 85.144859 -231.524302) (xy 84.836762 -231.524302)
			(xy 84.83625 -231.549748) (xy 84.828086 -231.599982) (xy 84.81197 -231.648256) (xy 84.788319 -231.693319)
			(xy 84.757746 -231.734005) (xy 84.721042 -231.76926) (xy 84.679158 -231.79817) (xy 84.633179 -231.819987)
			(xy 84.584295 -231.834147) (xy 84.533774 -231.840281) (xy 84.482922 -231.838232) (xy 84.433058 -231.828052)
			(xy 84.385472 -231.810005) (xy 84.341398 -231.784559) (xy 84.301976 -231.752372) (xy 84.268228 -231.714278)
			(xy 84.241027 -231.671264) (xy 84.221079 -231.624444) (xy 84.2089 -231.57503) (xy 84.204805 -231.524302)
			(xy 83.898994 -231.524302) (xy 83.898504 -231.549291) (xy 83.890685 -231.598654) (xy 83.875241 -231.646186)
			(xy 83.852551 -231.690718) (xy 83.823175 -231.731151) (xy 83.787835 -231.766491) (xy 83.747402 -231.795867)
			(xy 83.70287 -231.818557) (xy 83.655338 -231.834001) (xy 83.605975 -231.84182) (xy 83.555997 -231.84182)
			(xy 83.506634 -231.834001) (xy 83.459102 -231.818557) (xy 83.41457 -231.795867) (xy 83.374137 -231.766491)
			(xy 83.338797 -231.731151) (xy 83.309421 -231.690718) (xy 83.286731 -231.646186) (xy 83.271287 -231.598654)
			(xy 83.263468 -231.549291) (xy 82.956151 -231.549291) (xy 82.956142 -231.549748) (xy 82.947978 -231.599982)
			(xy 82.931862 -231.648256) (xy 82.908211 -231.693319) (xy 82.877638 -231.734005) (xy 82.840934 -231.76926)
			(xy 82.79905 -231.79817) (xy 82.753071 -231.819987) (xy 82.704187 -231.834147) (xy 82.653666 -231.840281)
			(xy 82.602814 -231.838232) (xy 82.55295 -231.828052) (xy 82.505364 -231.810005) (xy 82.46129 -231.784559)
			(xy 82.421868 -231.752372) (xy 82.38812 -231.714278) (xy 82.360919 -231.671264) (xy 82.340971 -231.624444)
			(xy 82.328792 -231.57503) (xy 82.324697 -231.524302) (xy 82.01914 -231.524302) (xy 82.01865 -231.549291)
			(xy 82.010831 -231.598654) (xy 81.995387 -231.646186) (xy 81.972697 -231.690718) (xy 81.943321 -231.731151)
			(xy 81.907981 -231.766491) (xy 81.867548 -231.795867) (xy 81.823016 -231.818557) (xy 81.775484 -231.834001)
			(xy 81.726121 -231.84182) (xy 81.676143 -231.84182) (xy 81.62678 -231.834001) (xy 81.579248 -231.818557)
			(xy 81.534716 -231.795867) (xy 81.494283 -231.766491) (xy 81.458943 -231.731151) (xy 81.429567 -231.690718)
			(xy 81.406877 -231.646186) (xy 81.391433 -231.598654) (xy 81.383614 -231.549291) (xy 81.076297 -231.549291)
			(xy 81.076288 -231.549748) (xy 81.068124 -231.599982) (xy 81.052008 -231.648256) (xy 81.028357 -231.693319)
			(xy 80.997784 -231.734005) (xy 80.96108 -231.76926) (xy 80.919196 -231.79817) (xy 80.873217 -231.819987)
			(xy 80.824333 -231.834147) (xy 80.773812 -231.840281) (xy 80.72296 -231.838232) (xy 80.673096 -231.828052)
			(xy 80.62551 -231.810005) (xy 80.581436 -231.784559) (xy 80.542014 -231.752372) (xy 80.508266 -231.714278)
			(xy 80.481065 -231.671264) (xy 80.461117 -231.624444) (xy 80.448938 -231.57503) (xy 80.444843 -231.524302)
			(xy 80.138769 -231.524302) (xy 80.138769 -231.549308) (xy 80.130946 -231.598708) (xy 80.115491 -231.646276)
			(xy 80.092785 -231.69084) (xy 80.063388 -231.731305) (xy 80.028023 -231.766672) (xy 79.987561 -231.796073)
			(xy 79.942998 -231.818782) (xy 79.895431 -231.83424) (xy 79.846032 -231.842068) (xy 79.821024 -231.842564)
			(xy 79.796529 -231.842116) (xy 79.748117 -231.834618) (xy 79.701425 -231.819794) (xy 79.679292 -231.80929)
			(xy 79.665839 -231.803167) (xy 79.636725 -231.798147) (xy 79.607392 -231.801665) (xy 79.580291 -231.813428)
			(xy 79.557688 -231.832453) (xy 79.541472 -231.857148) (xy 79.532998 -231.885451) (xy 79.53248 -231.900222)
			(xy 79.53248 -232.334308) (xy 80.914743 -232.334308) (xy 80.918838 -232.28358) (xy 80.931017 -232.234166)
			(xy 80.950965 -232.187346) (xy 80.978166 -232.144332) (xy 81.011914 -232.106238) (xy 81.051336 -232.074051)
			(xy 81.09541 -232.048605) (xy 81.142996 -232.030558) (xy 81.19286 -232.020378) (xy 81.243712 -232.018329)
			(xy 81.294233 -232.024463) (xy 81.343117 -232.038623) (xy 81.389096 -232.06044) (xy 81.43098 -232.08935)
			(xy 81.467684 -232.124605) (xy 81.498257 -232.165291) (xy 81.521908 -232.210354) (xy 81.538024 -232.258628)
			(xy 81.546188 -232.308862) (xy 81.5467 -232.334308) (xy 81.854797 -232.334308) (xy 81.858892 -232.28358)
			(xy 81.871071 -232.234166) (xy 81.891019 -232.187346) (xy 81.91822 -232.144332) (xy 81.951968 -232.106238)
			(xy 81.99139 -232.074051) (xy 82.035464 -232.048605) (xy 82.08305 -232.030558) (xy 82.132914 -232.020378)
			(xy 82.183766 -232.018329) (xy 82.234287 -232.024463) (xy 82.283171 -232.038623) (xy 82.32915 -232.06044)
			(xy 82.371034 -232.08935) (xy 82.407738 -232.124605) (xy 82.438311 -232.165291) (xy 82.461962 -232.210354)
			(xy 82.478078 -232.258628) (xy 82.486242 -232.308862) (xy 82.486754 -232.334308) (xy 82.486251 -232.359297)
			(xy 82.793568 -232.359297) (xy 82.793568 -232.309319) (xy 82.801387 -232.259956) (xy 82.816831 -232.212424)
			(xy 82.839521 -232.167892) (xy 82.868897 -232.127459) (xy 82.904237 -232.092119) (xy 82.94467 -232.062743)
			(xy 82.989202 -232.040053) (xy 83.036734 -232.024609) (xy 83.086097 -232.01679) (xy 83.136075 -232.01679)
			(xy 83.185438 -232.024609) (xy 83.23297 -232.040053) (xy 83.277502 -232.062743) (xy 83.317935 -232.092119)
			(xy 83.353275 -232.127459) (xy 83.382651 -232.167892) (xy 83.405341 -232.212424) (xy 83.420785 -232.259956)
			(xy 83.428604 -232.309319) (xy 83.429094 -232.334308) (xy 83.734905 -232.334308) (xy 83.739 -232.28358)
			(xy 83.751179 -232.234166) (xy 83.771127 -232.187346) (xy 83.798328 -232.144332) (xy 83.832076 -232.106238)
			(xy 83.871498 -232.074051) (xy 83.915572 -232.048605) (xy 83.963158 -232.030558) (xy 84.013022 -232.020378)
			(xy 84.063874 -232.018329) (xy 84.114395 -232.024463) (xy 84.163279 -232.038623) (xy 84.209258 -232.06044)
			(xy 84.251142 -232.08935) (xy 84.287846 -232.124605) (xy 84.318419 -232.165291) (xy 84.34207 -232.210354)
			(xy 84.358186 -232.258628) (xy 84.36635 -232.308862) (xy 84.366862 -232.334308) (xy 84.366359 -232.359297)
			(xy 84.673422 -232.359297) (xy 84.673422 -232.309319) (xy 84.681241 -232.259956) (xy 84.696685 -232.212424)
			(xy 84.719375 -232.167892) (xy 84.748751 -232.127459) (xy 84.784091 -232.092119) (xy 84.824524 -232.062743)
			(xy 84.869056 -232.040053) (xy 84.916588 -232.024609) (xy 84.965951 -232.01679) (xy 85.015929 -232.01679)
			(xy 85.065292 -232.024609) (xy 85.112824 -232.040053) (xy 85.157356 -232.062743) (xy 85.197789 -232.092119)
			(xy 85.233129 -232.127459) (xy 85.262505 -232.167892) (xy 85.285195 -232.212424) (xy 85.300639 -232.259956)
			(xy 85.308458 -232.309319) (xy 85.308948 -232.334308) (xy 85.614759 -232.334308) (xy 85.618854 -232.28358)
			(xy 85.631033 -232.234166) (xy 85.650981 -232.187346) (xy 85.678182 -232.144332) (xy 85.71193 -232.106238)
			(xy 85.751352 -232.074051) (xy 85.795426 -232.048605) (xy 85.843012 -232.030558) (xy 85.892876 -232.020378)
			(xy 85.943728 -232.018329) (xy 85.994249 -232.024463) (xy 86.043133 -232.038623) (xy 86.089112 -232.06044)
			(xy 86.130996 -232.08935) (xy 86.1677 -232.124605) (xy 86.198273 -232.165291) (xy 86.221924 -232.210354)
			(xy 86.23804 -232.258628) (xy 86.246204 -232.308862) (xy 86.246716 -232.334308) (xy 87.494867 -232.334308)
			(xy 87.498962 -232.28358) (xy 87.511141 -232.234166) (xy 87.531089 -232.187346) (xy 87.55829 -232.144332)
			(xy 87.592038 -232.106238) (xy 87.63146 -232.074051) (xy 87.675534 -232.048605) (xy 87.72312 -232.030558)
			(xy 87.772984 -232.020378) (xy 87.823836 -232.018329) (xy 87.874357 -232.024463) (xy 87.923241 -232.038623)
			(xy 87.96922 -232.06044) (xy 88.011104 -232.08935) (xy 88.047808 -232.124605) (xy 88.078381 -232.165291)
			(xy 88.102032 -232.210354) (xy 88.118148 -232.258628) (xy 88.126312 -232.308862) (xy 88.126824 -232.334308)
			(xy 88.434921 -232.334308) (xy 88.439016 -232.28358) (xy 88.451195 -232.234166) (xy 88.471143 -232.187346)
			(xy 88.498344 -232.144332) (xy 88.532092 -232.106238) (xy 88.571514 -232.074051) (xy 88.615588 -232.048605)
			(xy 88.663174 -232.030558) (xy 88.713038 -232.020378) (xy 88.76389 -232.018329) (xy 88.814411 -232.024463)
			(xy 88.863295 -232.038623) (xy 88.909274 -232.06044) (xy 88.951158 -232.08935) (xy 88.987862 -232.124605)
			(xy 89.018435 -232.165291) (xy 89.042086 -232.210354) (xy 89.058202 -232.258628) (xy 89.066366 -232.308862)
			(xy 89.066878 -232.334308) (xy 89.066375 -232.359297) (xy 89.373438 -232.359297) (xy 89.373438 -232.309319)
			(xy 89.381257 -232.259956) (xy 89.396701 -232.212424) (xy 89.419391 -232.167892) (xy 89.448767 -232.127459)
			(xy 89.484107 -232.092119) (xy 89.52454 -232.062743) (xy 89.569072 -232.040053) (xy 89.616604 -232.024609)
			(xy 89.665967 -232.01679) (xy 89.715945 -232.01679) (xy 89.765308 -232.024609) (xy 89.81284 -232.040053)
			(xy 89.857372 -232.062743) (xy 89.897805 -232.092119) (xy 89.933145 -232.127459) (xy 89.962521 -232.167892)
			(xy 89.985211 -232.212424) (xy 90.000655 -232.259956) (xy 90.008474 -232.309319) (xy 90.008964 -232.334308)
			(xy 90.314775 -232.334308) (xy 90.31887 -232.28358) (xy 90.331049 -232.234166) (xy 90.350997 -232.187346)
			(xy 90.378198 -232.144332) (xy 90.411946 -232.106238) (xy 90.451368 -232.074051) (xy 90.495442 -232.048605)
			(xy 90.543028 -232.030558) (xy 90.592892 -232.020378) (xy 90.643744 -232.018329) (xy 90.694265 -232.024463)
			(xy 90.743149 -232.038623) (xy 90.789128 -232.06044) (xy 90.831012 -232.08935) (xy 90.867716 -232.124605)
			(xy 90.898289 -232.165291) (xy 90.92194 -232.210354) (xy 90.938056 -232.258628) (xy 90.94622 -232.308862)
			(xy 90.946732 -232.334308) (xy 90.946229 -232.359297) (xy 91.253546 -232.359297) (xy 91.253546 -232.309319)
			(xy 91.261365 -232.259956) (xy 91.276809 -232.212424) (xy 91.299499 -232.167892) (xy 91.328875 -232.127459)
			(xy 91.364215 -232.092119) (xy 91.404648 -232.062743) (xy 91.44918 -232.040053) (xy 91.496712 -232.024609)
			(xy 91.546075 -232.01679) (xy 91.596053 -232.01679) (xy 91.645416 -232.024609) (xy 91.692948 -232.040053)
			(xy 91.73748 -232.062743) (xy 91.777913 -232.092119) (xy 91.813253 -232.127459) (xy 91.842629 -232.167892)
			(xy 91.865319 -232.212424) (xy 91.880763 -232.259956) (xy 91.888582 -232.309319) (xy 91.889072 -232.334308)
			(xy 92.194883 -232.334308) (xy 92.198978 -232.28358) (xy 92.211157 -232.234166) (xy 92.231105 -232.187346)
			(xy 92.258306 -232.144332) (xy 92.292054 -232.106238) (xy 92.331476 -232.074051) (xy 92.37555 -232.048605)
			(xy 92.423136 -232.030558) (xy 92.473 -232.020378) (xy 92.523852 -232.018329) (xy 92.574373 -232.024463)
			(xy 92.623257 -232.038623) (xy 92.669236 -232.06044) (xy 92.71112 -232.08935) (xy 92.747824 -232.124605)
			(xy 92.778397 -232.165291) (xy 92.802048 -232.210354) (xy 92.818164 -232.258628) (xy 92.826328 -232.308862)
			(xy 92.82684 -232.334308) (xy 94.074737 -232.334308) (xy 94.078832 -232.28358) (xy 94.091011 -232.234166)
			(xy 94.110959 -232.187346) (xy 94.13816 -232.144332) (xy 94.171908 -232.106238) (xy 94.21133 -232.074051)
			(xy 94.255404 -232.048605) (xy 94.30299 -232.030558) (xy 94.352854 -232.020378) (xy 94.403706 -232.018329)
			(xy 94.454227 -232.024463) (xy 94.503111 -232.038623) (xy 94.54909 -232.06044) (xy 94.590974 -232.08935)
			(xy 94.627678 -232.124605) (xy 94.658251 -232.165291) (xy 94.681902 -232.210354) (xy 94.698018 -232.258628)
			(xy 94.706182 -232.308862) (xy 94.706694 -232.334308) (xy 95.014791 -232.334308) (xy 95.018886 -232.28358)
			(xy 95.031065 -232.234166) (xy 95.051013 -232.187346) (xy 95.078214 -232.144332) (xy 95.111962 -232.106238)
			(xy 95.151384 -232.074051) (xy 95.195458 -232.048605) (xy 95.243044 -232.030558) (xy 95.292908 -232.020378)
			(xy 95.34376 -232.018329) (xy 95.394281 -232.024463) (xy 95.443165 -232.038623) (xy 95.489144 -232.06044)
			(xy 95.531028 -232.08935) (xy 95.567732 -232.124605) (xy 95.598305 -232.165291) (xy 95.621956 -232.210354)
			(xy 95.638072 -232.258628) (xy 95.646236 -232.308862) (xy 95.646748 -232.334308) (xy 95.646236 -232.359754)
			(xy 95.638072 -232.409988) (xy 95.621956 -232.458262) (xy 95.598305 -232.503325) (xy 95.567732 -232.544011)
			(xy 95.531028 -232.579266) (xy 95.489144 -232.608176) (xy 95.443165 -232.629993) (xy 95.394281 -232.644153)
			(xy 95.34376 -232.650287) (xy 95.292908 -232.648238) (xy 95.243044 -232.638058) (xy 95.195458 -232.620011)
			(xy 95.151384 -232.594565) (xy 95.111962 -232.562378) (xy 95.078214 -232.524284) (xy 95.051013 -232.48127)
			(xy 95.031065 -232.43445) (xy 95.018886 -232.385036) (xy 95.014791 -232.334308) (xy 94.706694 -232.334308)
			(xy 94.706182 -232.359754) (xy 94.698018 -232.409988) (xy 94.681902 -232.458262) (xy 94.658251 -232.503325)
			(xy 94.627678 -232.544011) (xy 94.590974 -232.579266) (xy 94.54909 -232.608176) (xy 94.503111 -232.629993)
			(xy 94.454227 -232.644153) (xy 94.403706 -232.650287) (xy 94.352854 -232.648238) (xy 94.30299 -232.638058)
			(xy 94.255404 -232.620011) (xy 94.21133 -232.594565) (xy 94.171908 -232.562378) (xy 94.13816 -232.524284)
			(xy 94.110959 -232.48127) (xy 94.091011 -232.43445) (xy 94.078832 -232.385036) (xy 94.074737 -232.334308)
			(xy 92.82684 -232.334308) (xy 92.826328 -232.359754) (xy 92.818164 -232.409988) (xy 92.802048 -232.458262)
			(xy 92.778397 -232.503325) (xy 92.747824 -232.544011) (xy 92.71112 -232.579266) (xy 92.669236 -232.608176)
			(xy 92.623257 -232.629993) (xy 92.574373 -232.644153) (xy 92.523852 -232.650287) (xy 92.473 -232.648238)
			(xy 92.423136 -232.638058) (xy 92.37555 -232.620011) (xy 92.331476 -232.594565) (xy 92.292054 -232.562378)
			(xy 92.258306 -232.524284) (xy 92.231105 -232.48127) (xy 92.211157 -232.43445) (xy 92.198978 -232.385036)
			(xy 92.194883 -232.334308) (xy 91.889072 -232.334308) (xy 91.888582 -232.359297) (xy 91.880763 -232.40866)
			(xy 91.865319 -232.456192) (xy 91.842629 -232.500724) (xy 91.813253 -232.541157) (xy 91.777913 -232.576497)
			(xy 91.73748 -232.605873) (xy 91.692948 -232.628563) (xy 91.645416 -232.644007) (xy 91.596053 -232.651826)
			(xy 91.546075 -232.651826) (xy 91.496712 -232.644007) (xy 91.44918 -232.628563) (xy 91.404648 -232.605873)
			(xy 91.364215 -232.576497) (xy 91.328875 -232.541157) (xy 91.299499 -232.500724) (xy 91.276809 -232.456192)
			(xy 91.261365 -232.40866) (xy 91.253546 -232.359297) (xy 90.946229 -232.359297) (xy 90.94622 -232.359754)
			(xy 90.938056 -232.409988) (xy 90.92194 -232.458262) (xy 90.898289 -232.503325) (xy 90.867716 -232.544011)
			(xy 90.831012 -232.579266) (xy 90.789128 -232.608176) (xy 90.743149 -232.629993) (xy 90.694265 -232.644153)
			(xy 90.643744 -232.650287) (xy 90.592892 -232.648238) (xy 90.543028 -232.638058) (xy 90.495442 -232.620011)
			(xy 90.451368 -232.594565) (xy 90.411946 -232.562378) (xy 90.378198 -232.524284) (xy 90.350997 -232.48127)
			(xy 90.331049 -232.43445) (xy 90.31887 -232.385036) (xy 90.314775 -232.334308) (xy 90.008964 -232.334308)
			(xy 90.008474 -232.359297) (xy 90.000655 -232.40866) (xy 89.985211 -232.456192) (xy 89.962521 -232.500724)
			(xy 89.933145 -232.541157) (xy 89.897805 -232.576497) (xy 89.857372 -232.605873) (xy 89.81284 -232.628563)
			(xy 89.765308 -232.644007) (xy 89.715945 -232.651826) (xy 89.665967 -232.651826) (xy 89.616604 -232.644007)
			(xy 89.569072 -232.628563) (xy 89.52454 -232.605873) (xy 89.484107 -232.576497) (xy 89.448767 -232.541157)
			(xy 89.419391 -232.500724) (xy 89.396701 -232.456192) (xy 89.381257 -232.40866) (xy 89.373438 -232.359297)
			(xy 89.066375 -232.359297) (xy 89.066366 -232.359754) (xy 89.058202 -232.409988) (xy 89.042086 -232.458262)
			(xy 89.018435 -232.503325) (xy 88.987862 -232.544011) (xy 88.951158 -232.579266) (xy 88.909274 -232.608176)
			(xy 88.863295 -232.629993) (xy 88.814411 -232.644153) (xy 88.76389 -232.650287) (xy 88.713038 -232.648238)
			(xy 88.663174 -232.638058) (xy 88.615588 -232.620011) (xy 88.571514 -232.594565) (xy 88.532092 -232.562378)
			(xy 88.498344 -232.524284) (xy 88.471143 -232.48127) (xy 88.451195 -232.43445) (xy 88.439016 -232.385036)
			(xy 88.434921 -232.334308) (xy 88.126824 -232.334308) (xy 88.126312 -232.359754) (xy 88.118148 -232.409988)
			(xy 88.102032 -232.458262) (xy 88.078381 -232.503325) (xy 88.047808 -232.544011) (xy 88.011104 -232.579266)
			(xy 87.96922 -232.608176) (xy 87.923241 -232.629993) (xy 87.874357 -232.644153) (xy 87.823836 -232.650287)
			(xy 87.772984 -232.648238) (xy 87.72312 -232.638058) (xy 87.675534 -232.620011) (xy 87.63146 -232.594565)
			(xy 87.592038 -232.562378) (xy 87.55829 -232.524284) (xy 87.531089 -232.48127) (xy 87.511141 -232.43445)
			(xy 87.498962 -232.385036) (xy 87.494867 -232.334308) (xy 86.246716 -232.334308) (xy 86.246204 -232.359754)
			(xy 86.23804 -232.409988) (xy 86.221924 -232.458262) (xy 86.198273 -232.503325) (xy 86.1677 -232.544011)
			(xy 86.130996 -232.579266) (xy 86.089112 -232.608176) (xy 86.043133 -232.629993) (xy 85.994249 -232.644153)
			(xy 85.943728 -232.650287) (xy 85.892876 -232.648238) (xy 85.843012 -232.638058) (xy 85.795426 -232.620011)
			(xy 85.751352 -232.594565) (xy 85.71193 -232.562378) (xy 85.678182 -232.524284) (xy 85.650981 -232.48127)
			(xy 85.631033 -232.43445) (xy 85.618854 -232.385036) (xy 85.614759 -232.334308) (xy 85.308948 -232.334308)
			(xy 85.308458 -232.359297) (xy 85.300639 -232.40866) (xy 85.285195 -232.456192) (xy 85.262505 -232.500724)
			(xy 85.233129 -232.541157) (xy 85.197789 -232.576497) (xy 85.157356 -232.605873) (xy 85.112824 -232.628563)
			(xy 85.065292 -232.644007) (xy 85.015929 -232.651826) (xy 84.965951 -232.651826) (xy 84.916588 -232.644007)
			(xy 84.869056 -232.628563) (xy 84.824524 -232.605873) (xy 84.784091 -232.576497) (xy 84.748751 -232.541157)
			(xy 84.719375 -232.500724) (xy 84.696685 -232.456192) (xy 84.681241 -232.40866) (xy 84.673422 -232.359297)
			(xy 84.366359 -232.359297) (xy 84.36635 -232.359754) (xy 84.358186 -232.409988) (xy 84.34207 -232.458262)
			(xy 84.318419 -232.503325) (xy 84.287846 -232.544011) (xy 84.251142 -232.579266) (xy 84.209258 -232.608176)
			(xy 84.163279 -232.629993) (xy 84.114395 -232.644153) (xy 84.063874 -232.650287) (xy 84.013022 -232.648238)
			(xy 83.963158 -232.638058) (xy 83.915572 -232.620011) (xy 83.871498 -232.594565) (xy 83.832076 -232.562378)
			(xy 83.798328 -232.524284) (xy 83.771127 -232.48127) (xy 83.751179 -232.43445) (xy 83.739 -232.385036)
			(xy 83.734905 -232.334308) (xy 83.429094 -232.334308) (xy 83.428604 -232.359297) (xy 83.420785 -232.40866)
			(xy 83.405341 -232.456192) (xy 83.382651 -232.500724) (xy 83.353275 -232.541157) (xy 83.317935 -232.576497)
			(xy 83.277502 -232.605873) (xy 83.23297 -232.628563) (xy 83.185438 -232.644007) (xy 83.136075 -232.651826)
			(xy 83.086097 -232.651826) (xy 83.036734 -232.644007) (xy 82.989202 -232.628563) (xy 82.94467 -232.605873)
			(xy 82.904237 -232.576497) (xy 82.868897 -232.541157) (xy 82.839521 -232.500724) (xy 82.816831 -232.456192)
			(xy 82.801387 -232.40866) (xy 82.793568 -232.359297) (xy 82.486251 -232.359297) (xy 82.486242 -232.359754)
			(xy 82.478078 -232.409988) (xy 82.461962 -232.458262) (xy 82.438311 -232.503325) (xy 82.407738 -232.544011)
			(xy 82.371034 -232.579266) (xy 82.32915 -232.608176) (xy 82.283171 -232.629993) (xy 82.234287 -232.644153)
			(xy 82.183766 -232.650287) (xy 82.132914 -232.648238) (xy 82.08305 -232.638058) (xy 82.035464 -232.620011)
			(xy 81.99139 -232.594565) (xy 81.951968 -232.562378) (xy 81.91822 -232.524284) (xy 81.891019 -232.48127)
			(xy 81.871071 -232.43445) (xy 81.858892 -232.385036) (xy 81.854797 -232.334308) (xy 81.5467 -232.334308)
			(xy 81.546188 -232.359754) (xy 81.538024 -232.409988) (xy 81.521908 -232.458262) (xy 81.498257 -232.503325)
			(xy 81.467684 -232.544011) (xy 81.43098 -232.579266) (xy 81.389096 -232.608176) (xy 81.343117 -232.629993)
			(xy 81.294233 -232.644153) (xy 81.243712 -232.650287) (xy 81.19286 -232.648238) (xy 81.142996 -232.638058)
			(xy 81.09541 -232.620011) (xy 81.051336 -232.594565) (xy 81.011914 -232.562378) (xy 80.978166 -232.524284)
			(xy 80.950965 -232.48127) (xy 80.931017 -232.43445) (xy 80.918838 -232.385036) (xy 80.914743 -232.334308)
			(xy 79.53248 -232.334308) (xy 79.53248 -232.768394) (xy 79.53298 -232.783167) (xy 79.54144 -232.811477)
			(xy 79.557652 -232.836179) (xy 79.580258 -232.855204) (xy 79.607366 -232.866958) (xy 79.636705 -232.870458)
			(xy 79.665817 -232.865409) (xy 79.679292 -232.859326) (xy 79.701428 -232.848832) (xy 79.74812 -232.834012)
			(xy 79.79653 -232.826516) (xy 79.821024 -232.826052) (xy 79.846031 -232.826544) (xy 79.895428 -232.834372)
			(xy 79.942993 -232.84983) (xy 79.987555 -232.872538) (xy 80.028015 -232.901937) (xy 80.063379 -232.937303)
			(xy 80.092775 -232.977766) (xy 80.11548 -233.022329) (xy 80.130934 -233.069895) (xy 80.138758 -233.119293)
			(xy 80.138758 -233.144314) (xy 80.444843 -233.144314) (xy 80.448938 -233.093586) (xy 80.461117 -233.044172)
			(xy 80.481065 -232.997352) (xy 80.508266 -232.954338) (xy 80.542014 -232.916244) (xy 80.581436 -232.884057)
			(xy 80.62551 -232.858611) (xy 80.673096 -232.840564) (xy 80.72296 -232.830384) (xy 80.773812 -232.828335)
			(xy 80.824333 -232.834469) (xy 80.873217 -232.848629) (xy 80.919196 -232.870446) (xy 80.96108 -232.899356)
			(xy 80.997784 -232.934611) (xy 81.028357 -232.975297) (xy 81.052008 -233.02036) (xy 81.068124 -233.068634)
			(xy 81.076288 -233.118868) (xy 81.0768 -233.144314) (xy 81.076297 -233.169303) (xy 81.383614 -233.169303)
			(xy 81.383614 -233.119325) (xy 81.391433 -233.069962) (xy 81.406877 -233.02243) (xy 81.429567 -232.977898)
			(xy 81.458943 -232.937465) (xy 81.494283 -232.902125) (xy 81.534716 -232.872749) (xy 81.579248 -232.850059)
			(xy 81.62678 -232.834615) (xy 81.676143 -232.826796) (xy 81.726121 -232.826796) (xy 81.775484 -232.834615)
			(xy 81.823016 -232.850059) (xy 81.867548 -232.872749) (xy 81.907981 -232.902125) (xy 81.943321 -232.937465)
			(xy 81.972697 -232.977898) (xy 81.995387 -233.02243) (xy 82.010831 -233.069962) (xy 82.01865 -233.119325)
			(xy 82.01914 -233.144314) (xy 82.324697 -233.144314) (xy 82.328792 -233.093586) (xy 82.340971 -233.044172)
			(xy 82.360919 -232.997352) (xy 82.38812 -232.954338) (xy 82.421868 -232.916244) (xy 82.46129 -232.884057)
			(xy 82.505364 -232.858611) (xy 82.55295 -232.840564) (xy 82.602814 -232.830384) (xy 82.653666 -232.828335)
			(xy 82.704187 -232.834469) (xy 82.753071 -232.848629) (xy 82.79905 -232.870446) (xy 82.840934 -232.899356)
			(xy 82.877638 -232.934611) (xy 82.908211 -232.975297) (xy 82.931862 -233.02036) (xy 82.947978 -233.068634)
			(xy 82.956142 -233.118868) (xy 82.956654 -233.144314) (xy 82.956151 -233.169303) (xy 83.263468 -233.169303)
			(xy 83.263468 -233.119325) (xy 83.271287 -233.069962) (xy 83.286731 -233.02243) (xy 83.309421 -232.977898)
			(xy 83.338797 -232.937465) (xy 83.374137 -232.902125) (xy 83.41457 -232.872749) (xy 83.459102 -232.850059)
			(xy 83.506634 -232.834615) (xy 83.555997 -232.826796) (xy 83.605975 -232.826796) (xy 83.655338 -232.834615)
			(xy 83.70287 -232.850059) (xy 83.747402 -232.872749) (xy 83.787835 -232.902125) (xy 83.823175 -232.937465)
			(xy 83.852551 -232.977898) (xy 83.875241 -233.02243) (xy 83.890685 -233.069962) (xy 83.898504 -233.119325)
			(xy 83.898994 -233.144314) (xy 84.204805 -233.144314) (xy 84.2089 -233.093586) (xy 84.221079 -233.044172)
			(xy 84.241027 -232.997352) (xy 84.268228 -232.954338) (xy 84.301976 -232.916244) (xy 84.341398 -232.884057)
			(xy 84.385472 -232.858611) (xy 84.433058 -232.840564) (xy 84.482922 -232.830384) (xy 84.533774 -232.828335)
			(xy 84.584295 -232.834469) (xy 84.633179 -232.848629) (xy 84.679158 -232.870446) (xy 84.721042 -232.899356)
			(xy 84.757746 -232.934611) (xy 84.788319 -232.975297) (xy 84.81197 -233.02036) (xy 84.828086 -233.068634)
			(xy 84.83625 -233.118868) (xy 84.836762 -233.144314) (xy 85.144859 -233.144314) (xy 85.148954 -233.093586)
			(xy 85.161133 -233.044172) (xy 85.181081 -232.997352) (xy 85.208282 -232.954338) (xy 85.24203 -232.916244)
			(xy 85.281452 -232.884057) (xy 85.325526 -232.858611) (xy 85.373112 -232.840564) (xy 85.422976 -232.830384)
			(xy 85.473828 -232.828335) (xy 85.524349 -232.834469) (xy 85.573233 -232.848629) (xy 85.619212 -232.870446)
			(xy 85.661096 -232.899356) (xy 85.6978 -232.934611) (xy 85.728373 -232.975297) (xy 85.752024 -233.02036)
			(xy 85.76814 -233.068634) (xy 85.776304 -233.118868) (xy 85.776816 -233.144314) (xy 85.776313 -233.169303)
			(xy 86.08363 -233.169303) (xy 86.08363 -233.119325) (xy 86.091449 -233.069962) (xy 86.106893 -233.02243)
			(xy 86.129583 -232.977898) (xy 86.158959 -232.937465) (xy 86.194299 -232.902125) (xy 86.234732 -232.872749)
			(xy 86.279264 -232.850059) (xy 86.326796 -232.834615) (xy 86.376159 -232.826796) (xy 86.426137 -232.826796)
			(xy 86.4755 -232.834615) (xy 86.523032 -232.850059) (xy 86.567564 -232.872749) (xy 86.607997 -232.902125)
			(xy 86.643337 -232.937465) (xy 86.672713 -232.977898) (xy 86.695403 -233.02243) (xy 86.710847 -233.069962)
			(xy 86.718666 -233.119325) (xy 86.719156 -233.144314) (xy 87.024713 -233.144314) (xy 87.028808 -233.093586)
			(xy 87.040987 -233.044172) (xy 87.060935 -232.997352) (xy 87.088136 -232.954338) (xy 87.121884 -232.916244)
			(xy 87.161306 -232.884057) (xy 87.20538 -232.858611) (xy 87.252966 -232.840564) (xy 87.30283 -232.830384)
			(xy 87.353682 -232.828335) (xy 87.404203 -232.834469) (xy 87.453087 -232.848629) (xy 87.499066 -232.870446)
			(xy 87.54095 -232.899356) (xy 87.577654 -232.934611) (xy 87.608227 -232.975297) (xy 87.631878 -233.02036)
			(xy 87.647994 -233.068634) (xy 87.656158 -233.118868) (xy 87.65667 -233.144314) (xy 87.656167 -233.169303)
			(xy 87.963484 -233.169303) (xy 87.963484 -233.119325) (xy 87.971303 -233.069962) (xy 87.986747 -233.02243)
			(xy 88.009437 -232.977898) (xy 88.038813 -232.937465) (xy 88.074153 -232.902125) (xy 88.114586 -232.872749)
			(xy 88.159118 -232.850059) (xy 88.20665 -232.834615) (xy 88.256013 -232.826796) (xy 88.305991 -232.826796)
			(xy 88.355354 -232.834615) (xy 88.402886 -232.850059) (xy 88.447418 -232.872749) (xy 88.487851 -232.902125)
			(xy 88.523191 -232.937465) (xy 88.552567 -232.977898) (xy 88.575257 -233.02243) (xy 88.590701 -233.069962)
			(xy 88.59852 -233.119325) (xy 88.59901 -233.144314) (xy 88.904821 -233.144314) (xy 88.908916 -233.093586)
			(xy 88.921095 -233.044172) (xy 88.941043 -232.997352) (xy 88.968244 -232.954338) (xy 89.001992 -232.916244)
			(xy 89.041414 -232.884057) (xy 89.085488 -232.858611) (xy 89.133074 -232.840564) (xy 89.182938 -232.830384)
			(xy 89.23379 -232.828335) (xy 89.284311 -232.834469) (xy 89.333195 -232.848629) (xy 89.379174 -232.870446)
			(xy 89.421058 -232.899356) (xy 89.457762 -232.934611) (xy 89.488335 -232.975297) (xy 89.511986 -233.02036)
			(xy 89.528102 -233.068634) (xy 89.536266 -233.118868) (xy 89.536778 -233.144314) (xy 89.536275 -233.169303)
			(xy 89.843592 -233.169303) (xy 89.843592 -233.119325) (xy 89.851411 -233.069962) (xy 89.866855 -233.02243)
			(xy 89.889545 -232.977898) (xy 89.918921 -232.937465) (xy 89.954261 -232.902125) (xy 89.994694 -232.872749)
			(xy 90.039226 -232.850059) (xy 90.086758 -232.834615) (xy 90.136121 -232.826796) (xy 90.186099 -232.826796)
			(xy 90.235462 -232.834615) (xy 90.282994 -232.850059) (xy 90.327526 -232.872749) (xy 90.367959 -232.902125)
			(xy 90.403299 -232.937465) (xy 90.432675 -232.977898) (xy 90.455365 -233.02243) (xy 90.470809 -233.069962)
			(xy 90.478628 -233.119325) (xy 90.479118 -233.144314) (xy 90.784675 -233.144314) (xy 90.78877 -233.093586)
			(xy 90.800949 -233.044172) (xy 90.820897 -232.997352) (xy 90.848098 -232.954338) (xy 90.881846 -232.916244)
			(xy 90.921268 -232.884057) (xy 90.965342 -232.858611) (xy 91.012928 -232.840564) (xy 91.062792 -232.830384)
			(xy 91.113644 -232.828335) (xy 91.164165 -232.834469) (xy 91.213049 -232.848629) (xy 91.259028 -232.870446)
			(xy 91.300912 -232.899356) (xy 91.337616 -232.934611) (xy 91.368189 -232.975297) (xy 91.39184 -233.02036)
			(xy 91.407956 -233.068634) (xy 91.41612 -233.118868) (xy 91.416632 -233.144314) (xy 91.724729 -233.144314)
			(xy 91.728824 -233.093586) (xy 91.741003 -233.044172) (xy 91.760951 -232.997352) (xy 91.788152 -232.954338)
			(xy 91.8219 -232.916244) (xy 91.861322 -232.884057) (xy 91.905396 -232.858611) (xy 91.952982 -232.840564)
			(xy 92.002846 -232.830384) (xy 92.053698 -232.828335) (xy 92.104219 -232.834469) (xy 92.153103 -232.848629)
			(xy 92.199082 -232.870446) (xy 92.240966 -232.899356) (xy 92.27767 -232.934611) (xy 92.308243 -232.975297)
			(xy 92.331894 -233.02036) (xy 92.34801 -233.068634) (xy 92.356174 -233.118868) (xy 92.356686 -233.144314)
			(xy 92.356183 -233.169303) (xy 92.6635 -233.169303) (xy 92.6635 -233.119325) (xy 92.671319 -233.069962)
			(xy 92.686763 -233.02243) (xy 92.709453 -232.977898) (xy 92.738829 -232.937465) (xy 92.774169 -232.902125)
			(xy 92.814602 -232.872749) (xy 92.859134 -232.850059) (xy 92.906666 -232.834615) (xy 92.956029 -232.826796)
			(xy 93.006007 -232.826796) (xy 93.05537 -232.834615) (xy 93.102902 -232.850059) (xy 93.147434 -232.872749)
			(xy 93.187867 -232.902125) (xy 93.223207 -232.937465) (xy 93.252583 -232.977898) (xy 93.275273 -233.02243)
			(xy 93.290717 -233.069962) (xy 93.298536 -233.119325) (xy 93.299026 -233.144314) (xy 93.604837 -233.144314)
			(xy 93.608932 -233.093586) (xy 93.621111 -233.044172) (xy 93.641059 -232.997352) (xy 93.66826 -232.954338)
			(xy 93.702008 -232.916244) (xy 93.74143 -232.884057) (xy 93.785504 -232.858611) (xy 93.83309 -232.840564)
			(xy 93.882954 -232.830384) (xy 93.933806 -232.828335) (xy 93.984327 -232.834469) (xy 94.033211 -232.848629)
			(xy 94.07919 -232.870446) (xy 94.121074 -232.899356) (xy 94.157778 -232.934611) (xy 94.188351 -232.975297)
			(xy 94.212002 -233.02036) (xy 94.228118 -233.068634) (xy 94.236282 -233.118868) (xy 94.236794 -233.144314)
			(xy 94.236291 -233.169303) (xy 94.543608 -233.169303) (xy 94.543608 -233.119325) (xy 94.551427 -233.069962)
			(xy 94.566871 -233.02243) (xy 94.589561 -232.977898) (xy 94.618937 -232.937465) (xy 94.654277 -232.902125)
			(xy 94.69471 -232.872749) (xy 94.739242 -232.850059) (xy 94.786774 -232.834615) (xy 94.836137 -232.826796)
			(xy 94.886115 -232.826796) (xy 94.935478 -232.834615) (xy 94.98301 -232.850059) (xy 95.027542 -232.872749)
			(xy 95.067975 -232.902125) (xy 95.103315 -232.937465) (xy 95.132691 -232.977898) (xy 95.155381 -233.02243)
			(xy 95.170825 -233.069962) (xy 95.178644 -233.119325) (xy 95.179134 -233.144314) (xy 95.484691 -233.144314)
			(xy 95.488786 -233.093586) (xy 95.500965 -233.044172) (xy 95.520913 -232.997352) (xy 95.548114 -232.954338)
			(xy 95.581862 -232.916244) (xy 95.621284 -232.884057) (xy 95.665358 -232.858611) (xy 95.712944 -232.840564)
			(xy 95.762808 -232.830384) (xy 95.81366 -232.828335) (xy 95.864181 -232.834469) (xy 95.913065 -232.848629)
			(xy 95.959044 -232.870446) (xy 96.000928 -232.899356) (xy 96.037632 -232.934611) (xy 96.068205 -232.975297)
			(xy 96.091856 -233.02036) (xy 96.107972 -233.068634) (xy 96.116136 -233.118868) (xy 96.116648 -233.144314)
			(xy 96.116136 -233.16976) (xy 96.107972 -233.219994) (xy 96.091856 -233.268268) (xy 96.068205 -233.313331)
			(xy 96.037632 -233.354017) (xy 96.000928 -233.389272) (xy 95.959044 -233.418182) (xy 95.913065 -233.439999)
			(xy 95.864181 -233.454159) (xy 95.81366 -233.460293) (xy 95.762808 -233.458244) (xy 95.712944 -233.448064)
			(xy 95.665358 -233.430017) (xy 95.621284 -233.404571) (xy 95.581862 -233.372384) (xy 95.548114 -233.33429)
			(xy 95.520913 -233.291276) (xy 95.500965 -233.244456) (xy 95.488786 -233.195042) (xy 95.484691 -233.144314)
			(xy 95.179134 -233.144314) (xy 95.178644 -233.169303) (xy 95.170825 -233.218666) (xy 95.155381 -233.266198)
			(xy 95.132691 -233.31073) (xy 95.103315 -233.351163) (xy 95.067975 -233.386503) (xy 95.027542 -233.415879)
			(xy 94.98301 -233.438569) (xy 94.935478 -233.454013) (xy 94.886115 -233.461832) (xy 94.836137 -233.461832)
			(xy 94.786774 -233.454013) (xy 94.739242 -233.438569) (xy 94.69471 -233.415879) (xy 94.654277 -233.386503)
			(xy 94.618937 -233.351163) (xy 94.589561 -233.31073) (xy 94.566871 -233.266198) (xy 94.551427 -233.218666)
			(xy 94.543608 -233.169303) (xy 94.236291 -233.169303) (xy 94.236282 -233.16976) (xy 94.228118 -233.219994)
			(xy 94.212002 -233.268268) (xy 94.188351 -233.313331) (xy 94.157778 -233.354017) (xy 94.121074 -233.389272)
			(xy 94.07919 -233.418182) (xy 94.033211 -233.439999) (xy 93.984327 -233.454159) (xy 93.933806 -233.460293)
			(xy 93.882954 -233.458244) (xy 93.83309 -233.448064) (xy 93.785504 -233.430017) (xy 93.74143 -233.404571)
			(xy 93.702008 -233.372384) (xy 93.66826 -233.33429) (xy 93.641059 -233.291276) (xy 93.621111 -233.244456)
			(xy 93.608932 -233.195042) (xy 93.604837 -233.144314) (xy 93.299026 -233.144314) (xy 93.298536 -233.169303)
			(xy 93.290717 -233.218666) (xy 93.275273 -233.266198) (xy 93.252583 -233.31073) (xy 93.223207 -233.351163)
			(xy 93.187867 -233.386503) (xy 93.147434 -233.415879) (xy 93.102902 -233.438569) (xy 93.05537 -233.454013)
			(xy 93.006007 -233.461832) (xy 92.956029 -233.461832) (xy 92.906666 -233.454013) (xy 92.859134 -233.438569)
			(xy 92.814602 -233.415879) (xy 92.774169 -233.386503) (xy 92.738829 -233.351163) (xy 92.709453 -233.31073)
			(xy 92.686763 -233.266198) (xy 92.671319 -233.218666) (xy 92.6635 -233.169303) (xy 92.356183 -233.169303)
			(xy 92.356174 -233.16976) (xy 92.34801 -233.219994) (xy 92.331894 -233.268268) (xy 92.308243 -233.313331)
			(xy 92.27767 -233.354017) (xy 92.240966 -233.389272) (xy 92.199082 -233.418182) (xy 92.153103 -233.439999)
			(xy 92.104219 -233.454159) (xy 92.053698 -233.460293) (xy 92.002846 -233.458244) (xy 91.952982 -233.448064)
			(xy 91.905396 -233.430017) (xy 91.861322 -233.404571) (xy 91.8219 -233.372384) (xy 91.788152 -233.33429)
			(xy 91.760951 -233.291276) (xy 91.741003 -233.244456) (xy 91.728824 -233.195042) (xy 91.724729 -233.144314)
			(xy 91.416632 -233.144314) (xy 91.41612 -233.16976) (xy 91.407956 -233.219994) (xy 91.39184 -233.268268)
			(xy 91.368189 -233.313331) (xy 91.337616 -233.354017) (xy 91.300912 -233.389272) (xy 91.259028 -233.418182)
			(xy 91.213049 -233.439999) (xy 91.164165 -233.454159) (xy 91.113644 -233.460293) (xy 91.062792 -233.458244)
			(xy 91.012928 -233.448064) (xy 90.965342 -233.430017) (xy 90.921268 -233.404571) (xy 90.881846 -233.372384)
			(xy 90.848098 -233.33429) (xy 90.820897 -233.291276) (xy 90.800949 -233.244456) (xy 90.78877 -233.195042)
			(xy 90.784675 -233.144314) (xy 90.479118 -233.144314) (xy 90.478628 -233.169303) (xy 90.470809 -233.218666)
			(xy 90.455365 -233.266198) (xy 90.432675 -233.31073) (xy 90.403299 -233.351163) (xy 90.367959 -233.386503)
			(xy 90.327526 -233.415879) (xy 90.282994 -233.438569) (xy 90.235462 -233.454013) (xy 90.186099 -233.461832)
			(xy 90.136121 -233.461832) (xy 90.086758 -233.454013) (xy 90.039226 -233.438569) (xy 89.994694 -233.415879)
			(xy 89.954261 -233.386503) (xy 89.918921 -233.351163) (xy 89.889545 -233.31073) (xy 89.866855 -233.266198)
			(xy 89.851411 -233.218666) (xy 89.843592 -233.169303) (xy 89.536275 -233.169303) (xy 89.536266 -233.16976)
			(xy 89.528102 -233.219994) (xy 89.511986 -233.268268) (xy 89.488335 -233.313331) (xy 89.457762 -233.354017)
			(xy 89.421058 -233.389272) (xy 89.379174 -233.418182) (xy 89.333195 -233.439999) (xy 89.284311 -233.454159)
			(xy 89.23379 -233.460293) (xy 89.182938 -233.458244) (xy 89.133074 -233.448064) (xy 89.085488 -233.430017)
			(xy 89.041414 -233.404571) (xy 89.001992 -233.372384) (xy 88.968244 -233.33429) (xy 88.941043 -233.291276)
			(xy 88.921095 -233.244456) (xy 88.908916 -233.195042) (xy 88.904821 -233.144314) (xy 88.59901 -233.144314)
			(xy 88.59852 -233.169303) (xy 88.590701 -233.218666) (xy 88.575257 -233.266198) (xy 88.552567 -233.31073)
			(xy 88.523191 -233.351163) (xy 88.487851 -233.386503) (xy 88.447418 -233.415879) (xy 88.402886 -233.438569)
			(xy 88.355354 -233.454013) (xy 88.305991 -233.461832) (xy 88.256013 -233.461832) (xy 88.20665 -233.454013)
			(xy 88.159118 -233.438569) (xy 88.114586 -233.415879) (xy 88.074153 -233.386503) (xy 88.038813 -233.351163)
			(xy 88.009437 -233.31073) (xy 87.986747 -233.266198) (xy 87.971303 -233.218666) (xy 87.963484 -233.169303)
			(xy 87.656167 -233.169303) (xy 87.656158 -233.16976) (xy 87.647994 -233.219994) (xy 87.631878 -233.268268)
			(xy 87.608227 -233.313331) (xy 87.577654 -233.354017) (xy 87.54095 -233.389272) (xy 87.499066 -233.418182)
			(xy 87.453087 -233.439999) (xy 87.404203 -233.454159) (xy 87.353682 -233.460293) (xy 87.30283 -233.458244)
			(xy 87.252966 -233.448064) (xy 87.20538 -233.430017) (xy 87.161306 -233.404571) (xy 87.121884 -233.372384)
			(xy 87.088136 -233.33429) (xy 87.060935 -233.291276) (xy 87.040987 -233.244456) (xy 87.028808 -233.195042)
			(xy 87.024713 -233.144314) (xy 86.719156 -233.144314) (xy 86.718666 -233.169303) (xy 86.710847 -233.218666)
			(xy 86.695403 -233.266198) (xy 86.672713 -233.31073) (xy 86.643337 -233.351163) (xy 86.607997 -233.386503)
			(xy 86.567564 -233.415879) (xy 86.523032 -233.438569) (xy 86.4755 -233.454013) (xy 86.426137 -233.461832)
			(xy 86.376159 -233.461832) (xy 86.326796 -233.454013) (xy 86.279264 -233.438569) (xy 86.234732 -233.415879)
			(xy 86.194299 -233.386503) (xy 86.158959 -233.351163) (xy 86.129583 -233.31073) (xy 86.106893 -233.266198)
			(xy 86.091449 -233.218666) (xy 86.08363 -233.169303) (xy 85.776313 -233.169303) (xy 85.776304 -233.16976)
			(xy 85.76814 -233.219994) (xy 85.752024 -233.268268) (xy 85.728373 -233.313331) (xy 85.6978 -233.354017)
			(xy 85.661096 -233.389272) (xy 85.619212 -233.418182) (xy 85.573233 -233.439999) (xy 85.524349 -233.454159)
			(xy 85.473828 -233.460293) (xy 85.422976 -233.458244) (xy 85.373112 -233.448064) (xy 85.325526 -233.430017)
			(xy 85.281452 -233.404571) (xy 85.24203 -233.372384) (xy 85.208282 -233.33429) (xy 85.181081 -233.291276)
			(xy 85.161133 -233.244456) (xy 85.148954 -233.195042) (xy 85.144859 -233.144314) (xy 84.836762 -233.144314)
			(xy 84.83625 -233.16976) (xy 84.828086 -233.219994) (xy 84.81197 -233.268268) (xy 84.788319 -233.313331)
			(xy 84.757746 -233.354017) (xy 84.721042 -233.389272) (xy 84.679158 -233.418182) (xy 84.633179 -233.439999)
			(xy 84.584295 -233.454159) (xy 84.533774 -233.460293) (xy 84.482922 -233.458244) (xy 84.433058 -233.448064)
			(xy 84.385472 -233.430017) (xy 84.341398 -233.404571) (xy 84.301976 -233.372384) (xy 84.268228 -233.33429)
			(xy 84.241027 -233.291276) (xy 84.221079 -233.244456) (xy 84.2089 -233.195042) (xy 84.204805 -233.144314)
			(xy 83.898994 -233.144314) (xy 83.898504 -233.169303) (xy 83.890685 -233.218666) (xy 83.875241 -233.266198)
			(xy 83.852551 -233.31073) (xy 83.823175 -233.351163) (xy 83.787835 -233.386503) (xy 83.747402 -233.415879)
			(xy 83.70287 -233.438569) (xy 83.655338 -233.454013) (xy 83.605975 -233.461832) (xy 83.555997 -233.461832)
			(xy 83.506634 -233.454013) (xy 83.459102 -233.438569) (xy 83.41457 -233.415879) (xy 83.374137 -233.386503)
			(xy 83.338797 -233.351163) (xy 83.309421 -233.31073) (xy 83.286731 -233.266198) (xy 83.271287 -233.218666)
			(xy 83.263468 -233.169303) (xy 82.956151 -233.169303) (xy 82.956142 -233.16976) (xy 82.947978 -233.219994)
			(xy 82.931862 -233.268268) (xy 82.908211 -233.313331) (xy 82.877638 -233.354017) (xy 82.840934 -233.389272)
			(xy 82.79905 -233.418182) (xy 82.753071 -233.439999) (xy 82.704187 -233.454159) (xy 82.653666 -233.460293)
			(xy 82.602814 -233.458244) (xy 82.55295 -233.448064) (xy 82.505364 -233.430017) (xy 82.46129 -233.404571)
			(xy 82.421868 -233.372384) (xy 82.38812 -233.33429) (xy 82.360919 -233.291276) (xy 82.340971 -233.244456)
			(xy 82.328792 -233.195042) (xy 82.324697 -233.144314) (xy 82.01914 -233.144314) (xy 82.01865 -233.169303)
			(xy 82.010831 -233.218666) (xy 81.995387 -233.266198) (xy 81.972697 -233.31073) (xy 81.943321 -233.351163)
			(xy 81.907981 -233.386503) (xy 81.867548 -233.415879) (xy 81.823016 -233.438569) (xy 81.775484 -233.454013)
			(xy 81.726121 -233.461832) (xy 81.676143 -233.461832) (xy 81.62678 -233.454013) (xy 81.579248 -233.438569)
			(xy 81.534716 -233.415879) (xy 81.494283 -233.386503) (xy 81.458943 -233.351163) (xy 81.429567 -233.31073)
			(xy 81.406877 -233.266198) (xy 81.391433 -233.218666) (xy 81.383614 -233.169303) (xy 81.076297 -233.169303)
			(xy 81.076288 -233.16976) (xy 81.068124 -233.219994) (xy 81.052008 -233.268268) (xy 81.028357 -233.313331)
			(xy 80.997784 -233.354017) (xy 80.96108 -233.389272) (xy 80.919196 -233.418182) (xy 80.873217 -233.439999)
			(xy 80.824333 -233.454159) (xy 80.773812 -233.460293) (xy 80.72296 -233.458244) (xy 80.673096 -233.448064)
			(xy 80.62551 -233.430017) (xy 80.581436 -233.404571) (xy 80.542014 -233.372384) (xy 80.508266 -233.33429)
			(xy 80.481065 -233.291276) (xy 80.461117 -233.244456) (xy 80.448938 -233.195042) (xy 80.444843 -233.144314)
			(xy 80.138758 -233.144314) (xy 80.138758 -233.169307) (xy 80.130934 -233.218705) (xy 80.11548 -233.266271)
			(xy 80.092775 -233.310834) (xy 80.063379 -233.351297) (xy 80.028015 -233.386663) (xy 79.987555 -233.416062)
			(xy 79.942993 -233.43877) (xy 79.895428 -233.454228) (xy 79.846031 -233.462056) (xy 79.821024 -233.462576)
			(xy 79.796529 -233.462128) (xy 79.748117 -233.45463) (xy 79.701424 -233.439807) (xy 79.679292 -233.429302)
			(xy 79.66584 -233.423179) (xy 79.636727 -233.418158) (xy 79.607394 -233.421676) (xy 79.580294 -233.433439)
			(xy 79.557692 -233.452464) (xy 79.541478 -233.47716) (xy 79.533007 -233.505463) (xy 79.53248 -233.520234)
			(xy 79.53248 -233.979309) (xy 79.97366 -233.979309) (xy 79.97366 -233.929331) (xy 79.981479 -233.879968)
			(xy 79.996923 -233.832436) (xy 80.019613 -233.787904) (xy 80.048989 -233.747471) (xy 80.084329 -233.712131)
			(xy 80.124762 -233.682755) (xy 80.169294 -233.660065) (xy 80.216826 -233.644621) (xy 80.266189 -233.636802)
			(xy 80.316167 -233.636802) (xy 80.36553 -233.644621) (xy 80.413062 -233.660065) (xy 80.457594 -233.682755)
			(xy 80.498027 -233.712131) (xy 80.533367 -233.747471) (xy 80.562743 -233.787904) (xy 80.585433 -233.832436)
			(xy 80.600877 -233.879968) (xy 80.608696 -233.929331) (xy 80.609186 -233.95432) (xy 80.914743 -233.95432)
			(xy 80.918838 -233.903592) (xy 80.931017 -233.854178) (xy 80.950965 -233.807358) (xy 80.978166 -233.764344)
			(xy 81.011914 -233.72625) (xy 81.051336 -233.694063) (xy 81.09541 -233.668617) (xy 81.142996 -233.65057)
			(xy 81.19286 -233.64039) (xy 81.243712 -233.638341) (xy 81.294233 -233.644475) (xy 81.343117 -233.658635)
			(xy 81.389096 -233.680452) (xy 81.43098 -233.709362) (xy 81.467684 -233.744617) (xy 81.498257 -233.785303)
			(xy 81.521908 -233.830366) (xy 81.538024 -233.87864) (xy 81.546188 -233.928874) (xy 81.5467 -233.95432)
			(xy 81.854797 -233.95432) (xy 81.858892 -233.903592) (xy 81.871071 -233.854178) (xy 81.891019 -233.807358)
			(xy 81.91822 -233.764344) (xy 81.951968 -233.72625) (xy 81.99139 -233.694063) (xy 82.035464 -233.668617)
			(xy 82.08305 -233.65057) (xy 82.132914 -233.64039) (xy 82.183766 -233.638341) (xy 82.234287 -233.644475)
			(xy 82.283171 -233.658635) (xy 82.32915 -233.680452) (xy 82.371034 -233.709362) (xy 82.407738 -233.744617)
			(xy 82.438311 -233.785303) (xy 82.461962 -233.830366) (xy 82.478078 -233.87864) (xy 82.486242 -233.928874)
			(xy 82.486754 -233.95432) (xy 82.486251 -233.979309) (xy 82.793568 -233.979309) (xy 82.793568 -233.929331)
			(xy 82.801387 -233.879968) (xy 82.816831 -233.832436) (xy 82.839521 -233.787904) (xy 82.868897 -233.747471)
			(xy 82.904237 -233.712131) (xy 82.94467 -233.682755) (xy 82.989202 -233.660065) (xy 83.036734 -233.644621)
			(xy 83.086097 -233.636802) (xy 83.136075 -233.636802) (xy 83.185438 -233.644621) (xy 83.23297 -233.660065)
			(xy 83.277502 -233.682755) (xy 83.317935 -233.712131) (xy 83.353275 -233.747471) (xy 83.382651 -233.787904)
			(xy 83.405341 -233.832436) (xy 83.420785 -233.879968) (xy 83.428604 -233.929331) (xy 83.429094 -233.95432)
			(xy 83.734905 -233.95432) (xy 83.739 -233.903592) (xy 83.751179 -233.854178) (xy 83.771127 -233.807358)
			(xy 83.798328 -233.764344) (xy 83.832076 -233.72625) (xy 83.871498 -233.694063) (xy 83.915572 -233.668617)
			(xy 83.963158 -233.65057) (xy 84.013022 -233.64039) (xy 84.063874 -233.638341) (xy 84.114395 -233.644475)
			(xy 84.163279 -233.658635) (xy 84.209258 -233.680452) (xy 84.251142 -233.709362) (xy 84.287846 -233.744617)
			(xy 84.318419 -233.785303) (xy 84.34207 -233.830366) (xy 84.358186 -233.87864) (xy 84.36635 -233.928874)
			(xy 84.366862 -233.95432) (xy 84.366359 -233.979309) (xy 84.673422 -233.979309) (xy 84.673422 -233.929331)
			(xy 84.681241 -233.879968) (xy 84.696685 -233.832436) (xy 84.719375 -233.787904) (xy 84.748751 -233.747471)
			(xy 84.784091 -233.712131) (xy 84.824524 -233.682755) (xy 84.869056 -233.660065) (xy 84.916588 -233.644621)
			(xy 84.965951 -233.636802) (xy 85.015929 -233.636802) (xy 85.065292 -233.644621) (xy 85.112824 -233.660065)
			(xy 85.157356 -233.682755) (xy 85.197789 -233.712131) (xy 85.233129 -233.747471) (xy 85.262505 -233.787904)
			(xy 85.285195 -233.832436) (xy 85.300639 -233.879968) (xy 85.308458 -233.929331) (xy 85.308948 -233.95432)
			(xy 85.614759 -233.95432) (xy 85.618854 -233.903592) (xy 85.631033 -233.854178) (xy 85.650981 -233.807358)
			(xy 85.678182 -233.764344) (xy 85.71193 -233.72625) (xy 85.751352 -233.694063) (xy 85.795426 -233.668617)
			(xy 85.843012 -233.65057) (xy 85.892876 -233.64039) (xy 85.943728 -233.638341) (xy 85.994249 -233.644475)
			(xy 86.043133 -233.658635) (xy 86.089112 -233.680452) (xy 86.130996 -233.709362) (xy 86.1677 -233.744617)
			(xy 86.198273 -233.785303) (xy 86.221924 -233.830366) (xy 86.23804 -233.87864) (xy 86.246204 -233.928874)
			(xy 86.246716 -233.95432) (xy 86.246213 -233.979309) (xy 86.55353 -233.979309) (xy 86.55353 -233.929331)
			(xy 86.561349 -233.879968) (xy 86.576793 -233.832436) (xy 86.599483 -233.787904) (xy 86.628859 -233.747471)
			(xy 86.664199 -233.712131) (xy 86.704632 -233.682755) (xy 86.749164 -233.660065) (xy 86.796696 -233.644621)
			(xy 86.846059 -233.636802) (xy 86.896037 -233.636802) (xy 86.9454 -233.644621) (xy 86.992932 -233.660065)
			(xy 87.037464 -233.682755) (xy 87.077897 -233.712131) (xy 87.113237 -233.747471) (xy 87.142613 -233.787904)
			(xy 87.165303 -233.832436) (xy 87.180747 -233.879968) (xy 87.188566 -233.929331) (xy 87.189056 -233.95432)
			(xy 87.494867 -233.95432) (xy 87.498962 -233.903592) (xy 87.511141 -233.854178) (xy 87.531089 -233.807358)
			(xy 87.55829 -233.764344) (xy 87.592038 -233.72625) (xy 87.63146 -233.694063) (xy 87.675534 -233.668617)
			(xy 87.72312 -233.65057) (xy 87.772984 -233.64039) (xy 87.823836 -233.638341) (xy 87.874357 -233.644475)
			(xy 87.923241 -233.658635) (xy 87.96922 -233.680452) (xy 88.011104 -233.709362) (xy 88.047808 -233.744617)
			(xy 88.078381 -233.785303) (xy 88.102032 -233.830366) (xy 88.118148 -233.87864) (xy 88.126312 -233.928874)
			(xy 88.126824 -233.95432) (xy 88.434921 -233.95432) (xy 88.439016 -233.903592) (xy 88.451195 -233.854178)
			(xy 88.471143 -233.807358) (xy 88.498344 -233.764344) (xy 88.532092 -233.72625) (xy 88.571514 -233.694063)
			(xy 88.615588 -233.668617) (xy 88.663174 -233.65057) (xy 88.713038 -233.64039) (xy 88.76389 -233.638341)
			(xy 88.814411 -233.644475) (xy 88.863295 -233.658635) (xy 88.909274 -233.680452) (xy 88.951158 -233.709362)
			(xy 88.987862 -233.744617) (xy 89.018435 -233.785303) (xy 89.042086 -233.830366) (xy 89.058202 -233.87864)
			(xy 89.066366 -233.928874) (xy 89.066878 -233.95432) (xy 89.066375 -233.979309) (xy 89.373438 -233.979309)
			(xy 89.373438 -233.929331) (xy 89.381257 -233.879968) (xy 89.396701 -233.832436) (xy 89.419391 -233.787904)
			(xy 89.448767 -233.747471) (xy 89.484107 -233.712131) (xy 89.52454 -233.682755) (xy 89.569072 -233.660065)
			(xy 89.616604 -233.644621) (xy 89.665967 -233.636802) (xy 89.715945 -233.636802) (xy 89.765308 -233.644621)
			(xy 89.81284 -233.660065) (xy 89.857372 -233.682755) (xy 89.897805 -233.712131) (xy 89.933145 -233.747471)
			(xy 89.962521 -233.787904) (xy 89.985211 -233.832436) (xy 90.000655 -233.879968) (xy 90.008474 -233.929331)
			(xy 90.008964 -233.95432) (xy 90.314775 -233.95432) (xy 90.31887 -233.903592) (xy 90.331049 -233.854178)
			(xy 90.350997 -233.807358) (xy 90.378198 -233.764344) (xy 90.411946 -233.72625) (xy 90.451368 -233.694063)
			(xy 90.495442 -233.668617) (xy 90.543028 -233.65057) (xy 90.592892 -233.64039) (xy 90.643744 -233.638341)
			(xy 90.694265 -233.644475) (xy 90.743149 -233.658635) (xy 90.789128 -233.680452) (xy 90.831012 -233.709362)
			(xy 90.867716 -233.744617) (xy 90.898289 -233.785303) (xy 90.92194 -233.830366) (xy 90.938056 -233.87864)
			(xy 90.94622 -233.928874) (xy 90.946732 -233.95432) (xy 90.946229 -233.979309) (xy 91.253546 -233.979309)
			(xy 91.253546 -233.929331) (xy 91.261365 -233.879968) (xy 91.276809 -233.832436) (xy 91.299499 -233.787904)
			(xy 91.328875 -233.747471) (xy 91.364215 -233.712131) (xy 91.404648 -233.682755) (xy 91.44918 -233.660065)
			(xy 91.496712 -233.644621) (xy 91.546075 -233.636802) (xy 91.596053 -233.636802) (xy 91.645416 -233.644621)
			(xy 91.692948 -233.660065) (xy 91.73748 -233.682755) (xy 91.777913 -233.712131) (xy 91.813253 -233.747471)
			(xy 91.842629 -233.787904) (xy 91.865319 -233.832436) (xy 91.880763 -233.879968) (xy 91.888582 -233.929331)
			(xy 91.889072 -233.95432) (xy 92.194883 -233.95432) (xy 92.198978 -233.903592) (xy 92.211157 -233.854178)
			(xy 92.231105 -233.807358) (xy 92.258306 -233.764344) (xy 92.292054 -233.72625) (xy 92.331476 -233.694063)
			(xy 92.37555 -233.668617) (xy 92.423136 -233.65057) (xy 92.473 -233.64039) (xy 92.523852 -233.638341)
			(xy 92.574373 -233.644475) (xy 92.623257 -233.658635) (xy 92.669236 -233.680452) (xy 92.71112 -233.709362)
			(xy 92.747824 -233.744617) (xy 92.778397 -233.785303) (xy 92.802048 -233.830366) (xy 92.818164 -233.87864)
			(xy 92.826328 -233.928874) (xy 92.82684 -233.95432) (xy 92.826337 -233.979309) (xy 93.1334 -233.979309)
			(xy 93.1334 -233.929331) (xy 93.141219 -233.879968) (xy 93.156663 -233.832436) (xy 93.179353 -233.787904)
			(xy 93.208729 -233.747471) (xy 93.244069 -233.712131) (xy 93.284502 -233.682755) (xy 93.329034 -233.660065)
			(xy 93.376566 -233.644621) (xy 93.425929 -233.636802) (xy 93.475907 -233.636802) (xy 93.52527 -233.644621)
			(xy 93.572802 -233.660065) (xy 93.617334 -233.682755) (xy 93.657767 -233.712131) (xy 93.693107 -233.747471)
			(xy 93.722483 -233.787904) (xy 93.745173 -233.832436) (xy 93.760617 -233.879968) (xy 93.768436 -233.929331)
			(xy 93.768926 -233.95432) (xy 94.074737 -233.95432) (xy 94.078832 -233.903592) (xy 94.091011 -233.854178)
			(xy 94.110959 -233.807358) (xy 94.13816 -233.764344) (xy 94.171908 -233.72625) (xy 94.21133 -233.694063)
			(xy 94.255404 -233.668617) (xy 94.30299 -233.65057) (xy 94.352854 -233.64039) (xy 94.403706 -233.638341)
			(xy 94.454227 -233.644475) (xy 94.503111 -233.658635) (xy 94.54909 -233.680452) (xy 94.590974 -233.709362)
			(xy 94.627678 -233.744617) (xy 94.658251 -233.785303) (xy 94.681902 -233.830366) (xy 94.698018 -233.87864)
			(xy 94.706182 -233.928874) (xy 94.706694 -233.95432) (xy 95.014791 -233.95432) (xy 95.018886 -233.903592)
			(xy 95.031065 -233.854178) (xy 95.051013 -233.807358) (xy 95.078214 -233.764344) (xy 95.111962 -233.72625)
			(xy 95.151384 -233.694063) (xy 95.195458 -233.668617) (xy 95.243044 -233.65057) (xy 95.292908 -233.64039)
			(xy 95.34376 -233.638341) (xy 95.394281 -233.644475) (xy 95.443165 -233.658635) (xy 95.489144 -233.680452)
			(xy 95.531028 -233.709362) (xy 95.567732 -233.744617) (xy 95.598305 -233.785303) (xy 95.621956 -233.830366)
			(xy 95.638072 -233.87864) (xy 95.646236 -233.928874) (xy 95.646748 -233.95432) (xy 95.646245 -233.979309)
			(xy 95.953562 -233.979309) (xy 95.953562 -233.929331) (xy 95.961381 -233.879968) (xy 95.976825 -233.832436)
			(xy 95.999515 -233.787904) (xy 96.028891 -233.747471) (xy 96.064231 -233.712131) (xy 96.104664 -233.682755)
			(xy 96.149196 -233.660065) (xy 96.196728 -233.644621) (xy 96.246091 -233.636802) (xy 96.296069 -233.636802)
			(xy 96.345432 -233.644621) (xy 96.392964 -233.660065) (xy 96.437496 -233.682755) (xy 96.477929 -233.712131)
			(xy 96.513269 -233.747471) (xy 96.542645 -233.787904) (xy 96.565335 -233.832436) (xy 96.580779 -233.879968)
			(xy 96.588598 -233.929331) (xy 96.589088 -233.95432) (xy 96.588598 -233.979309) (xy 96.580779 -234.028672)
			(xy 96.565335 -234.076204) (xy 96.542645 -234.120736) (xy 96.513269 -234.161169) (xy 96.477929 -234.196509)
			(xy 96.437496 -234.225885) (xy 96.392964 -234.248575) (xy 96.345432 -234.264019) (xy 96.296069 -234.271838)
			(xy 96.246091 -234.271838) (xy 96.196728 -234.264019) (xy 96.149196 -234.248575) (xy 96.104664 -234.225885)
			(xy 96.064231 -234.196509) (xy 96.028891 -234.161169) (xy 95.999515 -234.120736) (xy 95.976825 -234.076204)
			(xy 95.961381 -234.028672) (xy 95.953562 -233.979309) (xy 95.646245 -233.979309) (xy 95.646236 -233.979766)
			(xy 95.638072 -234.03) (xy 95.621956 -234.078274) (xy 95.598305 -234.123337) (xy 95.567732 -234.164023)
			(xy 95.531028 -234.199278) (xy 95.489144 -234.228188) (xy 95.443165 -234.250005) (xy 95.394281 -234.264165)
			(xy 95.34376 -234.270299) (xy 95.292908 -234.26825) (xy 95.243044 -234.25807) (xy 95.195458 -234.240023)
			(xy 95.151384 -234.214577) (xy 95.111962 -234.18239) (xy 95.078214 -234.144296) (xy 95.051013 -234.101282)
			(xy 95.031065 -234.054462) (xy 95.018886 -234.005048) (xy 95.014791 -233.95432) (xy 94.706694 -233.95432)
			(xy 94.706182 -233.979766) (xy 94.698018 -234.03) (xy 94.681902 -234.078274) (xy 94.658251 -234.123337)
			(xy 94.627678 -234.164023) (xy 94.590974 -234.199278) (xy 94.54909 -234.228188) (xy 94.503111 -234.250005)
			(xy 94.454227 -234.264165) (xy 94.403706 -234.270299) (xy 94.352854 -234.26825) (xy 94.30299 -234.25807)
			(xy 94.255404 -234.240023) (xy 94.21133 -234.214577) (xy 94.171908 -234.18239) (xy 94.13816 -234.144296)
			(xy 94.110959 -234.101282) (xy 94.091011 -234.054462) (xy 94.078832 -234.005048) (xy 94.074737 -233.95432)
			(xy 93.768926 -233.95432) (xy 93.768436 -233.979309) (xy 93.760617 -234.028672) (xy 93.745173 -234.076204)
			(xy 93.722483 -234.120736) (xy 93.693107 -234.161169) (xy 93.657767 -234.196509) (xy 93.617334 -234.225885)
			(xy 93.572802 -234.248575) (xy 93.52527 -234.264019) (xy 93.475907 -234.271838) (xy 93.425929 -234.271838)
			(xy 93.376566 -234.264019) (xy 93.329034 -234.248575) (xy 93.284502 -234.225885) (xy 93.244069 -234.196509)
			(xy 93.208729 -234.161169) (xy 93.179353 -234.120736) (xy 93.156663 -234.076204) (xy 93.141219 -234.028672)
			(xy 93.1334 -233.979309) (xy 92.826337 -233.979309) (xy 92.826328 -233.979766) (xy 92.818164 -234.03)
			(xy 92.802048 -234.078274) (xy 92.778397 -234.123337) (xy 92.747824 -234.164023) (xy 92.71112 -234.199278)
			(xy 92.669236 -234.228188) (xy 92.623257 -234.250005) (xy 92.574373 -234.264165) (xy 92.523852 -234.270299)
			(xy 92.473 -234.26825) (xy 92.423136 -234.25807) (xy 92.37555 -234.240023) (xy 92.331476 -234.214577)
			(xy 92.292054 -234.18239) (xy 92.258306 -234.144296) (xy 92.231105 -234.101282) (xy 92.211157 -234.054462)
			(xy 92.198978 -234.005048) (xy 92.194883 -233.95432) (xy 91.889072 -233.95432) (xy 91.888582 -233.979309)
			(xy 91.880763 -234.028672) (xy 91.865319 -234.076204) (xy 91.842629 -234.120736) (xy 91.813253 -234.161169)
			(xy 91.777913 -234.196509) (xy 91.73748 -234.225885) (xy 91.692948 -234.248575) (xy 91.645416 -234.264019)
			(xy 91.596053 -234.271838) (xy 91.546075 -234.271838) (xy 91.496712 -234.264019) (xy 91.44918 -234.248575)
			(xy 91.404648 -234.225885) (xy 91.364215 -234.196509) (xy 91.328875 -234.161169) (xy 91.299499 -234.120736)
			(xy 91.276809 -234.076204) (xy 91.261365 -234.028672) (xy 91.253546 -233.979309) (xy 90.946229 -233.979309)
			(xy 90.94622 -233.979766) (xy 90.938056 -234.03) (xy 90.92194 -234.078274) (xy 90.898289 -234.123337)
			(xy 90.867716 -234.164023) (xy 90.831012 -234.199278) (xy 90.789128 -234.228188) (xy 90.743149 -234.250005)
			(xy 90.694265 -234.264165) (xy 90.643744 -234.270299) (xy 90.592892 -234.26825) (xy 90.543028 -234.25807)
			(xy 90.495442 -234.240023) (xy 90.451368 -234.214577) (xy 90.411946 -234.18239) (xy 90.378198 -234.144296)
			(xy 90.350997 -234.101282) (xy 90.331049 -234.054462) (xy 90.31887 -234.005048) (xy 90.314775 -233.95432)
			(xy 90.008964 -233.95432) (xy 90.008474 -233.979309) (xy 90.000655 -234.028672) (xy 89.985211 -234.076204)
			(xy 89.962521 -234.120736) (xy 89.933145 -234.161169) (xy 89.897805 -234.196509) (xy 89.857372 -234.225885)
			(xy 89.81284 -234.248575) (xy 89.765308 -234.264019) (xy 89.715945 -234.271838) (xy 89.665967 -234.271838)
			(xy 89.616604 -234.264019) (xy 89.569072 -234.248575) (xy 89.52454 -234.225885) (xy 89.484107 -234.196509)
			(xy 89.448767 -234.161169) (xy 89.419391 -234.120736) (xy 89.396701 -234.076204) (xy 89.381257 -234.028672)
			(xy 89.373438 -233.979309) (xy 89.066375 -233.979309) (xy 89.066366 -233.979766) (xy 89.058202 -234.03)
			(xy 89.042086 -234.078274) (xy 89.018435 -234.123337) (xy 88.987862 -234.164023) (xy 88.951158 -234.199278)
			(xy 88.909274 -234.228188) (xy 88.863295 -234.250005) (xy 88.814411 -234.264165) (xy 88.76389 -234.270299)
			(xy 88.713038 -234.26825) (xy 88.663174 -234.25807) (xy 88.615588 -234.240023) (xy 88.571514 -234.214577)
			(xy 88.532092 -234.18239) (xy 88.498344 -234.144296) (xy 88.471143 -234.101282) (xy 88.451195 -234.054462)
			(xy 88.439016 -234.005048) (xy 88.434921 -233.95432) (xy 88.126824 -233.95432) (xy 88.126312 -233.979766)
			(xy 88.118148 -234.03) (xy 88.102032 -234.078274) (xy 88.078381 -234.123337) (xy 88.047808 -234.164023)
			(xy 88.011104 -234.199278) (xy 87.96922 -234.228188) (xy 87.923241 -234.250005) (xy 87.874357 -234.264165)
			(xy 87.823836 -234.270299) (xy 87.772984 -234.26825) (xy 87.72312 -234.25807) (xy 87.675534 -234.240023)
			(xy 87.63146 -234.214577) (xy 87.592038 -234.18239) (xy 87.55829 -234.144296) (xy 87.531089 -234.101282)
			(xy 87.511141 -234.054462) (xy 87.498962 -234.005048) (xy 87.494867 -233.95432) (xy 87.189056 -233.95432)
			(xy 87.188566 -233.979309) (xy 87.180747 -234.028672) (xy 87.165303 -234.076204) (xy 87.142613 -234.120736)
			(xy 87.113237 -234.161169) (xy 87.077897 -234.196509) (xy 87.037464 -234.225885) (xy 86.992932 -234.248575)
			(xy 86.9454 -234.264019) (xy 86.896037 -234.271838) (xy 86.846059 -234.271838) (xy 86.796696 -234.264019)
			(xy 86.749164 -234.248575) (xy 86.704632 -234.225885) (xy 86.664199 -234.196509) (xy 86.628859 -234.161169)
			(xy 86.599483 -234.120736) (xy 86.576793 -234.076204) (xy 86.561349 -234.028672) (xy 86.55353 -233.979309)
			(xy 86.246213 -233.979309) (xy 86.246204 -233.979766) (xy 86.23804 -234.03) (xy 86.221924 -234.078274)
			(xy 86.198273 -234.123337) (xy 86.1677 -234.164023) (xy 86.130996 -234.199278) (xy 86.089112 -234.228188)
			(xy 86.043133 -234.250005) (xy 85.994249 -234.264165) (xy 85.943728 -234.270299) (xy 85.892876 -234.26825)
			(xy 85.843012 -234.25807) (xy 85.795426 -234.240023) (xy 85.751352 -234.214577) (xy 85.71193 -234.18239)
			(xy 85.678182 -234.144296) (xy 85.650981 -234.101282) (xy 85.631033 -234.054462) (xy 85.618854 -234.005048)
			(xy 85.614759 -233.95432) (xy 85.308948 -233.95432) (xy 85.308458 -233.979309) (xy 85.300639 -234.028672)
			(xy 85.285195 -234.076204) (xy 85.262505 -234.120736) (xy 85.233129 -234.161169) (xy 85.197789 -234.196509)
			(xy 85.157356 -234.225885) (xy 85.112824 -234.248575) (xy 85.065292 -234.264019) (xy 85.015929 -234.271838)
			(xy 84.965951 -234.271838) (xy 84.916588 -234.264019) (xy 84.869056 -234.248575) (xy 84.824524 -234.225885)
			(xy 84.784091 -234.196509) (xy 84.748751 -234.161169) (xy 84.719375 -234.120736) (xy 84.696685 -234.076204)
			(xy 84.681241 -234.028672) (xy 84.673422 -233.979309) (xy 84.366359 -233.979309) (xy 84.36635 -233.979766)
			(xy 84.358186 -234.03) (xy 84.34207 -234.078274) (xy 84.318419 -234.123337) (xy 84.287846 -234.164023)
			(xy 84.251142 -234.199278) (xy 84.209258 -234.228188) (xy 84.163279 -234.250005) (xy 84.114395 -234.264165)
			(xy 84.063874 -234.270299) (xy 84.013022 -234.26825) (xy 83.963158 -234.25807) (xy 83.915572 -234.240023)
			(xy 83.871498 -234.214577) (xy 83.832076 -234.18239) (xy 83.798328 -234.144296) (xy 83.771127 -234.101282)
			(xy 83.751179 -234.054462) (xy 83.739 -234.005048) (xy 83.734905 -233.95432) (xy 83.429094 -233.95432)
			(xy 83.428604 -233.979309) (xy 83.420785 -234.028672) (xy 83.405341 -234.076204) (xy 83.382651 -234.120736)
			(xy 83.353275 -234.161169) (xy 83.317935 -234.196509) (xy 83.277502 -234.225885) (xy 83.23297 -234.248575)
			(xy 83.185438 -234.264019) (xy 83.136075 -234.271838) (xy 83.086097 -234.271838) (xy 83.036734 -234.264019)
			(xy 82.989202 -234.248575) (xy 82.94467 -234.225885) (xy 82.904237 -234.196509) (xy 82.868897 -234.161169)
			(xy 82.839521 -234.120736) (xy 82.816831 -234.076204) (xy 82.801387 -234.028672) (xy 82.793568 -233.979309)
			(xy 82.486251 -233.979309) (xy 82.486242 -233.979766) (xy 82.478078 -234.03) (xy 82.461962 -234.078274)
			(xy 82.438311 -234.123337) (xy 82.407738 -234.164023) (xy 82.371034 -234.199278) (xy 82.32915 -234.228188)
			(xy 82.283171 -234.250005) (xy 82.234287 -234.264165) (xy 82.183766 -234.270299) (xy 82.132914 -234.26825)
			(xy 82.08305 -234.25807) (xy 82.035464 -234.240023) (xy 81.99139 -234.214577) (xy 81.951968 -234.18239)
			(xy 81.91822 -234.144296) (xy 81.891019 -234.101282) (xy 81.871071 -234.054462) (xy 81.858892 -234.005048)
			(xy 81.854797 -233.95432) (xy 81.5467 -233.95432) (xy 81.546188 -233.979766) (xy 81.538024 -234.03)
			(xy 81.521908 -234.078274) (xy 81.498257 -234.123337) (xy 81.467684 -234.164023) (xy 81.43098 -234.199278)
			(xy 81.389096 -234.228188) (xy 81.343117 -234.250005) (xy 81.294233 -234.264165) (xy 81.243712 -234.270299)
			(xy 81.19286 -234.26825) (xy 81.142996 -234.25807) (xy 81.09541 -234.240023) (xy 81.051336 -234.214577)
			(xy 81.011914 -234.18239) (xy 80.978166 -234.144296) (xy 80.950965 -234.101282) (xy 80.931017 -234.054462)
			(xy 80.918838 -234.005048) (xy 80.914743 -233.95432) (xy 80.609186 -233.95432) (xy 80.608696 -233.979309)
			(xy 80.600877 -234.028672) (xy 80.585433 -234.076204) (xy 80.562743 -234.120736) (xy 80.533367 -234.161169)
			(xy 80.498027 -234.196509) (xy 80.457594 -234.225885) (xy 80.413062 -234.248575) (xy 80.36553 -234.264019)
			(xy 80.316167 -234.271838) (xy 80.266189 -234.271838) (xy 80.216826 -234.264019) (xy 80.169294 -234.248575)
			(xy 80.124762 -234.225885) (xy 80.084329 -234.196509) (xy 80.048989 -234.161169) (xy 80.019613 -234.120736)
			(xy 79.996923 -234.076204) (xy 79.981479 -234.028672) (xy 79.97366 -233.979309) (xy 79.53248 -233.979309)
			(xy 79.53248 -234.764326) (xy 80.444843 -234.764326) (xy 80.448938 -234.713598) (xy 80.461117 -234.664184)
			(xy 80.481065 -234.617364) (xy 80.508266 -234.57435) (xy 80.542014 -234.536256) (xy 80.581436 -234.504069)
			(xy 80.62551 -234.478623) (xy 80.673096 -234.460576) (xy 80.72296 -234.450396) (xy 80.773812 -234.448347)
			(xy 80.824333 -234.454481) (xy 80.873217 -234.468641) (xy 80.919196 -234.490458) (xy 80.96108 -234.519368)
			(xy 80.997784 -234.554623) (xy 81.028357 -234.595309) (xy 81.052008 -234.640372) (xy 81.068124 -234.688646)
			(xy 81.076288 -234.73888) (xy 81.0768 -234.764326) (xy 81.076297 -234.789315) (xy 81.383614 -234.789315)
			(xy 81.383614 -234.739337) (xy 81.391433 -234.689974) (xy 81.406877 -234.642442) (xy 81.429567 -234.59791)
			(xy 81.458943 -234.557477) (xy 81.494283 -234.522137) (xy 81.534716 -234.492761) (xy 81.579248 -234.470071)
			(xy 81.62678 -234.454627) (xy 81.676143 -234.446808) (xy 81.726121 -234.446808) (xy 81.775484 -234.454627)
			(xy 81.823016 -234.470071) (xy 81.867548 -234.492761) (xy 81.907981 -234.522137) (xy 81.943321 -234.557477)
			(xy 81.972697 -234.59791) (xy 81.995387 -234.642442) (xy 82.010831 -234.689974) (xy 82.01865 -234.739337)
			(xy 82.01914 -234.764326) (xy 82.324697 -234.764326) (xy 82.328792 -234.713598) (xy 82.340971 -234.664184)
			(xy 82.360919 -234.617364) (xy 82.38812 -234.57435) (xy 82.421868 -234.536256) (xy 82.46129 -234.504069)
			(xy 82.505364 -234.478623) (xy 82.55295 -234.460576) (xy 82.602814 -234.450396) (xy 82.653666 -234.448347)
			(xy 82.704187 -234.454481) (xy 82.753071 -234.468641) (xy 82.79905 -234.490458) (xy 82.840934 -234.519368)
			(xy 82.877638 -234.554623) (xy 82.908211 -234.595309) (xy 82.931862 -234.640372) (xy 82.947978 -234.688646)
			(xy 82.956142 -234.73888) (xy 82.956654 -234.764326) (xy 82.956151 -234.789315) (xy 83.263468 -234.789315)
			(xy 83.263468 -234.739337) (xy 83.271287 -234.689974) (xy 83.286731 -234.642442) (xy 83.309421 -234.59791)
			(xy 83.338797 -234.557477) (xy 83.374137 -234.522137) (xy 83.41457 -234.492761) (xy 83.459102 -234.470071)
			(xy 83.506634 -234.454627) (xy 83.555997 -234.446808) (xy 83.605975 -234.446808) (xy 83.655338 -234.454627)
			(xy 83.70287 -234.470071) (xy 83.747402 -234.492761) (xy 83.787835 -234.522137) (xy 83.823175 -234.557477)
			(xy 83.852551 -234.59791) (xy 83.875241 -234.642442) (xy 83.890685 -234.689974) (xy 83.898504 -234.739337)
			(xy 83.898994 -234.764326) (xy 84.204805 -234.764326) (xy 84.2089 -234.713598) (xy 84.221079 -234.664184)
			(xy 84.241027 -234.617364) (xy 84.268228 -234.57435) (xy 84.301976 -234.536256) (xy 84.341398 -234.504069)
			(xy 84.385472 -234.478623) (xy 84.433058 -234.460576) (xy 84.482922 -234.450396) (xy 84.533774 -234.448347)
			(xy 84.584295 -234.454481) (xy 84.633179 -234.468641) (xy 84.679158 -234.490458) (xy 84.721042 -234.519368)
			(xy 84.757746 -234.554623) (xy 84.788319 -234.595309) (xy 84.81197 -234.640372) (xy 84.828086 -234.688646)
			(xy 84.83625 -234.73888) (xy 84.836762 -234.764326) (xy 85.144859 -234.764326) (xy 85.148954 -234.713598)
			(xy 85.161133 -234.664184) (xy 85.181081 -234.617364) (xy 85.208282 -234.57435) (xy 85.24203 -234.536256)
			(xy 85.281452 -234.504069) (xy 85.325526 -234.478623) (xy 85.373112 -234.460576) (xy 85.422976 -234.450396)
			(xy 85.473828 -234.448347) (xy 85.524349 -234.454481) (xy 85.573233 -234.468641) (xy 85.619212 -234.490458)
			(xy 85.661096 -234.519368) (xy 85.6978 -234.554623) (xy 85.728373 -234.595309) (xy 85.752024 -234.640372)
			(xy 85.76814 -234.688646) (xy 85.776304 -234.73888) (xy 85.776816 -234.764326) (xy 87.024713 -234.764326)
			(xy 87.028808 -234.713598) (xy 87.040987 -234.664184) (xy 87.060935 -234.617364) (xy 87.088136 -234.57435)
			(xy 87.121884 -234.536256) (xy 87.161306 -234.504069) (xy 87.20538 -234.478623) (xy 87.252966 -234.460576)
			(xy 87.30283 -234.450396) (xy 87.353682 -234.448347) (xy 87.404203 -234.454481) (xy 87.453087 -234.468641)
			(xy 87.499066 -234.490458) (xy 87.54095 -234.519368) (xy 87.577654 -234.554623) (xy 87.608227 -234.595309)
			(xy 87.631878 -234.640372) (xy 87.647994 -234.688646) (xy 87.656158 -234.73888) (xy 87.65667 -234.764326)
			(xy 87.656167 -234.789315) (xy 87.963484 -234.789315) (xy 87.963484 -234.739337) (xy 87.971303 -234.689974)
			(xy 87.986747 -234.642442) (xy 88.009437 -234.59791) (xy 88.038813 -234.557477) (xy 88.074153 -234.522137)
			(xy 88.114586 -234.492761) (xy 88.159118 -234.470071) (xy 88.20665 -234.454627) (xy 88.256013 -234.446808)
			(xy 88.305991 -234.446808) (xy 88.355354 -234.454627) (xy 88.402886 -234.470071) (xy 88.447418 -234.492761)
			(xy 88.487851 -234.522137) (xy 88.523191 -234.557477) (xy 88.552567 -234.59791) (xy 88.575257 -234.642442)
			(xy 88.590701 -234.689974) (xy 88.59852 -234.739337) (xy 88.59901 -234.764326) (xy 88.904821 -234.764326)
			(xy 88.908916 -234.713598) (xy 88.921095 -234.664184) (xy 88.941043 -234.617364) (xy 88.968244 -234.57435)
			(xy 89.001992 -234.536256) (xy 89.041414 -234.504069) (xy 89.085488 -234.478623) (xy 89.133074 -234.460576)
			(xy 89.182938 -234.450396) (xy 89.23379 -234.448347) (xy 89.284311 -234.454481) (xy 89.333195 -234.468641)
			(xy 89.379174 -234.490458) (xy 89.421058 -234.519368) (xy 89.457762 -234.554623) (xy 89.488335 -234.595309)
			(xy 89.511986 -234.640372) (xy 89.528102 -234.688646) (xy 89.536266 -234.73888) (xy 89.536778 -234.764326)
			(xy 89.536275 -234.789315) (xy 89.843592 -234.789315) (xy 89.843592 -234.739337) (xy 89.851411 -234.689974)
			(xy 89.866855 -234.642442) (xy 89.889545 -234.59791) (xy 89.918921 -234.557477) (xy 89.954261 -234.522137)
			(xy 89.994694 -234.492761) (xy 90.039226 -234.470071) (xy 90.086758 -234.454627) (xy 90.136121 -234.446808)
			(xy 90.186099 -234.446808) (xy 90.235462 -234.454627) (xy 90.282994 -234.470071) (xy 90.327526 -234.492761)
			(xy 90.367959 -234.522137) (xy 90.403299 -234.557477) (xy 90.432675 -234.59791) (xy 90.455365 -234.642442)
			(xy 90.470809 -234.689974) (xy 90.478628 -234.739337) (xy 90.479118 -234.764326) (xy 90.784675 -234.764326)
			(xy 90.78877 -234.713598) (xy 90.800949 -234.664184) (xy 90.820897 -234.617364) (xy 90.848098 -234.57435)
			(xy 90.881846 -234.536256) (xy 90.921268 -234.504069) (xy 90.965342 -234.478623) (xy 91.012928 -234.460576)
			(xy 91.062792 -234.450396) (xy 91.113644 -234.448347) (xy 91.164165 -234.454481) (xy 91.213049 -234.468641)
			(xy 91.259028 -234.490458) (xy 91.300912 -234.519368) (xy 91.337616 -234.554623) (xy 91.368189 -234.595309)
			(xy 91.39184 -234.640372) (xy 91.407956 -234.688646) (xy 91.41612 -234.73888) (xy 91.416632 -234.764326)
			(xy 91.724729 -234.764326) (xy 91.728824 -234.713598) (xy 91.741003 -234.664184) (xy 91.760951 -234.617364)
			(xy 91.788152 -234.57435) (xy 91.8219 -234.536256) (xy 91.861322 -234.504069) (xy 91.905396 -234.478623)
			(xy 91.952982 -234.460576) (xy 92.002846 -234.450396) (xy 92.053698 -234.448347) (xy 92.104219 -234.454481)
			(xy 92.153103 -234.468641) (xy 92.199082 -234.490458) (xy 92.240966 -234.519368) (xy 92.27767 -234.554623)
			(xy 92.308243 -234.595309) (xy 92.331894 -234.640372) (xy 92.34801 -234.688646) (xy 92.356174 -234.73888)
			(xy 92.356686 -234.764326) (xy 93.604837 -234.764326) (xy 93.608932 -234.713598) (xy 93.621111 -234.664184)
			(xy 93.641059 -234.617364) (xy 93.66826 -234.57435) (xy 93.702008 -234.536256) (xy 93.74143 -234.504069)
			(xy 93.785504 -234.478623) (xy 93.83309 -234.460576) (xy 93.882954 -234.450396) (xy 93.933806 -234.448347)
			(xy 93.984327 -234.454481) (xy 94.033211 -234.468641) (xy 94.07919 -234.490458) (xy 94.121074 -234.519368)
			(xy 94.157778 -234.554623) (xy 94.188351 -234.595309) (xy 94.212002 -234.640372) (xy 94.228118 -234.688646)
			(xy 94.236282 -234.73888) (xy 94.236794 -234.764326) (xy 94.236291 -234.789315) (xy 94.543608 -234.789315)
			(xy 94.543608 -234.739337) (xy 94.551427 -234.689974) (xy 94.566871 -234.642442) (xy 94.589561 -234.59791)
			(xy 94.618937 -234.557477) (xy 94.654277 -234.522137) (xy 94.69471 -234.492761) (xy 94.739242 -234.470071)
			(xy 94.786774 -234.454627) (xy 94.836137 -234.446808) (xy 94.886115 -234.446808) (xy 94.935478 -234.454627)
			(xy 94.98301 -234.470071) (xy 95.027542 -234.492761) (xy 95.067975 -234.522137) (xy 95.103315 -234.557477)
			(xy 95.132691 -234.59791) (xy 95.155381 -234.642442) (xy 95.170825 -234.689974) (xy 95.178644 -234.739337)
			(xy 95.179134 -234.764326) (xy 95.484691 -234.764326) (xy 95.488786 -234.713598) (xy 95.500965 -234.664184)
			(xy 95.520913 -234.617364) (xy 95.548114 -234.57435) (xy 95.581862 -234.536256) (xy 95.621284 -234.504069)
			(xy 95.665358 -234.478623) (xy 95.712944 -234.460576) (xy 95.762808 -234.450396) (xy 95.81366 -234.448347)
			(xy 95.864181 -234.454481) (xy 95.913065 -234.468641) (xy 95.959044 -234.490458) (xy 96.000928 -234.519368)
			(xy 96.037632 -234.554623) (xy 96.068205 -234.595309) (xy 96.091856 -234.640372) (xy 96.107972 -234.688646)
			(xy 96.116136 -234.73888) (xy 96.116648 -234.764326) (xy 96.116136 -234.789772) (xy 96.107972 -234.840006)
			(xy 96.091856 -234.88828) (xy 96.068205 -234.933343) (xy 96.037632 -234.974029) (xy 96.000928 -235.009284)
			(xy 95.959044 -235.038194) (xy 95.913065 -235.060011) (xy 95.864181 -235.074171) (xy 95.81366 -235.080305)
			(xy 95.762808 -235.078256) (xy 95.712944 -235.068076) (xy 95.665358 -235.050029) (xy 95.621284 -235.024583)
			(xy 95.581862 -234.992396) (xy 95.548114 -234.954302) (xy 95.520913 -234.911288) (xy 95.500965 -234.864468)
			(xy 95.488786 -234.815054) (xy 95.484691 -234.764326) (xy 95.179134 -234.764326) (xy 95.178644 -234.789315)
			(xy 95.170825 -234.838678) (xy 95.155381 -234.88621) (xy 95.132691 -234.930742) (xy 95.103315 -234.971175)
			(xy 95.067975 -235.006515) (xy 95.027542 -235.035891) (xy 94.98301 -235.058581) (xy 94.935478 -235.074025)
			(xy 94.886115 -235.081844) (xy 94.836137 -235.081844) (xy 94.786774 -235.074025) (xy 94.739242 -235.058581)
			(xy 94.69471 -235.035891) (xy 94.654277 -235.006515) (xy 94.618937 -234.971175) (xy 94.589561 -234.930742)
			(xy 94.566871 -234.88621) (xy 94.551427 -234.838678) (xy 94.543608 -234.789315) (xy 94.236291 -234.789315)
			(xy 94.236282 -234.789772) (xy 94.228118 -234.840006) (xy 94.212002 -234.88828) (xy 94.188351 -234.933343)
			(xy 94.157778 -234.974029) (xy 94.121074 -235.009284) (xy 94.07919 -235.038194) (xy 94.033211 -235.060011)
			(xy 93.984327 -235.074171) (xy 93.933806 -235.080305) (xy 93.882954 -235.078256) (xy 93.83309 -235.068076)
			(xy 93.785504 -235.050029) (xy 93.74143 -235.024583) (xy 93.702008 -234.992396) (xy 93.66826 -234.954302)
			(xy 93.641059 -234.911288) (xy 93.621111 -234.864468) (xy 93.608932 -234.815054) (xy 93.604837 -234.764326)
			(xy 92.356686 -234.764326) (xy 92.356174 -234.789772) (xy 92.34801 -234.840006) (xy 92.331894 -234.88828)
			(xy 92.308243 -234.933343) (xy 92.27767 -234.974029) (xy 92.240966 -235.009284) (xy 92.199082 -235.038194)
			(xy 92.153103 -235.060011) (xy 92.104219 -235.074171) (xy 92.053698 -235.080305) (xy 92.002846 -235.078256)
			(xy 91.952982 -235.068076) (xy 91.905396 -235.050029) (xy 91.861322 -235.024583) (xy 91.8219 -234.992396)
			(xy 91.788152 -234.954302) (xy 91.760951 -234.911288) (xy 91.741003 -234.864468) (xy 91.728824 -234.815054)
			(xy 91.724729 -234.764326) (xy 91.416632 -234.764326) (xy 91.41612 -234.789772) (xy 91.407956 -234.840006)
			(xy 91.39184 -234.88828) (xy 91.368189 -234.933343) (xy 91.337616 -234.974029) (xy 91.300912 -235.009284)
			(xy 91.259028 -235.038194) (xy 91.213049 -235.060011) (xy 91.164165 -235.074171) (xy 91.113644 -235.080305)
			(xy 91.062792 -235.078256) (xy 91.012928 -235.068076) (xy 90.965342 -235.050029) (xy 90.921268 -235.024583)
			(xy 90.881846 -234.992396) (xy 90.848098 -234.954302) (xy 90.820897 -234.911288) (xy 90.800949 -234.864468)
			(xy 90.78877 -234.815054) (xy 90.784675 -234.764326) (xy 90.479118 -234.764326) (xy 90.478628 -234.789315)
			(xy 90.470809 -234.838678) (xy 90.455365 -234.88621) (xy 90.432675 -234.930742) (xy 90.403299 -234.971175)
			(xy 90.367959 -235.006515) (xy 90.327526 -235.035891) (xy 90.282994 -235.058581) (xy 90.235462 -235.074025)
			(xy 90.186099 -235.081844) (xy 90.136121 -235.081844) (xy 90.086758 -235.074025) (xy 90.039226 -235.058581)
			(xy 89.994694 -235.035891) (xy 89.954261 -235.006515) (xy 89.918921 -234.971175) (xy 89.889545 -234.930742)
			(xy 89.866855 -234.88621) (xy 89.851411 -234.838678) (xy 89.843592 -234.789315) (xy 89.536275 -234.789315)
			(xy 89.536266 -234.789772) (xy 89.528102 -234.840006) (xy 89.511986 -234.88828) (xy 89.488335 -234.933343)
			(xy 89.457762 -234.974029) (xy 89.421058 -235.009284) (xy 89.379174 -235.038194) (xy 89.333195 -235.060011)
			(xy 89.284311 -235.074171) (xy 89.23379 -235.080305) (xy 89.182938 -235.078256) (xy 89.133074 -235.068076)
			(xy 89.085488 -235.050029) (xy 89.041414 -235.024583) (xy 89.001992 -234.992396) (xy 88.968244 -234.954302)
			(xy 88.941043 -234.911288) (xy 88.921095 -234.864468) (xy 88.908916 -234.815054) (xy 88.904821 -234.764326)
			(xy 88.59901 -234.764326) (xy 88.59852 -234.789315) (xy 88.590701 -234.838678) (xy 88.575257 -234.88621)
			(xy 88.552567 -234.930742) (xy 88.523191 -234.971175) (xy 88.487851 -235.006515) (xy 88.447418 -235.035891)
			(xy 88.402886 -235.058581) (xy 88.355354 -235.074025) (xy 88.305991 -235.081844) (xy 88.256013 -235.081844)
			(xy 88.20665 -235.074025) (xy 88.159118 -235.058581) (xy 88.114586 -235.035891) (xy 88.074153 -235.006515)
			(xy 88.038813 -234.971175) (xy 88.009437 -234.930742) (xy 87.986747 -234.88621) (xy 87.971303 -234.838678)
			(xy 87.963484 -234.789315) (xy 87.656167 -234.789315) (xy 87.656158 -234.789772) (xy 87.647994 -234.840006)
			(xy 87.631878 -234.88828) (xy 87.608227 -234.933343) (xy 87.577654 -234.974029) (xy 87.54095 -235.009284)
			(xy 87.499066 -235.038194) (xy 87.453087 -235.060011) (xy 87.404203 -235.074171) (xy 87.353682 -235.080305)
			(xy 87.30283 -235.078256) (xy 87.252966 -235.068076) (xy 87.20538 -235.050029) (xy 87.161306 -235.024583)
			(xy 87.121884 -234.992396) (xy 87.088136 -234.954302) (xy 87.060935 -234.911288) (xy 87.040987 -234.864468)
			(xy 87.028808 -234.815054) (xy 87.024713 -234.764326) (xy 85.776816 -234.764326) (xy 85.776304 -234.789772)
			(xy 85.76814 -234.840006) (xy 85.752024 -234.88828) (xy 85.728373 -234.933343) (xy 85.6978 -234.974029)
			(xy 85.661096 -235.009284) (xy 85.619212 -235.038194) (xy 85.573233 -235.060011) (xy 85.524349 -235.074171)
			(xy 85.473828 -235.080305) (xy 85.422976 -235.078256) (xy 85.373112 -235.068076) (xy 85.325526 -235.050029)
			(xy 85.281452 -235.024583) (xy 85.24203 -234.992396) (xy 85.208282 -234.954302) (xy 85.181081 -234.911288)
			(xy 85.161133 -234.864468) (xy 85.148954 -234.815054) (xy 85.144859 -234.764326) (xy 84.836762 -234.764326)
			(xy 84.83625 -234.789772) (xy 84.828086 -234.840006) (xy 84.81197 -234.88828) (xy 84.788319 -234.933343)
			(xy 84.757746 -234.974029) (xy 84.721042 -235.009284) (xy 84.679158 -235.038194) (xy 84.633179 -235.060011)
			(xy 84.584295 -235.074171) (xy 84.533774 -235.080305) (xy 84.482922 -235.078256) (xy 84.433058 -235.068076)
			(xy 84.385472 -235.050029) (xy 84.341398 -235.024583) (xy 84.301976 -234.992396) (xy 84.268228 -234.954302)
			(xy 84.241027 -234.911288) (xy 84.221079 -234.864468) (xy 84.2089 -234.815054) (xy 84.204805 -234.764326)
			(xy 83.898994 -234.764326) (xy 83.898504 -234.789315) (xy 83.890685 -234.838678) (xy 83.875241 -234.88621)
			(xy 83.852551 -234.930742) (xy 83.823175 -234.971175) (xy 83.787835 -235.006515) (xy 83.747402 -235.035891)
			(xy 83.70287 -235.058581) (xy 83.655338 -235.074025) (xy 83.605975 -235.081844) (xy 83.555997 -235.081844)
			(xy 83.506634 -235.074025) (xy 83.459102 -235.058581) (xy 83.41457 -235.035891) (xy 83.374137 -235.006515)
			(xy 83.338797 -234.971175) (xy 83.309421 -234.930742) (xy 83.286731 -234.88621) (xy 83.271287 -234.838678)
			(xy 83.263468 -234.789315) (xy 82.956151 -234.789315) (xy 82.956142 -234.789772) (xy 82.947978 -234.840006)
			(xy 82.931862 -234.88828) (xy 82.908211 -234.933343) (xy 82.877638 -234.974029) (xy 82.840934 -235.009284)
			(xy 82.79905 -235.038194) (xy 82.753071 -235.060011) (xy 82.704187 -235.074171) (xy 82.653666 -235.080305)
			(xy 82.602814 -235.078256) (xy 82.55295 -235.068076) (xy 82.505364 -235.050029) (xy 82.46129 -235.024583)
			(xy 82.421868 -234.992396) (xy 82.38812 -234.954302) (xy 82.360919 -234.911288) (xy 82.340971 -234.864468)
			(xy 82.328792 -234.815054) (xy 82.324697 -234.764326) (xy 82.01914 -234.764326) (xy 82.01865 -234.789315)
			(xy 82.010831 -234.838678) (xy 81.995387 -234.88621) (xy 81.972697 -234.930742) (xy 81.943321 -234.971175)
			(xy 81.907981 -235.006515) (xy 81.867548 -235.035891) (xy 81.823016 -235.058581) (xy 81.775484 -235.074025)
			(xy 81.726121 -235.081844) (xy 81.676143 -235.081844) (xy 81.62678 -235.074025) (xy 81.579248 -235.058581)
			(xy 81.534716 -235.035891) (xy 81.494283 -235.006515) (xy 81.458943 -234.971175) (xy 81.429567 -234.930742)
			(xy 81.406877 -234.88621) (xy 81.391433 -234.838678) (xy 81.383614 -234.789315) (xy 81.076297 -234.789315)
			(xy 81.076288 -234.789772) (xy 81.068124 -234.840006) (xy 81.052008 -234.88828) (xy 81.028357 -234.933343)
			(xy 80.997784 -234.974029) (xy 80.96108 -235.009284) (xy 80.919196 -235.038194) (xy 80.873217 -235.060011)
			(xy 80.824333 -235.074171) (xy 80.773812 -235.080305) (xy 80.72296 -235.078256) (xy 80.673096 -235.068076)
			(xy 80.62551 -235.050029) (xy 80.581436 -235.024583) (xy 80.542014 -234.992396) (xy 80.508266 -234.954302)
			(xy 80.481065 -234.911288) (xy 80.461117 -234.864468) (xy 80.448938 -234.815054) (xy 80.444843 -234.764326)
			(xy 79.53248 -234.764326) (xy 79.53248 -235.599321) (xy 79.97366 -235.599321) (xy 79.97366 -235.549343)
			(xy 79.981479 -235.49998) (xy 79.996923 -235.452448) (xy 80.019613 -235.407916) (xy 80.048989 -235.367483)
			(xy 80.084329 -235.332143) (xy 80.124762 -235.302767) (xy 80.169294 -235.280077) (xy 80.216826 -235.264633)
			(xy 80.266189 -235.256814) (xy 80.316167 -235.256814) (xy 80.36553 -235.264633) (xy 80.413062 -235.280077)
			(xy 80.457594 -235.302767) (xy 80.498027 -235.332143) (xy 80.533367 -235.367483) (xy 80.562743 -235.407916)
			(xy 80.585433 -235.452448) (xy 80.600877 -235.49998) (xy 80.608696 -235.549343) (xy 80.609186 -235.574332)
			(xy 80.914743 -235.574332) (xy 80.918838 -235.523604) (xy 80.931017 -235.47419) (xy 80.950965 -235.42737)
			(xy 80.978166 -235.384356) (xy 81.011914 -235.346262) (xy 81.051336 -235.314075) (xy 81.09541 -235.288629)
			(xy 81.142996 -235.270582) (xy 81.19286 -235.260402) (xy 81.243712 -235.258353) (xy 81.294233 -235.264487)
			(xy 81.343117 -235.278647) (xy 81.389096 -235.300464) (xy 81.43098 -235.329374) (xy 81.467684 -235.364629)
			(xy 81.498257 -235.405315) (xy 81.521908 -235.450378) (xy 81.538024 -235.498652) (xy 81.546188 -235.548886)
			(xy 81.5467 -235.574332) (xy 81.854797 -235.574332) (xy 81.858892 -235.523604) (xy 81.871071 -235.47419)
			(xy 81.891019 -235.42737) (xy 81.91822 -235.384356) (xy 81.951968 -235.346262) (xy 81.99139 -235.314075)
			(xy 82.035464 -235.288629) (xy 82.08305 -235.270582) (xy 82.132914 -235.260402) (xy 82.183766 -235.258353)
			(xy 82.234287 -235.264487) (xy 82.283171 -235.278647) (xy 82.32915 -235.300464) (xy 82.371034 -235.329374)
			(xy 82.407738 -235.364629) (xy 82.438311 -235.405315) (xy 82.461962 -235.450378) (xy 82.478078 -235.498652)
			(xy 82.486242 -235.548886) (xy 82.486754 -235.574332) (xy 82.486251 -235.599321) (xy 82.793568 -235.599321)
			(xy 82.793568 -235.549343) (xy 82.801387 -235.49998) (xy 82.816831 -235.452448) (xy 82.839521 -235.407916)
			(xy 82.868897 -235.367483) (xy 82.904237 -235.332143) (xy 82.94467 -235.302767) (xy 82.989202 -235.280077)
			(xy 83.036734 -235.264633) (xy 83.086097 -235.256814) (xy 83.136075 -235.256814) (xy 83.185438 -235.264633)
			(xy 83.23297 -235.280077) (xy 83.277502 -235.302767) (xy 83.317935 -235.332143) (xy 83.353275 -235.367483)
			(xy 83.382651 -235.407916) (xy 83.405341 -235.452448) (xy 83.420785 -235.49998) (xy 83.428604 -235.549343)
			(xy 83.429094 -235.574332) (xy 83.734905 -235.574332) (xy 83.739 -235.523604) (xy 83.751179 -235.47419)
			(xy 83.771127 -235.42737) (xy 83.798328 -235.384356) (xy 83.832076 -235.346262) (xy 83.871498 -235.314075)
			(xy 83.915572 -235.288629) (xy 83.963158 -235.270582) (xy 84.013022 -235.260402) (xy 84.063874 -235.258353)
			(xy 84.114395 -235.264487) (xy 84.163279 -235.278647) (xy 84.209258 -235.300464) (xy 84.251142 -235.329374)
			(xy 84.287846 -235.364629) (xy 84.318419 -235.405315) (xy 84.34207 -235.450378) (xy 84.358186 -235.498652)
			(xy 84.36635 -235.548886) (xy 84.366862 -235.574332) (xy 84.366359 -235.599321) (xy 84.673422 -235.599321)
			(xy 84.673422 -235.549343) (xy 84.681241 -235.49998) (xy 84.696685 -235.452448) (xy 84.719375 -235.407916)
			(xy 84.748751 -235.367483) (xy 84.784091 -235.332143) (xy 84.824524 -235.302767) (xy 84.869056 -235.280077)
			(xy 84.916588 -235.264633) (xy 84.965951 -235.256814) (xy 85.015929 -235.256814) (xy 85.065292 -235.264633)
			(xy 85.112824 -235.280077) (xy 85.157356 -235.302767) (xy 85.197789 -235.332143) (xy 85.233129 -235.367483)
			(xy 85.262505 -235.407916) (xy 85.285195 -235.452448) (xy 85.300639 -235.49998) (xy 85.308458 -235.549343)
			(xy 85.308948 -235.574332) (xy 85.614759 -235.574332) (xy 85.618854 -235.523604) (xy 85.631033 -235.47419)
			(xy 85.650981 -235.42737) (xy 85.678182 -235.384356) (xy 85.71193 -235.346262) (xy 85.751352 -235.314075)
			(xy 85.795426 -235.288629) (xy 85.843012 -235.270582) (xy 85.892876 -235.260402) (xy 85.943728 -235.258353)
			(xy 85.994249 -235.264487) (xy 86.043133 -235.278647) (xy 86.089112 -235.300464) (xy 86.130996 -235.329374)
			(xy 86.1677 -235.364629) (xy 86.198273 -235.405315) (xy 86.221924 -235.450378) (xy 86.23804 -235.498652)
			(xy 86.246204 -235.548886) (xy 86.246716 -235.574332) (xy 86.246213 -235.599321) (xy 86.55353 -235.599321)
			(xy 86.55353 -235.549343) (xy 86.561349 -235.49998) (xy 86.576793 -235.452448) (xy 86.599483 -235.407916)
			(xy 86.628859 -235.367483) (xy 86.664199 -235.332143) (xy 86.704632 -235.302767) (xy 86.749164 -235.280077)
			(xy 86.796696 -235.264633) (xy 86.846059 -235.256814) (xy 86.896037 -235.256814) (xy 86.9454 -235.264633)
			(xy 86.992932 -235.280077) (xy 87.037464 -235.302767) (xy 87.077897 -235.332143) (xy 87.113237 -235.367483)
			(xy 87.142613 -235.407916) (xy 87.165303 -235.452448) (xy 87.180747 -235.49998) (xy 87.188566 -235.549343)
			(xy 87.189056 -235.574332) (xy 87.494867 -235.574332) (xy 87.498962 -235.523604) (xy 87.511141 -235.47419)
			(xy 87.531089 -235.42737) (xy 87.55829 -235.384356) (xy 87.592038 -235.346262) (xy 87.63146 -235.314075)
			(xy 87.675534 -235.288629) (xy 87.72312 -235.270582) (xy 87.772984 -235.260402) (xy 87.823836 -235.258353)
			(xy 87.874357 -235.264487) (xy 87.923241 -235.278647) (xy 87.96922 -235.300464) (xy 88.011104 -235.329374)
			(xy 88.047808 -235.364629) (xy 88.078381 -235.405315) (xy 88.102032 -235.450378) (xy 88.118148 -235.498652)
			(xy 88.126312 -235.548886) (xy 88.126824 -235.574332) (xy 88.434921 -235.574332) (xy 88.439016 -235.523604)
			(xy 88.451195 -235.47419) (xy 88.471143 -235.42737) (xy 88.498344 -235.384356) (xy 88.532092 -235.346262)
			(xy 88.571514 -235.314075) (xy 88.615588 -235.288629) (xy 88.663174 -235.270582) (xy 88.713038 -235.260402)
			(xy 88.76389 -235.258353) (xy 88.814411 -235.264487) (xy 88.863295 -235.278647) (xy 88.909274 -235.300464)
			(xy 88.951158 -235.329374) (xy 88.987862 -235.364629) (xy 89.018435 -235.405315) (xy 89.042086 -235.450378)
			(xy 89.058202 -235.498652) (xy 89.066366 -235.548886) (xy 89.066878 -235.574332) (xy 89.066375 -235.599321)
			(xy 89.373438 -235.599321) (xy 89.373438 -235.549343) (xy 89.381257 -235.49998) (xy 89.396701 -235.452448)
			(xy 89.419391 -235.407916) (xy 89.448767 -235.367483) (xy 89.484107 -235.332143) (xy 89.52454 -235.302767)
			(xy 89.569072 -235.280077) (xy 89.616604 -235.264633) (xy 89.665967 -235.256814) (xy 89.715945 -235.256814)
			(xy 89.765308 -235.264633) (xy 89.81284 -235.280077) (xy 89.857372 -235.302767) (xy 89.897805 -235.332143)
			(xy 89.933145 -235.367483) (xy 89.962521 -235.407916) (xy 89.985211 -235.452448) (xy 90.000655 -235.49998)
			(xy 90.008474 -235.549343) (xy 90.008964 -235.574332) (xy 90.314775 -235.574332) (xy 90.31887 -235.523604)
			(xy 90.331049 -235.47419) (xy 90.350997 -235.42737) (xy 90.378198 -235.384356) (xy 90.411946 -235.346262)
			(xy 90.451368 -235.314075) (xy 90.495442 -235.288629) (xy 90.543028 -235.270582) (xy 90.592892 -235.260402)
			(xy 90.643744 -235.258353) (xy 90.694265 -235.264487) (xy 90.743149 -235.278647) (xy 90.789128 -235.300464)
			(xy 90.831012 -235.329374) (xy 90.867716 -235.364629) (xy 90.898289 -235.405315) (xy 90.92194 -235.450378)
			(xy 90.938056 -235.498652) (xy 90.94622 -235.548886) (xy 90.946732 -235.574332) (xy 90.946229 -235.599321)
			(xy 91.253546 -235.599321) (xy 91.253546 -235.549343) (xy 91.261365 -235.49998) (xy 91.276809 -235.452448)
			(xy 91.299499 -235.407916) (xy 91.328875 -235.367483) (xy 91.364215 -235.332143) (xy 91.404648 -235.302767)
			(xy 91.44918 -235.280077) (xy 91.496712 -235.264633) (xy 91.546075 -235.256814) (xy 91.596053 -235.256814)
			(xy 91.645416 -235.264633) (xy 91.692948 -235.280077) (xy 91.73748 -235.302767) (xy 91.777913 -235.332143)
			(xy 91.813253 -235.367483) (xy 91.842629 -235.407916) (xy 91.865319 -235.452448) (xy 91.880763 -235.49998)
			(xy 91.888582 -235.549343) (xy 91.889072 -235.574332) (xy 92.194883 -235.574332) (xy 92.198978 -235.523604)
			(xy 92.211157 -235.47419) (xy 92.231105 -235.42737) (xy 92.258306 -235.384356) (xy 92.292054 -235.346262)
			(xy 92.331476 -235.314075) (xy 92.37555 -235.288629) (xy 92.423136 -235.270582) (xy 92.473 -235.260402)
			(xy 92.523852 -235.258353) (xy 92.574373 -235.264487) (xy 92.623257 -235.278647) (xy 92.669236 -235.300464)
			(xy 92.71112 -235.329374) (xy 92.747824 -235.364629) (xy 92.778397 -235.405315) (xy 92.802048 -235.450378)
			(xy 92.818164 -235.498652) (xy 92.826328 -235.548886) (xy 92.82684 -235.574332) (xy 92.826337 -235.599321)
			(xy 93.1334 -235.599321) (xy 93.1334 -235.549343) (xy 93.141219 -235.49998) (xy 93.156663 -235.452448)
			(xy 93.179353 -235.407916) (xy 93.208729 -235.367483) (xy 93.244069 -235.332143) (xy 93.284502 -235.302767)
			(xy 93.329034 -235.280077) (xy 93.376566 -235.264633) (xy 93.425929 -235.256814) (xy 93.475907 -235.256814)
			(xy 93.52527 -235.264633) (xy 93.572802 -235.280077) (xy 93.617334 -235.302767) (xy 93.657767 -235.332143)
			(xy 93.693107 -235.367483) (xy 93.722483 -235.407916) (xy 93.745173 -235.452448) (xy 93.760617 -235.49998)
			(xy 93.768436 -235.549343) (xy 93.768926 -235.574332) (xy 94.074737 -235.574332) (xy 94.078832 -235.523604)
			(xy 94.091011 -235.47419) (xy 94.110959 -235.42737) (xy 94.13816 -235.384356) (xy 94.171908 -235.346262)
			(xy 94.21133 -235.314075) (xy 94.255404 -235.288629) (xy 94.30299 -235.270582) (xy 94.352854 -235.260402)
			(xy 94.403706 -235.258353) (xy 94.454227 -235.264487) (xy 94.503111 -235.278647) (xy 94.54909 -235.300464)
			(xy 94.590974 -235.329374) (xy 94.627678 -235.364629) (xy 94.658251 -235.405315) (xy 94.681902 -235.450378)
			(xy 94.698018 -235.498652) (xy 94.706182 -235.548886) (xy 94.706694 -235.574332) (xy 95.014791 -235.574332)
			(xy 95.018886 -235.523604) (xy 95.031065 -235.47419) (xy 95.051013 -235.42737) (xy 95.078214 -235.384356)
			(xy 95.111962 -235.346262) (xy 95.151384 -235.314075) (xy 95.195458 -235.288629) (xy 95.243044 -235.270582)
			(xy 95.292908 -235.260402) (xy 95.34376 -235.258353) (xy 95.394281 -235.264487) (xy 95.443165 -235.278647)
			(xy 95.489144 -235.300464) (xy 95.531028 -235.329374) (xy 95.567732 -235.364629) (xy 95.598305 -235.405315)
			(xy 95.621956 -235.450378) (xy 95.638072 -235.498652) (xy 95.646236 -235.548886) (xy 95.646748 -235.574332)
			(xy 95.646236 -235.599778) (xy 95.638072 -235.650012) (xy 95.621956 -235.698286) (xy 95.598305 -235.743349)
			(xy 95.567732 -235.784035) (xy 95.531028 -235.81929) (xy 95.489144 -235.8482) (xy 95.443165 -235.870017)
			(xy 95.394281 -235.884177) (xy 95.34376 -235.890311) (xy 95.292908 -235.888262) (xy 95.243044 -235.878082)
			(xy 95.195458 -235.860035) (xy 95.151384 -235.834589) (xy 95.111962 -235.802402) (xy 95.078214 -235.764308)
			(xy 95.051013 -235.721294) (xy 95.031065 -235.674474) (xy 95.018886 -235.62506) (xy 95.014791 -235.574332)
			(xy 94.706694 -235.574332) (xy 94.706182 -235.599778) (xy 94.698018 -235.650012) (xy 94.681902 -235.698286)
			(xy 94.658251 -235.743349) (xy 94.627678 -235.784035) (xy 94.590974 -235.81929) (xy 94.54909 -235.8482)
			(xy 94.503111 -235.870017) (xy 94.454227 -235.884177) (xy 94.403706 -235.890311) (xy 94.352854 -235.888262)
			(xy 94.30299 -235.878082) (xy 94.255404 -235.860035) (xy 94.21133 -235.834589) (xy 94.171908 -235.802402)
			(xy 94.13816 -235.764308) (xy 94.110959 -235.721294) (xy 94.091011 -235.674474) (xy 94.078832 -235.62506)
			(xy 94.074737 -235.574332) (xy 93.768926 -235.574332) (xy 93.768436 -235.599321) (xy 93.760617 -235.648684)
			(xy 93.745173 -235.696216) (xy 93.722483 -235.740748) (xy 93.693107 -235.781181) (xy 93.657767 -235.816521)
			(xy 93.617334 -235.845897) (xy 93.572802 -235.868587) (xy 93.52527 -235.884031) (xy 93.475907 -235.89185)
			(xy 93.425929 -235.89185) (xy 93.376566 -235.884031) (xy 93.329034 -235.868587) (xy 93.284502 -235.845897)
			(xy 93.244069 -235.816521) (xy 93.208729 -235.781181) (xy 93.179353 -235.740748) (xy 93.156663 -235.696216)
			(xy 93.141219 -235.648684) (xy 93.1334 -235.599321) (xy 92.826337 -235.599321) (xy 92.826328 -235.599778)
			(xy 92.818164 -235.650012) (xy 92.802048 -235.698286) (xy 92.778397 -235.743349) (xy 92.747824 -235.784035)
			(xy 92.71112 -235.81929) (xy 92.669236 -235.8482) (xy 92.623257 -235.870017) (xy 92.574373 -235.884177)
			(xy 92.523852 -235.890311) (xy 92.473 -235.888262) (xy 92.423136 -235.878082) (xy 92.37555 -235.860035)
			(xy 92.331476 -235.834589) (xy 92.292054 -235.802402) (xy 92.258306 -235.764308) (xy 92.231105 -235.721294)
			(xy 92.211157 -235.674474) (xy 92.198978 -235.62506) (xy 92.194883 -235.574332) (xy 91.889072 -235.574332)
			(xy 91.888582 -235.599321) (xy 91.880763 -235.648684) (xy 91.865319 -235.696216) (xy 91.842629 -235.740748)
			(xy 91.813253 -235.781181) (xy 91.777913 -235.816521) (xy 91.73748 -235.845897) (xy 91.692948 -235.868587)
			(xy 91.645416 -235.884031) (xy 91.596053 -235.89185) (xy 91.546075 -235.89185) (xy 91.496712 -235.884031)
			(xy 91.44918 -235.868587) (xy 91.404648 -235.845897) (xy 91.364215 -235.816521) (xy 91.328875 -235.781181)
			(xy 91.299499 -235.740748) (xy 91.276809 -235.696216) (xy 91.261365 -235.648684) (xy 91.253546 -235.599321)
			(xy 90.946229 -235.599321) (xy 90.94622 -235.599778) (xy 90.938056 -235.650012) (xy 90.92194 -235.698286)
			(xy 90.898289 -235.743349) (xy 90.867716 -235.784035) (xy 90.831012 -235.81929) (xy 90.789128 -235.8482)
			(xy 90.743149 -235.870017) (xy 90.694265 -235.884177) (xy 90.643744 -235.890311) (xy 90.592892 -235.888262)
			(xy 90.543028 -235.878082) (xy 90.495442 -235.860035) (xy 90.451368 -235.834589) (xy 90.411946 -235.802402)
			(xy 90.378198 -235.764308) (xy 90.350997 -235.721294) (xy 90.331049 -235.674474) (xy 90.31887 -235.62506)
			(xy 90.314775 -235.574332) (xy 90.008964 -235.574332) (xy 90.008474 -235.599321) (xy 90.000655 -235.648684)
			(xy 89.985211 -235.696216) (xy 89.962521 -235.740748) (xy 89.933145 -235.781181) (xy 89.897805 -235.816521)
			(xy 89.857372 -235.845897) (xy 89.81284 -235.868587) (xy 89.765308 -235.884031) (xy 89.715945 -235.89185)
			(xy 89.665967 -235.89185) (xy 89.616604 -235.884031) (xy 89.569072 -235.868587) (xy 89.52454 -235.845897)
			(xy 89.484107 -235.816521) (xy 89.448767 -235.781181) (xy 89.419391 -235.740748) (xy 89.396701 -235.696216)
			(xy 89.381257 -235.648684) (xy 89.373438 -235.599321) (xy 89.066375 -235.599321) (xy 89.066366 -235.599778)
			(xy 89.058202 -235.650012) (xy 89.042086 -235.698286) (xy 89.018435 -235.743349) (xy 88.987862 -235.784035)
			(xy 88.951158 -235.81929) (xy 88.909274 -235.8482) (xy 88.863295 -235.870017) (xy 88.814411 -235.884177)
			(xy 88.76389 -235.890311) (xy 88.713038 -235.888262) (xy 88.663174 -235.878082) (xy 88.615588 -235.860035)
			(xy 88.571514 -235.834589) (xy 88.532092 -235.802402) (xy 88.498344 -235.764308) (xy 88.471143 -235.721294)
			(xy 88.451195 -235.674474) (xy 88.439016 -235.62506) (xy 88.434921 -235.574332) (xy 88.126824 -235.574332)
			(xy 88.126312 -235.599778) (xy 88.118148 -235.650012) (xy 88.102032 -235.698286) (xy 88.078381 -235.743349)
			(xy 88.047808 -235.784035) (xy 88.011104 -235.81929) (xy 87.96922 -235.8482) (xy 87.923241 -235.870017)
			(xy 87.874357 -235.884177) (xy 87.823836 -235.890311) (xy 87.772984 -235.888262) (xy 87.72312 -235.878082)
			(xy 87.675534 -235.860035) (xy 87.63146 -235.834589) (xy 87.592038 -235.802402) (xy 87.55829 -235.764308)
			(xy 87.531089 -235.721294) (xy 87.511141 -235.674474) (xy 87.498962 -235.62506) (xy 87.494867 -235.574332)
			(xy 87.189056 -235.574332) (xy 87.188566 -235.599321) (xy 87.180747 -235.648684) (xy 87.165303 -235.696216)
			(xy 87.142613 -235.740748) (xy 87.113237 -235.781181) (xy 87.077897 -235.816521) (xy 87.037464 -235.845897)
			(xy 86.992932 -235.868587) (xy 86.9454 -235.884031) (xy 86.896037 -235.89185) (xy 86.846059 -235.89185)
			(xy 86.796696 -235.884031) (xy 86.749164 -235.868587) (xy 86.704632 -235.845897) (xy 86.664199 -235.816521)
			(xy 86.628859 -235.781181) (xy 86.599483 -235.740748) (xy 86.576793 -235.696216) (xy 86.561349 -235.648684)
			(xy 86.55353 -235.599321) (xy 86.246213 -235.599321) (xy 86.246204 -235.599778) (xy 86.23804 -235.650012)
			(xy 86.221924 -235.698286) (xy 86.198273 -235.743349) (xy 86.1677 -235.784035) (xy 86.130996 -235.81929)
			(xy 86.089112 -235.8482) (xy 86.043133 -235.870017) (xy 85.994249 -235.884177) (xy 85.943728 -235.890311)
			(xy 85.892876 -235.888262) (xy 85.843012 -235.878082) (xy 85.795426 -235.860035) (xy 85.751352 -235.834589)
			(xy 85.71193 -235.802402) (xy 85.678182 -235.764308) (xy 85.650981 -235.721294) (xy 85.631033 -235.674474)
			(xy 85.618854 -235.62506) (xy 85.614759 -235.574332) (xy 85.308948 -235.574332) (xy 85.308458 -235.599321)
			(xy 85.300639 -235.648684) (xy 85.285195 -235.696216) (xy 85.262505 -235.740748) (xy 85.233129 -235.781181)
			(xy 85.197789 -235.816521) (xy 85.157356 -235.845897) (xy 85.112824 -235.868587) (xy 85.065292 -235.884031)
			(xy 85.015929 -235.89185) (xy 84.965951 -235.89185) (xy 84.916588 -235.884031) (xy 84.869056 -235.868587)
			(xy 84.824524 -235.845897) (xy 84.784091 -235.816521) (xy 84.748751 -235.781181) (xy 84.719375 -235.740748)
			(xy 84.696685 -235.696216) (xy 84.681241 -235.648684) (xy 84.673422 -235.599321) (xy 84.366359 -235.599321)
			(xy 84.36635 -235.599778) (xy 84.358186 -235.650012) (xy 84.34207 -235.698286) (xy 84.318419 -235.743349)
			(xy 84.287846 -235.784035) (xy 84.251142 -235.81929) (xy 84.209258 -235.8482) (xy 84.163279 -235.870017)
			(xy 84.114395 -235.884177) (xy 84.063874 -235.890311) (xy 84.013022 -235.888262) (xy 83.963158 -235.878082)
			(xy 83.915572 -235.860035) (xy 83.871498 -235.834589) (xy 83.832076 -235.802402) (xy 83.798328 -235.764308)
			(xy 83.771127 -235.721294) (xy 83.751179 -235.674474) (xy 83.739 -235.62506) (xy 83.734905 -235.574332)
			(xy 83.429094 -235.574332) (xy 83.428604 -235.599321) (xy 83.420785 -235.648684) (xy 83.405341 -235.696216)
			(xy 83.382651 -235.740748) (xy 83.353275 -235.781181) (xy 83.317935 -235.816521) (xy 83.277502 -235.845897)
			(xy 83.23297 -235.868587) (xy 83.185438 -235.884031) (xy 83.136075 -235.89185) (xy 83.086097 -235.89185)
			(xy 83.036734 -235.884031) (xy 82.989202 -235.868587) (xy 82.94467 -235.845897) (xy 82.904237 -235.816521)
			(xy 82.868897 -235.781181) (xy 82.839521 -235.740748) (xy 82.816831 -235.696216) (xy 82.801387 -235.648684)
			(xy 82.793568 -235.599321) (xy 82.486251 -235.599321) (xy 82.486242 -235.599778) (xy 82.478078 -235.650012)
			(xy 82.461962 -235.698286) (xy 82.438311 -235.743349) (xy 82.407738 -235.784035) (xy 82.371034 -235.81929)
			(xy 82.32915 -235.8482) (xy 82.283171 -235.870017) (xy 82.234287 -235.884177) (xy 82.183766 -235.890311)
			(xy 82.132914 -235.888262) (xy 82.08305 -235.878082) (xy 82.035464 -235.860035) (xy 81.99139 -235.834589)
			(xy 81.951968 -235.802402) (xy 81.91822 -235.764308) (xy 81.891019 -235.721294) (xy 81.871071 -235.674474)
			(xy 81.858892 -235.62506) (xy 81.854797 -235.574332) (xy 81.5467 -235.574332) (xy 81.546188 -235.599778)
			(xy 81.538024 -235.650012) (xy 81.521908 -235.698286) (xy 81.498257 -235.743349) (xy 81.467684 -235.784035)
			(xy 81.43098 -235.81929) (xy 81.389096 -235.8482) (xy 81.343117 -235.870017) (xy 81.294233 -235.884177)
			(xy 81.243712 -235.890311) (xy 81.19286 -235.888262) (xy 81.142996 -235.878082) (xy 81.09541 -235.860035)
			(xy 81.051336 -235.834589) (xy 81.011914 -235.802402) (xy 80.978166 -235.764308) (xy 80.950965 -235.721294)
			(xy 80.931017 -235.674474) (xy 80.918838 -235.62506) (xy 80.914743 -235.574332) (xy 80.609186 -235.574332)
			(xy 80.608696 -235.599321) (xy 80.600877 -235.648684) (xy 80.585433 -235.696216) (xy 80.562743 -235.740748)
			(xy 80.533367 -235.781181) (xy 80.498027 -235.816521) (xy 80.457594 -235.845897) (xy 80.413062 -235.868587)
			(xy 80.36553 -235.884031) (xy 80.316167 -235.89185) (xy 80.266189 -235.89185) (xy 80.216826 -235.884031)
			(xy 80.169294 -235.868587) (xy 80.124762 -235.845897) (xy 80.084329 -235.816521) (xy 80.048989 -235.781181)
			(xy 80.019613 -235.740748) (xy 79.996923 -235.696216) (xy 79.981479 -235.648684) (xy 79.97366 -235.599321)
			(xy 79.53248 -235.599321) (xy 79.53248 -236.008418) (xy 79.532983 -236.023189) (xy 79.541447 -236.051492)
			(xy 79.557659 -236.076188) (xy 79.580264 -236.095207) (xy 79.607368 -236.106959) (xy 79.636702 -236.110458)
			(xy 79.665809 -236.105412) (xy 79.679292 -236.09935) (xy 79.701428 -236.088855) (xy 79.74812 -236.074034)
			(xy 79.79653 -236.066537) (xy 79.821024 -236.066076) (xy 79.846029 -236.066568) (xy 79.895423 -236.074395)
			(xy 79.942984 -236.089852) (xy 79.987542 -236.112558) (xy 80.028 -236.141955) (xy 80.063361 -236.177319)
			(xy 80.092754 -236.217779) (xy 80.115457 -236.262338) (xy 80.130911 -236.309901) (xy 80.138734 -236.359295)
			(xy 80.138734 -236.384338) (xy 80.444843 -236.384338) (xy 80.448938 -236.33361) (xy 80.461117 -236.284196)
			(xy 80.481065 -236.237376) (xy 80.508266 -236.194362) (xy 80.542014 -236.156268) (xy 80.581436 -236.124081)
			(xy 80.62551 -236.098635) (xy 80.673096 -236.080588) (xy 80.72296 -236.070408) (xy 80.773812 -236.068359)
			(xy 80.824333 -236.074493) (xy 80.873217 -236.088653) (xy 80.919196 -236.11047) (xy 80.96108 -236.13938)
			(xy 80.997784 -236.174635) (xy 81.028357 -236.215321) (xy 81.052008 -236.260384) (xy 81.068124 -236.308658)
			(xy 81.076288 -236.358892) (xy 81.0768 -236.384338) (xy 81.076297 -236.409327) (xy 81.383614 -236.409327)
			(xy 81.383614 -236.359349) (xy 81.391433 -236.309986) (xy 81.406877 -236.262454) (xy 81.429567 -236.217922)
			(xy 81.458943 -236.177489) (xy 81.494283 -236.142149) (xy 81.534716 -236.112773) (xy 81.579248 -236.090083)
			(xy 81.62678 -236.074639) (xy 81.676143 -236.06682) (xy 81.726121 -236.06682) (xy 81.775484 -236.074639)
			(xy 81.823016 -236.090083) (xy 81.867548 -236.112773) (xy 81.907981 -236.142149) (xy 81.943321 -236.177489)
			(xy 81.972697 -236.217922) (xy 81.995387 -236.262454) (xy 82.010831 -236.309986) (xy 82.01865 -236.359349)
			(xy 82.01914 -236.384338) (xy 82.324697 -236.384338) (xy 82.328792 -236.33361) (xy 82.340971 -236.284196)
			(xy 82.360919 -236.237376) (xy 82.38812 -236.194362) (xy 82.421868 -236.156268) (xy 82.46129 -236.124081)
			(xy 82.505364 -236.098635) (xy 82.55295 -236.080588) (xy 82.602814 -236.070408) (xy 82.653666 -236.068359)
			(xy 82.704187 -236.074493) (xy 82.753071 -236.088653) (xy 82.79905 -236.11047) (xy 82.840934 -236.13938)
			(xy 82.877638 -236.174635) (xy 82.908211 -236.215321) (xy 82.931862 -236.260384) (xy 82.947978 -236.308658)
			(xy 82.956142 -236.358892) (xy 82.956654 -236.384338) (xy 82.956151 -236.409327) (xy 83.263468 -236.409327)
			(xy 83.263468 -236.359349) (xy 83.271287 -236.309986) (xy 83.286731 -236.262454) (xy 83.309421 -236.217922)
			(xy 83.338797 -236.177489) (xy 83.374137 -236.142149) (xy 83.41457 -236.112773) (xy 83.459102 -236.090083)
			(xy 83.506634 -236.074639) (xy 83.555997 -236.06682) (xy 83.605975 -236.06682) (xy 83.655338 -236.074639)
			(xy 83.70287 -236.090083) (xy 83.747402 -236.112773) (xy 83.787835 -236.142149) (xy 83.823175 -236.177489)
			(xy 83.852551 -236.217922) (xy 83.875241 -236.262454) (xy 83.890685 -236.309986) (xy 83.898504 -236.359349)
			(xy 83.898994 -236.384338) (xy 84.204805 -236.384338) (xy 84.2089 -236.33361) (xy 84.221079 -236.284196)
			(xy 84.241027 -236.237376) (xy 84.268228 -236.194362) (xy 84.301976 -236.156268) (xy 84.341398 -236.124081)
			(xy 84.385472 -236.098635) (xy 84.433058 -236.080588) (xy 84.482922 -236.070408) (xy 84.533774 -236.068359)
			(xy 84.584295 -236.074493) (xy 84.633179 -236.088653) (xy 84.679158 -236.11047) (xy 84.721042 -236.13938)
			(xy 84.757746 -236.174635) (xy 84.788319 -236.215321) (xy 84.81197 -236.260384) (xy 84.828086 -236.308658)
			(xy 84.83625 -236.358892) (xy 84.836762 -236.384338) (xy 85.144859 -236.384338) (xy 85.148954 -236.33361)
			(xy 85.161133 -236.284196) (xy 85.181081 -236.237376) (xy 85.208282 -236.194362) (xy 85.24203 -236.156268)
			(xy 85.281452 -236.124081) (xy 85.325526 -236.098635) (xy 85.373112 -236.080588) (xy 85.422976 -236.070408)
			(xy 85.473828 -236.068359) (xy 85.524349 -236.074493) (xy 85.573233 -236.088653) (xy 85.619212 -236.11047)
			(xy 85.661096 -236.13938) (xy 85.6978 -236.174635) (xy 85.728373 -236.215321) (xy 85.752024 -236.260384)
			(xy 85.76814 -236.308658) (xy 85.776304 -236.358892) (xy 85.776816 -236.384338) (xy 85.776313 -236.409327)
			(xy 86.08363 -236.409327) (xy 86.08363 -236.359349) (xy 86.091449 -236.309986) (xy 86.106893 -236.262454)
			(xy 86.129583 -236.217922) (xy 86.158959 -236.177489) (xy 86.194299 -236.142149) (xy 86.234732 -236.112773)
			(xy 86.279264 -236.090083) (xy 86.326796 -236.074639) (xy 86.376159 -236.06682) (xy 86.426137 -236.06682)
			(xy 86.4755 -236.074639) (xy 86.523032 -236.090083) (xy 86.567564 -236.112773) (xy 86.607997 -236.142149)
			(xy 86.643337 -236.177489) (xy 86.672713 -236.217922) (xy 86.695403 -236.262454) (xy 86.710847 -236.309986)
			(xy 86.718666 -236.359349) (xy 86.719156 -236.384338) (xy 87.024713 -236.384338) (xy 87.028808 -236.33361)
			(xy 87.040987 -236.284196) (xy 87.060935 -236.237376) (xy 87.088136 -236.194362) (xy 87.121884 -236.156268)
			(xy 87.161306 -236.124081) (xy 87.20538 -236.098635) (xy 87.252966 -236.080588) (xy 87.30283 -236.070408)
			(xy 87.353682 -236.068359) (xy 87.404203 -236.074493) (xy 87.453087 -236.088653) (xy 87.499066 -236.11047)
			(xy 87.54095 -236.13938) (xy 87.577654 -236.174635) (xy 87.608227 -236.215321) (xy 87.631878 -236.260384)
			(xy 87.647994 -236.308658) (xy 87.656158 -236.358892) (xy 87.65667 -236.384338) (xy 87.656167 -236.409327)
			(xy 87.963484 -236.409327) (xy 87.963484 -236.359349) (xy 87.971303 -236.309986) (xy 87.986747 -236.262454)
			(xy 88.009437 -236.217922) (xy 88.038813 -236.177489) (xy 88.074153 -236.142149) (xy 88.114586 -236.112773)
			(xy 88.159118 -236.090083) (xy 88.20665 -236.074639) (xy 88.256013 -236.06682) (xy 88.305991 -236.06682)
			(xy 88.355354 -236.074639) (xy 88.402886 -236.090083) (xy 88.447418 -236.112773) (xy 88.487851 -236.142149)
			(xy 88.523191 -236.177489) (xy 88.552567 -236.217922) (xy 88.575257 -236.262454) (xy 88.590701 -236.309986)
			(xy 88.59852 -236.359349) (xy 88.59901 -236.384338) (xy 88.904821 -236.384338) (xy 88.908916 -236.33361)
			(xy 88.921095 -236.284196) (xy 88.941043 -236.237376) (xy 88.968244 -236.194362) (xy 89.001992 -236.156268)
			(xy 89.041414 -236.124081) (xy 89.085488 -236.098635) (xy 89.133074 -236.080588) (xy 89.182938 -236.070408)
			(xy 89.23379 -236.068359) (xy 89.284311 -236.074493) (xy 89.333195 -236.088653) (xy 89.379174 -236.11047)
			(xy 89.421058 -236.13938) (xy 89.457762 -236.174635) (xy 89.488335 -236.215321) (xy 89.511986 -236.260384)
			(xy 89.528102 -236.308658) (xy 89.536266 -236.358892) (xy 89.536778 -236.384338) (xy 89.536275 -236.409327)
			(xy 89.843592 -236.409327) (xy 89.843592 -236.359349) (xy 89.851411 -236.309986) (xy 89.866855 -236.262454)
			(xy 89.889545 -236.217922) (xy 89.918921 -236.177489) (xy 89.954261 -236.142149) (xy 89.994694 -236.112773)
			(xy 90.039226 -236.090083) (xy 90.086758 -236.074639) (xy 90.136121 -236.06682) (xy 90.186099 -236.06682)
			(xy 90.235462 -236.074639) (xy 90.282994 -236.090083) (xy 90.327526 -236.112773) (xy 90.367959 -236.142149)
			(xy 90.403299 -236.177489) (xy 90.432675 -236.217922) (xy 90.455365 -236.262454) (xy 90.470809 -236.309986)
			(xy 90.478628 -236.359349) (xy 90.479118 -236.384338) (xy 90.784675 -236.384338) (xy 90.78877 -236.33361)
			(xy 90.800949 -236.284196) (xy 90.820897 -236.237376) (xy 90.848098 -236.194362) (xy 90.881846 -236.156268)
			(xy 90.921268 -236.124081) (xy 90.965342 -236.098635) (xy 91.012928 -236.080588) (xy 91.062792 -236.070408)
			(xy 91.113644 -236.068359) (xy 91.164165 -236.074493) (xy 91.213049 -236.088653) (xy 91.259028 -236.11047)
			(xy 91.300912 -236.13938) (xy 91.337616 -236.174635) (xy 91.368189 -236.215321) (xy 91.39184 -236.260384)
			(xy 91.407956 -236.308658) (xy 91.41612 -236.358892) (xy 91.416632 -236.384338) (xy 91.724729 -236.384338)
			(xy 91.728824 -236.33361) (xy 91.741003 -236.284196) (xy 91.760951 -236.237376) (xy 91.788152 -236.194362)
			(xy 91.8219 -236.156268) (xy 91.861322 -236.124081) (xy 91.905396 -236.098635) (xy 91.952982 -236.080588)
			(xy 92.002846 -236.070408) (xy 92.053698 -236.068359) (xy 92.104219 -236.074493) (xy 92.153103 -236.088653)
			(xy 92.199082 -236.11047) (xy 92.240966 -236.13938) (xy 92.27767 -236.174635) (xy 92.308243 -236.215321)
			(xy 92.331894 -236.260384) (xy 92.34801 -236.308658) (xy 92.356174 -236.358892) (xy 92.356686 -236.384338)
			(xy 92.356183 -236.409327) (xy 92.6635 -236.409327) (xy 92.6635 -236.359349) (xy 92.671319 -236.309986)
			(xy 92.686763 -236.262454) (xy 92.709453 -236.217922) (xy 92.738829 -236.177489) (xy 92.774169 -236.142149)
			(xy 92.814602 -236.112773) (xy 92.859134 -236.090083) (xy 92.906666 -236.074639) (xy 92.956029 -236.06682)
			(xy 93.006007 -236.06682) (xy 93.05537 -236.074639) (xy 93.102902 -236.090083) (xy 93.147434 -236.112773)
			(xy 93.187867 -236.142149) (xy 93.223207 -236.177489) (xy 93.252583 -236.217922) (xy 93.275273 -236.262454)
			(xy 93.290717 -236.309986) (xy 93.298536 -236.359349) (xy 93.299026 -236.384338) (xy 93.604837 -236.384338)
			(xy 93.608932 -236.33361) (xy 93.621111 -236.284196) (xy 93.641059 -236.237376) (xy 93.66826 -236.194362)
			(xy 93.702008 -236.156268) (xy 93.74143 -236.124081) (xy 93.785504 -236.098635) (xy 93.83309 -236.080588)
			(xy 93.882954 -236.070408) (xy 93.933806 -236.068359) (xy 93.984327 -236.074493) (xy 94.033211 -236.088653)
			(xy 94.07919 -236.11047) (xy 94.121074 -236.13938) (xy 94.157778 -236.174635) (xy 94.188351 -236.215321)
			(xy 94.212002 -236.260384) (xy 94.228118 -236.308658) (xy 94.236282 -236.358892) (xy 94.236794 -236.384338)
			(xy 94.236291 -236.409327) (xy 94.543608 -236.409327) (xy 94.543608 -236.359349) (xy 94.551427 -236.309986)
			(xy 94.566871 -236.262454) (xy 94.589561 -236.217922) (xy 94.618937 -236.177489) (xy 94.654277 -236.142149)
			(xy 94.69471 -236.112773) (xy 94.739242 -236.090083) (xy 94.786774 -236.074639) (xy 94.836137 -236.06682)
			(xy 94.886115 -236.06682) (xy 94.935478 -236.074639) (xy 94.98301 -236.090083) (xy 95.027542 -236.112773)
			(xy 95.067975 -236.142149) (xy 95.103315 -236.177489) (xy 95.132691 -236.217922) (xy 95.155381 -236.262454)
			(xy 95.170825 -236.309986) (xy 95.178644 -236.359349) (xy 95.179134 -236.384338) (xy 95.484691 -236.384338)
			(xy 95.488786 -236.33361) (xy 95.500965 -236.284196) (xy 95.520913 -236.237376) (xy 95.548114 -236.194362)
			(xy 95.581862 -236.156268) (xy 95.621284 -236.124081) (xy 95.665358 -236.098635) (xy 95.712944 -236.080588)
			(xy 95.762808 -236.070408) (xy 95.81366 -236.068359) (xy 95.864181 -236.074493) (xy 95.913065 -236.088653)
			(xy 95.959044 -236.11047) (xy 96.000928 -236.13938) (xy 96.037632 -236.174635) (xy 96.068205 -236.215321)
			(xy 96.091856 -236.260384) (xy 96.107972 -236.308658) (xy 96.116136 -236.358892) (xy 96.116648 -236.384338)
			(xy 96.116136 -236.409784) (xy 96.107972 -236.460018) (xy 96.091856 -236.508292) (xy 96.068205 -236.553355)
			(xy 96.037632 -236.594041) (xy 96.000928 -236.629296) (xy 95.959044 -236.658206) (xy 95.913065 -236.680023)
			(xy 95.864181 -236.694183) (xy 95.81366 -236.700317) (xy 95.762808 -236.698268) (xy 95.712944 -236.688088)
			(xy 95.665358 -236.670041) (xy 95.621284 -236.644595) (xy 95.581862 -236.612408) (xy 95.548114 -236.574314)
			(xy 95.520913 -236.5313) (xy 95.500965 -236.48448) (xy 95.488786 -236.435066) (xy 95.484691 -236.384338)
			(xy 95.179134 -236.384338) (xy 95.178644 -236.409327) (xy 95.170825 -236.45869) (xy 95.155381 -236.506222)
			(xy 95.132691 -236.550754) (xy 95.103315 -236.591187) (xy 95.067975 -236.626527) (xy 95.027542 -236.655903)
			(xy 94.98301 -236.678593) (xy 94.935478 -236.694037) (xy 94.886115 -236.701856) (xy 94.836137 -236.701856)
			(xy 94.786774 -236.694037) (xy 94.739242 -236.678593) (xy 94.69471 -236.655903) (xy 94.654277 -236.626527)
			(xy 94.618937 -236.591187) (xy 94.589561 -236.550754) (xy 94.566871 -236.506222) (xy 94.551427 -236.45869)
			(xy 94.543608 -236.409327) (xy 94.236291 -236.409327) (xy 94.236282 -236.409784) (xy 94.228118 -236.460018)
			(xy 94.212002 -236.508292) (xy 94.188351 -236.553355) (xy 94.157778 -236.594041) (xy 94.121074 -236.629296)
			(xy 94.07919 -236.658206) (xy 94.033211 -236.680023) (xy 93.984327 -236.694183) (xy 93.933806 -236.700317)
			(xy 93.882954 -236.698268) (xy 93.83309 -236.688088) (xy 93.785504 -236.670041) (xy 93.74143 -236.644595)
			(xy 93.702008 -236.612408) (xy 93.66826 -236.574314) (xy 93.641059 -236.5313) (xy 93.621111 -236.48448)
			(xy 93.608932 -236.435066) (xy 93.604837 -236.384338) (xy 93.299026 -236.384338) (xy 93.298536 -236.409327)
			(xy 93.290717 -236.45869) (xy 93.275273 -236.506222) (xy 93.252583 -236.550754) (xy 93.223207 -236.591187)
			(xy 93.187867 -236.626527) (xy 93.147434 -236.655903) (xy 93.102902 -236.678593) (xy 93.05537 -236.694037)
			(xy 93.006007 -236.701856) (xy 92.956029 -236.701856) (xy 92.906666 -236.694037) (xy 92.859134 -236.678593)
			(xy 92.814602 -236.655903) (xy 92.774169 -236.626527) (xy 92.738829 -236.591187) (xy 92.709453 -236.550754)
			(xy 92.686763 -236.506222) (xy 92.671319 -236.45869) (xy 92.6635 -236.409327) (xy 92.356183 -236.409327)
			(xy 92.356174 -236.409784) (xy 92.34801 -236.460018) (xy 92.331894 -236.508292) (xy 92.308243 -236.553355)
			(xy 92.27767 -236.594041) (xy 92.240966 -236.629296) (xy 92.199082 -236.658206) (xy 92.153103 -236.680023)
			(xy 92.104219 -236.694183) (xy 92.053698 -236.700317) (xy 92.002846 -236.698268) (xy 91.952982 -236.688088)
			(xy 91.905396 -236.670041) (xy 91.861322 -236.644595) (xy 91.8219 -236.612408) (xy 91.788152 -236.574314)
			(xy 91.760951 -236.5313) (xy 91.741003 -236.48448) (xy 91.728824 -236.435066) (xy 91.724729 -236.384338)
			(xy 91.416632 -236.384338) (xy 91.41612 -236.409784) (xy 91.407956 -236.460018) (xy 91.39184 -236.508292)
			(xy 91.368189 -236.553355) (xy 91.337616 -236.594041) (xy 91.300912 -236.629296) (xy 91.259028 -236.658206)
			(xy 91.213049 -236.680023) (xy 91.164165 -236.694183) (xy 91.113644 -236.700317) (xy 91.062792 -236.698268)
			(xy 91.012928 -236.688088) (xy 90.965342 -236.670041) (xy 90.921268 -236.644595) (xy 90.881846 -236.612408)
			(xy 90.848098 -236.574314) (xy 90.820897 -236.5313) (xy 90.800949 -236.48448) (xy 90.78877 -236.435066)
			(xy 90.784675 -236.384338) (xy 90.479118 -236.384338) (xy 90.478628 -236.409327) (xy 90.470809 -236.45869)
			(xy 90.455365 -236.506222) (xy 90.432675 -236.550754) (xy 90.403299 -236.591187) (xy 90.367959 -236.626527)
			(xy 90.327526 -236.655903) (xy 90.282994 -236.678593) (xy 90.235462 -236.694037) (xy 90.186099 -236.701856)
			(xy 90.136121 -236.701856) (xy 90.086758 -236.694037) (xy 90.039226 -236.678593) (xy 89.994694 -236.655903)
			(xy 89.954261 -236.626527) (xy 89.918921 -236.591187) (xy 89.889545 -236.550754) (xy 89.866855 -236.506222)
			(xy 89.851411 -236.45869) (xy 89.843592 -236.409327) (xy 89.536275 -236.409327) (xy 89.536266 -236.409784)
			(xy 89.528102 -236.460018) (xy 89.511986 -236.508292) (xy 89.488335 -236.553355) (xy 89.457762 -236.594041)
			(xy 89.421058 -236.629296) (xy 89.379174 -236.658206) (xy 89.333195 -236.680023) (xy 89.284311 -236.694183)
			(xy 89.23379 -236.700317) (xy 89.182938 -236.698268) (xy 89.133074 -236.688088) (xy 89.085488 -236.670041)
			(xy 89.041414 -236.644595) (xy 89.001992 -236.612408) (xy 88.968244 -236.574314) (xy 88.941043 -236.5313)
			(xy 88.921095 -236.48448) (xy 88.908916 -236.435066) (xy 88.904821 -236.384338) (xy 88.59901 -236.384338)
			(xy 88.59852 -236.409327) (xy 88.590701 -236.45869) (xy 88.575257 -236.506222) (xy 88.552567 -236.550754)
			(xy 88.523191 -236.591187) (xy 88.487851 -236.626527) (xy 88.447418 -236.655903) (xy 88.402886 -236.678593)
			(xy 88.355354 -236.694037) (xy 88.305991 -236.701856) (xy 88.256013 -236.701856) (xy 88.20665 -236.694037)
			(xy 88.159118 -236.678593) (xy 88.114586 -236.655903) (xy 88.074153 -236.626527) (xy 88.038813 -236.591187)
			(xy 88.009437 -236.550754) (xy 87.986747 -236.506222) (xy 87.971303 -236.45869) (xy 87.963484 -236.409327)
			(xy 87.656167 -236.409327) (xy 87.656158 -236.409784) (xy 87.647994 -236.460018) (xy 87.631878 -236.508292)
			(xy 87.608227 -236.553355) (xy 87.577654 -236.594041) (xy 87.54095 -236.629296) (xy 87.499066 -236.658206)
			(xy 87.453087 -236.680023) (xy 87.404203 -236.694183) (xy 87.353682 -236.700317) (xy 87.30283 -236.698268)
			(xy 87.252966 -236.688088) (xy 87.20538 -236.670041) (xy 87.161306 -236.644595) (xy 87.121884 -236.612408)
			(xy 87.088136 -236.574314) (xy 87.060935 -236.5313) (xy 87.040987 -236.48448) (xy 87.028808 -236.435066)
			(xy 87.024713 -236.384338) (xy 86.719156 -236.384338) (xy 86.718666 -236.409327) (xy 86.710847 -236.45869)
			(xy 86.695403 -236.506222) (xy 86.672713 -236.550754) (xy 86.643337 -236.591187) (xy 86.607997 -236.626527)
			(xy 86.567564 -236.655903) (xy 86.523032 -236.678593) (xy 86.4755 -236.694037) (xy 86.426137 -236.701856)
			(xy 86.376159 -236.701856) (xy 86.326796 -236.694037) (xy 86.279264 -236.678593) (xy 86.234732 -236.655903)
			(xy 86.194299 -236.626527) (xy 86.158959 -236.591187) (xy 86.129583 -236.550754) (xy 86.106893 -236.506222)
			(xy 86.091449 -236.45869) (xy 86.08363 -236.409327) (xy 85.776313 -236.409327) (xy 85.776304 -236.409784)
			(xy 85.76814 -236.460018) (xy 85.752024 -236.508292) (xy 85.728373 -236.553355) (xy 85.6978 -236.594041)
			(xy 85.661096 -236.629296) (xy 85.619212 -236.658206) (xy 85.573233 -236.680023) (xy 85.524349 -236.694183)
			(xy 85.473828 -236.700317) (xy 85.422976 -236.698268) (xy 85.373112 -236.688088) (xy 85.325526 -236.670041)
			(xy 85.281452 -236.644595) (xy 85.24203 -236.612408) (xy 85.208282 -236.574314) (xy 85.181081 -236.5313)
			(xy 85.161133 -236.48448) (xy 85.148954 -236.435066) (xy 85.144859 -236.384338) (xy 84.836762 -236.384338)
			(xy 84.83625 -236.409784) (xy 84.828086 -236.460018) (xy 84.81197 -236.508292) (xy 84.788319 -236.553355)
			(xy 84.757746 -236.594041) (xy 84.721042 -236.629296) (xy 84.679158 -236.658206) (xy 84.633179 -236.680023)
			(xy 84.584295 -236.694183) (xy 84.533774 -236.700317) (xy 84.482922 -236.698268) (xy 84.433058 -236.688088)
			(xy 84.385472 -236.670041) (xy 84.341398 -236.644595) (xy 84.301976 -236.612408) (xy 84.268228 -236.574314)
			(xy 84.241027 -236.5313) (xy 84.221079 -236.48448) (xy 84.2089 -236.435066) (xy 84.204805 -236.384338)
			(xy 83.898994 -236.384338) (xy 83.898504 -236.409327) (xy 83.890685 -236.45869) (xy 83.875241 -236.506222)
			(xy 83.852551 -236.550754) (xy 83.823175 -236.591187) (xy 83.787835 -236.626527) (xy 83.747402 -236.655903)
			(xy 83.70287 -236.678593) (xy 83.655338 -236.694037) (xy 83.605975 -236.701856) (xy 83.555997 -236.701856)
			(xy 83.506634 -236.694037) (xy 83.459102 -236.678593) (xy 83.41457 -236.655903) (xy 83.374137 -236.626527)
			(xy 83.338797 -236.591187) (xy 83.309421 -236.550754) (xy 83.286731 -236.506222) (xy 83.271287 -236.45869)
			(xy 83.263468 -236.409327) (xy 82.956151 -236.409327) (xy 82.956142 -236.409784) (xy 82.947978 -236.460018)
			(xy 82.931862 -236.508292) (xy 82.908211 -236.553355) (xy 82.877638 -236.594041) (xy 82.840934 -236.629296)
			(xy 82.79905 -236.658206) (xy 82.753071 -236.680023) (xy 82.704187 -236.694183) (xy 82.653666 -236.700317)
			(xy 82.602814 -236.698268) (xy 82.55295 -236.688088) (xy 82.505364 -236.670041) (xy 82.46129 -236.644595)
			(xy 82.421868 -236.612408) (xy 82.38812 -236.574314) (xy 82.360919 -236.5313) (xy 82.340971 -236.48448)
			(xy 82.328792 -236.435066) (xy 82.324697 -236.384338) (xy 82.01914 -236.384338) (xy 82.01865 -236.409327)
			(xy 82.010831 -236.45869) (xy 81.995387 -236.506222) (xy 81.972697 -236.550754) (xy 81.943321 -236.591187)
			(xy 81.907981 -236.626527) (xy 81.867548 -236.655903) (xy 81.823016 -236.678593) (xy 81.775484 -236.694037)
			(xy 81.726121 -236.701856) (xy 81.676143 -236.701856) (xy 81.62678 -236.694037) (xy 81.579248 -236.678593)
			(xy 81.534716 -236.655903) (xy 81.494283 -236.626527) (xy 81.458943 -236.591187) (xy 81.429567 -236.550754)
			(xy 81.406877 -236.506222) (xy 81.391433 -236.45869) (xy 81.383614 -236.409327) (xy 81.076297 -236.409327)
			(xy 81.076288 -236.409784) (xy 81.068124 -236.460018) (xy 81.052008 -236.508292) (xy 81.028357 -236.553355)
			(xy 80.997784 -236.594041) (xy 80.96108 -236.629296) (xy 80.919196 -236.658206) (xy 80.873217 -236.680023)
			(xy 80.824333 -236.694183) (xy 80.773812 -236.700317) (xy 80.72296 -236.698268) (xy 80.673096 -236.688088)
			(xy 80.62551 -236.670041) (xy 80.581436 -236.644595) (xy 80.542014 -236.612408) (xy 80.508266 -236.574314)
			(xy 80.481065 -236.5313) (xy 80.461117 -236.48448) (xy 80.448938 -236.435066) (xy 80.444843 -236.384338)
			(xy 80.138734 -236.384338) (xy 80.138734 -236.409305) (xy 80.130911 -236.458699) (xy 80.115457 -236.506262)
			(xy 80.092754 -236.550821) (xy 80.063361 -236.591281) (xy 80.028 -236.626645) (xy 79.987542 -236.656042)
			(xy 79.942984 -236.678748) (xy 79.895423 -236.694205) (xy 79.846029 -236.702032) (xy 79.821024 -236.7026)
			(xy 79.796529 -236.702153) (xy 79.748117 -236.694655) (xy 79.701423 -236.679832) (xy 79.679292 -236.669326)
			(xy 79.665841 -236.663202) (xy 79.636729 -236.65818) (xy 79.607398 -236.661698) (xy 79.5803 -236.673461)
			(xy 79.557701 -236.692487) (xy 79.541491 -236.717185) (xy 79.533026 -236.745487) (xy 79.53248 -236.760258)
			(xy 79.53248 -237.194344) (xy 80.914743 -237.194344) (xy 80.918838 -237.143616) (xy 80.931017 -237.094202)
			(xy 80.950965 -237.047382) (xy 80.978166 -237.004368) (xy 81.011914 -236.966274) (xy 81.051336 -236.934087)
			(xy 81.09541 -236.908641) (xy 81.142996 -236.890594) (xy 81.19286 -236.880414) (xy 81.243712 -236.878365)
			(xy 81.294233 -236.884499) (xy 81.343117 -236.898659) (xy 81.389096 -236.920476) (xy 81.43098 -236.949386)
			(xy 81.467684 -236.984641) (xy 81.498257 -237.025327) (xy 81.521908 -237.07039) (xy 81.538024 -237.118664)
			(xy 81.546188 -237.168898) (xy 81.5467 -237.194344) (xy 81.854797 -237.194344) (xy 81.858892 -237.143616)
			(xy 81.871071 -237.094202) (xy 81.891019 -237.047382) (xy 81.91822 -237.004368) (xy 81.951968 -236.966274)
			(xy 81.99139 -236.934087) (xy 82.035464 -236.908641) (xy 82.08305 -236.890594) (xy 82.132914 -236.880414)
			(xy 82.183766 -236.878365) (xy 82.234287 -236.884499) (xy 82.283171 -236.898659) (xy 82.32915 -236.920476)
			(xy 82.371034 -236.949386) (xy 82.407738 -236.984641) (xy 82.438311 -237.025327) (xy 82.461962 -237.07039)
			(xy 82.478078 -237.118664) (xy 82.486242 -237.168898) (xy 82.486754 -237.194344) (xy 82.486251 -237.219333)
			(xy 82.793568 -237.219333) (xy 82.793568 -237.169355) (xy 82.801387 -237.119992) (xy 82.816831 -237.07246)
			(xy 82.839521 -237.027928) (xy 82.868897 -236.987495) (xy 82.904237 -236.952155) (xy 82.94467 -236.922779)
			(xy 82.989202 -236.900089) (xy 83.036734 -236.884645) (xy 83.086097 -236.876826) (xy 83.136075 -236.876826)
			(xy 83.185438 -236.884645) (xy 83.23297 -236.900089) (xy 83.277502 -236.922779) (xy 83.317935 -236.952155)
			(xy 83.353275 -236.987495) (xy 83.382651 -237.027928) (xy 83.405341 -237.07246) (xy 83.420785 -237.119992)
			(xy 83.428604 -237.169355) (xy 83.429094 -237.194344) (xy 83.734905 -237.194344) (xy 83.739 -237.143616)
			(xy 83.751179 -237.094202) (xy 83.771127 -237.047382) (xy 83.798328 -237.004368) (xy 83.832076 -236.966274)
			(xy 83.871498 -236.934087) (xy 83.915572 -236.908641) (xy 83.963158 -236.890594) (xy 84.013022 -236.880414)
			(xy 84.063874 -236.878365) (xy 84.114395 -236.884499) (xy 84.163279 -236.898659) (xy 84.209258 -236.920476)
			(xy 84.251142 -236.949386) (xy 84.287846 -236.984641) (xy 84.318419 -237.025327) (xy 84.34207 -237.07039)
			(xy 84.358186 -237.118664) (xy 84.36635 -237.168898) (xy 84.366862 -237.194344) (xy 84.366359 -237.219333)
			(xy 84.673422 -237.219333) (xy 84.673422 -237.169355) (xy 84.681241 -237.119992) (xy 84.696685 -237.07246)
			(xy 84.719375 -237.027928) (xy 84.748751 -236.987495) (xy 84.784091 -236.952155) (xy 84.824524 -236.922779)
			(xy 84.869056 -236.900089) (xy 84.916588 -236.884645) (xy 84.965951 -236.876826) (xy 85.015929 -236.876826)
			(xy 85.065292 -236.884645) (xy 85.112824 -236.900089) (xy 85.157356 -236.922779) (xy 85.197789 -236.952155)
			(xy 85.233129 -236.987495) (xy 85.262505 -237.027928) (xy 85.285195 -237.07246) (xy 85.300639 -237.119992)
			(xy 85.308458 -237.169355) (xy 85.308948 -237.194344) (xy 85.614759 -237.194344) (xy 85.618854 -237.143616)
			(xy 85.631033 -237.094202) (xy 85.650981 -237.047382) (xy 85.678182 -237.004368) (xy 85.71193 -236.966274)
			(xy 85.751352 -236.934087) (xy 85.795426 -236.908641) (xy 85.843012 -236.890594) (xy 85.892876 -236.880414)
			(xy 85.943728 -236.878365) (xy 85.994249 -236.884499) (xy 86.043133 -236.898659) (xy 86.089112 -236.920476)
			(xy 86.130996 -236.949386) (xy 86.1677 -236.984641) (xy 86.198273 -237.025327) (xy 86.221924 -237.07039)
			(xy 86.23804 -237.118664) (xy 86.246204 -237.168898) (xy 86.246716 -237.194344) (xy 87.494867 -237.194344)
			(xy 87.498962 -237.143616) (xy 87.511141 -237.094202) (xy 87.531089 -237.047382) (xy 87.55829 -237.004368)
			(xy 87.592038 -236.966274) (xy 87.63146 -236.934087) (xy 87.675534 -236.908641) (xy 87.72312 -236.890594)
			(xy 87.772984 -236.880414) (xy 87.823836 -236.878365) (xy 87.874357 -236.884499) (xy 87.923241 -236.898659)
			(xy 87.96922 -236.920476) (xy 88.011104 -236.949386) (xy 88.047808 -236.984641) (xy 88.078381 -237.025327)
			(xy 88.102032 -237.07039) (xy 88.118148 -237.118664) (xy 88.126312 -237.168898) (xy 88.126824 -237.194344)
			(xy 88.434921 -237.194344) (xy 88.439016 -237.143616) (xy 88.451195 -237.094202) (xy 88.471143 -237.047382)
			(xy 88.498344 -237.004368) (xy 88.532092 -236.966274) (xy 88.571514 -236.934087) (xy 88.615588 -236.908641)
			(xy 88.663174 -236.890594) (xy 88.713038 -236.880414) (xy 88.76389 -236.878365) (xy 88.814411 -236.884499)
			(xy 88.863295 -236.898659) (xy 88.909274 -236.920476) (xy 88.951158 -236.949386) (xy 88.987862 -236.984641)
			(xy 89.018435 -237.025327) (xy 89.042086 -237.07039) (xy 89.058202 -237.118664) (xy 89.066366 -237.168898)
			(xy 89.066878 -237.194344) (xy 89.066375 -237.219333) (xy 89.373438 -237.219333) (xy 89.373438 -237.169355)
			(xy 89.381257 -237.119992) (xy 89.396701 -237.07246) (xy 89.419391 -237.027928) (xy 89.448767 -236.987495)
			(xy 89.484107 -236.952155) (xy 89.52454 -236.922779) (xy 89.569072 -236.900089) (xy 89.616604 -236.884645)
			(xy 89.665967 -236.876826) (xy 89.715945 -236.876826) (xy 89.765308 -236.884645) (xy 89.81284 -236.900089)
			(xy 89.857372 -236.922779) (xy 89.897805 -236.952155) (xy 89.933145 -236.987495) (xy 89.962521 -237.027928)
			(xy 89.985211 -237.07246) (xy 90.000655 -237.119992) (xy 90.008474 -237.169355) (xy 90.008964 -237.194344)
			(xy 90.314775 -237.194344) (xy 90.31887 -237.143616) (xy 90.331049 -237.094202) (xy 90.350997 -237.047382)
			(xy 90.378198 -237.004368) (xy 90.411946 -236.966274) (xy 90.451368 -236.934087) (xy 90.495442 -236.908641)
			(xy 90.543028 -236.890594) (xy 90.592892 -236.880414) (xy 90.643744 -236.878365) (xy 90.694265 -236.884499)
			(xy 90.743149 -236.898659) (xy 90.789128 -236.920476) (xy 90.831012 -236.949386) (xy 90.867716 -236.984641)
			(xy 90.898289 -237.025327) (xy 90.92194 -237.07039) (xy 90.938056 -237.118664) (xy 90.94622 -237.168898)
			(xy 90.946732 -237.194344) (xy 90.946229 -237.219333) (xy 91.253546 -237.219333) (xy 91.253546 -237.169355)
			(xy 91.261365 -237.119992) (xy 91.276809 -237.07246) (xy 91.299499 -237.027928) (xy 91.328875 -236.987495)
			(xy 91.364215 -236.952155) (xy 91.404648 -236.922779) (xy 91.44918 -236.900089) (xy 91.496712 -236.884645)
			(xy 91.546075 -236.876826) (xy 91.596053 -236.876826) (xy 91.645416 -236.884645) (xy 91.692948 -236.900089)
			(xy 91.73748 -236.922779) (xy 91.777913 -236.952155) (xy 91.813253 -236.987495) (xy 91.842629 -237.027928)
			(xy 91.865319 -237.07246) (xy 91.880763 -237.119992) (xy 91.888582 -237.169355) (xy 91.889072 -237.194344)
			(xy 92.194883 -237.194344) (xy 92.198978 -237.143616) (xy 92.211157 -237.094202) (xy 92.231105 -237.047382)
			(xy 92.258306 -237.004368) (xy 92.292054 -236.966274) (xy 92.331476 -236.934087) (xy 92.37555 -236.908641)
			(xy 92.423136 -236.890594) (xy 92.473 -236.880414) (xy 92.523852 -236.878365) (xy 92.574373 -236.884499)
			(xy 92.623257 -236.898659) (xy 92.669236 -236.920476) (xy 92.71112 -236.949386) (xy 92.747824 -236.984641)
			(xy 92.778397 -237.025327) (xy 92.802048 -237.07039) (xy 92.818164 -237.118664) (xy 92.826328 -237.168898)
			(xy 92.82684 -237.194344) (xy 94.074737 -237.194344) (xy 94.078832 -237.143616) (xy 94.091011 -237.094202)
			(xy 94.110959 -237.047382) (xy 94.13816 -237.004368) (xy 94.171908 -236.966274) (xy 94.21133 -236.934087)
			(xy 94.255404 -236.908641) (xy 94.30299 -236.890594) (xy 94.352854 -236.880414) (xy 94.403706 -236.878365)
			(xy 94.454227 -236.884499) (xy 94.503111 -236.898659) (xy 94.54909 -236.920476) (xy 94.590974 -236.949386)
			(xy 94.627678 -236.984641) (xy 94.658251 -237.025327) (xy 94.681902 -237.07039) (xy 94.698018 -237.118664)
			(xy 94.706182 -237.168898) (xy 94.706694 -237.194344) (xy 95.014791 -237.194344) (xy 95.018886 -237.143616)
			(xy 95.031065 -237.094202) (xy 95.051013 -237.047382) (xy 95.078214 -237.004368) (xy 95.111962 -236.966274)
			(xy 95.151384 -236.934087) (xy 95.195458 -236.908641) (xy 95.243044 -236.890594) (xy 95.292908 -236.880414)
			(xy 95.34376 -236.878365) (xy 95.394281 -236.884499) (xy 95.443165 -236.898659) (xy 95.489144 -236.920476)
			(xy 95.531028 -236.949386) (xy 95.567732 -236.984641) (xy 95.598305 -237.025327) (xy 95.621956 -237.07039)
			(xy 95.638072 -237.118664) (xy 95.646236 -237.168898) (xy 95.646748 -237.194344) (xy 95.646245 -237.219333)
			(xy 95.953562 -237.219333) (xy 95.953562 -237.169355) (xy 95.961381 -237.119992) (xy 95.976825 -237.07246)
			(xy 95.999515 -237.027928) (xy 96.028891 -236.987495) (xy 96.064231 -236.952155) (xy 96.104664 -236.922779)
			(xy 96.149196 -236.900089) (xy 96.196728 -236.884645) (xy 96.246091 -236.876826) (xy 96.296069 -236.876826)
			(xy 96.345432 -236.884645) (xy 96.392964 -236.900089) (xy 96.437496 -236.922779) (xy 96.477929 -236.952155)
			(xy 96.513269 -236.987495) (xy 96.542645 -237.027928) (xy 96.565335 -237.07246) (xy 96.580779 -237.119992)
			(xy 96.588598 -237.169355) (xy 96.589088 -237.194344) (xy 96.588598 -237.219333) (xy 96.580779 -237.268696)
			(xy 96.565335 -237.316228) (xy 96.542645 -237.36076) (xy 96.513269 -237.401193) (xy 96.477929 -237.436533)
			(xy 96.437496 -237.465909) (xy 96.392964 -237.488599) (xy 96.345432 -237.504043) (xy 96.296069 -237.511862)
			(xy 96.246091 -237.511862) (xy 96.196728 -237.504043) (xy 96.149196 -237.488599) (xy 96.104664 -237.465909)
			(xy 96.064231 -237.436533) (xy 96.028891 -237.401193) (xy 95.999515 -237.36076) (xy 95.976825 -237.316228)
			(xy 95.961381 -237.268696) (xy 95.953562 -237.219333) (xy 95.646245 -237.219333) (xy 95.646236 -237.21979)
			(xy 95.638072 -237.270024) (xy 95.621956 -237.318298) (xy 95.598305 -237.363361) (xy 95.567732 -237.404047)
			(xy 95.531028 -237.439302) (xy 95.489144 -237.468212) (xy 95.443165 -237.490029) (xy 95.394281 -237.504189)
			(xy 95.34376 -237.510323) (xy 95.292908 -237.508274) (xy 95.243044 -237.498094) (xy 95.195458 -237.480047)
			(xy 95.151384 -237.454601) (xy 95.111962 -237.422414) (xy 95.078214 -237.38432) (xy 95.051013 -237.341306)
			(xy 95.031065 -237.294486) (xy 95.018886 -237.245072) (xy 95.014791 -237.194344) (xy 94.706694 -237.194344)
			(xy 94.706182 -237.21979) (xy 94.698018 -237.270024) (xy 94.681902 -237.318298) (xy 94.658251 -237.363361)
			(xy 94.627678 -237.404047) (xy 94.590974 -237.439302) (xy 94.54909 -237.468212) (xy 94.503111 -237.490029)
			(xy 94.454227 -237.504189) (xy 94.403706 -237.510323) (xy 94.352854 -237.508274) (xy 94.30299 -237.498094)
			(xy 94.255404 -237.480047) (xy 94.21133 -237.454601) (xy 94.171908 -237.422414) (xy 94.13816 -237.38432)
			(xy 94.110959 -237.341306) (xy 94.091011 -237.294486) (xy 94.078832 -237.245072) (xy 94.074737 -237.194344)
			(xy 92.82684 -237.194344) (xy 92.826328 -237.21979) (xy 92.818164 -237.270024) (xy 92.802048 -237.318298)
			(xy 92.778397 -237.363361) (xy 92.747824 -237.404047) (xy 92.71112 -237.439302) (xy 92.669236 -237.468212)
			(xy 92.623257 -237.490029) (xy 92.574373 -237.504189) (xy 92.523852 -237.510323) (xy 92.473 -237.508274)
			(xy 92.423136 -237.498094) (xy 92.37555 -237.480047) (xy 92.331476 -237.454601) (xy 92.292054 -237.422414)
			(xy 92.258306 -237.38432) (xy 92.231105 -237.341306) (xy 92.211157 -237.294486) (xy 92.198978 -237.245072)
			(xy 92.194883 -237.194344) (xy 91.889072 -237.194344) (xy 91.888582 -237.219333) (xy 91.880763 -237.268696)
			(xy 91.865319 -237.316228) (xy 91.842629 -237.36076) (xy 91.813253 -237.401193) (xy 91.777913 -237.436533)
			(xy 91.73748 -237.465909) (xy 91.692948 -237.488599) (xy 91.645416 -237.504043) (xy 91.596053 -237.511862)
			(xy 91.546075 -237.511862) (xy 91.496712 -237.504043) (xy 91.44918 -237.488599) (xy 91.404648 -237.465909)
			(xy 91.364215 -237.436533) (xy 91.328875 -237.401193) (xy 91.299499 -237.36076) (xy 91.276809 -237.316228)
			(xy 91.261365 -237.268696) (xy 91.253546 -237.219333) (xy 90.946229 -237.219333) (xy 90.94622 -237.21979)
			(xy 90.938056 -237.270024) (xy 90.92194 -237.318298) (xy 90.898289 -237.363361) (xy 90.867716 -237.404047)
			(xy 90.831012 -237.439302) (xy 90.789128 -237.468212) (xy 90.743149 -237.490029) (xy 90.694265 -237.504189)
			(xy 90.643744 -237.510323) (xy 90.592892 -237.508274) (xy 90.543028 -237.498094) (xy 90.495442 -237.480047)
			(xy 90.451368 -237.454601) (xy 90.411946 -237.422414) (xy 90.378198 -237.38432) (xy 90.350997 -237.341306)
			(xy 90.331049 -237.294486) (xy 90.31887 -237.245072) (xy 90.314775 -237.194344) (xy 90.008964 -237.194344)
			(xy 90.008474 -237.219333) (xy 90.000655 -237.268696) (xy 89.985211 -237.316228) (xy 89.962521 -237.36076)
			(xy 89.933145 -237.401193) (xy 89.897805 -237.436533) (xy 89.857372 -237.465909) (xy 89.81284 -237.488599)
			(xy 89.765308 -237.504043) (xy 89.715945 -237.511862) (xy 89.665967 -237.511862) (xy 89.616604 -237.504043)
			(xy 89.569072 -237.488599) (xy 89.52454 -237.465909) (xy 89.484107 -237.436533) (xy 89.448767 -237.401193)
			(xy 89.419391 -237.36076) (xy 89.396701 -237.316228) (xy 89.381257 -237.268696) (xy 89.373438 -237.219333)
			(xy 89.066375 -237.219333) (xy 89.066366 -237.21979) (xy 89.058202 -237.270024) (xy 89.042086 -237.318298)
			(xy 89.018435 -237.363361) (xy 88.987862 -237.404047) (xy 88.951158 -237.439302) (xy 88.909274 -237.468212)
			(xy 88.863295 -237.490029) (xy 88.814411 -237.504189) (xy 88.76389 -237.510323) (xy 88.713038 -237.508274)
			(xy 88.663174 -237.498094) (xy 88.615588 -237.480047) (xy 88.571514 -237.454601) (xy 88.532092 -237.422414)
			(xy 88.498344 -237.38432) (xy 88.471143 -237.341306) (xy 88.451195 -237.294486) (xy 88.439016 -237.245072)
			(xy 88.434921 -237.194344) (xy 88.126824 -237.194344) (xy 88.126312 -237.21979) (xy 88.118148 -237.270024)
			(xy 88.102032 -237.318298) (xy 88.078381 -237.363361) (xy 88.047808 -237.404047) (xy 88.011104 -237.439302)
			(xy 87.96922 -237.468212) (xy 87.923241 -237.490029) (xy 87.874357 -237.504189) (xy 87.823836 -237.510323)
			(xy 87.772984 -237.508274) (xy 87.72312 -237.498094) (xy 87.675534 -237.480047) (xy 87.63146 -237.454601)
			(xy 87.592038 -237.422414) (xy 87.55829 -237.38432) (xy 87.531089 -237.341306) (xy 87.511141 -237.294486)
			(xy 87.498962 -237.245072) (xy 87.494867 -237.194344) (xy 86.246716 -237.194344) (xy 86.246204 -237.21979)
			(xy 86.23804 -237.270024) (xy 86.221924 -237.318298) (xy 86.198273 -237.363361) (xy 86.1677 -237.404047)
			(xy 86.130996 -237.439302) (xy 86.089112 -237.468212) (xy 86.043133 -237.490029) (xy 85.994249 -237.504189)
			(xy 85.943728 -237.510323) (xy 85.892876 -237.508274) (xy 85.843012 -237.498094) (xy 85.795426 -237.480047)
			(xy 85.751352 -237.454601) (xy 85.71193 -237.422414) (xy 85.678182 -237.38432) (xy 85.650981 -237.341306)
			(xy 85.631033 -237.294486) (xy 85.618854 -237.245072) (xy 85.614759 -237.194344) (xy 85.308948 -237.194344)
			(xy 85.308458 -237.219333) (xy 85.300639 -237.268696) (xy 85.285195 -237.316228) (xy 85.262505 -237.36076)
			(xy 85.233129 -237.401193) (xy 85.197789 -237.436533) (xy 85.157356 -237.465909) (xy 85.112824 -237.488599)
			(xy 85.065292 -237.504043) (xy 85.015929 -237.511862) (xy 84.965951 -237.511862) (xy 84.916588 -237.504043)
			(xy 84.869056 -237.488599) (xy 84.824524 -237.465909) (xy 84.784091 -237.436533) (xy 84.748751 -237.401193)
			(xy 84.719375 -237.36076) (xy 84.696685 -237.316228) (xy 84.681241 -237.268696) (xy 84.673422 -237.219333)
			(xy 84.366359 -237.219333) (xy 84.36635 -237.21979) (xy 84.358186 -237.270024) (xy 84.34207 -237.318298)
			(xy 84.318419 -237.363361) (xy 84.287846 -237.404047) (xy 84.251142 -237.439302) (xy 84.209258 -237.468212)
			(xy 84.163279 -237.490029) (xy 84.114395 -237.504189) (xy 84.063874 -237.510323) (xy 84.013022 -237.508274)
			(xy 83.963158 -237.498094) (xy 83.915572 -237.480047) (xy 83.871498 -237.454601) (xy 83.832076 -237.422414)
			(xy 83.798328 -237.38432) (xy 83.771127 -237.341306) (xy 83.751179 -237.294486) (xy 83.739 -237.245072)
			(xy 83.734905 -237.194344) (xy 83.429094 -237.194344) (xy 83.428604 -237.219333) (xy 83.420785 -237.268696)
			(xy 83.405341 -237.316228) (xy 83.382651 -237.36076) (xy 83.353275 -237.401193) (xy 83.317935 -237.436533)
			(xy 83.277502 -237.465909) (xy 83.23297 -237.488599) (xy 83.185438 -237.504043) (xy 83.136075 -237.511862)
			(xy 83.086097 -237.511862) (xy 83.036734 -237.504043) (xy 82.989202 -237.488599) (xy 82.94467 -237.465909)
			(xy 82.904237 -237.436533) (xy 82.868897 -237.401193) (xy 82.839521 -237.36076) (xy 82.816831 -237.316228)
			(xy 82.801387 -237.268696) (xy 82.793568 -237.219333) (xy 82.486251 -237.219333) (xy 82.486242 -237.21979)
			(xy 82.478078 -237.270024) (xy 82.461962 -237.318298) (xy 82.438311 -237.363361) (xy 82.407738 -237.404047)
			(xy 82.371034 -237.439302) (xy 82.32915 -237.468212) (xy 82.283171 -237.490029) (xy 82.234287 -237.504189)
			(xy 82.183766 -237.510323) (xy 82.132914 -237.508274) (xy 82.08305 -237.498094) (xy 82.035464 -237.480047)
			(xy 81.99139 -237.454601) (xy 81.951968 -237.422414) (xy 81.91822 -237.38432) (xy 81.891019 -237.341306)
			(xy 81.871071 -237.294486) (xy 81.858892 -237.245072) (xy 81.854797 -237.194344) (xy 81.5467 -237.194344)
			(xy 81.546188 -237.21979) (xy 81.538024 -237.270024) (xy 81.521908 -237.318298) (xy 81.498257 -237.363361)
			(xy 81.467684 -237.404047) (xy 81.43098 -237.439302) (xy 81.389096 -237.468212) (xy 81.343117 -237.490029)
			(xy 81.294233 -237.504189) (xy 81.243712 -237.510323) (xy 81.19286 -237.508274) (xy 81.142996 -237.498094)
			(xy 81.09541 -237.480047) (xy 81.051336 -237.454601) (xy 81.011914 -237.422414) (xy 80.978166 -237.38432)
			(xy 80.950965 -237.341306) (xy 80.931017 -237.294486) (xy 80.918838 -237.245072) (xy 80.914743 -237.194344)
			(xy 79.53248 -237.194344) (xy 79.53248 -237.62843) (xy 79.532972 -237.64321) (xy 79.541421 -237.671537)
			(xy 79.557631 -237.696256) (xy 79.580243 -237.715295) (xy 79.607362 -237.727057) (xy 79.636714 -237.730557)
			(xy 79.665838 -237.725502) (xy 79.679292 -237.719362) (xy 79.701429 -237.70887) (xy 79.748121 -237.694053)
			(xy 79.796531 -237.686558) (xy 79.821024 -237.686088) (xy 79.846028 -237.68658) (xy 79.89542 -237.694407)
			(xy 79.942979 -237.709863) (xy 79.987536 -237.732568) (xy 80.027992 -237.761964) (xy 80.063351 -237.797327)
			(xy 80.092744 -237.837785) (xy 80.115446 -237.882343) (xy 80.130899 -237.929904) (xy 80.138722 -237.979296)
			(xy 80.138722 -238.00435) (xy 80.444843 -238.00435) (xy 80.448938 -237.953622) (xy 80.461117 -237.904208)
			(xy 80.481065 -237.857388) (xy 80.508266 -237.814374) (xy 80.542014 -237.77628) (xy 80.581436 -237.744093)
			(xy 80.62551 -237.718647) (xy 80.673096 -237.7006) (xy 80.72296 -237.69042) (xy 80.773812 -237.688371)
			(xy 80.824333 -237.694505) (xy 80.873217 -237.708665) (xy 80.919196 -237.730482) (xy 80.96108 -237.759392)
			(xy 80.997784 -237.794647) (xy 81.028357 -237.835333) (xy 81.052008 -237.880396) (xy 81.068124 -237.92867)
			(xy 81.076288 -237.978904) (xy 81.0768 -238.00435) (xy 81.076297 -238.029339) (xy 81.383614 -238.029339)
			(xy 81.383614 -237.979361) (xy 81.391433 -237.929998) (xy 81.406877 -237.882466) (xy 81.429567 -237.837934)
			(xy 81.458943 -237.797501) (xy 81.494283 -237.762161) (xy 81.534716 -237.732785) (xy 81.579248 -237.710095)
			(xy 81.62678 -237.694651) (xy 81.676143 -237.686832) (xy 81.726121 -237.686832) (xy 81.775484 -237.694651)
			(xy 81.823016 -237.710095) (xy 81.867548 -237.732785) (xy 81.907981 -237.762161) (xy 81.943321 -237.797501)
			(xy 81.972697 -237.837934) (xy 81.995387 -237.882466) (xy 82.010831 -237.929998) (xy 82.01865 -237.979361)
			(xy 82.01914 -238.00435) (xy 82.324697 -238.00435) (xy 82.328792 -237.953622) (xy 82.340971 -237.904208)
			(xy 82.360919 -237.857388) (xy 82.38812 -237.814374) (xy 82.421868 -237.77628) (xy 82.46129 -237.744093)
			(xy 82.505364 -237.718647) (xy 82.55295 -237.7006) (xy 82.602814 -237.69042) (xy 82.653666 -237.688371)
			(xy 82.704187 -237.694505) (xy 82.753071 -237.708665) (xy 82.79905 -237.730482) (xy 82.840934 -237.759392)
			(xy 82.877638 -237.794647) (xy 82.908211 -237.835333) (xy 82.931862 -237.880396) (xy 82.947978 -237.92867)
			(xy 82.956142 -237.978904) (xy 82.956654 -238.00435) (xy 82.956151 -238.029339) (xy 83.263468 -238.029339)
			(xy 83.263468 -237.979361) (xy 83.271287 -237.929998) (xy 83.286731 -237.882466) (xy 83.309421 -237.837934)
			(xy 83.338797 -237.797501) (xy 83.374137 -237.762161) (xy 83.41457 -237.732785) (xy 83.459102 -237.710095)
			(xy 83.506634 -237.694651) (xy 83.555997 -237.686832) (xy 83.605975 -237.686832) (xy 83.655338 -237.694651)
			(xy 83.70287 -237.710095) (xy 83.747402 -237.732785) (xy 83.787835 -237.762161) (xy 83.823175 -237.797501)
			(xy 83.852551 -237.837934) (xy 83.875241 -237.882466) (xy 83.890685 -237.929998) (xy 83.898504 -237.979361)
			(xy 83.898994 -238.00435) (xy 84.204805 -238.00435) (xy 84.2089 -237.953622) (xy 84.221079 -237.904208)
			(xy 84.241027 -237.857388) (xy 84.268228 -237.814374) (xy 84.301976 -237.77628) (xy 84.341398 -237.744093)
			(xy 84.385472 -237.718647) (xy 84.433058 -237.7006) (xy 84.482922 -237.69042) (xy 84.533774 -237.688371)
			(xy 84.584295 -237.694505) (xy 84.633179 -237.708665) (xy 84.679158 -237.730482) (xy 84.721042 -237.759392)
			(xy 84.757746 -237.794647) (xy 84.788319 -237.835333) (xy 84.81197 -237.880396) (xy 84.828086 -237.92867)
			(xy 84.83625 -237.978904) (xy 84.836762 -238.00435) (xy 85.144859 -238.00435) (xy 85.148954 -237.953622)
			(xy 85.161133 -237.904208) (xy 85.181081 -237.857388) (xy 85.208282 -237.814374) (xy 85.24203 -237.77628)
			(xy 85.281452 -237.744093) (xy 85.325526 -237.718647) (xy 85.373112 -237.7006) (xy 85.422976 -237.69042)
			(xy 85.473828 -237.688371) (xy 85.524349 -237.694505) (xy 85.573233 -237.708665) (xy 85.619212 -237.730482)
			(xy 85.661096 -237.759392) (xy 85.6978 -237.794647) (xy 85.728373 -237.835333) (xy 85.752024 -237.880396)
			(xy 85.76814 -237.92867) (xy 85.776304 -237.978904) (xy 85.776816 -238.00435) (xy 85.776313 -238.029339)
			(xy 86.08363 -238.029339) (xy 86.08363 -237.979361) (xy 86.091449 -237.929998) (xy 86.106893 -237.882466)
			(xy 86.129583 -237.837934) (xy 86.158959 -237.797501) (xy 86.194299 -237.762161) (xy 86.234732 -237.732785)
			(xy 86.279264 -237.710095) (xy 86.326796 -237.694651) (xy 86.376159 -237.686832) (xy 86.426137 -237.686832)
			(xy 86.4755 -237.694651) (xy 86.523032 -237.710095) (xy 86.567564 -237.732785) (xy 86.607997 -237.762161)
			(xy 86.643337 -237.797501) (xy 86.672713 -237.837934) (xy 86.695403 -237.882466) (xy 86.710847 -237.929998)
			(xy 86.718666 -237.979361) (xy 86.719156 -238.00435) (xy 87.024713 -238.00435) (xy 87.028808 -237.953622)
			(xy 87.040987 -237.904208) (xy 87.060935 -237.857388) (xy 87.088136 -237.814374) (xy 87.121884 -237.77628)
			(xy 87.161306 -237.744093) (xy 87.20538 -237.718647) (xy 87.252966 -237.7006) (xy 87.30283 -237.69042)
			(xy 87.353682 -237.688371) (xy 87.404203 -237.694505) (xy 87.453087 -237.708665) (xy 87.499066 -237.730482)
			(xy 87.54095 -237.759392) (xy 87.577654 -237.794647) (xy 87.608227 -237.835333) (xy 87.631878 -237.880396)
			(xy 87.647994 -237.92867) (xy 87.656158 -237.978904) (xy 87.65667 -238.00435) (xy 87.656167 -238.029339)
			(xy 87.963484 -238.029339) (xy 87.963484 -237.979361) (xy 87.971303 -237.929998) (xy 87.986747 -237.882466)
			(xy 88.009437 -237.837934) (xy 88.038813 -237.797501) (xy 88.074153 -237.762161) (xy 88.114586 -237.732785)
			(xy 88.159118 -237.710095) (xy 88.20665 -237.694651) (xy 88.256013 -237.686832) (xy 88.305991 -237.686832)
			(xy 88.355354 -237.694651) (xy 88.402886 -237.710095) (xy 88.447418 -237.732785) (xy 88.487851 -237.762161)
			(xy 88.523191 -237.797501) (xy 88.552567 -237.837934) (xy 88.575257 -237.882466) (xy 88.590701 -237.929998)
			(xy 88.59852 -237.979361) (xy 88.59901 -238.00435) (xy 88.904821 -238.00435) (xy 88.908916 -237.953622)
			(xy 88.921095 -237.904208) (xy 88.941043 -237.857388) (xy 88.968244 -237.814374) (xy 89.001992 -237.77628)
			(xy 89.041414 -237.744093) (xy 89.085488 -237.718647) (xy 89.133074 -237.7006) (xy 89.182938 -237.69042)
			(xy 89.23379 -237.688371) (xy 89.284311 -237.694505) (xy 89.333195 -237.708665) (xy 89.379174 -237.730482)
			(xy 89.421058 -237.759392) (xy 89.457762 -237.794647) (xy 89.488335 -237.835333) (xy 89.511986 -237.880396)
			(xy 89.528102 -237.92867) (xy 89.536266 -237.978904) (xy 89.536778 -238.00435) (xy 89.536275 -238.029339)
			(xy 89.843592 -238.029339) (xy 89.843592 -237.979361) (xy 89.851411 -237.929998) (xy 89.866855 -237.882466)
			(xy 89.889545 -237.837934) (xy 89.918921 -237.797501) (xy 89.954261 -237.762161) (xy 89.994694 -237.732785)
			(xy 90.039226 -237.710095) (xy 90.086758 -237.694651) (xy 90.136121 -237.686832) (xy 90.186099 -237.686832)
			(xy 90.235462 -237.694651) (xy 90.282994 -237.710095) (xy 90.327526 -237.732785) (xy 90.367959 -237.762161)
			(xy 90.403299 -237.797501) (xy 90.432675 -237.837934) (xy 90.455365 -237.882466) (xy 90.470809 -237.929998)
			(xy 90.478628 -237.979361) (xy 90.479118 -238.00435) (xy 90.784675 -238.00435) (xy 90.78877 -237.953622)
			(xy 90.800949 -237.904208) (xy 90.820897 -237.857388) (xy 90.848098 -237.814374) (xy 90.881846 -237.77628)
			(xy 90.921268 -237.744093) (xy 90.965342 -237.718647) (xy 91.012928 -237.7006) (xy 91.062792 -237.69042)
			(xy 91.113644 -237.688371) (xy 91.164165 -237.694505) (xy 91.213049 -237.708665) (xy 91.259028 -237.730482)
			(xy 91.300912 -237.759392) (xy 91.337616 -237.794647) (xy 91.368189 -237.835333) (xy 91.39184 -237.880396)
			(xy 91.407956 -237.92867) (xy 91.41612 -237.978904) (xy 91.416632 -238.00435) (xy 91.724729 -238.00435)
			(xy 91.728824 -237.953622) (xy 91.741003 -237.904208) (xy 91.760951 -237.857388) (xy 91.788152 -237.814374)
			(xy 91.8219 -237.77628) (xy 91.861322 -237.744093) (xy 91.905396 -237.718647) (xy 91.952982 -237.7006)
			(xy 92.002846 -237.69042) (xy 92.053698 -237.688371) (xy 92.104219 -237.694505) (xy 92.153103 -237.708665)
			(xy 92.199082 -237.730482) (xy 92.240966 -237.759392) (xy 92.27767 -237.794647) (xy 92.308243 -237.835333)
			(xy 92.331894 -237.880396) (xy 92.34801 -237.92867) (xy 92.356174 -237.978904) (xy 92.356686 -238.00435)
			(xy 92.356183 -238.029339) (xy 92.6635 -238.029339) (xy 92.6635 -237.979361) (xy 92.671319 -237.929998)
			(xy 92.686763 -237.882466) (xy 92.709453 -237.837934) (xy 92.738829 -237.797501) (xy 92.774169 -237.762161)
			(xy 92.814602 -237.732785) (xy 92.859134 -237.710095) (xy 92.906666 -237.694651) (xy 92.956029 -237.686832)
			(xy 93.006007 -237.686832) (xy 93.05537 -237.694651) (xy 93.102902 -237.710095) (xy 93.147434 -237.732785)
			(xy 93.187867 -237.762161) (xy 93.223207 -237.797501) (xy 93.252583 -237.837934) (xy 93.275273 -237.882466)
			(xy 93.290717 -237.929998) (xy 93.298536 -237.979361) (xy 93.299026 -238.00435) (xy 93.604837 -238.00435)
			(xy 93.608932 -237.953622) (xy 93.621111 -237.904208) (xy 93.641059 -237.857388) (xy 93.66826 -237.814374)
			(xy 93.702008 -237.77628) (xy 93.74143 -237.744093) (xy 93.785504 -237.718647) (xy 93.83309 -237.7006)
			(xy 93.882954 -237.69042) (xy 93.933806 -237.688371) (xy 93.984327 -237.694505) (xy 94.033211 -237.708665)
			(xy 94.07919 -237.730482) (xy 94.121074 -237.759392) (xy 94.157778 -237.794647) (xy 94.188351 -237.835333)
			(xy 94.212002 -237.880396) (xy 94.228118 -237.92867) (xy 94.236282 -237.978904) (xy 94.236794 -238.00435)
			(xy 94.236291 -238.029339) (xy 94.543608 -238.029339) (xy 94.543608 -237.979361) (xy 94.551427 -237.929998)
			(xy 94.566871 -237.882466) (xy 94.589561 -237.837934) (xy 94.618937 -237.797501) (xy 94.654277 -237.762161)
			(xy 94.69471 -237.732785) (xy 94.739242 -237.710095) (xy 94.786774 -237.694651) (xy 94.836137 -237.686832)
			(xy 94.886115 -237.686832) (xy 94.935478 -237.694651) (xy 94.98301 -237.710095) (xy 95.027542 -237.732785)
			(xy 95.067975 -237.762161) (xy 95.103315 -237.797501) (xy 95.132691 -237.837934) (xy 95.155381 -237.882466)
			(xy 95.170825 -237.929998) (xy 95.178644 -237.979361) (xy 95.179134 -238.00435) (xy 95.484691 -238.00435)
			(xy 95.488786 -237.953622) (xy 95.500965 -237.904208) (xy 95.520913 -237.857388) (xy 95.548114 -237.814374)
			(xy 95.581862 -237.77628) (xy 95.621284 -237.744093) (xy 95.665358 -237.718647) (xy 95.712944 -237.7006)
			(xy 95.762808 -237.69042) (xy 95.81366 -237.688371) (xy 95.864181 -237.694505) (xy 95.913065 -237.708665)
			(xy 95.959044 -237.730482) (xy 96.000928 -237.759392) (xy 96.037632 -237.794647) (xy 96.068205 -237.835333)
			(xy 96.091856 -237.880396) (xy 96.107972 -237.92867) (xy 96.116136 -237.978904) (xy 96.116648 -238.00435)
			(xy 96.116136 -238.029796) (xy 96.107972 -238.08003) (xy 96.091856 -238.128304) (xy 96.068205 -238.173367)
			(xy 96.037632 -238.214053) (xy 96.000928 -238.249308) (xy 95.959044 -238.278218) (xy 95.913065 -238.300035)
			(xy 95.864181 -238.314195) (xy 95.81366 -238.320329) (xy 95.762808 -238.31828) (xy 95.712944 -238.3081)
			(xy 95.665358 -238.290053) (xy 95.621284 -238.264607) (xy 95.581862 -238.23242) (xy 95.548114 -238.194326)
			(xy 95.520913 -238.151312) (xy 95.500965 -238.104492) (xy 95.488786 -238.055078) (xy 95.484691 -238.00435)
			(xy 95.179134 -238.00435) (xy 95.178644 -238.029339) (xy 95.170825 -238.078702) (xy 95.155381 -238.126234)
			(xy 95.132691 -238.170766) (xy 95.103315 -238.211199) (xy 95.067975 -238.246539) (xy 95.027542 -238.275915)
			(xy 94.98301 -238.298605) (xy 94.935478 -238.314049) (xy 94.886115 -238.321868) (xy 94.836137 -238.321868)
			(xy 94.786774 -238.314049) (xy 94.739242 -238.298605) (xy 94.69471 -238.275915) (xy 94.654277 -238.246539)
			(xy 94.618937 -238.211199) (xy 94.589561 -238.170766) (xy 94.566871 -238.126234) (xy 94.551427 -238.078702)
			(xy 94.543608 -238.029339) (xy 94.236291 -238.029339) (xy 94.236282 -238.029796) (xy 94.228118 -238.08003)
			(xy 94.212002 -238.128304) (xy 94.188351 -238.173367) (xy 94.157778 -238.214053) (xy 94.121074 -238.249308)
			(xy 94.07919 -238.278218) (xy 94.033211 -238.300035) (xy 93.984327 -238.314195) (xy 93.933806 -238.320329)
			(xy 93.882954 -238.31828) (xy 93.83309 -238.3081) (xy 93.785504 -238.290053) (xy 93.74143 -238.264607)
			(xy 93.702008 -238.23242) (xy 93.66826 -238.194326) (xy 93.641059 -238.151312) (xy 93.621111 -238.104492)
			(xy 93.608932 -238.055078) (xy 93.604837 -238.00435) (xy 93.299026 -238.00435) (xy 93.298536 -238.029339)
			(xy 93.290717 -238.078702) (xy 93.275273 -238.126234) (xy 93.252583 -238.170766) (xy 93.223207 -238.211199)
			(xy 93.187867 -238.246539) (xy 93.147434 -238.275915) (xy 93.102902 -238.298605) (xy 93.05537 -238.314049)
			(xy 93.006007 -238.321868) (xy 92.956029 -238.321868) (xy 92.906666 -238.314049) (xy 92.859134 -238.298605)
			(xy 92.814602 -238.275915) (xy 92.774169 -238.246539) (xy 92.738829 -238.211199) (xy 92.709453 -238.170766)
			(xy 92.686763 -238.126234) (xy 92.671319 -238.078702) (xy 92.6635 -238.029339) (xy 92.356183 -238.029339)
			(xy 92.356174 -238.029796) (xy 92.34801 -238.08003) (xy 92.331894 -238.128304) (xy 92.308243 -238.173367)
			(xy 92.27767 -238.214053) (xy 92.240966 -238.249308) (xy 92.199082 -238.278218) (xy 92.153103 -238.300035)
			(xy 92.104219 -238.314195) (xy 92.053698 -238.320329) (xy 92.002846 -238.31828) (xy 91.952982 -238.3081)
			(xy 91.905396 -238.290053) (xy 91.861322 -238.264607) (xy 91.8219 -238.23242) (xy 91.788152 -238.194326)
			(xy 91.760951 -238.151312) (xy 91.741003 -238.104492) (xy 91.728824 -238.055078) (xy 91.724729 -238.00435)
			(xy 91.416632 -238.00435) (xy 91.41612 -238.029796) (xy 91.407956 -238.08003) (xy 91.39184 -238.128304)
			(xy 91.368189 -238.173367) (xy 91.337616 -238.214053) (xy 91.300912 -238.249308) (xy 91.259028 -238.278218)
			(xy 91.213049 -238.300035) (xy 91.164165 -238.314195) (xy 91.113644 -238.320329) (xy 91.062792 -238.31828)
			(xy 91.012928 -238.3081) (xy 90.965342 -238.290053) (xy 90.921268 -238.264607) (xy 90.881846 -238.23242)
			(xy 90.848098 -238.194326) (xy 90.820897 -238.151312) (xy 90.800949 -238.104492) (xy 90.78877 -238.055078)
			(xy 90.784675 -238.00435) (xy 90.479118 -238.00435) (xy 90.478628 -238.029339) (xy 90.470809 -238.078702)
			(xy 90.455365 -238.126234) (xy 90.432675 -238.170766) (xy 90.403299 -238.211199) (xy 90.367959 -238.246539)
			(xy 90.327526 -238.275915) (xy 90.282994 -238.298605) (xy 90.235462 -238.314049) (xy 90.186099 -238.321868)
			(xy 90.136121 -238.321868) (xy 90.086758 -238.314049) (xy 90.039226 -238.298605) (xy 89.994694 -238.275915)
			(xy 89.954261 -238.246539) (xy 89.918921 -238.211199) (xy 89.889545 -238.170766) (xy 89.866855 -238.126234)
			(xy 89.851411 -238.078702) (xy 89.843592 -238.029339) (xy 89.536275 -238.029339) (xy 89.536266 -238.029796)
			(xy 89.528102 -238.08003) (xy 89.511986 -238.128304) (xy 89.488335 -238.173367) (xy 89.457762 -238.214053)
			(xy 89.421058 -238.249308) (xy 89.379174 -238.278218) (xy 89.333195 -238.300035) (xy 89.284311 -238.314195)
			(xy 89.23379 -238.320329) (xy 89.182938 -238.31828) (xy 89.133074 -238.3081) (xy 89.085488 -238.290053)
			(xy 89.041414 -238.264607) (xy 89.001992 -238.23242) (xy 88.968244 -238.194326) (xy 88.941043 -238.151312)
			(xy 88.921095 -238.104492) (xy 88.908916 -238.055078) (xy 88.904821 -238.00435) (xy 88.59901 -238.00435)
			(xy 88.59852 -238.029339) (xy 88.590701 -238.078702) (xy 88.575257 -238.126234) (xy 88.552567 -238.170766)
			(xy 88.523191 -238.211199) (xy 88.487851 -238.246539) (xy 88.447418 -238.275915) (xy 88.402886 -238.298605)
			(xy 88.355354 -238.314049) (xy 88.305991 -238.321868) (xy 88.256013 -238.321868) (xy 88.20665 -238.314049)
			(xy 88.159118 -238.298605) (xy 88.114586 -238.275915) (xy 88.074153 -238.246539) (xy 88.038813 -238.211199)
			(xy 88.009437 -238.170766) (xy 87.986747 -238.126234) (xy 87.971303 -238.078702) (xy 87.963484 -238.029339)
			(xy 87.656167 -238.029339) (xy 87.656158 -238.029796) (xy 87.647994 -238.08003) (xy 87.631878 -238.128304)
			(xy 87.608227 -238.173367) (xy 87.577654 -238.214053) (xy 87.54095 -238.249308) (xy 87.499066 -238.278218)
			(xy 87.453087 -238.300035) (xy 87.404203 -238.314195) (xy 87.353682 -238.320329) (xy 87.30283 -238.31828)
			(xy 87.252966 -238.3081) (xy 87.20538 -238.290053) (xy 87.161306 -238.264607) (xy 87.121884 -238.23242)
			(xy 87.088136 -238.194326) (xy 87.060935 -238.151312) (xy 87.040987 -238.104492) (xy 87.028808 -238.055078)
			(xy 87.024713 -238.00435) (xy 86.719156 -238.00435) (xy 86.718666 -238.029339) (xy 86.710847 -238.078702)
			(xy 86.695403 -238.126234) (xy 86.672713 -238.170766) (xy 86.643337 -238.211199) (xy 86.607997 -238.246539)
			(xy 86.567564 -238.275915) (xy 86.523032 -238.298605) (xy 86.4755 -238.314049) (xy 86.426137 -238.321868)
			(xy 86.376159 -238.321868) (xy 86.326796 -238.314049) (xy 86.279264 -238.298605) (xy 86.234732 -238.275915)
			(xy 86.194299 -238.246539) (xy 86.158959 -238.211199) (xy 86.129583 -238.170766) (xy 86.106893 -238.126234)
			(xy 86.091449 -238.078702) (xy 86.08363 -238.029339) (xy 85.776313 -238.029339) (xy 85.776304 -238.029796)
			(xy 85.76814 -238.08003) (xy 85.752024 -238.128304) (xy 85.728373 -238.173367) (xy 85.6978 -238.214053)
			(xy 85.661096 -238.249308) (xy 85.619212 -238.278218) (xy 85.573233 -238.300035) (xy 85.524349 -238.314195)
			(xy 85.473828 -238.320329) (xy 85.422976 -238.31828) (xy 85.373112 -238.3081) (xy 85.325526 -238.290053)
			(xy 85.281452 -238.264607) (xy 85.24203 -238.23242) (xy 85.208282 -238.194326) (xy 85.181081 -238.151312)
			(xy 85.161133 -238.104492) (xy 85.148954 -238.055078) (xy 85.144859 -238.00435) (xy 84.836762 -238.00435)
			(xy 84.83625 -238.029796) (xy 84.828086 -238.08003) (xy 84.81197 -238.128304) (xy 84.788319 -238.173367)
			(xy 84.757746 -238.214053) (xy 84.721042 -238.249308) (xy 84.679158 -238.278218) (xy 84.633179 -238.300035)
			(xy 84.584295 -238.314195) (xy 84.533774 -238.320329) (xy 84.482922 -238.31828) (xy 84.433058 -238.3081)
			(xy 84.385472 -238.290053) (xy 84.341398 -238.264607) (xy 84.301976 -238.23242) (xy 84.268228 -238.194326)
			(xy 84.241027 -238.151312) (xy 84.221079 -238.104492) (xy 84.2089 -238.055078) (xy 84.204805 -238.00435)
			(xy 83.898994 -238.00435) (xy 83.898504 -238.029339) (xy 83.890685 -238.078702) (xy 83.875241 -238.126234)
			(xy 83.852551 -238.170766) (xy 83.823175 -238.211199) (xy 83.787835 -238.246539) (xy 83.747402 -238.275915)
			(xy 83.70287 -238.298605) (xy 83.655338 -238.314049) (xy 83.605975 -238.321868) (xy 83.555997 -238.321868)
			(xy 83.506634 -238.314049) (xy 83.459102 -238.298605) (xy 83.41457 -238.275915) (xy 83.374137 -238.246539)
			(xy 83.338797 -238.211199) (xy 83.309421 -238.170766) (xy 83.286731 -238.126234) (xy 83.271287 -238.078702)
			(xy 83.263468 -238.029339) (xy 82.956151 -238.029339) (xy 82.956142 -238.029796) (xy 82.947978 -238.08003)
			(xy 82.931862 -238.128304) (xy 82.908211 -238.173367) (xy 82.877638 -238.214053) (xy 82.840934 -238.249308)
			(xy 82.79905 -238.278218) (xy 82.753071 -238.300035) (xy 82.704187 -238.314195) (xy 82.653666 -238.320329)
			(xy 82.602814 -238.31828) (xy 82.55295 -238.3081) (xy 82.505364 -238.290053) (xy 82.46129 -238.264607)
			(xy 82.421868 -238.23242) (xy 82.38812 -238.194326) (xy 82.360919 -238.151312) (xy 82.340971 -238.104492)
			(xy 82.328792 -238.055078) (xy 82.324697 -238.00435) (xy 82.01914 -238.00435) (xy 82.01865 -238.029339)
			(xy 82.010831 -238.078702) (xy 81.995387 -238.126234) (xy 81.972697 -238.170766) (xy 81.943321 -238.211199)
			(xy 81.907981 -238.246539) (xy 81.867548 -238.275915) (xy 81.823016 -238.298605) (xy 81.775484 -238.314049)
			(xy 81.726121 -238.321868) (xy 81.676143 -238.321868) (xy 81.62678 -238.314049) (xy 81.579248 -238.298605)
			(xy 81.534716 -238.275915) (xy 81.494283 -238.246539) (xy 81.458943 -238.211199) (xy 81.429567 -238.170766)
			(xy 81.406877 -238.126234) (xy 81.391433 -238.078702) (xy 81.383614 -238.029339) (xy 81.076297 -238.029339)
			(xy 81.076288 -238.029796) (xy 81.068124 -238.08003) (xy 81.052008 -238.128304) (xy 81.028357 -238.173367)
			(xy 80.997784 -238.214053) (xy 80.96108 -238.249308) (xy 80.919196 -238.278218) (xy 80.873217 -238.300035)
			(xy 80.824333 -238.314195) (xy 80.773812 -238.320329) (xy 80.72296 -238.31828) (xy 80.673096 -238.3081)
			(xy 80.62551 -238.290053) (xy 80.581436 -238.264607) (xy 80.542014 -238.23242) (xy 80.508266 -238.194326)
			(xy 80.481065 -238.151312) (xy 80.461117 -238.104492) (xy 80.448938 -238.055078) (xy 80.444843 -238.00435)
			(xy 80.138722 -238.00435) (xy 80.138722 -238.029304) (xy 80.130899 -238.078696) (xy 80.115446 -238.126257)
			(xy 80.092744 -238.170815) (xy 80.063351 -238.211273) (xy 80.027992 -238.246636) (xy 79.987536 -238.276032)
			(xy 79.942979 -238.298737) (xy 79.89542 -238.314193) (xy 79.846028 -238.32202) (xy 79.821024 -238.322612)
			(xy 79.796529 -238.322165) (xy 79.748117 -238.314667) (xy 79.701423 -238.299845) (xy 79.679292 -238.289338)
			(xy 79.665842 -238.283214) (xy 79.636731 -238.278191) (xy 79.6074 -238.281708) (xy 79.580302 -238.293472)
			(xy 79.557705 -238.312499) (xy 79.541497 -238.337197) (xy 79.533035 -238.3655) (xy 79.53248 -238.38027)
			(xy 79.53248 -238.839345) (xy 79.97366 -238.839345) (xy 79.97366 -238.789367) (xy 79.981479 -238.740004)
			(xy 79.996923 -238.692472) (xy 80.019613 -238.64794) (xy 80.048989 -238.607507) (xy 80.084329 -238.572167)
			(xy 80.124762 -238.542791) (xy 80.169294 -238.520101) (xy 80.216826 -238.504657) (xy 80.266189 -238.496838)
			(xy 80.316167 -238.496838) (xy 80.36553 -238.504657) (xy 80.413062 -238.520101) (xy 80.457594 -238.542791)
			(xy 80.498027 -238.572167) (xy 80.533367 -238.607507) (xy 80.562743 -238.64794) (xy 80.585433 -238.692472)
			(xy 80.600877 -238.740004) (xy 80.608696 -238.789367) (xy 80.609186 -238.814356) (xy 80.914743 -238.814356)
			(xy 80.918838 -238.763628) (xy 80.931017 -238.714214) (xy 80.950965 -238.667394) (xy 80.978166 -238.62438)
			(xy 81.011914 -238.586286) (xy 81.051336 -238.554099) (xy 81.09541 -238.528653) (xy 81.142996 -238.510606)
			(xy 81.19286 -238.500426) (xy 81.243712 -238.498377) (xy 81.294233 -238.504511) (xy 81.343117 -238.518671)
			(xy 81.389096 -238.540488) (xy 81.43098 -238.569398) (xy 81.467684 -238.604653) (xy 81.498257 -238.645339)
			(xy 81.521908 -238.690402) (xy 81.538024 -238.738676) (xy 81.546188 -238.78891) (xy 81.5467 -238.814356)
			(xy 81.854797 -238.814356) (xy 81.858892 -238.763628) (xy 81.871071 -238.714214) (xy 81.891019 -238.667394)
			(xy 81.91822 -238.62438) (xy 81.951968 -238.586286) (xy 81.99139 -238.554099) (xy 82.035464 -238.528653)
			(xy 82.08305 -238.510606) (xy 82.132914 -238.500426) (xy 82.183766 -238.498377) (xy 82.234287 -238.504511)
			(xy 82.283171 -238.518671) (xy 82.32915 -238.540488) (xy 82.371034 -238.569398) (xy 82.407738 -238.604653)
			(xy 82.438311 -238.645339) (xy 82.461962 -238.690402) (xy 82.478078 -238.738676) (xy 82.486242 -238.78891)
			(xy 82.486754 -238.814356) (xy 82.486251 -238.839345) (xy 82.793568 -238.839345) (xy 82.793568 -238.789367)
			(xy 82.801387 -238.740004) (xy 82.816831 -238.692472) (xy 82.839521 -238.64794) (xy 82.868897 -238.607507)
			(xy 82.904237 -238.572167) (xy 82.94467 -238.542791) (xy 82.989202 -238.520101) (xy 83.036734 -238.504657)
			(xy 83.086097 -238.496838) (xy 83.136075 -238.496838) (xy 83.185438 -238.504657) (xy 83.23297 -238.520101)
			(xy 83.277502 -238.542791) (xy 83.317935 -238.572167) (xy 83.353275 -238.607507) (xy 83.382651 -238.64794)
			(xy 83.405341 -238.692472) (xy 83.420785 -238.740004) (xy 83.428604 -238.789367) (xy 83.429094 -238.814356)
			(xy 83.734905 -238.814356) (xy 83.739 -238.763628) (xy 83.751179 -238.714214) (xy 83.771127 -238.667394)
			(xy 83.798328 -238.62438) (xy 83.832076 -238.586286) (xy 83.871498 -238.554099) (xy 83.915572 -238.528653)
			(xy 83.963158 -238.510606) (xy 84.013022 -238.500426) (xy 84.063874 -238.498377) (xy 84.114395 -238.504511)
			(xy 84.163279 -238.518671) (xy 84.209258 -238.540488) (xy 84.251142 -238.569398) (xy 84.287846 -238.604653)
			(xy 84.318419 -238.645339) (xy 84.34207 -238.690402) (xy 84.358186 -238.738676) (xy 84.36635 -238.78891)
			(xy 84.366862 -238.814356) (xy 84.366359 -238.839345) (xy 84.673422 -238.839345) (xy 84.673422 -238.789367)
			(xy 84.681241 -238.740004) (xy 84.696685 -238.692472) (xy 84.719375 -238.64794) (xy 84.748751 -238.607507)
			(xy 84.784091 -238.572167) (xy 84.824524 -238.542791) (xy 84.869056 -238.520101) (xy 84.916588 -238.504657)
			(xy 84.965951 -238.496838) (xy 85.015929 -238.496838) (xy 85.065292 -238.504657) (xy 85.112824 -238.520101)
			(xy 85.157356 -238.542791) (xy 85.197789 -238.572167) (xy 85.233129 -238.607507) (xy 85.262505 -238.64794)
			(xy 85.285195 -238.692472) (xy 85.300639 -238.740004) (xy 85.308458 -238.789367) (xy 85.308948 -238.814356)
			(xy 85.614759 -238.814356) (xy 85.618854 -238.763628) (xy 85.631033 -238.714214) (xy 85.650981 -238.667394)
			(xy 85.678182 -238.62438) (xy 85.71193 -238.586286) (xy 85.751352 -238.554099) (xy 85.795426 -238.528653)
			(xy 85.843012 -238.510606) (xy 85.892876 -238.500426) (xy 85.943728 -238.498377) (xy 85.994249 -238.504511)
			(xy 86.043133 -238.518671) (xy 86.089112 -238.540488) (xy 86.130996 -238.569398) (xy 86.1677 -238.604653)
			(xy 86.198273 -238.645339) (xy 86.221924 -238.690402) (xy 86.23804 -238.738676) (xy 86.246204 -238.78891)
			(xy 86.246716 -238.814356) (xy 86.246213 -238.839345) (xy 86.55353 -238.839345) (xy 86.55353 -238.789367)
			(xy 86.561349 -238.740004) (xy 86.576793 -238.692472) (xy 86.599483 -238.64794) (xy 86.628859 -238.607507)
			(xy 86.664199 -238.572167) (xy 86.704632 -238.542791) (xy 86.749164 -238.520101) (xy 86.796696 -238.504657)
			(xy 86.846059 -238.496838) (xy 86.896037 -238.496838) (xy 86.9454 -238.504657) (xy 86.992932 -238.520101)
			(xy 87.037464 -238.542791) (xy 87.077897 -238.572167) (xy 87.113237 -238.607507) (xy 87.142613 -238.64794)
			(xy 87.165303 -238.692472) (xy 87.180747 -238.740004) (xy 87.188566 -238.789367) (xy 87.189056 -238.814356)
			(xy 87.494867 -238.814356) (xy 87.498962 -238.763628) (xy 87.511141 -238.714214) (xy 87.531089 -238.667394)
			(xy 87.55829 -238.62438) (xy 87.592038 -238.586286) (xy 87.63146 -238.554099) (xy 87.675534 -238.528653)
			(xy 87.72312 -238.510606) (xy 87.772984 -238.500426) (xy 87.823836 -238.498377) (xy 87.874357 -238.504511)
			(xy 87.923241 -238.518671) (xy 87.96922 -238.540488) (xy 88.011104 -238.569398) (xy 88.047808 -238.604653)
			(xy 88.078381 -238.645339) (xy 88.102032 -238.690402) (xy 88.118148 -238.738676) (xy 88.126312 -238.78891)
			(xy 88.126824 -238.814356) (xy 88.434921 -238.814356) (xy 88.439016 -238.763628) (xy 88.451195 -238.714214)
			(xy 88.471143 -238.667394) (xy 88.498344 -238.62438) (xy 88.532092 -238.586286) (xy 88.571514 -238.554099)
			(xy 88.615588 -238.528653) (xy 88.663174 -238.510606) (xy 88.713038 -238.500426) (xy 88.76389 -238.498377)
			(xy 88.814411 -238.504511) (xy 88.863295 -238.518671) (xy 88.909274 -238.540488) (xy 88.951158 -238.569398)
			(xy 88.987862 -238.604653) (xy 89.018435 -238.645339) (xy 89.042086 -238.690402) (xy 89.058202 -238.738676)
			(xy 89.066366 -238.78891) (xy 89.066878 -238.814356) (xy 89.066375 -238.839345) (xy 89.373438 -238.839345)
			(xy 89.373438 -238.789367) (xy 89.381257 -238.740004) (xy 89.396701 -238.692472) (xy 89.419391 -238.64794)
			(xy 89.448767 -238.607507) (xy 89.484107 -238.572167) (xy 89.52454 -238.542791) (xy 89.569072 -238.520101)
			(xy 89.616604 -238.504657) (xy 89.665967 -238.496838) (xy 89.715945 -238.496838) (xy 89.765308 -238.504657)
			(xy 89.81284 -238.520101) (xy 89.857372 -238.542791) (xy 89.897805 -238.572167) (xy 89.933145 -238.607507)
			(xy 89.962521 -238.64794) (xy 89.985211 -238.692472) (xy 90.000655 -238.740004) (xy 90.008474 -238.789367)
			(xy 90.008964 -238.814356) (xy 90.314775 -238.814356) (xy 90.31887 -238.763628) (xy 90.331049 -238.714214)
			(xy 90.350997 -238.667394) (xy 90.378198 -238.62438) (xy 90.411946 -238.586286) (xy 90.451368 -238.554099)
			(xy 90.495442 -238.528653) (xy 90.543028 -238.510606) (xy 90.592892 -238.500426) (xy 90.643744 -238.498377)
			(xy 90.694265 -238.504511) (xy 90.743149 -238.518671) (xy 90.789128 -238.540488) (xy 90.831012 -238.569398)
			(xy 90.867716 -238.604653) (xy 90.898289 -238.645339) (xy 90.92194 -238.690402) (xy 90.938056 -238.738676)
			(xy 90.94622 -238.78891) (xy 90.946732 -238.814356) (xy 90.946229 -238.839345) (xy 91.253546 -238.839345)
			(xy 91.253546 -238.789367) (xy 91.261365 -238.740004) (xy 91.276809 -238.692472) (xy 91.299499 -238.64794)
			(xy 91.328875 -238.607507) (xy 91.364215 -238.572167) (xy 91.404648 -238.542791) (xy 91.44918 -238.520101)
			(xy 91.496712 -238.504657) (xy 91.546075 -238.496838) (xy 91.596053 -238.496838) (xy 91.645416 -238.504657)
			(xy 91.692948 -238.520101) (xy 91.73748 -238.542791) (xy 91.777913 -238.572167) (xy 91.813253 -238.607507)
			(xy 91.842629 -238.64794) (xy 91.865319 -238.692472) (xy 91.880763 -238.740004) (xy 91.888582 -238.789367)
			(xy 91.889072 -238.814356) (xy 92.194883 -238.814356) (xy 92.198978 -238.763628) (xy 92.211157 -238.714214)
			(xy 92.231105 -238.667394) (xy 92.258306 -238.62438) (xy 92.292054 -238.586286) (xy 92.331476 -238.554099)
			(xy 92.37555 -238.528653) (xy 92.423136 -238.510606) (xy 92.473 -238.500426) (xy 92.523852 -238.498377)
			(xy 92.574373 -238.504511) (xy 92.623257 -238.518671) (xy 92.669236 -238.540488) (xy 92.71112 -238.569398)
			(xy 92.747824 -238.604653) (xy 92.778397 -238.645339) (xy 92.802048 -238.690402) (xy 92.818164 -238.738676)
			(xy 92.826328 -238.78891) (xy 92.82684 -238.814356) (xy 92.826337 -238.839345) (xy 93.1334 -238.839345)
			(xy 93.1334 -238.789367) (xy 93.141219 -238.740004) (xy 93.156663 -238.692472) (xy 93.179353 -238.64794)
			(xy 93.208729 -238.607507) (xy 93.244069 -238.572167) (xy 93.284502 -238.542791) (xy 93.329034 -238.520101)
			(xy 93.376566 -238.504657) (xy 93.425929 -238.496838) (xy 93.475907 -238.496838) (xy 93.52527 -238.504657)
			(xy 93.572802 -238.520101) (xy 93.617334 -238.542791) (xy 93.657767 -238.572167) (xy 93.693107 -238.607507)
			(xy 93.722483 -238.64794) (xy 93.745173 -238.692472) (xy 93.760617 -238.740004) (xy 93.768436 -238.789367)
			(xy 93.768926 -238.814356) (xy 94.074737 -238.814356) (xy 94.078832 -238.763628) (xy 94.091011 -238.714214)
			(xy 94.110959 -238.667394) (xy 94.13816 -238.62438) (xy 94.171908 -238.586286) (xy 94.21133 -238.554099)
			(xy 94.255404 -238.528653) (xy 94.30299 -238.510606) (xy 94.352854 -238.500426) (xy 94.403706 -238.498377)
			(xy 94.454227 -238.504511) (xy 94.503111 -238.518671) (xy 94.54909 -238.540488) (xy 94.590974 -238.569398)
			(xy 94.627678 -238.604653) (xy 94.658251 -238.645339) (xy 94.681902 -238.690402) (xy 94.698018 -238.738676)
			(xy 94.706182 -238.78891) (xy 94.706694 -238.814356) (xy 95.014791 -238.814356) (xy 95.018886 -238.763628)
			(xy 95.031065 -238.714214) (xy 95.051013 -238.667394) (xy 95.078214 -238.62438) (xy 95.111962 -238.586286)
			(xy 95.151384 -238.554099) (xy 95.195458 -238.528653) (xy 95.243044 -238.510606) (xy 95.292908 -238.500426)
			(xy 95.34376 -238.498377) (xy 95.394281 -238.504511) (xy 95.443165 -238.518671) (xy 95.489144 -238.540488)
			(xy 95.531028 -238.569398) (xy 95.567732 -238.604653) (xy 95.598305 -238.645339) (xy 95.621956 -238.690402)
			(xy 95.638072 -238.738676) (xy 95.646236 -238.78891) (xy 95.646748 -238.814356) (xy 95.646245 -238.839345)
			(xy 95.953562 -238.839345) (xy 95.953562 -238.789367) (xy 95.961381 -238.740004) (xy 95.976825 -238.692472)
			(xy 95.999515 -238.64794) (xy 96.028891 -238.607507) (xy 96.064231 -238.572167) (xy 96.104664 -238.542791)
			(xy 96.149196 -238.520101) (xy 96.196728 -238.504657) (xy 96.246091 -238.496838) (xy 96.296069 -238.496838)
			(xy 96.345432 -238.504657) (xy 96.392964 -238.520101) (xy 96.437496 -238.542791) (xy 96.477929 -238.572167)
			(xy 96.513269 -238.607507) (xy 96.542645 -238.64794) (xy 96.565335 -238.692472) (xy 96.580779 -238.740004)
			(xy 96.588598 -238.789367) (xy 96.589088 -238.814356) (xy 96.588598 -238.839345) (xy 96.580779 -238.888708)
			(xy 96.565335 -238.93624) (xy 96.542645 -238.980772) (xy 96.513269 -239.021205) (xy 96.477929 -239.056545)
			(xy 96.437496 -239.085921) (xy 96.392964 -239.108611) (xy 96.345432 -239.124055) (xy 96.296069 -239.131874)
			(xy 96.246091 -239.131874) (xy 96.196728 -239.124055) (xy 96.149196 -239.108611) (xy 96.104664 -239.085921)
			(xy 96.064231 -239.056545) (xy 96.028891 -239.021205) (xy 95.999515 -238.980772) (xy 95.976825 -238.93624)
			(xy 95.961381 -238.888708) (xy 95.953562 -238.839345) (xy 95.646245 -238.839345) (xy 95.646236 -238.839802)
			(xy 95.638072 -238.890036) (xy 95.621956 -238.93831) (xy 95.598305 -238.983373) (xy 95.567732 -239.024059)
			(xy 95.531028 -239.059314) (xy 95.489144 -239.088224) (xy 95.443165 -239.110041) (xy 95.394281 -239.124201)
			(xy 95.34376 -239.130335) (xy 95.292908 -239.128286) (xy 95.243044 -239.118106) (xy 95.195458 -239.100059)
			(xy 95.151384 -239.074613) (xy 95.111962 -239.042426) (xy 95.078214 -239.004332) (xy 95.051013 -238.961318)
			(xy 95.031065 -238.914498) (xy 95.018886 -238.865084) (xy 95.014791 -238.814356) (xy 94.706694 -238.814356)
			(xy 94.706182 -238.839802) (xy 94.698018 -238.890036) (xy 94.681902 -238.93831) (xy 94.658251 -238.983373)
			(xy 94.627678 -239.024059) (xy 94.590974 -239.059314) (xy 94.54909 -239.088224) (xy 94.503111 -239.110041)
			(xy 94.454227 -239.124201) (xy 94.403706 -239.130335) (xy 94.352854 -239.128286) (xy 94.30299 -239.118106)
			(xy 94.255404 -239.100059) (xy 94.21133 -239.074613) (xy 94.171908 -239.042426) (xy 94.13816 -239.004332)
			(xy 94.110959 -238.961318) (xy 94.091011 -238.914498) (xy 94.078832 -238.865084) (xy 94.074737 -238.814356)
			(xy 93.768926 -238.814356) (xy 93.768436 -238.839345) (xy 93.760617 -238.888708) (xy 93.745173 -238.93624)
			(xy 93.722483 -238.980772) (xy 93.693107 -239.021205) (xy 93.657767 -239.056545) (xy 93.617334 -239.085921)
			(xy 93.572802 -239.108611) (xy 93.52527 -239.124055) (xy 93.475907 -239.131874) (xy 93.425929 -239.131874)
			(xy 93.376566 -239.124055) (xy 93.329034 -239.108611) (xy 93.284502 -239.085921) (xy 93.244069 -239.056545)
			(xy 93.208729 -239.021205) (xy 93.179353 -238.980772) (xy 93.156663 -238.93624) (xy 93.141219 -238.888708)
			(xy 93.1334 -238.839345) (xy 92.826337 -238.839345) (xy 92.826328 -238.839802) (xy 92.818164 -238.890036)
			(xy 92.802048 -238.93831) (xy 92.778397 -238.983373) (xy 92.747824 -239.024059) (xy 92.71112 -239.059314)
			(xy 92.669236 -239.088224) (xy 92.623257 -239.110041) (xy 92.574373 -239.124201) (xy 92.523852 -239.130335)
			(xy 92.473 -239.128286) (xy 92.423136 -239.118106) (xy 92.37555 -239.100059) (xy 92.331476 -239.074613)
			(xy 92.292054 -239.042426) (xy 92.258306 -239.004332) (xy 92.231105 -238.961318) (xy 92.211157 -238.914498)
			(xy 92.198978 -238.865084) (xy 92.194883 -238.814356) (xy 91.889072 -238.814356) (xy 91.888582 -238.839345)
			(xy 91.880763 -238.888708) (xy 91.865319 -238.93624) (xy 91.842629 -238.980772) (xy 91.813253 -239.021205)
			(xy 91.777913 -239.056545) (xy 91.73748 -239.085921) (xy 91.692948 -239.108611) (xy 91.645416 -239.124055)
			(xy 91.596053 -239.131874) (xy 91.546075 -239.131874) (xy 91.496712 -239.124055) (xy 91.44918 -239.108611)
			(xy 91.404648 -239.085921) (xy 91.364215 -239.056545) (xy 91.328875 -239.021205) (xy 91.299499 -238.980772)
			(xy 91.276809 -238.93624) (xy 91.261365 -238.888708) (xy 91.253546 -238.839345) (xy 90.946229 -238.839345)
			(xy 90.94622 -238.839802) (xy 90.938056 -238.890036) (xy 90.92194 -238.93831) (xy 90.898289 -238.983373)
			(xy 90.867716 -239.024059) (xy 90.831012 -239.059314) (xy 90.789128 -239.088224) (xy 90.743149 -239.110041)
			(xy 90.694265 -239.124201) (xy 90.643744 -239.130335) (xy 90.592892 -239.128286) (xy 90.543028 -239.118106)
			(xy 90.495442 -239.100059) (xy 90.451368 -239.074613) (xy 90.411946 -239.042426) (xy 90.378198 -239.004332)
			(xy 90.350997 -238.961318) (xy 90.331049 -238.914498) (xy 90.31887 -238.865084) (xy 90.314775 -238.814356)
			(xy 90.008964 -238.814356) (xy 90.008474 -238.839345) (xy 90.000655 -238.888708) (xy 89.985211 -238.93624)
			(xy 89.962521 -238.980772) (xy 89.933145 -239.021205) (xy 89.897805 -239.056545) (xy 89.857372 -239.085921)
			(xy 89.81284 -239.108611) (xy 89.765308 -239.124055) (xy 89.715945 -239.131874) (xy 89.665967 -239.131874)
			(xy 89.616604 -239.124055) (xy 89.569072 -239.108611) (xy 89.52454 -239.085921) (xy 89.484107 -239.056545)
			(xy 89.448767 -239.021205) (xy 89.419391 -238.980772) (xy 89.396701 -238.93624) (xy 89.381257 -238.888708)
			(xy 89.373438 -238.839345) (xy 89.066375 -238.839345) (xy 89.066366 -238.839802) (xy 89.058202 -238.890036)
			(xy 89.042086 -238.93831) (xy 89.018435 -238.983373) (xy 88.987862 -239.024059) (xy 88.951158 -239.059314)
			(xy 88.909274 -239.088224) (xy 88.863295 -239.110041) (xy 88.814411 -239.124201) (xy 88.76389 -239.130335)
			(xy 88.713038 -239.128286) (xy 88.663174 -239.118106) (xy 88.615588 -239.100059) (xy 88.571514 -239.074613)
			(xy 88.532092 -239.042426) (xy 88.498344 -239.004332) (xy 88.471143 -238.961318) (xy 88.451195 -238.914498)
			(xy 88.439016 -238.865084) (xy 88.434921 -238.814356) (xy 88.126824 -238.814356) (xy 88.126312 -238.839802)
			(xy 88.118148 -238.890036) (xy 88.102032 -238.93831) (xy 88.078381 -238.983373) (xy 88.047808 -239.024059)
			(xy 88.011104 -239.059314) (xy 87.96922 -239.088224) (xy 87.923241 -239.110041) (xy 87.874357 -239.124201)
			(xy 87.823836 -239.130335) (xy 87.772984 -239.128286) (xy 87.72312 -239.118106) (xy 87.675534 -239.100059)
			(xy 87.63146 -239.074613) (xy 87.592038 -239.042426) (xy 87.55829 -239.004332) (xy 87.531089 -238.961318)
			(xy 87.511141 -238.914498) (xy 87.498962 -238.865084) (xy 87.494867 -238.814356) (xy 87.189056 -238.814356)
			(xy 87.188566 -238.839345) (xy 87.180747 -238.888708) (xy 87.165303 -238.93624) (xy 87.142613 -238.980772)
			(xy 87.113237 -239.021205) (xy 87.077897 -239.056545) (xy 87.037464 -239.085921) (xy 86.992932 -239.108611)
			(xy 86.9454 -239.124055) (xy 86.896037 -239.131874) (xy 86.846059 -239.131874) (xy 86.796696 -239.124055)
			(xy 86.749164 -239.108611) (xy 86.704632 -239.085921) (xy 86.664199 -239.056545) (xy 86.628859 -239.021205)
			(xy 86.599483 -238.980772) (xy 86.576793 -238.93624) (xy 86.561349 -238.888708) (xy 86.55353 -238.839345)
			(xy 86.246213 -238.839345) (xy 86.246204 -238.839802) (xy 86.23804 -238.890036) (xy 86.221924 -238.93831)
			(xy 86.198273 -238.983373) (xy 86.1677 -239.024059) (xy 86.130996 -239.059314) (xy 86.089112 -239.088224)
			(xy 86.043133 -239.110041) (xy 85.994249 -239.124201) (xy 85.943728 -239.130335) (xy 85.892876 -239.128286)
			(xy 85.843012 -239.118106) (xy 85.795426 -239.100059) (xy 85.751352 -239.074613) (xy 85.71193 -239.042426)
			(xy 85.678182 -239.004332) (xy 85.650981 -238.961318) (xy 85.631033 -238.914498) (xy 85.618854 -238.865084)
			(xy 85.614759 -238.814356) (xy 85.308948 -238.814356) (xy 85.308458 -238.839345) (xy 85.300639 -238.888708)
			(xy 85.285195 -238.93624) (xy 85.262505 -238.980772) (xy 85.233129 -239.021205) (xy 85.197789 -239.056545)
			(xy 85.157356 -239.085921) (xy 85.112824 -239.108611) (xy 85.065292 -239.124055) (xy 85.015929 -239.131874)
			(xy 84.965951 -239.131874) (xy 84.916588 -239.124055) (xy 84.869056 -239.108611) (xy 84.824524 -239.085921)
			(xy 84.784091 -239.056545) (xy 84.748751 -239.021205) (xy 84.719375 -238.980772) (xy 84.696685 -238.93624)
			(xy 84.681241 -238.888708) (xy 84.673422 -238.839345) (xy 84.366359 -238.839345) (xy 84.36635 -238.839802)
			(xy 84.358186 -238.890036) (xy 84.34207 -238.93831) (xy 84.318419 -238.983373) (xy 84.287846 -239.024059)
			(xy 84.251142 -239.059314) (xy 84.209258 -239.088224) (xy 84.163279 -239.110041) (xy 84.114395 -239.124201)
			(xy 84.063874 -239.130335) (xy 84.013022 -239.128286) (xy 83.963158 -239.118106) (xy 83.915572 -239.100059)
			(xy 83.871498 -239.074613) (xy 83.832076 -239.042426) (xy 83.798328 -239.004332) (xy 83.771127 -238.961318)
			(xy 83.751179 -238.914498) (xy 83.739 -238.865084) (xy 83.734905 -238.814356) (xy 83.429094 -238.814356)
			(xy 83.428604 -238.839345) (xy 83.420785 -238.888708) (xy 83.405341 -238.93624) (xy 83.382651 -238.980772)
			(xy 83.353275 -239.021205) (xy 83.317935 -239.056545) (xy 83.277502 -239.085921) (xy 83.23297 -239.108611)
			(xy 83.185438 -239.124055) (xy 83.136075 -239.131874) (xy 83.086097 -239.131874) (xy 83.036734 -239.124055)
			(xy 82.989202 -239.108611) (xy 82.94467 -239.085921) (xy 82.904237 -239.056545) (xy 82.868897 -239.021205)
			(xy 82.839521 -238.980772) (xy 82.816831 -238.93624) (xy 82.801387 -238.888708) (xy 82.793568 -238.839345)
			(xy 82.486251 -238.839345) (xy 82.486242 -238.839802) (xy 82.478078 -238.890036) (xy 82.461962 -238.93831)
			(xy 82.438311 -238.983373) (xy 82.407738 -239.024059) (xy 82.371034 -239.059314) (xy 82.32915 -239.088224)
			(xy 82.283171 -239.110041) (xy 82.234287 -239.124201) (xy 82.183766 -239.130335) (xy 82.132914 -239.128286)
			(xy 82.08305 -239.118106) (xy 82.035464 -239.100059) (xy 81.99139 -239.074613) (xy 81.951968 -239.042426)
			(xy 81.91822 -239.004332) (xy 81.891019 -238.961318) (xy 81.871071 -238.914498) (xy 81.858892 -238.865084)
			(xy 81.854797 -238.814356) (xy 81.5467 -238.814356) (xy 81.546188 -238.839802) (xy 81.538024 -238.890036)
			(xy 81.521908 -238.93831) (xy 81.498257 -238.983373) (xy 81.467684 -239.024059) (xy 81.43098 -239.059314)
			(xy 81.389096 -239.088224) (xy 81.343117 -239.110041) (xy 81.294233 -239.124201) (xy 81.243712 -239.130335)
			(xy 81.19286 -239.128286) (xy 81.142996 -239.118106) (xy 81.09541 -239.100059) (xy 81.051336 -239.074613)
			(xy 81.011914 -239.042426) (xy 80.978166 -239.004332) (xy 80.950965 -238.961318) (xy 80.931017 -238.914498)
			(xy 80.918838 -238.865084) (xy 80.914743 -238.814356) (xy 80.609186 -238.814356) (xy 80.608696 -238.839345)
			(xy 80.600877 -238.888708) (xy 80.585433 -238.93624) (xy 80.562743 -238.980772) (xy 80.533367 -239.021205)
			(xy 80.498027 -239.056545) (xy 80.457594 -239.085921) (xy 80.413062 -239.108611) (xy 80.36553 -239.124055)
			(xy 80.316167 -239.131874) (xy 80.266189 -239.131874) (xy 80.216826 -239.124055) (xy 80.169294 -239.108611)
			(xy 80.124762 -239.085921) (xy 80.084329 -239.056545) (xy 80.048989 -239.021205) (xy 80.019613 -238.980772)
			(xy 79.996923 -238.93624) (xy 79.981479 -238.888708) (xy 79.97366 -238.839345) (xy 79.53248 -238.839345)
			(xy 79.53248 -239.624362) (xy 80.444843 -239.624362) (xy 80.448938 -239.573634) (xy 80.461117 -239.52422)
			(xy 80.481065 -239.4774) (xy 80.508266 -239.434386) (xy 80.542014 -239.396292) (xy 80.581436 -239.364105)
			(xy 80.62551 -239.338659) (xy 80.673096 -239.320612) (xy 80.72296 -239.310432) (xy 80.773812 -239.308383)
			(xy 80.824333 -239.314517) (xy 80.873217 -239.328677) (xy 80.919196 -239.350494) (xy 80.96108 -239.379404)
			(xy 80.997784 -239.414659) (xy 81.028357 -239.455345) (xy 81.052008 -239.500408) (xy 81.068124 -239.548682)
			(xy 81.076288 -239.598916) (xy 81.0768 -239.624362) (xy 81.076297 -239.649351) (xy 81.383614 -239.649351)
			(xy 81.383614 -239.599373) (xy 81.391433 -239.55001) (xy 81.406877 -239.502478) (xy 81.429567 -239.457946)
			(xy 81.458943 -239.417513) (xy 81.494283 -239.382173) (xy 81.534716 -239.352797) (xy 81.579248 -239.330107)
			(xy 81.62678 -239.314663) (xy 81.676143 -239.306844) (xy 81.726121 -239.306844) (xy 81.775484 -239.314663)
			(xy 81.823016 -239.330107) (xy 81.867548 -239.352797) (xy 81.907981 -239.382173) (xy 81.943321 -239.417513)
			(xy 81.972697 -239.457946) (xy 81.995387 -239.502478) (xy 82.010831 -239.55001) (xy 82.01865 -239.599373)
			(xy 82.01914 -239.624362) (xy 82.324697 -239.624362) (xy 82.328792 -239.573634) (xy 82.340971 -239.52422)
			(xy 82.360919 -239.4774) (xy 82.38812 -239.434386) (xy 82.421868 -239.396292) (xy 82.46129 -239.364105)
			(xy 82.505364 -239.338659) (xy 82.55295 -239.320612) (xy 82.602814 -239.310432) (xy 82.653666 -239.308383)
			(xy 82.704187 -239.314517) (xy 82.753071 -239.328677) (xy 82.79905 -239.350494) (xy 82.840934 -239.379404)
			(xy 82.877638 -239.414659) (xy 82.908211 -239.455345) (xy 82.931862 -239.500408) (xy 82.947978 -239.548682)
			(xy 82.956142 -239.598916) (xy 82.956654 -239.624362) (xy 82.956151 -239.649351) (xy 83.263468 -239.649351)
			(xy 83.263468 -239.599373) (xy 83.271287 -239.55001) (xy 83.286731 -239.502478) (xy 83.309421 -239.457946)
			(xy 83.338797 -239.417513) (xy 83.374137 -239.382173) (xy 83.41457 -239.352797) (xy 83.459102 -239.330107)
			(xy 83.506634 -239.314663) (xy 83.555997 -239.306844) (xy 83.605975 -239.306844) (xy 83.655338 -239.314663)
			(xy 83.70287 -239.330107) (xy 83.747402 -239.352797) (xy 83.787835 -239.382173) (xy 83.823175 -239.417513)
			(xy 83.852551 -239.457946) (xy 83.875241 -239.502478) (xy 83.890685 -239.55001) (xy 83.898504 -239.599373)
			(xy 83.898994 -239.624362) (xy 84.204805 -239.624362) (xy 84.2089 -239.573634) (xy 84.221079 -239.52422)
			(xy 84.241027 -239.4774) (xy 84.268228 -239.434386) (xy 84.301976 -239.396292) (xy 84.341398 -239.364105)
			(xy 84.385472 -239.338659) (xy 84.433058 -239.320612) (xy 84.482922 -239.310432) (xy 84.533774 -239.308383)
			(xy 84.584295 -239.314517) (xy 84.633179 -239.328677) (xy 84.679158 -239.350494) (xy 84.721042 -239.379404)
			(xy 84.757746 -239.414659) (xy 84.788319 -239.455345) (xy 84.81197 -239.500408) (xy 84.828086 -239.548682)
			(xy 84.83625 -239.598916) (xy 84.836762 -239.624362) (xy 85.144859 -239.624362) (xy 85.148954 -239.573634)
			(xy 85.161133 -239.52422) (xy 85.181081 -239.4774) (xy 85.208282 -239.434386) (xy 85.24203 -239.396292)
			(xy 85.281452 -239.364105) (xy 85.325526 -239.338659) (xy 85.373112 -239.320612) (xy 85.422976 -239.310432)
			(xy 85.473828 -239.308383) (xy 85.524349 -239.314517) (xy 85.573233 -239.328677) (xy 85.619212 -239.350494)
			(xy 85.661096 -239.379404) (xy 85.6978 -239.414659) (xy 85.728373 -239.455345) (xy 85.752024 -239.500408)
			(xy 85.76814 -239.548682) (xy 85.776304 -239.598916) (xy 85.776816 -239.624362) (xy 87.024713 -239.624362)
			(xy 87.028808 -239.573634) (xy 87.040987 -239.52422) (xy 87.060935 -239.4774) (xy 87.088136 -239.434386)
			(xy 87.121884 -239.396292) (xy 87.161306 -239.364105) (xy 87.20538 -239.338659) (xy 87.252966 -239.320612)
			(xy 87.30283 -239.310432) (xy 87.353682 -239.308383) (xy 87.404203 -239.314517) (xy 87.453087 -239.328677)
			(xy 87.499066 -239.350494) (xy 87.54095 -239.379404) (xy 87.577654 -239.414659) (xy 87.608227 -239.455345)
			(xy 87.631878 -239.500408) (xy 87.647994 -239.548682) (xy 87.656158 -239.598916) (xy 87.65667 -239.624362)
			(xy 87.656167 -239.649351) (xy 87.963484 -239.649351) (xy 87.963484 -239.599373) (xy 87.971303 -239.55001)
			(xy 87.986747 -239.502478) (xy 88.009437 -239.457946) (xy 88.038813 -239.417513) (xy 88.074153 -239.382173)
			(xy 88.114586 -239.352797) (xy 88.159118 -239.330107) (xy 88.20665 -239.314663) (xy 88.256013 -239.306844)
			(xy 88.305991 -239.306844) (xy 88.355354 -239.314663) (xy 88.402886 -239.330107) (xy 88.447418 -239.352797)
			(xy 88.487851 -239.382173) (xy 88.523191 -239.417513) (xy 88.552567 -239.457946) (xy 88.575257 -239.502478)
			(xy 88.590701 -239.55001) (xy 88.59852 -239.599373) (xy 88.59901 -239.624362) (xy 88.904821 -239.624362)
			(xy 88.908916 -239.573634) (xy 88.921095 -239.52422) (xy 88.941043 -239.4774) (xy 88.968244 -239.434386)
			(xy 89.001992 -239.396292) (xy 89.041414 -239.364105) (xy 89.085488 -239.338659) (xy 89.133074 -239.320612)
			(xy 89.182938 -239.310432) (xy 89.23379 -239.308383) (xy 89.284311 -239.314517) (xy 89.333195 -239.328677)
			(xy 89.379174 -239.350494) (xy 89.421058 -239.379404) (xy 89.457762 -239.414659) (xy 89.488335 -239.455345)
			(xy 89.511986 -239.500408) (xy 89.528102 -239.548682) (xy 89.536266 -239.598916) (xy 89.536778 -239.624362)
			(xy 89.536275 -239.649351) (xy 89.843592 -239.649351) (xy 89.843592 -239.599373) (xy 89.851411 -239.55001)
			(xy 89.866855 -239.502478) (xy 89.889545 -239.457946) (xy 89.918921 -239.417513) (xy 89.954261 -239.382173)
			(xy 89.994694 -239.352797) (xy 90.039226 -239.330107) (xy 90.086758 -239.314663) (xy 90.136121 -239.306844)
			(xy 90.186099 -239.306844) (xy 90.235462 -239.314663) (xy 90.282994 -239.330107) (xy 90.327526 -239.352797)
			(xy 90.367959 -239.382173) (xy 90.403299 -239.417513) (xy 90.432675 -239.457946) (xy 90.455365 -239.502478)
			(xy 90.470809 -239.55001) (xy 90.478628 -239.599373) (xy 90.479118 -239.624362) (xy 90.784675 -239.624362)
			(xy 90.78877 -239.573634) (xy 90.800949 -239.52422) (xy 90.820897 -239.4774) (xy 90.848098 -239.434386)
			(xy 90.881846 -239.396292) (xy 90.921268 -239.364105) (xy 90.965342 -239.338659) (xy 91.012928 -239.320612)
			(xy 91.062792 -239.310432) (xy 91.113644 -239.308383) (xy 91.164165 -239.314517) (xy 91.213049 -239.328677)
			(xy 91.259028 -239.350494) (xy 91.300912 -239.379404) (xy 91.337616 -239.414659) (xy 91.368189 -239.455345)
			(xy 91.39184 -239.500408) (xy 91.407956 -239.548682) (xy 91.41612 -239.598916) (xy 91.416632 -239.624362)
			(xy 91.724729 -239.624362) (xy 91.728824 -239.573634) (xy 91.741003 -239.52422) (xy 91.760951 -239.4774)
			(xy 91.788152 -239.434386) (xy 91.8219 -239.396292) (xy 91.861322 -239.364105) (xy 91.905396 -239.338659)
			(xy 91.952982 -239.320612) (xy 92.002846 -239.310432) (xy 92.053698 -239.308383) (xy 92.104219 -239.314517)
			(xy 92.153103 -239.328677) (xy 92.199082 -239.350494) (xy 92.240966 -239.379404) (xy 92.27767 -239.414659)
			(xy 92.308243 -239.455345) (xy 92.331894 -239.500408) (xy 92.34801 -239.548682) (xy 92.356174 -239.598916)
			(xy 92.356686 -239.624362) (xy 93.604837 -239.624362) (xy 93.608932 -239.573634) (xy 93.621111 -239.52422)
			(xy 93.641059 -239.4774) (xy 93.66826 -239.434386) (xy 93.702008 -239.396292) (xy 93.74143 -239.364105)
			(xy 93.785504 -239.338659) (xy 93.83309 -239.320612) (xy 93.882954 -239.310432) (xy 93.933806 -239.308383)
			(xy 93.984327 -239.314517) (xy 94.033211 -239.328677) (xy 94.07919 -239.350494) (xy 94.121074 -239.379404)
			(xy 94.157778 -239.414659) (xy 94.188351 -239.455345) (xy 94.212002 -239.500408) (xy 94.228118 -239.548682)
			(xy 94.236282 -239.598916) (xy 94.236794 -239.624362) (xy 94.236291 -239.649351) (xy 94.543608 -239.649351)
			(xy 94.543608 -239.599373) (xy 94.551427 -239.55001) (xy 94.566871 -239.502478) (xy 94.589561 -239.457946)
			(xy 94.618937 -239.417513) (xy 94.654277 -239.382173) (xy 94.69471 -239.352797) (xy 94.739242 -239.330107)
			(xy 94.786774 -239.314663) (xy 94.836137 -239.306844) (xy 94.886115 -239.306844) (xy 94.935478 -239.314663)
			(xy 94.98301 -239.330107) (xy 95.027542 -239.352797) (xy 95.067975 -239.382173) (xy 95.103315 -239.417513)
			(xy 95.132691 -239.457946) (xy 95.155381 -239.502478) (xy 95.170825 -239.55001) (xy 95.178644 -239.599373)
			(xy 95.179134 -239.624362) (xy 95.484691 -239.624362) (xy 95.488786 -239.573634) (xy 95.500965 -239.52422)
			(xy 95.520913 -239.4774) (xy 95.548114 -239.434386) (xy 95.581862 -239.396292) (xy 95.621284 -239.364105)
			(xy 95.665358 -239.338659) (xy 95.712944 -239.320612) (xy 95.762808 -239.310432) (xy 95.81366 -239.308383)
			(xy 95.864181 -239.314517) (xy 95.913065 -239.328677) (xy 95.959044 -239.350494) (xy 96.000928 -239.379404)
			(xy 96.037632 -239.414659) (xy 96.068205 -239.455345) (xy 96.091856 -239.500408) (xy 96.107972 -239.548682)
			(xy 96.116136 -239.598916) (xy 96.116648 -239.624362) (xy 96.116136 -239.649808) (xy 96.107972 -239.700042)
			(xy 96.091856 -239.748316) (xy 96.068205 -239.793379) (xy 96.037632 -239.834065) (xy 96.000928 -239.86932)
			(xy 95.959044 -239.89823) (xy 95.913065 -239.920047) (xy 95.864181 -239.934207) (xy 95.81366 -239.940341)
			(xy 95.762808 -239.938292) (xy 95.712944 -239.928112) (xy 95.665358 -239.910065) (xy 95.621284 -239.884619)
			(xy 95.581862 -239.852432) (xy 95.548114 -239.814338) (xy 95.520913 -239.771324) (xy 95.500965 -239.724504)
			(xy 95.488786 -239.67509) (xy 95.484691 -239.624362) (xy 95.179134 -239.624362) (xy 95.178644 -239.649351)
			(xy 95.170825 -239.698714) (xy 95.155381 -239.746246) (xy 95.132691 -239.790778) (xy 95.103315 -239.831211)
			(xy 95.067975 -239.866551) (xy 95.027542 -239.895927) (xy 94.98301 -239.918617) (xy 94.935478 -239.934061)
			(xy 94.886115 -239.94188) (xy 94.836137 -239.94188) (xy 94.786774 -239.934061) (xy 94.739242 -239.918617)
			(xy 94.69471 -239.895927) (xy 94.654277 -239.866551) (xy 94.618937 -239.831211) (xy 94.589561 -239.790778)
			(xy 94.566871 -239.746246) (xy 94.551427 -239.698714) (xy 94.543608 -239.649351) (xy 94.236291 -239.649351)
			(xy 94.236282 -239.649808) (xy 94.228118 -239.700042) (xy 94.212002 -239.748316) (xy 94.188351 -239.793379)
			(xy 94.157778 -239.834065) (xy 94.121074 -239.86932) (xy 94.07919 -239.89823) (xy 94.033211 -239.920047)
			(xy 93.984327 -239.934207) (xy 93.933806 -239.940341) (xy 93.882954 -239.938292) (xy 93.83309 -239.928112)
			(xy 93.785504 -239.910065) (xy 93.74143 -239.884619) (xy 93.702008 -239.852432) (xy 93.66826 -239.814338)
			(xy 93.641059 -239.771324) (xy 93.621111 -239.724504) (xy 93.608932 -239.67509) (xy 93.604837 -239.624362)
			(xy 92.356686 -239.624362) (xy 92.356174 -239.649808) (xy 92.34801 -239.700042) (xy 92.331894 -239.748316)
			(xy 92.308243 -239.793379) (xy 92.27767 -239.834065) (xy 92.240966 -239.86932) (xy 92.199082 -239.89823)
			(xy 92.153103 -239.920047) (xy 92.104219 -239.934207) (xy 92.053698 -239.940341) (xy 92.002846 -239.938292)
			(xy 91.952982 -239.928112) (xy 91.905396 -239.910065) (xy 91.861322 -239.884619) (xy 91.8219 -239.852432)
			(xy 91.788152 -239.814338) (xy 91.760951 -239.771324) (xy 91.741003 -239.724504) (xy 91.728824 -239.67509)
			(xy 91.724729 -239.624362) (xy 91.416632 -239.624362) (xy 91.41612 -239.649808) (xy 91.407956 -239.700042)
			(xy 91.39184 -239.748316) (xy 91.368189 -239.793379) (xy 91.337616 -239.834065) (xy 91.300912 -239.86932)
			(xy 91.259028 -239.89823) (xy 91.213049 -239.920047) (xy 91.164165 -239.934207) (xy 91.113644 -239.940341)
			(xy 91.062792 -239.938292) (xy 91.012928 -239.928112) (xy 90.965342 -239.910065) (xy 90.921268 -239.884619)
			(xy 90.881846 -239.852432) (xy 90.848098 -239.814338) (xy 90.820897 -239.771324) (xy 90.800949 -239.724504)
			(xy 90.78877 -239.67509) (xy 90.784675 -239.624362) (xy 90.479118 -239.624362) (xy 90.478628 -239.649351)
			(xy 90.470809 -239.698714) (xy 90.455365 -239.746246) (xy 90.432675 -239.790778) (xy 90.403299 -239.831211)
			(xy 90.367959 -239.866551) (xy 90.327526 -239.895927) (xy 90.282994 -239.918617) (xy 90.235462 -239.934061)
			(xy 90.186099 -239.94188) (xy 90.136121 -239.94188) (xy 90.086758 -239.934061) (xy 90.039226 -239.918617)
			(xy 89.994694 -239.895927) (xy 89.954261 -239.866551) (xy 89.918921 -239.831211) (xy 89.889545 -239.790778)
			(xy 89.866855 -239.746246) (xy 89.851411 -239.698714) (xy 89.843592 -239.649351) (xy 89.536275 -239.649351)
			(xy 89.536266 -239.649808) (xy 89.528102 -239.700042) (xy 89.511986 -239.748316) (xy 89.488335 -239.793379)
			(xy 89.457762 -239.834065) (xy 89.421058 -239.86932) (xy 89.379174 -239.89823) (xy 89.333195 -239.920047)
			(xy 89.284311 -239.934207) (xy 89.23379 -239.940341) (xy 89.182938 -239.938292) (xy 89.133074 -239.928112)
			(xy 89.085488 -239.910065) (xy 89.041414 -239.884619) (xy 89.001992 -239.852432) (xy 88.968244 -239.814338)
			(xy 88.941043 -239.771324) (xy 88.921095 -239.724504) (xy 88.908916 -239.67509) (xy 88.904821 -239.624362)
			(xy 88.59901 -239.624362) (xy 88.59852 -239.649351) (xy 88.590701 -239.698714) (xy 88.575257 -239.746246)
			(xy 88.552567 -239.790778) (xy 88.523191 -239.831211) (xy 88.487851 -239.866551) (xy 88.447418 -239.895927)
			(xy 88.402886 -239.918617) (xy 88.355354 -239.934061) (xy 88.305991 -239.94188) (xy 88.256013 -239.94188)
			(xy 88.20665 -239.934061) (xy 88.159118 -239.918617) (xy 88.114586 -239.895927) (xy 88.074153 -239.866551)
			(xy 88.038813 -239.831211) (xy 88.009437 -239.790778) (xy 87.986747 -239.746246) (xy 87.971303 -239.698714)
			(xy 87.963484 -239.649351) (xy 87.656167 -239.649351) (xy 87.656158 -239.649808) (xy 87.647994 -239.700042)
			(xy 87.631878 -239.748316) (xy 87.608227 -239.793379) (xy 87.577654 -239.834065) (xy 87.54095 -239.86932)
			(xy 87.499066 -239.89823) (xy 87.453087 -239.920047) (xy 87.404203 -239.934207) (xy 87.353682 -239.940341)
			(xy 87.30283 -239.938292) (xy 87.252966 -239.928112) (xy 87.20538 -239.910065) (xy 87.161306 -239.884619)
			(xy 87.121884 -239.852432) (xy 87.088136 -239.814338) (xy 87.060935 -239.771324) (xy 87.040987 -239.724504)
			(xy 87.028808 -239.67509) (xy 87.024713 -239.624362) (xy 85.776816 -239.624362) (xy 85.776304 -239.649808)
			(xy 85.76814 -239.700042) (xy 85.752024 -239.748316) (xy 85.728373 -239.793379) (xy 85.6978 -239.834065)
			(xy 85.661096 -239.86932) (xy 85.619212 -239.89823) (xy 85.573233 -239.920047) (xy 85.524349 -239.934207)
			(xy 85.473828 -239.940341) (xy 85.422976 -239.938292) (xy 85.373112 -239.928112) (xy 85.325526 -239.910065)
			(xy 85.281452 -239.884619) (xy 85.24203 -239.852432) (xy 85.208282 -239.814338) (xy 85.181081 -239.771324)
			(xy 85.161133 -239.724504) (xy 85.148954 -239.67509) (xy 85.144859 -239.624362) (xy 84.836762 -239.624362)
			(xy 84.83625 -239.649808) (xy 84.828086 -239.700042) (xy 84.81197 -239.748316) (xy 84.788319 -239.793379)
			(xy 84.757746 -239.834065) (xy 84.721042 -239.86932) (xy 84.679158 -239.89823) (xy 84.633179 -239.920047)
			(xy 84.584295 -239.934207) (xy 84.533774 -239.940341) (xy 84.482922 -239.938292) (xy 84.433058 -239.928112)
			(xy 84.385472 -239.910065) (xy 84.341398 -239.884619) (xy 84.301976 -239.852432) (xy 84.268228 -239.814338)
			(xy 84.241027 -239.771324) (xy 84.221079 -239.724504) (xy 84.2089 -239.67509) (xy 84.204805 -239.624362)
			(xy 83.898994 -239.624362) (xy 83.898504 -239.649351) (xy 83.890685 -239.698714) (xy 83.875241 -239.746246)
			(xy 83.852551 -239.790778) (xy 83.823175 -239.831211) (xy 83.787835 -239.866551) (xy 83.747402 -239.895927)
			(xy 83.70287 -239.918617) (xy 83.655338 -239.934061) (xy 83.605975 -239.94188) (xy 83.555997 -239.94188)
			(xy 83.506634 -239.934061) (xy 83.459102 -239.918617) (xy 83.41457 -239.895927) (xy 83.374137 -239.866551)
			(xy 83.338797 -239.831211) (xy 83.309421 -239.790778) (xy 83.286731 -239.746246) (xy 83.271287 -239.698714)
			(xy 83.263468 -239.649351) (xy 82.956151 -239.649351) (xy 82.956142 -239.649808) (xy 82.947978 -239.700042)
			(xy 82.931862 -239.748316) (xy 82.908211 -239.793379) (xy 82.877638 -239.834065) (xy 82.840934 -239.86932)
			(xy 82.79905 -239.89823) (xy 82.753071 -239.920047) (xy 82.704187 -239.934207) (xy 82.653666 -239.940341)
			(xy 82.602814 -239.938292) (xy 82.55295 -239.928112) (xy 82.505364 -239.910065) (xy 82.46129 -239.884619)
			(xy 82.421868 -239.852432) (xy 82.38812 -239.814338) (xy 82.360919 -239.771324) (xy 82.340971 -239.724504)
			(xy 82.328792 -239.67509) (xy 82.324697 -239.624362) (xy 82.01914 -239.624362) (xy 82.01865 -239.649351)
			(xy 82.010831 -239.698714) (xy 81.995387 -239.746246) (xy 81.972697 -239.790778) (xy 81.943321 -239.831211)
			(xy 81.907981 -239.866551) (xy 81.867548 -239.895927) (xy 81.823016 -239.918617) (xy 81.775484 -239.934061)
			(xy 81.726121 -239.94188) (xy 81.676143 -239.94188) (xy 81.62678 -239.934061) (xy 81.579248 -239.918617)
			(xy 81.534716 -239.895927) (xy 81.494283 -239.866551) (xy 81.458943 -239.831211) (xy 81.429567 -239.790778)
			(xy 81.406877 -239.746246) (xy 81.391433 -239.698714) (xy 81.383614 -239.649351) (xy 81.076297 -239.649351)
			(xy 81.076288 -239.649808) (xy 81.068124 -239.700042) (xy 81.052008 -239.748316) (xy 81.028357 -239.793379)
			(xy 80.997784 -239.834065) (xy 80.96108 -239.86932) (xy 80.919196 -239.89823) (xy 80.873217 -239.920047)
			(xy 80.824333 -239.934207) (xy 80.773812 -239.940341) (xy 80.72296 -239.938292) (xy 80.673096 -239.928112)
			(xy 80.62551 -239.910065) (xy 80.581436 -239.884619) (xy 80.542014 -239.852432) (xy 80.508266 -239.814338)
			(xy 80.481065 -239.771324) (xy 80.461117 -239.724504) (xy 80.448938 -239.67509) (xy 80.444843 -239.624362)
			(xy 79.53248 -239.624362) (xy 79.53248 -240.459357) (xy 79.97366 -240.459357) (xy 79.97366 -240.409379)
			(xy 79.981479 -240.360016) (xy 79.996923 -240.312484) (xy 80.019613 -240.267952) (xy 80.048989 -240.227519)
			(xy 80.084329 -240.192179) (xy 80.124762 -240.162803) (xy 80.169294 -240.140113) (xy 80.216826 -240.124669)
			(xy 80.266189 -240.11685) (xy 80.316167 -240.11685) (xy 80.36553 -240.124669) (xy 80.413062 -240.140113)
			(xy 80.457594 -240.162803) (xy 80.498027 -240.192179) (xy 80.533367 -240.227519) (xy 80.562743 -240.267952)
			(xy 80.585433 -240.312484) (xy 80.600877 -240.360016) (xy 80.608696 -240.409379) (xy 80.609186 -240.434368)
			(xy 80.914743 -240.434368) (xy 80.918838 -240.38364) (xy 80.931017 -240.334226) (xy 80.950965 -240.287406)
			(xy 80.978166 -240.244392) (xy 81.011914 -240.206298) (xy 81.051336 -240.174111) (xy 81.09541 -240.148665)
			(xy 81.142996 -240.130618) (xy 81.19286 -240.120438) (xy 81.243712 -240.118389) (xy 81.294233 -240.124523)
			(xy 81.343117 -240.138683) (xy 81.389096 -240.1605) (xy 81.43098 -240.18941) (xy 81.467684 -240.224665)
			(xy 81.498257 -240.265351) (xy 81.521908 -240.310414) (xy 81.538024 -240.358688) (xy 81.546188 -240.408922)
			(xy 81.5467 -240.434368) (xy 81.854797 -240.434368) (xy 81.858892 -240.38364) (xy 81.871071 -240.334226)
			(xy 81.891019 -240.287406) (xy 81.91822 -240.244392) (xy 81.951968 -240.206298) (xy 81.99139 -240.174111)
			(xy 82.035464 -240.148665) (xy 82.08305 -240.130618) (xy 82.132914 -240.120438) (xy 82.183766 -240.118389)
			(xy 82.234287 -240.124523) (xy 82.283171 -240.138683) (xy 82.32915 -240.1605) (xy 82.371034 -240.18941)
			(xy 82.407738 -240.224665) (xy 82.438311 -240.265351) (xy 82.461962 -240.310414) (xy 82.478078 -240.358688)
			(xy 82.486242 -240.408922) (xy 82.486754 -240.434368) (xy 82.486251 -240.459357) (xy 82.793568 -240.459357)
			(xy 82.793568 -240.409379) (xy 82.801387 -240.360016) (xy 82.816831 -240.312484) (xy 82.839521 -240.267952)
			(xy 82.868897 -240.227519) (xy 82.904237 -240.192179) (xy 82.94467 -240.162803) (xy 82.989202 -240.140113)
			(xy 83.036734 -240.124669) (xy 83.086097 -240.11685) (xy 83.136075 -240.11685) (xy 83.185438 -240.124669)
			(xy 83.23297 -240.140113) (xy 83.277502 -240.162803) (xy 83.317935 -240.192179) (xy 83.353275 -240.227519)
			(xy 83.382651 -240.267952) (xy 83.405341 -240.312484) (xy 83.420785 -240.360016) (xy 83.428604 -240.409379)
			(xy 83.429094 -240.434368) (xy 83.734905 -240.434368) (xy 83.739 -240.38364) (xy 83.751179 -240.334226)
			(xy 83.771127 -240.287406) (xy 83.798328 -240.244392) (xy 83.832076 -240.206298) (xy 83.871498 -240.174111)
			(xy 83.915572 -240.148665) (xy 83.963158 -240.130618) (xy 84.013022 -240.120438) (xy 84.063874 -240.118389)
			(xy 84.114395 -240.124523) (xy 84.163279 -240.138683) (xy 84.209258 -240.1605) (xy 84.251142 -240.18941)
			(xy 84.287846 -240.224665) (xy 84.318419 -240.265351) (xy 84.34207 -240.310414) (xy 84.358186 -240.358688)
			(xy 84.36635 -240.408922) (xy 84.366862 -240.434368) (xy 84.366359 -240.459357) (xy 84.673422 -240.459357)
			(xy 84.673422 -240.409379) (xy 84.681241 -240.360016) (xy 84.696685 -240.312484) (xy 84.719375 -240.267952)
			(xy 84.748751 -240.227519) (xy 84.784091 -240.192179) (xy 84.824524 -240.162803) (xy 84.869056 -240.140113)
			(xy 84.916588 -240.124669) (xy 84.965951 -240.11685) (xy 85.015929 -240.11685) (xy 85.065292 -240.124669)
			(xy 85.112824 -240.140113) (xy 85.157356 -240.162803) (xy 85.197789 -240.192179) (xy 85.233129 -240.227519)
			(xy 85.262505 -240.267952) (xy 85.285195 -240.312484) (xy 85.300639 -240.360016) (xy 85.308458 -240.409379)
			(xy 85.308948 -240.434368) (xy 85.614759 -240.434368) (xy 85.618854 -240.38364) (xy 85.631033 -240.334226)
			(xy 85.650981 -240.287406) (xy 85.678182 -240.244392) (xy 85.71193 -240.206298) (xy 85.751352 -240.174111)
			(xy 85.795426 -240.148665) (xy 85.843012 -240.130618) (xy 85.892876 -240.120438) (xy 85.943728 -240.118389)
			(xy 85.994249 -240.124523) (xy 86.043133 -240.138683) (xy 86.089112 -240.1605) (xy 86.130996 -240.18941)
			(xy 86.1677 -240.224665) (xy 86.198273 -240.265351) (xy 86.221924 -240.310414) (xy 86.23804 -240.358688)
			(xy 86.246204 -240.408922) (xy 86.246716 -240.434368) (xy 86.246213 -240.459357) (xy 86.55353 -240.459357)
			(xy 86.55353 -240.409379) (xy 86.561349 -240.360016) (xy 86.576793 -240.312484) (xy 86.599483 -240.267952)
			(xy 86.628859 -240.227519) (xy 86.664199 -240.192179) (xy 86.704632 -240.162803) (xy 86.749164 -240.140113)
			(xy 86.796696 -240.124669) (xy 86.846059 -240.11685) (xy 86.896037 -240.11685) (xy 86.9454 -240.124669)
			(xy 86.992932 -240.140113) (xy 87.037464 -240.162803) (xy 87.077897 -240.192179) (xy 87.113237 -240.227519)
			(xy 87.142613 -240.267952) (xy 87.165303 -240.312484) (xy 87.180747 -240.360016) (xy 87.188566 -240.409379)
			(xy 87.189056 -240.434368) (xy 87.494867 -240.434368) (xy 87.498962 -240.38364) (xy 87.511141 -240.334226)
			(xy 87.531089 -240.287406) (xy 87.55829 -240.244392) (xy 87.592038 -240.206298) (xy 87.63146 -240.174111)
			(xy 87.675534 -240.148665) (xy 87.72312 -240.130618) (xy 87.772984 -240.120438) (xy 87.823836 -240.118389)
			(xy 87.874357 -240.124523) (xy 87.923241 -240.138683) (xy 87.96922 -240.1605) (xy 88.011104 -240.18941)
			(xy 88.047808 -240.224665) (xy 88.078381 -240.265351) (xy 88.102032 -240.310414) (xy 88.118148 -240.358688)
			(xy 88.126312 -240.408922) (xy 88.126824 -240.434368) (xy 88.434921 -240.434368) (xy 88.439016 -240.38364)
			(xy 88.451195 -240.334226) (xy 88.471143 -240.287406) (xy 88.498344 -240.244392) (xy 88.532092 -240.206298)
			(xy 88.571514 -240.174111) (xy 88.615588 -240.148665) (xy 88.663174 -240.130618) (xy 88.713038 -240.120438)
			(xy 88.76389 -240.118389) (xy 88.814411 -240.124523) (xy 88.863295 -240.138683) (xy 88.909274 -240.1605)
			(xy 88.951158 -240.18941) (xy 88.987862 -240.224665) (xy 89.018435 -240.265351) (xy 89.042086 -240.310414)
			(xy 89.058202 -240.358688) (xy 89.066366 -240.408922) (xy 89.066878 -240.434368) (xy 89.066375 -240.459357)
			(xy 89.373438 -240.459357) (xy 89.373438 -240.409379) (xy 89.381257 -240.360016) (xy 89.396701 -240.312484)
			(xy 89.419391 -240.267952) (xy 89.448767 -240.227519) (xy 89.484107 -240.192179) (xy 89.52454 -240.162803)
			(xy 89.569072 -240.140113) (xy 89.616604 -240.124669) (xy 89.665967 -240.11685) (xy 89.715945 -240.11685)
			(xy 89.765308 -240.124669) (xy 89.81284 -240.140113) (xy 89.857372 -240.162803) (xy 89.897805 -240.192179)
			(xy 89.933145 -240.227519) (xy 89.962521 -240.267952) (xy 89.985211 -240.312484) (xy 90.000655 -240.360016)
			(xy 90.008474 -240.409379) (xy 90.008964 -240.434368) (xy 90.314775 -240.434368) (xy 90.31887 -240.38364)
			(xy 90.331049 -240.334226) (xy 90.350997 -240.287406) (xy 90.378198 -240.244392) (xy 90.411946 -240.206298)
			(xy 90.451368 -240.174111) (xy 90.495442 -240.148665) (xy 90.543028 -240.130618) (xy 90.592892 -240.120438)
			(xy 90.643744 -240.118389) (xy 90.694265 -240.124523) (xy 90.743149 -240.138683) (xy 90.789128 -240.1605)
			(xy 90.831012 -240.18941) (xy 90.867716 -240.224665) (xy 90.898289 -240.265351) (xy 90.92194 -240.310414)
			(xy 90.938056 -240.358688) (xy 90.94622 -240.408922) (xy 90.946732 -240.434368) (xy 90.946229 -240.459357)
			(xy 91.253546 -240.459357) (xy 91.253546 -240.409379) (xy 91.261365 -240.360016) (xy 91.276809 -240.312484)
			(xy 91.299499 -240.267952) (xy 91.328875 -240.227519) (xy 91.364215 -240.192179) (xy 91.404648 -240.162803)
			(xy 91.44918 -240.140113) (xy 91.496712 -240.124669) (xy 91.546075 -240.11685) (xy 91.596053 -240.11685)
			(xy 91.645416 -240.124669) (xy 91.692948 -240.140113) (xy 91.73748 -240.162803) (xy 91.777913 -240.192179)
			(xy 91.813253 -240.227519) (xy 91.842629 -240.267952) (xy 91.865319 -240.312484) (xy 91.880763 -240.360016)
			(xy 91.888582 -240.409379) (xy 91.889072 -240.434368) (xy 92.194883 -240.434368) (xy 92.198978 -240.38364)
			(xy 92.211157 -240.334226) (xy 92.231105 -240.287406) (xy 92.258306 -240.244392) (xy 92.292054 -240.206298)
			(xy 92.331476 -240.174111) (xy 92.37555 -240.148665) (xy 92.423136 -240.130618) (xy 92.473 -240.120438)
			(xy 92.523852 -240.118389) (xy 92.574373 -240.124523) (xy 92.623257 -240.138683) (xy 92.669236 -240.1605)
			(xy 92.71112 -240.18941) (xy 92.747824 -240.224665) (xy 92.778397 -240.265351) (xy 92.802048 -240.310414)
			(xy 92.818164 -240.358688) (xy 92.826328 -240.408922) (xy 92.82684 -240.434368) (xy 92.826337 -240.459357)
			(xy 93.1334 -240.459357) (xy 93.1334 -240.409379) (xy 93.141219 -240.360016) (xy 93.156663 -240.312484)
			(xy 93.179353 -240.267952) (xy 93.208729 -240.227519) (xy 93.244069 -240.192179) (xy 93.284502 -240.162803)
			(xy 93.329034 -240.140113) (xy 93.376566 -240.124669) (xy 93.425929 -240.11685) (xy 93.475907 -240.11685)
			(xy 93.52527 -240.124669) (xy 93.572802 -240.140113) (xy 93.617334 -240.162803) (xy 93.657767 -240.192179)
			(xy 93.693107 -240.227519) (xy 93.722483 -240.267952) (xy 93.745173 -240.312484) (xy 93.760617 -240.360016)
			(xy 93.768436 -240.409379) (xy 93.768926 -240.434368) (xy 94.074737 -240.434368) (xy 94.078832 -240.38364)
			(xy 94.091011 -240.334226) (xy 94.110959 -240.287406) (xy 94.13816 -240.244392) (xy 94.171908 -240.206298)
			(xy 94.21133 -240.174111) (xy 94.255404 -240.148665) (xy 94.30299 -240.130618) (xy 94.352854 -240.120438)
			(xy 94.403706 -240.118389) (xy 94.454227 -240.124523) (xy 94.503111 -240.138683) (xy 94.54909 -240.1605)
			(xy 94.590974 -240.18941) (xy 94.627678 -240.224665) (xy 94.658251 -240.265351) (xy 94.681902 -240.310414)
			(xy 94.698018 -240.358688) (xy 94.706182 -240.408922) (xy 94.706694 -240.434368) (xy 95.014791 -240.434368)
			(xy 95.018886 -240.38364) (xy 95.031065 -240.334226) (xy 95.051013 -240.287406) (xy 95.078214 -240.244392)
			(xy 95.111962 -240.206298) (xy 95.151384 -240.174111) (xy 95.195458 -240.148665) (xy 95.243044 -240.130618)
			(xy 95.292908 -240.120438) (xy 95.34376 -240.118389) (xy 95.394281 -240.124523) (xy 95.443165 -240.138683)
			(xy 95.489144 -240.1605) (xy 95.531028 -240.18941) (xy 95.567732 -240.224665) (xy 95.598305 -240.265351)
			(xy 95.621956 -240.310414) (xy 95.638072 -240.358688) (xy 95.646236 -240.408922) (xy 95.646748 -240.434368)
			(xy 95.646236 -240.459814) (xy 95.638072 -240.510048) (xy 95.621956 -240.558322) (xy 95.598305 -240.603385)
			(xy 95.567732 -240.644071) (xy 95.531028 -240.679326) (xy 95.489144 -240.708236) (xy 95.443165 -240.730053)
			(xy 95.394281 -240.744213) (xy 95.34376 -240.750347) (xy 95.292908 -240.748298) (xy 95.243044 -240.738118)
			(xy 95.195458 -240.720071) (xy 95.151384 -240.694625) (xy 95.111962 -240.662438) (xy 95.078214 -240.624344)
			(xy 95.051013 -240.58133) (xy 95.031065 -240.53451) (xy 95.018886 -240.485096) (xy 95.014791 -240.434368)
			(xy 94.706694 -240.434368) (xy 94.706182 -240.459814) (xy 94.698018 -240.510048) (xy 94.681902 -240.558322)
			(xy 94.658251 -240.603385) (xy 94.627678 -240.644071) (xy 94.590974 -240.679326) (xy 94.54909 -240.708236)
			(xy 94.503111 -240.730053) (xy 94.454227 -240.744213) (xy 94.403706 -240.750347) (xy 94.352854 -240.748298)
			(xy 94.30299 -240.738118) (xy 94.255404 -240.720071) (xy 94.21133 -240.694625) (xy 94.171908 -240.662438)
			(xy 94.13816 -240.624344) (xy 94.110959 -240.58133) (xy 94.091011 -240.53451) (xy 94.078832 -240.485096)
			(xy 94.074737 -240.434368) (xy 93.768926 -240.434368) (xy 93.768436 -240.459357) (xy 93.760617 -240.50872)
			(xy 93.745173 -240.556252) (xy 93.722483 -240.600784) (xy 93.693107 -240.641217) (xy 93.657767 -240.676557)
			(xy 93.617334 -240.705933) (xy 93.572802 -240.728623) (xy 93.52527 -240.744067) (xy 93.475907 -240.751886)
			(xy 93.425929 -240.751886) (xy 93.376566 -240.744067) (xy 93.329034 -240.728623) (xy 93.284502 -240.705933)
			(xy 93.244069 -240.676557) (xy 93.208729 -240.641217) (xy 93.179353 -240.600784) (xy 93.156663 -240.556252)
			(xy 93.141219 -240.50872) (xy 93.1334 -240.459357) (xy 92.826337 -240.459357) (xy 92.826328 -240.459814)
			(xy 92.818164 -240.510048) (xy 92.802048 -240.558322) (xy 92.778397 -240.603385) (xy 92.747824 -240.644071)
			(xy 92.71112 -240.679326) (xy 92.669236 -240.708236) (xy 92.623257 -240.730053) (xy 92.574373 -240.744213)
			(xy 92.523852 -240.750347) (xy 92.473 -240.748298) (xy 92.423136 -240.738118) (xy 92.37555 -240.720071)
			(xy 92.331476 -240.694625) (xy 92.292054 -240.662438) (xy 92.258306 -240.624344) (xy 92.231105 -240.58133)
			(xy 92.211157 -240.53451) (xy 92.198978 -240.485096) (xy 92.194883 -240.434368) (xy 91.889072 -240.434368)
			(xy 91.888582 -240.459357) (xy 91.880763 -240.50872) (xy 91.865319 -240.556252) (xy 91.842629 -240.600784)
			(xy 91.813253 -240.641217) (xy 91.777913 -240.676557) (xy 91.73748 -240.705933) (xy 91.692948 -240.728623)
			(xy 91.645416 -240.744067) (xy 91.596053 -240.751886) (xy 91.546075 -240.751886) (xy 91.496712 -240.744067)
			(xy 91.44918 -240.728623) (xy 91.404648 -240.705933) (xy 91.364215 -240.676557) (xy 91.328875 -240.641217)
			(xy 91.299499 -240.600784) (xy 91.276809 -240.556252) (xy 91.261365 -240.50872) (xy 91.253546 -240.459357)
			(xy 90.946229 -240.459357) (xy 90.94622 -240.459814) (xy 90.938056 -240.510048) (xy 90.92194 -240.558322)
			(xy 90.898289 -240.603385) (xy 90.867716 -240.644071) (xy 90.831012 -240.679326) (xy 90.789128 -240.708236)
			(xy 90.743149 -240.730053) (xy 90.694265 -240.744213) (xy 90.643744 -240.750347) (xy 90.592892 -240.748298)
			(xy 90.543028 -240.738118) (xy 90.495442 -240.720071) (xy 90.451368 -240.694625) (xy 90.411946 -240.662438)
			(xy 90.378198 -240.624344) (xy 90.350997 -240.58133) (xy 90.331049 -240.53451) (xy 90.31887 -240.485096)
			(xy 90.314775 -240.434368) (xy 90.008964 -240.434368) (xy 90.008474 -240.459357) (xy 90.000655 -240.50872)
			(xy 89.985211 -240.556252) (xy 89.962521 -240.600784) (xy 89.933145 -240.641217) (xy 89.897805 -240.676557)
			(xy 89.857372 -240.705933) (xy 89.81284 -240.728623) (xy 89.765308 -240.744067) (xy 89.715945 -240.751886)
			(xy 89.665967 -240.751886) (xy 89.616604 -240.744067) (xy 89.569072 -240.728623) (xy 89.52454 -240.705933)
			(xy 89.484107 -240.676557) (xy 89.448767 -240.641217) (xy 89.419391 -240.600784) (xy 89.396701 -240.556252)
			(xy 89.381257 -240.50872) (xy 89.373438 -240.459357) (xy 89.066375 -240.459357) (xy 89.066366 -240.459814)
			(xy 89.058202 -240.510048) (xy 89.042086 -240.558322) (xy 89.018435 -240.603385) (xy 88.987862 -240.644071)
			(xy 88.951158 -240.679326) (xy 88.909274 -240.708236) (xy 88.863295 -240.730053) (xy 88.814411 -240.744213)
			(xy 88.76389 -240.750347) (xy 88.713038 -240.748298) (xy 88.663174 -240.738118) (xy 88.615588 -240.720071)
			(xy 88.571514 -240.694625) (xy 88.532092 -240.662438) (xy 88.498344 -240.624344) (xy 88.471143 -240.58133)
			(xy 88.451195 -240.53451) (xy 88.439016 -240.485096) (xy 88.434921 -240.434368) (xy 88.126824 -240.434368)
			(xy 88.126312 -240.459814) (xy 88.118148 -240.510048) (xy 88.102032 -240.558322) (xy 88.078381 -240.603385)
			(xy 88.047808 -240.644071) (xy 88.011104 -240.679326) (xy 87.96922 -240.708236) (xy 87.923241 -240.730053)
			(xy 87.874357 -240.744213) (xy 87.823836 -240.750347) (xy 87.772984 -240.748298) (xy 87.72312 -240.738118)
			(xy 87.675534 -240.720071) (xy 87.63146 -240.694625) (xy 87.592038 -240.662438) (xy 87.55829 -240.624344)
			(xy 87.531089 -240.58133) (xy 87.511141 -240.53451) (xy 87.498962 -240.485096) (xy 87.494867 -240.434368)
			(xy 87.189056 -240.434368) (xy 87.188566 -240.459357) (xy 87.180747 -240.50872) (xy 87.165303 -240.556252)
			(xy 87.142613 -240.600784) (xy 87.113237 -240.641217) (xy 87.077897 -240.676557) (xy 87.037464 -240.705933)
			(xy 86.992932 -240.728623) (xy 86.9454 -240.744067) (xy 86.896037 -240.751886) (xy 86.846059 -240.751886)
			(xy 86.796696 -240.744067) (xy 86.749164 -240.728623) (xy 86.704632 -240.705933) (xy 86.664199 -240.676557)
			(xy 86.628859 -240.641217) (xy 86.599483 -240.600784) (xy 86.576793 -240.556252) (xy 86.561349 -240.50872)
			(xy 86.55353 -240.459357) (xy 86.246213 -240.459357) (xy 86.246204 -240.459814) (xy 86.23804 -240.510048)
			(xy 86.221924 -240.558322) (xy 86.198273 -240.603385) (xy 86.1677 -240.644071) (xy 86.130996 -240.679326)
			(xy 86.089112 -240.708236) (xy 86.043133 -240.730053) (xy 85.994249 -240.744213) (xy 85.943728 -240.750347)
			(xy 85.892876 -240.748298) (xy 85.843012 -240.738118) (xy 85.795426 -240.720071) (xy 85.751352 -240.694625)
			(xy 85.71193 -240.662438) (xy 85.678182 -240.624344) (xy 85.650981 -240.58133) (xy 85.631033 -240.53451)
			(xy 85.618854 -240.485096) (xy 85.614759 -240.434368) (xy 85.308948 -240.434368) (xy 85.308458 -240.459357)
			(xy 85.300639 -240.50872) (xy 85.285195 -240.556252) (xy 85.262505 -240.600784) (xy 85.233129 -240.641217)
			(xy 85.197789 -240.676557) (xy 85.157356 -240.705933) (xy 85.112824 -240.728623) (xy 85.065292 -240.744067)
			(xy 85.015929 -240.751886) (xy 84.965951 -240.751886) (xy 84.916588 -240.744067) (xy 84.869056 -240.728623)
			(xy 84.824524 -240.705933) (xy 84.784091 -240.676557) (xy 84.748751 -240.641217) (xy 84.719375 -240.600784)
			(xy 84.696685 -240.556252) (xy 84.681241 -240.50872) (xy 84.673422 -240.459357) (xy 84.366359 -240.459357)
			(xy 84.36635 -240.459814) (xy 84.358186 -240.510048) (xy 84.34207 -240.558322) (xy 84.318419 -240.603385)
			(xy 84.287846 -240.644071) (xy 84.251142 -240.679326) (xy 84.209258 -240.708236) (xy 84.163279 -240.730053)
			(xy 84.114395 -240.744213) (xy 84.063874 -240.750347) (xy 84.013022 -240.748298) (xy 83.963158 -240.738118)
			(xy 83.915572 -240.720071) (xy 83.871498 -240.694625) (xy 83.832076 -240.662438) (xy 83.798328 -240.624344)
			(xy 83.771127 -240.58133) (xy 83.751179 -240.53451) (xy 83.739 -240.485096) (xy 83.734905 -240.434368)
			(xy 83.429094 -240.434368) (xy 83.428604 -240.459357) (xy 83.420785 -240.50872) (xy 83.405341 -240.556252)
			(xy 83.382651 -240.600784) (xy 83.353275 -240.641217) (xy 83.317935 -240.676557) (xy 83.277502 -240.705933)
			(xy 83.23297 -240.728623) (xy 83.185438 -240.744067) (xy 83.136075 -240.751886) (xy 83.086097 -240.751886)
			(xy 83.036734 -240.744067) (xy 82.989202 -240.728623) (xy 82.94467 -240.705933) (xy 82.904237 -240.676557)
			(xy 82.868897 -240.641217) (xy 82.839521 -240.600784) (xy 82.816831 -240.556252) (xy 82.801387 -240.50872)
			(xy 82.793568 -240.459357) (xy 82.486251 -240.459357) (xy 82.486242 -240.459814) (xy 82.478078 -240.510048)
			(xy 82.461962 -240.558322) (xy 82.438311 -240.603385) (xy 82.407738 -240.644071) (xy 82.371034 -240.679326)
			(xy 82.32915 -240.708236) (xy 82.283171 -240.730053) (xy 82.234287 -240.744213) (xy 82.183766 -240.750347)
			(xy 82.132914 -240.748298) (xy 82.08305 -240.738118) (xy 82.035464 -240.720071) (xy 81.99139 -240.694625)
			(xy 81.951968 -240.662438) (xy 81.91822 -240.624344) (xy 81.891019 -240.58133) (xy 81.871071 -240.53451)
			(xy 81.858892 -240.485096) (xy 81.854797 -240.434368) (xy 81.5467 -240.434368) (xy 81.546188 -240.459814)
			(xy 81.538024 -240.510048) (xy 81.521908 -240.558322) (xy 81.498257 -240.603385) (xy 81.467684 -240.644071)
			(xy 81.43098 -240.679326) (xy 81.389096 -240.708236) (xy 81.343117 -240.730053) (xy 81.294233 -240.744213)
			(xy 81.243712 -240.750347) (xy 81.19286 -240.748298) (xy 81.142996 -240.738118) (xy 81.09541 -240.720071)
			(xy 81.051336 -240.694625) (xy 81.011914 -240.662438) (xy 80.978166 -240.624344) (xy 80.950965 -240.58133)
			(xy 80.931017 -240.53451) (xy 80.918838 -240.485096) (xy 80.914743 -240.434368) (xy 80.609186 -240.434368)
			(xy 80.608696 -240.459357) (xy 80.600877 -240.50872) (xy 80.585433 -240.556252) (xy 80.562743 -240.600784)
			(xy 80.533367 -240.641217) (xy 80.498027 -240.676557) (xy 80.457594 -240.705933) (xy 80.413062 -240.728623)
			(xy 80.36553 -240.744067) (xy 80.316167 -240.751886) (xy 80.266189 -240.751886) (xy 80.216826 -240.744067)
			(xy 80.169294 -240.728623) (xy 80.124762 -240.705933) (xy 80.084329 -240.676557) (xy 80.048989 -240.641217)
			(xy 80.019613 -240.600784) (xy 79.996923 -240.556252) (xy 79.981479 -240.50872) (xy 79.97366 -240.459357)
			(xy 79.53248 -240.459357) (xy 79.53248 -240.868454) (xy 79.532975 -240.883232) (xy 79.541428 -240.911552)
			(xy 79.557639 -240.936265) (xy 79.580249 -240.955298) (xy 79.607364 -240.967058) (xy 79.636711 -240.970558)
			(xy 79.66583 -240.965505) (xy 79.679292 -240.959386) (xy 79.701428 -240.948893) (xy 79.74812 -240.934075)
			(xy 79.796531 -240.92658) (xy 79.821024 -240.926112) (xy 79.846034 -240.926604) (xy 79.895438 -240.934433)
			(xy 79.943008 -240.949893) (xy 79.987575 -240.972604) (xy 80.028041 -241.002006) (xy 80.063409 -241.037377)
			(xy 80.092809 -241.077845) (xy 80.115517 -241.122414) (xy 80.130973 -241.169986) (xy 80.138797 -241.21939)
			(xy 80.138797 -241.244374) (xy 80.444843 -241.244374) (xy 80.448938 -241.193646) (xy 80.461117 -241.144232)
			(xy 80.481065 -241.097412) (xy 80.508266 -241.054398) (xy 80.542014 -241.016304) (xy 80.581436 -240.984117)
			(xy 80.62551 -240.958671) (xy 80.673096 -240.940624) (xy 80.72296 -240.930444) (xy 80.773812 -240.928395)
			(xy 80.824333 -240.934529) (xy 80.873217 -240.948689) (xy 80.919196 -240.970506) (xy 80.96108 -240.999416)
			(xy 80.997784 -241.034671) (xy 81.028357 -241.075357) (xy 81.052008 -241.12042) (xy 81.068124 -241.168694)
			(xy 81.076288 -241.218928) (xy 81.0768 -241.244374) (xy 81.076297 -241.269363) (xy 81.383614 -241.269363)
			(xy 81.383614 -241.219385) (xy 81.391433 -241.170022) (xy 81.406877 -241.12249) (xy 81.429567 -241.077958)
			(xy 81.458943 -241.037525) (xy 81.494283 -241.002185) (xy 81.534716 -240.972809) (xy 81.579248 -240.950119)
			(xy 81.62678 -240.934675) (xy 81.676143 -240.926856) (xy 81.726121 -240.926856) (xy 81.775484 -240.934675)
			(xy 81.823016 -240.950119) (xy 81.867548 -240.972809) (xy 81.907981 -241.002185) (xy 81.943321 -241.037525)
			(xy 81.972697 -241.077958) (xy 81.995387 -241.12249) (xy 82.010831 -241.170022) (xy 82.01865 -241.219385)
			(xy 82.01914 -241.244374) (xy 82.324697 -241.244374) (xy 82.328792 -241.193646) (xy 82.340971 -241.144232)
			(xy 82.360919 -241.097412) (xy 82.38812 -241.054398) (xy 82.421868 -241.016304) (xy 82.46129 -240.984117)
			(xy 82.505364 -240.958671) (xy 82.55295 -240.940624) (xy 82.602814 -240.930444) (xy 82.653666 -240.928395)
			(xy 82.704187 -240.934529) (xy 82.753071 -240.948689) (xy 82.79905 -240.970506) (xy 82.840934 -240.999416)
			(xy 82.877638 -241.034671) (xy 82.908211 -241.075357) (xy 82.931862 -241.12042) (xy 82.947978 -241.168694)
			(xy 82.956142 -241.218928) (xy 82.956654 -241.244374) (xy 82.956151 -241.269363) (xy 83.263468 -241.269363)
			(xy 83.263468 -241.219385) (xy 83.271287 -241.170022) (xy 83.286731 -241.12249) (xy 83.309421 -241.077958)
			(xy 83.338797 -241.037525) (xy 83.374137 -241.002185) (xy 83.41457 -240.972809) (xy 83.459102 -240.950119)
			(xy 83.506634 -240.934675) (xy 83.555997 -240.926856) (xy 83.605975 -240.926856) (xy 83.655338 -240.934675)
			(xy 83.70287 -240.950119) (xy 83.747402 -240.972809) (xy 83.787835 -241.002185) (xy 83.823175 -241.037525)
			(xy 83.852551 -241.077958) (xy 83.875241 -241.12249) (xy 83.890685 -241.170022) (xy 83.898504 -241.219385)
			(xy 83.898994 -241.244374) (xy 84.204805 -241.244374) (xy 84.2089 -241.193646) (xy 84.221079 -241.144232)
			(xy 84.241027 -241.097412) (xy 84.268228 -241.054398) (xy 84.301976 -241.016304) (xy 84.341398 -240.984117)
			(xy 84.385472 -240.958671) (xy 84.433058 -240.940624) (xy 84.482922 -240.930444) (xy 84.533774 -240.928395)
			(xy 84.584295 -240.934529) (xy 84.633179 -240.948689) (xy 84.679158 -240.970506) (xy 84.721042 -240.999416)
			(xy 84.757746 -241.034671) (xy 84.788319 -241.075357) (xy 84.81197 -241.12042) (xy 84.828086 -241.168694)
			(xy 84.83625 -241.218928) (xy 84.836762 -241.244374) (xy 85.144859 -241.244374) (xy 85.148954 -241.193646)
			(xy 85.161133 -241.144232) (xy 85.181081 -241.097412) (xy 85.208282 -241.054398) (xy 85.24203 -241.016304)
			(xy 85.281452 -240.984117) (xy 85.325526 -240.958671) (xy 85.373112 -240.940624) (xy 85.422976 -240.930444)
			(xy 85.473828 -240.928395) (xy 85.524349 -240.934529) (xy 85.573233 -240.948689) (xy 85.619212 -240.970506)
			(xy 85.661096 -240.999416) (xy 85.6978 -241.034671) (xy 85.728373 -241.075357) (xy 85.752024 -241.12042)
			(xy 85.76814 -241.168694) (xy 85.776304 -241.218928) (xy 85.776816 -241.244374) (xy 85.776313 -241.269363)
			(xy 86.08363 -241.269363) (xy 86.08363 -241.219385) (xy 86.091449 -241.170022) (xy 86.106893 -241.12249)
			(xy 86.129583 -241.077958) (xy 86.158959 -241.037525) (xy 86.194299 -241.002185) (xy 86.234732 -240.972809)
			(xy 86.279264 -240.950119) (xy 86.326796 -240.934675) (xy 86.376159 -240.926856) (xy 86.426137 -240.926856)
			(xy 86.4755 -240.934675) (xy 86.523032 -240.950119) (xy 86.567564 -240.972809) (xy 86.607997 -241.002185)
			(xy 86.643337 -241.037525) (xy 86.672713 -241.077958) (xy 86.695403 -241.12249) (xy 86.710847 -241.170022)
			(xy 86.718666 -241.219385) (xy 86.719156 -241.244374) (xy 87.024713 -241.244374) (xy 87.028808 -241.193646)
			(xy 87.040987 -241.144232) (xy 87.060935 -241.097412) (xy 87.088136 -241.054398) (xy 87.121884 -241.016304)
			(xy 87.161306 -240.984117) (xy 87.20538 -240.958671) (xy 87.252966 -240.940624) (xy 87.30283 -240.930444)
			(xy 87.353682 -240.928395) (xy 87.404203 -240.934529) (xy 87.453087 -240.948689) (xy 87.499066 -240.970506)
			(xy 87.54095 -240.999416) (xy 87.577654 -241.034671) (xy 87.608227 -241.075357) (xy 87.631878 -241.12042)
			(xy 87.647994 -241.168694) (xy 87.656158 -241.218928) (xy 87.65667 -241.244374) (xy 87.656167 -241.269363)
			(xy 87.963484 -241.269363) (xy 87.963484 -241.219385) (xy 87.971303 -241.170022) (xy 87.986747 -241.12249)
			(xy 88.009437 -241.077958) (xy 88.038813 -241.037525) (xy 88.074153 -241.002185) (xy 88.114586 -240.972809)
			(xy 88.159118 -240.950119) (xy 88.20665 -240.934675) (xy 88.256013 -240.926856) (xy 88.305991 -240.926856)
			(xy 88.355354 -240.934675) (xy 88.402886 -240.950119) (xy 88.447418 -240.972809) (xy 88.487851 -241.002185)
			(xy 88.523191 -241.037525) (xy 88.552567 -241.077958) (xy 88.575257 -241.12249) (xy 88.590701 -241.170022)
			(xy 88.59852 -241.219385) (xy 88.59901 -241.244374) (xy 88.904821 -241.244374) (xy 88.908916 -241.193646)
			(xy 88.921095 -241.144232) (xy 88.941043 -241.097412) (xy 88.968244 -241.054398) (xy 89.001992 -241.016304)
			(xy 89.041414 -240.984117) (xy 89.085488 -240.958671) (xy 89.133074 -240.940624) (xy 89.182938 -240.930444)
			(xy 89.23379 -240.928395) (xy 89.284311 -240.934529) (xy 89.333195 -240.948689) (xy 89.379174 -240.970506)
			(xy 89.421058 -240.999416) (xy 89.457762 -241.034671) (xy 89.488335 -241.075357) (xy 89.511986 -241.12042)
			(xy 89.528102 -241.168694) (xy 89.536266 -241.218928) (xy 89.536778 -241.244374) (xy 89.536275 -241.269363)
			(xy 89.843592 -241.269363) (xy 89.843592 -241.219385) (xy 89.851411 -241.170022) (xy 89.866855 -241.12249)
			(xy 89.889545 -241.077958) (xy 89.918921 -241.037525) (xy 89.954261 -241.002185) (xy 89.994694 -240.972809)
			(xy 90.039226 -240.950119) (xy 90.086758 -240.934675) (xy 90.136121 -240.926856) (xy 90.186099 -240.926856)
			(xy 90.235462 -240.934675) (xy 90.282994 -240.950119) (xy 90.327526 -240.972809) (xy 90.367959 -241.002185)
			(xy 90.403299 -241.037525) (xy 90.432675 -241.077958) (xy 90.455365 -241.12249) (xy 90.470809 -241.170022)
			(xy 90.478628 -241.219385) (xy 90.479118 -241.244374) (xy 90.784675 -241.244374) (xy 90.78877 -241.193646)
			(xy 90.800949 -241.144232) (xy 90.820897 -241.097412) (xy 90.848098 -241.054398) (xy 90.881846 -241.016304)
			(xy 90.921268 -240.984117) (xy 90.965342 -240.958671) (xy 91.012928 -240.940624) (xy 91.062792 -240.930444)
			(xy 91.113644 -240.928395) (xy 91.164165 -240.934529) (xy 91.213049 -240.948689) (xy 91.259028 -240.970506)
			(xy 91.300912 -240.999416) (xy 91.337616 -241.034671) (xy 91.368189 -241.075357) (xy 91.39184 -241.12042)
			(xy 91.407956 -241.168694) (xy 91.41612 -241.218928) (xy 91.416632 -241.244374) (xy 91.724729 -241.244374)
			(xy 91.728824 -241.193646) (xy 91.741003 -241.144232) (xy 91.760951 -241.097412) (xy 91.788152 -241.054398)
			(xy 91.8219 -241.016304) (xy 91.861322 -240.984117) (xy 91.905396 -240.958671) (xy 91.952982 -240.940624)
			(xy 92.002846 -240.930444) (xy 92.053698 -240.928395) (xy 92.104219 -240.934529) (xy 92.153103 -240.948689)
			(xy 92.199082 -240.970506) (xy 92.240966 -240.999416) (xy 92.27767 -241.034671) (xy 92.308243 -241.075357)
			(xy 92.331894 -241.12042) (xy 92.34801 -241.168694) (xy 92.356174 -241.218928) (xy 92.356686 -241.244374)
			(xy 92.356183 -241.269363) (xy 92.6635 -241.269363) (xy 92.6635 -241.219385) (xy 92.671319 -241.170022)
			(xy 92.686763 -241.12249) (xy 92.709453 -241.077958) (xy 92.738829 -241.037525) (xy 92.774169 -241.002185)
			(xy 92.814602 -240.972809) (xy 92.859134 -240.950119) (xy 92.906666 -240.934675) (xy 92.956029 -240.926856)
			(xy 93.006007 -240.926856) (xy 93.05537 -240.934675) (xy 93.102902 -240.950119) (xy 93.147434 -240.972809)
			(xy 93.187867 -241.002185) (xy 93.223207 -241.037525) (xy 93.252583 -241.077958) (xy 93.275273 -241.12249)
			(xy 93.290717 -241.170022) (xy 93.298536 -241.219385) (xy 93.299026 -241.244374) (xy 93.604837 -241.244374)
			(xy 93.608932 -241.193646) (xy 93.621111 -241.144232) (xy 93.641059 -241.097412) (xy 93.66826 -241.054398)
			(xy 93.702008 -241.016304) (xy 93.74143 -240.984117) (xy 93.785504 -240.958671) (xy 93.83309 -240.940624)
			(xy 93.882954 -240.930444) (xy 93.933806 -240.928395) (xy 93.984327 -240.934529) (xy 94.033211 -240.948689)
			(xy 94.07919 -240.970506) (xy 94.121074 -240.999416) (xy 94.157778 -241.034671) (xy 94.188351 -241.075357)
			(xy 94.212002 -241.12042) (xy 94.228118 -241.168694) (xy 94.236282 -241.218928) (xy 94.236794 -241.244374)
			(xy 94.236291 -241.269363) (xy 94.543608 -241.269363) (xy 94.543608 -241.219385) (xy 94.551427 -241.170022)
			(xy 94.566871 -241.12249) (xy 94.589561 -241.077958) (xy 94.618937 -241.037525) (xy 94.654277 -241.002185)
			(xy 94.69471 -240.972809) (xy 94.739242 -240.950119) (xy 94.786774 -240.934675) (xy 94.836137 -240.926856)
			(xy 94.886115 -240.926856) (xy 94.935478 -240.934675) (xy 94.98301 -240.950119) (xy 95.027542 -240.972809)
			(xy 95.067975 -241.002185) (xy 95.103315 -241.037525) (xy 95.132691 -241.077958) (xy 95.155381 -241.12249)
			(xy 95.170825 -241.170022) (xy 95.178644 -241.219385) (xy 95.179134 -241.244374) (xy 95.484691 -241.244374)
			(xy 95.488786 -241.193646) (xy 95.500965 -241.144232) (xy 95.520913 -241.097412) (xy 95.548114 -241.054398)
			(xy 95.581862 -241.016304) (xy 95.621284 -240.984117) (xy 95.665358 -240.958671) (xy 95.712944 -240.940624)
			(xy 95.762808 -240.930444) (xy 95.81366 -240.928395) (xy 95.864181 -240.934529) (xy 95.913065 -240.948689)
			(xy 95.959044 -240.970506) (xy 96.000928 -240.999416) (xy 96.037632 -241.034671) (xy 96.068205 -241.075357)
			(xy 96.091856 -241.12042) (xy 96.107972 -241.168694) (xy 96.116136 -241.218928) (xy 96.116648 -241.244374)
			(xy 96.116136 -241.26982) (xy 96.107972 -241.320054) (xy 96.091856 -241.368328) (xy 96.068205 -241.413391)
			(xy 96.037632 -241.454077) (xy 96.000928 -241.489332) (xy 95.959044 -241.518242) (xy 95.913065 -241.540059)
			(xy 95.864181 -241.554219) (xy 95.81366 -241.560353) (xy 95.762808 -241.558304) (xy 95.712944 -241.548124)
			(xy 95.665358 -241.530077) (xy 95.621284 -241.504631) (xy 95.581862 -241.472444) (xy 95.548114 -241.43435)
			(xy 95.520913 -241.391336) (xy 95.500965 -241.344516) (xy 95.488786 -241.295102) (xy 95.484691 -241.244374)
			(xy 95.179134 -241.244374) (xy 95.178644 -241.269363) (xy 95.170825 -241.318726) (xy 95.155381 -241.366258)
			(xy 95.132691 -241.41079) (xy 95.103315 -241.451223) (xy 95.067975 -241.486563) (xy 95.027542 -241.515939)
			(xy 94.98301 -241.538629) (xy 94.935478 -241.554073) (xy 94.886115 -241.561892) (xy 94.836137 -241.561892)
			(xy 94.786774 -241.554073) (xy 94.739242 -241.538629) (xy 94.69471 -241.515939) (xy 94.654277 -241.486563)
			(xy 94.618937 -241.451223) (xy 94.589561 -241.41079) (xy 94.566871 -241.366258) (xy 94.551427 -241.318726)
			(xy 94.543608 -241.269363) (xy 94.236291 -241.269363) (xy 94.236282 -241.26982) (xy 94.228118 -241.320054)
			(xy 94.212002 -241.368328) (xy 94.188351 -241.413391) (xy 94.157778 -241.454077) (xy 94.121074 -241.489332)
			(xy 94.07919 -241.518242) (xy 94.033211 -241.540059) (xy 93.984327 -241.554219) (xy 93.933806 -241.560353)
			(xy 93.882954 -241.558304) (xy 93.83309 -241.548124) (xy 93.785504 -241.530077) (xy 93.74143 -241.504631)
			(xy 93.702008 -241.472444) (xy 93.66826 -241.43435) (xy 93.641059 -241.391336) (xy 93.621111 -241.344516)
			(xy 93.608932 -241.295102) (xy 93.604837 -241.244374) (xy 93.299026 -241.244374) (xy 93.298536 -241.269363)
			(xy 93.290717 -241.318726) (xy 93.275273 -241.366258) (xy 93.252583 -241.41079) (xy 93.223207 -241.451223)
			(xy 93.187867 -241.486563) (xy 93.147434 -241.515939) (xy 93.102902 -241.538629) (xy 93.05537 -241.554073)
			(xy 93.006007 -241.561892) (xy 92.956029 -241.561892) (xy 92.906666 -241.554073) (xy 92.859134 -241.538629)
			(xy 92.814602 -241.515939) (xy 92.774169 -241.486563) (xy 92.738829 -241.451223) (xy 92.709453 -241.41079)
			(xy 92.686763 -241.366258) (xy 92.671319 -241.318726) (xy 92.6635 -241.269363) (xy 92.356183 -241.269363)
			(xy 92.356174 -241.26982) (xy 92.34801 -241.320054) (xy 92.331894 -241.368328) (xy 92.308243 -241.413391)
			(xy 92.27767 -241.454077) (xy 92.240966 -241.489332) (xy 92.199082 -241.518242) (xy 92.153103 -241.540059)
			(xy 92.104219 -241.554219) (xy 92.053698 -241.560353) (xy 92.002846 -241.558304) (xy 91.952982 -241.548124)
			(xy 91.905396 -241.530077) (xy 91.861322 -241.504631) (xy 91.8219 -241.472444) (xy 91.788152 -241.43435)
			(xy 91.760951 -241.391336) (xy 91.741003 -241.344516) (xy 91.728824 -241.295102) (xy 91.724729 -241.244374)
			(xy 91.416632 -241.244374) (xy 91.41612 -241.26982) (xy 91.407956 -241.320054) (xy 91.39184 -241.368328)
			(xy 91.368189 -241.413391) (xy 91.337616 -241.454077) (xy 91.300912 -241.489332) (xy 91.259028 -241.518242)
			(xy 91.213049 -241.540059) (xy 91.164165 -241.554219) (xy 91.113644 -241.560353) (xy 91.062792 -241.558304)
			(xy 91.012928 -241.548124) (xy 90.965342 -241.530077) (xy 90.921268 -241.504631) (xy 90.881846 -241.472444)
			(xy 90.848098 -241.43435) (xy 90.820897 -241.391336) (xy 90.800949 -241.344516) (xy 90.78877 -241.295102)
			(xy 90.784675 -241.244374) (xy 90.479118 -241.244374) (xy 90.478628 -241.269363) (xy 90.470809 -241.318726)
			(xy 90.455365 -241.366258) (xy 90.432675 -241.41079) (xy 90.403299 -241.451223) (xy 90.367959 -241.486563)
			(xy 90.327526 -241.515939) (xy 90.282994 -241.538629) (xy 90.235462 -241.554073) (xy 90.186099 -241.561892)
			(xy 90.136121 -241.561892) (xy 90.086758 -241.554073) (xy 90.039226 -241.538629) (xy 89.994694 -241.515939)
			(xy 89.954261 -241.486563) (xy 89.918921 -241.451223) (xy 89.889545 -241.41079) (xy 89.866855 -241.366258)
			(xy 89.851411 -241.318726) (xy 89.843592 -241.269363) (xy 89.536275 -241.269363) (xy 89.536266 -241.26982)
			(xy 89.528102 -241.320054) (xy 89.511986 -241.368328) (xy 89.488335 -241.413391) (xy 89.457762 -241.454077)
			(xy 89.421058 -241.489332) (xy 89.379174 -241.518242) (xy 89.333195 -241.540059) (xy 89.284311 -241.554219)
			(xy 89.23379 -241.560353) (xy 89.182938 -241.558304) (xy 89.133074 -241.548124) (xy 89.085488 -241.530077)
			(xy 89.041414 -241.504631) (xy 89.001992 -241.472444) (xy 88.968244 -241.43435) (xy 88.941043 -241.391336)
			(xy 88.921095 -241.344516) (xy 88.908916 -241.295102) (xy 88.904821 -241.244374) (xy 88.59901 -241.244374)
			(xy 88.59852 -241.269363) (xy 88.590701 -241.318726) (xy 88.575257 -241.366258) (xy 88.552567 -241.41079)
			(xy 88.523191 -241.451223) (xy 88.487851 -241.486563) (xy 88.447418 -241.515939) (xy 88.402886 -241.538629)
			(xy 88.355354 -241.554073) (xy 88.305991 -241.561892) (xy 88.256013 -241.561892) (xy 88.20665 -241.554073)
			(xy 88.159118 -241.538629) (xy 88.114586 -241.515939) (xy 88.074153 -241.486563) (xy 88.038813 -241.451223)
			(xy 88.009437 -241.41079) (xy 87.986747 -241.366258) (xy 87.971303 -241.318726) (xy 87.963484 -241.269363)
			(xy 87.656167 -241.269363) (xy 87.656158 -241.26982) (xy 87.647994 -241.320054) (xy 87.631878 -241.368328)
			(xy 87.608227 -241.413391) (xy 87.577654 -241.454077) (xy 87.54095 -241.489332) (xy 87.499066 -241.518242)
			(xy 87.453087 -241.540059) (xy 87.404203 -241.554219) (xy 87.353682 -241.560353) (xy 87.30283 -241.558304)
			(xy 87.252966 -241.548124) (xy 87.20538 -241.530077) (xy 87.161306 -241.504631) (xy 87.121884 -241.472444)
			(xy 87.088136 -241.43435) (xy 87.060935 -241.391336) (xy 87.040987 -241.344516) (xy 87.028808 -241.295102)
			(xy 87.024713 -241.244374) (xy 86.719156 -241.244374) (xy 86.718666 -241.269363) (xy 86.710847 -241.318726)
			(xy 86.695403 -241.366258) (xy 86.672713 -241.41079) (xy 86.643337 -241.451223) (xy 86.607997 -241.486563)
			(xy 86.567564 -241.515939) (xy 86.523032 -241.538629) (xy 86.4755 -241.554073) (xy 86.426137 -241.561892)
			(xy 86.376159 -241.561892) (xy 86.326796 -241.554073) (xy 86.279264 -241.538629) (xy 86.234732 -241.515939)
			(xy 86.194299 -241.486563) (xy 86.158959 -241.451223) (xy 86.129583 -241.41079) (xy 86.106893 -241.366258)
			(xy 86.091449 -241.318726) (xy 86.08363 -241.269363) (xy 85.776313 -241.269363) (xy 85.776304 -241.26982)
			(xy 85.76814 -241.320054) (xy 85.752024 -241.368328) (xy 85.728373 -241.413391) (xy 85.6978 -241.454077)
			(xy 85.661096 -241.489332) (xy 85.619212 -241.518242) (xy 85.573233 -241.540059) (xy 85.524349 -241.554219)
			(xy 85.473828 -241.560353) (xy 85.422976 -241.558304) (xy 85.373112 -241.548124) (xy 85.325526 -241.530077)
			(xy 85.281452 -241.504631) (xy 85.24203 -241.472444) (xy 85.208282 -241.43435) (xy 85.181081 -241.391336)
			(xy 85.161133 -241.344516) (xy 85.148954 -241.295102) (xy 85.144859 -241.244374) (xy 84.836762 -241.244374)
			(xy 84.83625 -241.26982) (xy 84.828086 -241.320054) (xy 84.81197 -241.368328) (xy 84.788319 -241.413391)
			(xy 84.757746 -241.454077) (xy 84.721042 -241.489332) (xy 84.679158 -241.518242) (xy 84.633179 -241.540059)
			(xy 84.584295 -241.554219) (xy 84.533774 -241.560353) (xy 84.482922 -241.558304) (xy 84.433058 -241.548124)
			(xy 84.385472 -241.530077) (xy 84.341398 -241.504631) (xy 84.301976 -241.472444) (xy 84.268228 -241.43435)
			(xy 84.241027 -241.391336) (xy 84.221079 -241.344516) (xy 84.2089 -241.295102) (xy 84.204805 -241.244374)
			(xy 83.898994 -241.244374) (xy 83.898504 -241.269363) (xy 83.890685 -241.318726) (xy 83.875241 -241.366258)
			(xy 83.852551 -241.41079) (xy 83.823175 -241.451223) (xy 83.787835 -241.486563) (xy 83.747402 -241.515939)
			(xy 83.70287 -241.538629) (xy 83.655338 -241.554073) (xy 83.605975 -241.561892) (xy 83.555997 -241.561892)
			(xy 83.506634 -241.554073) (xy 83.459102 -241.538629) (xy 83.41457 -241.515939) (xy 83.374137 -241.486563)
			(xy 83.338797 -241.451223) (xy 83.309421 -241.41079) (xy 83.286731 -241.366258) (xy 83.271287 -241.318726)
			(xy 83.263468 -241.269363) (xy 82.956151 -241.269363) (xy 82.956142 -241.26982) (xy 82.947978 -241.320054)
			(xy 82.931862 -241.368328) (xy 82.908211 -241.413391) (xy 82.877638 -241.454077) (xy 82.840934 -241.489332)
			(xy 82.79905 -241.518242) (xy 82.753071 -241.540059) (xy 82.704187 -241.554219) (xy 82.653666 -241.560353)
			(xy 82.602814 -241.558304) (xy 82.55295 -241.548124) (xy 82.505364 -241.530077) (xy 82.46129 -241.504631)
			(xy 82.421868 -241.472444) (xy 82.38812 -241.43435) (xy 82.360919 -241.391336) (xy 82.340971 -241.344516)
			(xy 82.328792 -241.295102) (xy 82.324697 -241.244374) (xy 82.01914 -241.244374) (xy 82.01865 -241.269363)
			(xy 82.010831 -241.318726) (xy 81.995387 -241.366258) (xy 81.972697 -241.41079) (xy 81.943321 -241.451223)
			(xy 81.907981 -241.486563) (xy 81.867548 -241.515939) (xy 81.823016 -241.538629) (xy 81.775484 -241.554073)
			(xy 81.726121 -241.561892) (xy 81.676143 -241.561892) (xy 81.62678 -241.554073) (xy 81.579248 -241.538629)
			(xy 81.534716 -241.515939) (xy 81.494283 -241.486563) (xy 81.458943 -241.451223) (xy 81.429567 -241.41079)
			(xy 81.406877 -241.366258) (xy 81.391433 -241.318726) (xy 81.383614 -241.269363) (xy 81.076297 -241.269363)
			(xy 81.076288 -241.26982) (xy 81.068124 -241.320054) (xy 81.052008 -241.368328) (xy 81.028357 -241.413391)
			(xy 80.997784 -241.454077) (xy 80.96108 -241.489332) (xy 80.919196 -241.518242) (xy 80.873217 -241.540059)
			(xy 80.824333 -241.554219) (xy 80.773812 -241.560353) (xy 80.72296 -241.558304) (xy 80.673096 -241.548124)
			(xy 80.62551 -241.530077) (xy 80.581436 -241.504631) (xy 80.542014 -241.472444) (xy 80.508266 -241.43435)
			(xy 80.481065 -241.391336) (xy 80.461117 -241.344516) (xy 80.448938 -241.295102) (xy 80.444843 -241.244374)
			(xy 80.138797 -241.244374) (xy 80.138797 -241.26941) (xy 80.130973 -241.318814) (xy 80.115517 -241.366386)
			(xy 80.092809 -241.410955) (xy 80.063409 -241.451423) (xy 80.028041 -241.486794) (xy 79.987575 -241.516196)
			(xy 79.943008 -241.538907) (xy 79.895438 -241.554367) (xy 79.846034 -241.562196) (xy 79.821024 -241.562636)
			(xy 79.796529 -241.562189) (xy 79.748116 -241.554692) (xy 79.701422 -241.539871) (xy 79.679292 -241.529362)
			(xy 79.665838 -241.523241) (xy 79.636722 -241.518222) (xy 79.607387 -241.521741) (xy 79.580284 -241.533503)
			(xy 79.557678 -241.552526) (xy 79.541457 -241.57722) (xy 79.532977 -241.605522) (xy 79.53248 -241.620294)
			(xy 79.53248 -242.05438) (xy 80.914743 -242.05438) (xy 80.918838 -242.003652) (xy 80.931017 -241.954238)
			(xy 80.950965 -241.907418) (xy 80.978166 -241.864404) (xy 81.011914 -241.82631) (xy 81.051336 -241.794123)
			(xy 81.09541 -241.768677) (xy 81.142996 -241.75063) (xy 81.19286 -241.74045) (xy 81.243712 -241.738401)
			(xy 81.294233 -241.744535) (xy 81.343117 -241.758695) (xy 81.389096 -241.780512) (xy 81.43098 -241.809422)
			(xy 81.467684 -241.844677) (xy 81.498257 -241.885363) (xy 81.521908 -241.930426) (xy 81.538024 -241.9787)
			(xy 81.546188 -242.028934) (xy 81.5467 -242.05438) (xy 81.854797 -242.05438) (xy 81.858892 -242.003652)
			(xy 81.871071 -241.954238) (xy 81.891019 -241.907418) (xy 81.91822 -241.864404) (xy 81.951968 -241.82631)
			(xy 81.99139 -241.794123) (xy 82.035464 -241.768677) (xy 82.08305 -241.75063) (xy 82.132914 -241.74045)
			(xy 82.183766 -241.738401) (xy 82.234287 -241.744535) (xy 82.283171 -241.758695) (xy 82.32915 -241.780512)
			(xy 82.371034 -241.809422) (xy 82.407738 -241.844677) (xy 82.438311 -241.885363) (xy 82.461962 -241.930426)
			(xy 82.478078 -241.9787) (xy 82.486242 -242.028934) (xy 82.486754 -242.05438) (xy 82.486251 -242.079369)
			(xy 82.793568 -242.079369) (xy 82.793568 -242.029391) (xy 82.801387 -241.980028) (xy 82.816831 -241.932496)
			(xy 82.839521 -241.887964) (xy 82.868897 -241.847531) (xy 82.904237 -241.812191) (xy 82.94467 -241.782815)
			(xy 82.989202 -241.760125) (xy 83.036734 -241.744681) (xy 83.086097 -241.736862) (xy 83.136075 -241.736862)
			(xy 83.185438 -241.744681) (xy 83.23297 -241.760125) (xy 83.277502 -241.782815) (xy 83.317935 -241.812191)
			(xy 83.353275 -241.847531) (xy 83.382651 -241.887964) (xy 83.405341 -241.932496) (xy 83.420785 -241.980028)
			(xy 83.428604 -242.029391) (xy 83.429094 -242.05438) (xy 83.734905 -242.05438) (xy 83.739 -242.003652)
			(xy 83.751179 -241.954238) (xy 83.771127 -241.907418) (xy 83.798328 -241.864404) (xy 83.832076 -241.82631)
			(xy 83.871498 -241.794123) (xy 83.915572 -241.768677) (xy 83.963158 -241.75063) (xy 84.013022 -241.74045)
			(xy 84.063874 -241.738401) (xy 84.114395 -241.744535) (xy 84.163279 -241.758695) (xy 84.209258 -241.780512)
			(xy 84.251142 -241.809422) (xy 84.287846 -241.844677) (xy 84.318419 -241.885363) (xy 84.34207 -241.930426)
			(xy 84.358186 -241.9787) (xy 84.36635 -242.028934) (xy 84.366862 -242.05438) (xy 84.366359 -242.079369)
			(xy 84.673422 -242.079369) (xy 84.673422 -242.029391) (xy 84.681241 -241.980028) (xy 84.696685 -241.932496)
			(xy 84.719375 -241.887964) (xy 84.748751 -241.847531) (xy 84.784091 -241.812191) (xy 84.824524 -241.782815)
			(xy 84.869056 -241.760125) (xy 84.916588 -241.744681) (xy 84.965951 -241.736862) (xy 85.015929 -241.736862)
			(xy 85.065292 -241.744681) (xy 85.112824 -241.760125) (xy 85.157356 -241.782815) (xy 85.197789 -241.812191)
			(xy 85.233129 -241.847531) (xy 85.262505 -241.887964) (xy 85.285195 -241.932496) (xy 85.300639 -241.980028)
			(xy 85.308458 -242.029391) (xy 85.308948 -242.05438) (xy 85.614759 -242.05438) (xy 85.618854 -242.003652)
			(xy 85.631033 -241.954238) (xy 85.650981 -241.907418) (xy 85.678182 -241.864404) (xy 85.71193 -241.82631)
			(xy 85.751352 -241.794123) (xy 85.795426 -241.768677) (xy 85.843012 -241.75063) (xy 85.892876 -241.74045)
			(xy 85.943728 -241.738401) (xy 85.994249 -241.744535) (xy 86.043133 -241.758695) (xy 86.089112 -241.780512)
			(xy 86.130996 -241.809422) (xy 86.1677 -241.844677) (xy 86.198273 -241.885363) (xy 86.221924 -241.930426)
			(xy 86.23804 -241.9787) (xy 86.246204 -242.028934) (xy 86.246716 -242.05438) (xy 87.494867 -242.05438)
			(xy 87.498962 -242.003652) (xy 87.511141 -241.954238) (xy 87.531089 -241.907418) (xy 87.55829 -241.864404)
			(xy 87.592038 -241.82631) (xy 87.63146 -241.794123) (xy 87.675534 -241.768677) (xy 87.72312 -241.75063)
			(xy 87.772984 -241.74045) (xy 87.823836 -241.738401) (xy 87.874357 -241.744535) (xy 87.923241 -241.758695)
			(xy 87.96922 -241.780512) (xy 88.011104 -241.809422) (xy 88.047808 -241.844677) (xy 88.078381 -241.885363)
			(xy 88.102032 -241.930426) (xy 88.118148 -241.9787) (xy 88.126312 -242.028934) (xy 88.126824 -242.05438)
			(xy 88.434921 -242.05438) (xy 88.439016 -242.003652) (xy 88.451195 -241.954238) (xy 88.471143 -241.907418)
			(xy 88.498344 -241.864404) (xy 88.532092 -241.82631) (xy 88.571514 -241.794123) (xy 88.615588 -241.768677)
			(xy 88.663174 -241.75063) (xy 88.713038 -241.74045) (xy 88.76389 -241.738401) (xy 88.814411 -241.744535)
			(xy 88.863295 -241.758695) (xy 88.909274 -241.780512) (xy 88.951158 -241.809422) (xy 88.987862 -241.844677)
			(xy 89.018435 -241.885363) (xy 89.042086 -241.930426) (xy 89.058202 -241.9787) (xy 89.066366 -242.028934)
			(xy 89.066878 -242.05438) (xy 89.066375 -242.079369) (xy 89.373438 -242.079369) (xy 89.373438 -242.029391)
			(xy 89.381257 -241.980028) (xy 89.396701 -241.932496) (xy 89.419391 -241.887964) (xy 89.448767 -241.847531)
			(xy 89.484107 -241.812191) (xy 89.52454 -241.782815) (xy 89.569072 -241.760125) (xy 89.616604 -241.744681)
			(xy 89.665967 -241.736862) (xy 89.715945 -241.736862) (xy 89.765308 -241.744681) (xy 89.81284 -241.760125)
			(xy 89.857372 -241.782815) (xy 89.897805 -241.812191) (xy 89.933145 -241.847531) (xy 89.962521 -241.887964)
			(xy 89.985211 -241.932496) (xy 90.000655 -241.980028) (xy 90.008474 -242.029391) (xy 90.008964 -242.05438)
			(xy 90.314775 -242.05438) (xy 90.31887 -242.003652) (xy 90.331049 -241.954238) (xy 90.350997 -241.907418)
			(xy 90.378198 -241.864404) (xy 90.411946 -241.82631) (xy 90.451368 -241.794123) (xy 90.495442 -241.768677)
			(xy 90.543028 -241.75063) (xy 90.592892 -241.74045) (xy 90.643744 -241.738401) (xy 90.694265 -241.744535)
			(xy 90.743149 -241.758695) (xy 90.789128 -241.780512) (xy 90.831012 -241.809422) (xy 90.867716 -241.844677)
			(xy 90.898289 -241.885363) (xy 90.92194 -241.930426) (xy 90.938056 -241.9787) (xy 90.94622 -242.028934)
			(xy 90.946732 -242.05438) (xy 90.946229 -242.079369) (xy 91.253546 -242.079369) (xy 91.253546 -242.029391)
			(xy 91.261365 -241.980028) (xy 91.276809 -241.932496) (xy 91.299499 -241.887964) (xy 91.328875 -241.847531)
			(xy 91.364215 -241.812191) (xy 91.404648 -241.782815) (xy 91.44918 -241.760125) (xy 91.496712 -241.744681)
			(xy 91.546075 -241.736862) (xy 91.596053 -241.736862) (xy 91.645416 -241.744681) (xy 91.692948 -241.760125)
			(xy 91.73748 -241.782815) (xy 91.777913 -241.812191) (xy 91.813253 -241.847531) (xy 91.842629 -241.887964)
			(xy 91.865319 -241.932496) (xy 91.880763 -241.980028) (xy 91.888582 -242.029391) (xy 91.889072 -242.05438)
			(xy 92.194883 -242.05438) (xy 92.198978 -242.003652) (xy 92.211157 -241.954238) (xy 92.231105 -241.907418)
			(xy 92.258306 -241.864404) (xy 92.292054 -241.82631) (xy 92.331476 -241.794123) (xy 92.37555 -241.768677)
			(xy 92.423136 -241.75063) (xy 92.473 -241.74045) (xy 92.523852 -241.738401) (xy 92.574373 -241.744535)
			(xy 92.623257 -241.758695) (xy 92.669236 -241.780512) (xy 92.71112 -241.809422) (xy 92.747824 -241.844677)
			(xy 92.778397 -241.885363) (xy 92.802048 -241.930426) (xy 92.818164 -241.9787) (xy 92.826328 -242.028934)
			(xy 92.82684 -242.05438) (xy 94.074737 -242.05438) (xy 94.078832 -242.003652) (xy 94.091011 -241.954238)
			(xy 94.110959 -241.907418) (xy 94.13816 -241.864404) (xy 94.171908 -241.82631) (xy 94.21133 -241.794123)
			(xy 94.255404 -241.768677) (xy 94.30299 -241.75063) (xy 94.352854 -241.74045) (xy 94.403706 -241.738401)
			(xy 94.454227 -241.744535) (xy 94.503111 -241.758695) (xy 94.54909 -241.780512) (xy 94.590974 -241.809422)
			(xy 94.627678 -241.844677) (xy 94.658251 -241.885363) (xy 94.681902 -241.930426) (xy 94.698018 -241.9787)
			(xy 94.706182 -242.028934) (xy 94.706694 -242.05438) (xy 95.014791 -242.05438) (xy 95.018886 -242.003652)
			(xy 95.031065 -241.954238) (xy 95.051013 -241.907418) (xy 95.078214 -241.864404) (xy 95.111962 -241.82631)
			(xy 95.151384 -241.794123) (xy 95.195458 -241.768677) (xy 95.243044 -241.75063) (xy 95.292908 -241.74045)
			(xy 95.34376 -241.738401) (xy 95.394281 -241.744535) (xy 95.443165 -241.758695) (xy 95.489144 -241.780512)
			(xy 95.531028 -241.809422) (xy 95.567732 -241.844677) (xy 95.598305 -241.885363) (xy 95.621956 -241.930426)
			(xy 95.638072 -241.9787) (xy 95.646236 -242.028934) (xy 95.646748 -242.05438) (xy 95.646245 -242.079369)
			(xy 95.953562 -242.079369) (xy 95.953562 -242.029391) (xy 95.961381 -241.980028) (xy 95.976825 -241.932496)
			(xy 95.999515 -241.887964) (xy 96.028891 -241.847531) (xy 96.064231 -241.812191) (xy 96.104664 -241.782815)
			(xy 96.149196 -241.760125) (xy 96.196728 -241.744681) (xy 96.246091 -241.736862) (xy 96.296069 -241.736862)
			(xy 96.345432 -241.744681) (xy 96.392964 -241.760125) (xy 96.437496 -241.782815) (xy 96.477929 -241.812191)
			(xy 96.513269 -241.847531) (xy 96.542645 -241.887964) (xy 96.565335 -241.932496) (xy 96.580779 -241.980028)
			(xy 96.588598 -242.029391) (xy 96.589088 -242.05438) (xy 96.588598 -242.079369) (xy 96.580779 -242.128732)
			(xy 96.565335 -242.176264) (xy 96.542645 -242.220796) (xy 96.513269 -242.261229) (xy 96.477929 -242.296569)
			(xy 96.437496 -242.325945) (xy 96.392964 -242.348635) (xy 96.345432 -242.364079) (xy 96.296069 -242.371898)
			(xy 96.246091 -242.371898) (xy 96.196728 -242.364079) (xy 96.149196 -242.348635) (xy 96.104664 -242.325945)
			(xy 96.064231 -242.296569) (xy 96.028891 -242.261229) (xy 95.999515 -242.220796) (xy 95.976825 -242.176264)
			(xy 95.961381 -242.128732) (xy 95.953562 -242.079369) (xy 95.646245 -242.079369) (xy 95.646236 -242.079826)
			(xy 95.638072 -242.13006) (xy 95.621956 -242.178334) (xy 95.598305 -242.223397) (xy 95.567732 -242.264083)
			(xy 95.531028 -242.299338) (xy 95.489144 -242.328248) (xy 95.443165 -242.350065) (xy 95.394281 -242.364225)
			(xy 95.34376 -242.370359) (xy 95.292908 -242.36831) (xy 95.243044 -242.35813) (xy 95.195458 -242.340083)
			(xy 95.151384 -242.314637) (xy 95.111962 -242.28245) (xy 95.078214 -242.244356) (xy 95.051013 -242.201342)
			(xy 95.031065 -242.154522) (xy 95.018886 -242.105108) (xy 95.014791 -242.05438) (xy 94.706694 -242.05438)
			(xy 94.706182 -242.079826) (xy 94.698018 -242.13006) (xy 94.681902 -242.178334) (xy 94.658251 -242.223397)
			(xy 94.627678 -242.264083) (xy 94.590974 -242.299338) (xy 94.54909 -242.328248) (xy 94.503111 -242.350065)
			(xy 94.454227 -242.364225) (xy 94.403706 -242.370359) (xy 94.352854 -242.36831) (xy 94.30299 -242.35813)
			(xy 94.255404 -242.340083) (xy 94.21133 -242.314637) (xy 94.171908 -242.28245) (xy 94.13816 -242.244356)
			(xy 94.110959 -242.201342) (xy 94.091011 -242.154522) (xy 94.078832 -242.105108) (xy 94.074737 -242.05438)
			(xy 92.82684 -242.05438) (xy 92.826328 -242.079826) (xy 92.818164 -242.13006) (xy 92.802048 -242.178334)
			(xy 92.778397 -242.223397) (xy 92.747824 -242.264083) (xy 92.71112 -242.299338) (xy 92.669236 -242.328248)
			(xy 92.623257 -242.350065) (xy 92.574373 -242.364225) (xy 92.523852 -242.370359) (xy 92.473 -242.36831)
			(xy 92.423136 -242.35813) (xy 92.37555 -242.340083) (xy 92.331476 -242.314637) (xy 92.292054 -242.28245)
			(xy 92.258306 -242.244356) (xy 92.231105 -242.201342) (xy 92.211157 -242.154522) (xy 92.198978 -242.105108)
			(xy 92.194883 -242.05438) (xy 91.889072 -242.05438) (xy 91.888582 -242.079369) (xy 91.880763 -242.128732)
			(xy 91.865319 -242.176264) (xy 91.842629 -242.220796) (xy 91.813253 -242.261229) (xy 91.777913 -242.296569)
			(xy 91.73748 -242.325945) (xy 91.692948 -242.348635) (xy 91.645416 -242.364079) (xy 91.596053 -242.371898)
			(xy 91.546075 -242.371898) (xy 91.496712 -242.364079) (xy 91.44918 -242.348635) (xy 91.404648 -242.325945)
			(xy 91.364215 -242.296569) (xy 91.328875 -242.261229) (xy 91.299499 -242.220796) (xy 91.276809 -242.176264)
			(xy 91.261365 -242.128732) (xy 91.253546 -242.079369) (xy 90.946229 -242.079369) (xy 90.94622 -242.079826)
			(xy 90.938056 -242.13006) (xy 90.92194 -242.178334) (xy 90.898289 -242.223397) (xy 90.867716 -242.264083)
			(xy 90.831012 -242.299338) (xy 90.789128 -242.328248) (xy 90.743149 -242.350065) (xy 90.694265 -242.364225)
			(xy 90.643744 -242.370359) (xy 90.592892 -242.36831) (xy 90.543028 -242.35813) (xy 90.495442 -242.340083)
			(xy 90.451368 -242.314637) (xy 90.411946 -242.28245) (xy 90.378198 -242.244356) (xy 90.350997 -242.201342)
			(xy 90.331049 -242.154522) (xy 90.31887 -242.105108) (xy 90.314775 -242.05438) (xy 90.008964 -242.05438)
			(xy 90.008474 -242.079369) (xy 90.000655 -242.128732) (xy 89.985211 -242.176264) (xy 89.962521 -242.220796)
			(xy 89.933145 -242.261229) (xy 89.897805 -242.296569) (xy 89.857372 -242.325945) (xy 89.81284 -242.348635)
			(xy 89.765308 -242.364079) (xy 89.715945 -242.371898) (xy 89.665967 -242.371898) (xy 89.616604 -242.364079)
			(xy 89.569072 -242.348635) (xy 89.52454 -242.325945) (xy 89.484107 -242.296569) (xy 89.448767 -242.261229)
			(xy 89.419391 -242.220796) (xy 89.396701 -242.176264) (xy 89.381257 -242.128732) (xy 89.373438 -242.079369)
			(xy 89.066375 -242.079369) (xy 89.066366 -242.079826) (xy 89.058202 -242.13006) (xy 89.042086 -242.178334)
			(xy 89.018435 -242.223397) (xy 88.987862 -242.264083) (xy 88.951158 -242.299338) (xy 88.909274 -242.328248)
			(xy 88.863295 -242.350065) (xy 88.814411 -242.364225) (xy 88.76389 -242.370359) (xy 88.713038 -242.36831)
			(xy 88.663174 -242.35813) (xy 88.615588 -242.340083) (xy 88.571514 -242.314637) (xy 88.532092 -242.28245)
			(xy 88.498344 -242.244356) (xy 88.471143 -242.201342) (xy 88.451195 -242.154522) (xy 88.439016 -242.105108)
			(xy 88.434921 -242.05438) (xy 88.126824 -242.05438) (xy 88.126312 -242.079826) (xy 88.118148 -242.13006)
			(xy 88.102032 -242.178334) (xy 88.078381 -242.223397) (xy 88.047808 -242.264083) (xy 88.011104 -242.299338)
			(xy 87.96922 -242.328248) (xy 87.923241 -242.350065) (xy 87.874357 -242.364225) (xy 87.823836 -242.370359)
			(xy 87.772984 -242.36831) (xy 87.72312 -242.35813) (xy 87.675534 -242.340083) (xy 87.63146 -242.314637)
			(xy 87.592038 -242.28245) (xy 87.55829 -242.244356) (xy 87.531089 -242.201342) (xy 87.511141 -242.154522)
			(xy 87.498962 -242.105108) (xy 87.494867 -242.05438) (xy 86.246716 -242.05438) (xy 86.246204 -242.079826)
			(xy 86.23804 -242.13006) (xy 86.221924 -242.178334) (xy 86.198273 -242.223397) (xy 86.1677 -242.264083)
			(xy 86.130996 -242.299338) (xy 86.089112 -242.328248) (xy 86.043133 -242.350065) (xy 85.994249 -242.364225)
			(xy 85.943728 -242.370359) (xy 85.892876 -242.36831) (xy 85.843012 -242.35813) (xy 85.795426 -242.340083)
			(xy 85.751352 -242.314637) (xy 85.71193 -242.28245) (xy 85.678182 -242.244356) (xy 85.650981 -242.201342)
			(xy 85.631033 -242.154522) (xy 85.618854 -242.105108) (xy 85.614759 -242.05438) (xy 85.308948 -242.05438)
			(xy 85.308458 -242.079369) (xy 85.300639 -242.128732) (xy 85.285195 -242.176264) (xy 85.262505 -242.220796)
			(xy 85.233129 -242.261229) (xy 85.197789 -242.296569) (xy 85.157356 -242.325945) (xy 85.112824 -242.348635)
			(xy 85.065292 -242.364079) (xy 85.015929 -242.371898) (xy 84.965951 -242.371898) (xy 84.916588 -242.364079)
			(xy 84.869056 -242.348635) (xy 84.824524 -242.325945) (xy 84.784091 -242.296569) (xy 84.748751 -242.261229)
			(xy 84.719375 -242.220796) (xy 84.696685 -242.176264) (xy 84.681241 -242.128732) (xy 84.673422 -242.079369)
			(xy 84.366359 -242.079369) (xy 84.36635 -242.079826) (xy 84.358186 -242.13006) (xy 84.34207 -242.178334)
			(xy 84.318419 -242.223397) (xy 84.287846 -242.264083) (xy 84.251142 -242.299338) (xy 84.209258 -242.328248)
			(xy 84.163279 -242.350065) (xy 84.114395 -242.364225) (xy 84.063874 -242.370359) (xy 84.013022 -242.36831)
			(xy 83.963158 -242.35813) (xy 83.915572 -242.340083) (xy 83.871498 -242.314637) (xy 83.832076 -242.28245)
			(xy 83.798328 -242.244356) (xy 83.771127 -242.201342) (xy 83.751179 -242.154522) (xy 83.739 -242.105108)
			(xy 83.734905 -242.05438) (xy 83.429094 -242.05438) (xy 83.428604 -242.079369) (xy 83.420785 -242.128732)
			(xy 83.405341 -242.176264) (xy 83.382651 -242.220796) (xy 83.353275 -242.261229) (xy 83.317935 -242.296569)
			(xy 83.277502 -242.325945) (xy 83.23297 -242.348635) (xy 83.185438 -242.364079) (xy 83.136075 -242.371898)
			(xy 83.086097 -242.371898) (xy 83.036734 -242.364079) (xy 82.989202 -242.348635) (xy 82.94467 -242.325945)
			(xy 82.904237 -242.296569) (xy 82.868897 -242.261229) (xy 82.839521 -242.220796) (xy 82.816831 -242.176264)
			(xy 82.801387 -242.128732) (xy 82.793568 -242.079369) (xy 82.486251 -242.079369) (xy 82.486242 -242.079826)
			(xy 82.478078 -242.13006) (xy 82.461962 -242.178334) (xy 82.438311 -242.223397) (xy 82.407738 -242.264083)
			(xy 82.371034 -242.299338) (xy 82.32915 -242.328248) (xy 82.283171 -242.350065) (xy 82.234287 -242.364225)
			(xy 82.183766 -242.370359) (xy 82.132914 -242.36831) (xy 82.08305 -242.35813) (xy 82.035464 -242.340083)
			(xy 81.99139 -242.314637) (xy 81.951968 -242.28245) (xy 81.91822 -242.244356) (xy 81.891019 -242.201342)
			(xy 81.871071 -242.154522) (xy 81.858892 -242.105108) (xy 81.854797 -242.05438) (xy 81.5467 -242.05438)
			(xy 81.546188 -242.079826) (xy 81.538024 -242.13006) (xy 81.521908 -242.178334) (xy 81.498257 -242.223397)
			(xy 81.467684 -242.264083) (xy 81.43098 -242.299338) (xy 81.389096 -242.328248) (xy 81.343117 -242.350065)
			(xy 81.294233 -242.364225) (xy 81.243712 -242.370359) (xy 81.19286 -242.36831) (xy 81.142996 -242.35813)
			(xy 81.09541 -242.340083) (xy 81.051336 -242.314637) (xy 81.011914 -242.28245) (xy 80.978166 -242.244356)
			(xy 80.950965 -242.201342) (xy 80.931017 -242.154522) (xy 80.918838 -242.105108) (xy 80.914743 -242.05438)
			(xy 79.53248 -242.05438) (xy 79.53248 -242.488466) (xy 79.532977 -242.503242) (xy 79.541431 -242.53156)
			(xy 79.557643 -242.556269) (xy 79.580252 -242.5753) (xy 79.607364 -242.587058) (xy 79.636709 -242.590558)
			(xy 79.665826 -242.585506) (xy 79.679292 -242.579398) (xy 79.701428 -242.568904) (xy 79.74812 -242.554086)
			(xy 79.79653 -242.546591) (xy 79.821024 -242.546124) (xy 79.846033 -242.546616) (xy 79.895435 -242.554444)
			(xy 79.943004 -242.569904) (xy 79.987569 -242.592614) (xy 80.028033 -242.622015) (xy 80.0634 -242.657385)
			(xy 80.092799 -242.697851) (xy 80.115506 -242.742418) (xy 80.130961 -242.789989) (xy 80.138785 -242.839391)
			(xy 80.138785 -242.864386) (xy 80.444843 -242.864386) (xy 80.448938 -242.813658) (xy 80.461117 -242.764244)
			(xy 80.481065 -242.717424) (xy 80.508266 -242.67441) (xy 80.542014 -242.636316) (xy 80.581436 -242.604129)
			(xy 80.62551 -242.578683) (xy 80.673096 -242.560636) (xy 80.72296 -242.550456) (xy 80.773812 -242.548407)
			(xy 80.824333 -242.554541) (xy 80.873217 -242.568701) (xy 80.919196 -242.590518) (xy 80.96108 -242.619428)
			(xy 80.997784 -242.654683) (xy 81.028357 -242.695369) (xy 81.052008 -242.740432) (xy 81.068124 -242.788706)
			(xy 81.076288 -242.83894) (xy 81.0768 -242.864386) (xy 81.076297 -242.889375) (xy 81.383614 -242.889375)
			(xy 81.383614 -242.839397) (xy 81.391433 -242.790034) (xy 81.406877 -242.742502) (xy 81.429567 -242.69797)
			(xy 81.458943 -242.657537) (xy 81.494283 -242.622197) (xy 81.534716 -242.592821) (xy 81.579248 -242.570131)
			(xy 81.62678 -242.554687) (xy 81.676143 -242.546868) (xy 81.726121 -242.546868) (xy 81.775484 -242.554687)
			(xy 81.823016 -242.570131) (xy 81.867548 -242.592821) (xy 81.907981 -242.622197) (xy 81.943321 -242.657537)
			(xy 81.972697 -242.69797) (xy 81.995387 -242.742502) (xy 82.010831 -242.790034) (xy 82.01865 -242.839397)
			(xy 82.01914 -242.864386) (xy 82.324697 -242.864386) (xy 82.328792 -242.813658) (xy 82.340971 -242.764244)
			(xy 82.360919 -242.717424) (xy 82.38812 -242.67441) (xy 82.421868 -242.636316) (xy 82.46129 -242.604129)
			(xy 82.505364 -242.578683) (xy 82.55295 -242.560636) (xy 82.602814 -242.550456) (xy 82.653666 -242.548407)
			(xy 82.704187 -242.554541) (xy 82.753071 -242.568701) (xy 82.79905 -242.590518) (xy 82.840934 -242.619428)
			(xy 82.877638 -242.654683) (xy 82.908211 -242.695369) (xy 82.931862 -242.740432) (xy 82.947978 -242.788706)
			(xy 82.956142 -242.83894) (xy 82.956654 -242.864386) (xy 82.956151 -242.889375) (xy 83.263468 -242.889375)
			(xy 83.263468 -242.839397) (xy 83.271287 -242.790034) (xy 83.286731 -242.742502) (xy 83.309421 -242.69797)
			(xy 83.338797 -242.657537) (xy 83.374137 -242.622197) (xy 83.41457 -242.592821) (xy 83.459102 -242.570131)
			(xy 83.506634 -242.554687) (xy 83.555997 -242.546868) (xy 83.605975 -242.546868) (xy 83.655338 -242.554687)
			(xy 83.70287 -242.570131) (xy 83.747402 -242.592821) (xy 83.787835 -242.622197) (xy 83.823175 -242.657537)
			(xy 83.852551 -242.69797) (xy 83.875241 -242.742502) (xy 83.890685 -242.790034) (xy 83.898504 -242.839397)
			(xy 83.898994 -242.864386) (xy 84.204805 -242.864386) (xy 84.2089 -242.813658) (xy 84.221079 -242.764244)
			(xy 84.241027 -242.717424) (xy 84.268228 -242.67441) (xy 84.301976 -242.636316) (xy 84.341398 -242.604129)
			(xy 84.385472 -242.578683) (xy 84.433058 -242.560636) (xy 84.482922 -242.550456) (xy 84.533774 -242.548407)
			(xy 84.584295 -242.554541) (xy 84.633179 -242.568701) (xy 84.679158 -242.590518) (xy 84.721042 -242.619428)
			(xy 84.757746 -242.654683) (xy 84.788319 -242.695369) (xy 84.81197 -242.740432) (xy 84.828086 -242.788706)
			(xy 84.83625 -242.83894) (xy 84.836762 -242.864386) (xy 85.144859 -242.864386) (xy 85.148954 -242.813658)
			(xy 85.161133 -242.764244) (xy 85.181081 -242.717424) (xy 85.208282 -242.67441) (xy 85.24203 -242.636316)
			(xy 85.281452 -242.604129) (xy 85.325526 -242.578683) (xy 85.373112 -242.560636) (xy 85.422976 -242.550456)
			(xy 85.473828 -242.548407) (xy 85.524349 -242.554541) (xy 85.573233 -242.568701) (xy 85.619212 -242.590518)
			(xy 85.661096 -242.619428) (xy 85.6978 -242.654683) (xy 85.728373 -242.695369) (xy 85.752024 -242.740432)
			(xy 85.76814 -242.788706) (xy 85.776304 -242.83894) (xy 85.776816 -242.864386) (xy 85.776313 -242.889375)
			(xy 86.08363 -242.889375) (xy 86.08363 -242.839397) (xy 86.091449 -242.790034) (xy 86.106893 -242.742502)
			(xy 86.129583 -242.69797) (xy 86.158959 -242.657537) (xy 86.194299 -242.622197) (xy 86.234732 -242.592821)
			(xy 86.279264 -242.570131) (xy 86.326796 -242.554687) (xy 86.376159 -242.546868) (xy 86.426137 -242.546868)
			(xy 86.4755 -242.554687) (xy 86.523032 -242.570131) (xy 86.567564 -242.592821) (xy 86.607997 -242.622197)
			(xy 86.643337 -242.657537) (xy 86.672713 -242.69797) (xy 86.695403 -242.742502) (xy 86.710847 -242.790034)
			(xy 86.718666 -242.839397) (xy 86.719156 -242.864386) (xy 87.024713 -242.864386) (xy 87.028808 -242.813658)
			(xy 87.040987 -242.764244) (xy 87.060935 -242.717424) (xy 87.088136 -242.67441) (xy 87.121884 -242.636316)
			(xy 87.161306 -242.604129) (xy 87.20538 -242.578683) (xy 87.252966 -242.560636) (xy 87.30283 -242.550456)
			(xy 87.353682 -242.548407) (xy 87.404203 -242.554541) (xy 87.453087 -242.568701) (xy 87.499066 -242.590518)
			(xy 87.54095 -242.619428) (xy 87.577654 -242.654683) (xy 87.608227 -242.695369) (xy 87.631878 -242.740432)
			(xy 87.647994 -242.788706) (xy 87.656158 -242.83894) (xy 87.65667 -242.864386) (xy 87.656167 -242.889375)
			(xy 87.963484 -242.889375) (xy 87.963484 -242.839397) (xy 87.971303 -242.790034) (xy 87.986747 -242.742502)
			(xy 88.009437 -242.69797) (xy 88.038813 -242.657537) (xy 88.074153 -242.622197) (xy 88.114586 -242.592821)
			(xy 88.159118 -242.570131) (xy 88.20665 -242.554687) (xy 88.256013 -242.546868) (xy 88.305991 -242.546868)
			(xy 88.355354 -242.554687) (xy 88.402886 -242.570131) (xy 88.447418 -242.592821) (xy 88.487851 -242.622197)
			(xy 88.523191 -242.657537) (xy 88.552567 -242.69797) (xy 88.575257 -242.742502) (xy 88.590701 -242.790034)
			(xy 88.59852 -242.839397) (xy 88.59901 -242.864386) (xy 88.904821 -242.864386) (xy 88.908916 -242.813658)
			(xy 88.921095 -242.764244) (xy 88.941043 -242.717424) (xy 88.968244 -242.67441) (xy 89.001992 -242.636316)
			(xy 89.041414 -242.604129) (xy 89.085488 -242.578683) (xy 89.133074 -242.560636) (xy 89.182938 -242.550456)
			(xy 89.23379 -242.548407) (xy 89.284311 -242.554541) (xy 89.333195 -242.568701) (xy 89.379174 -242.590518)
			(xy 89.421058 -242.619428) (xy 89.457762 -242.654683) (xy 89.488335 -242.695369) (xy 89.511986 -242.740432)
			(xy 89.528102 -242.788706) (xy 89.536266 -242.83894) (xy 89.536778 -242.864386) (xy 89.536275 -242.889375)
			(xy 89.843592 -242.889375) (xy 89.843592 -242.839397) (xy 89.851411 -242.790034) (xy 89.866855 -242.742502)
			(xy 89.889545 -242.69797) (xy 89.918921 -242.657537) (xy 89.954261 -242.622197) (xy 89.994694 -242.592821)
			(xy 90.039226 -242.570131) (xy 90.086758 -242.554687) (xy 90.136121 -242.546868) (xy 90.186099 -242.546868)
			(xy 90.235462 -242.554687) (xy 90.282994 -242.570131) (xy 90.327526 -242.592821) (xy 90.367959 -242.622197)
			(xy 90.403299 -242.657537) (xy 90.432675 -242.69797) (xy 90.455365 -242.742502) (xy 90.470809 -242.790034)
			(xy 90.478628 -242.839397) (xy 90.479118 -242.864386) (xy 90.784675 -242.864386) (xy 90.78877 -242.813658)
			(xy 90.800949 -242.764244) (xy 90.820897 -242.717424) (xy 90.848098 -242.67441) (xy 90.881846 -242.636316)
			(xy 90.921268 -242.604129) (xy 90.965342 -242.578683) (xy 91.012928 -242.560636) (xy 91.062792 -242.550456)
			(xy 91.113644 -242.548407) (xy 91.164165 -242.554541) (xy 91.213049 -242.568701) (xy 91.259028 -242.590518)
			(xy 91.300912 -242.619428) (xy 91.337616 -242.654683) (xy 91.368189 -242.695369) (xy 91.39184 -242.740432)
			(xy 91.407956 -242.788706) (xy 91.41612 -242.83894) (xy 91.416632 -242.864386) (xy 91.724729 -242.864386)
			(xy 91.728824 -242.813658) (xy 91.741003 -242.764244) (xy 91.760951 -242.717424) (xy 91.788152 -242.67441)
			(xy 91.8219 -242.636316) (xy 91.861322 -242.604129) (xy 91.905396 -242.578683) (xy 91.952982 -242.560636)
			(xy 92.002846 -242.550456) (xy 92.053698 -242.548407) (xy 92.104219 -242.554541) (xy 92.153103 -242.568701)
			(xy 92.199082 -242.590518) (xy 92.240966 -242.619428) (xy 92.27767 -242.654683) (xy 92.308243 -242.695369)
			(xy 92.331894 -242.740432) (xy 92.34801 -242.788706) (xy 92.356174 -242.83894) (xy 92.356686 -242.864386)
			(xy 92.356183 -242.889375) (xy 92.6635 -242.889375) (xy 92.6635 -242.839397) (xy 92.671319 -242.790034)
			(xy 92.686763 -242.742502) (xy 92.709453 -242.69797) (xy 92.738829 -242.657537) (xy 92.774169 -242.622197)
			(xy 92.814602 -242.592821) (xy 92.859134 -242.570131) (xy 92.906666 -242.554687) (xy 92.956029 -242.546868)
			(xy 93.006007 -242.546868) (xy 93.05537 -242.554687) (xy 93.102902 -242.570131) (xy 93.147434 -242.592821)
			(xy 93.187867 -242.622197) (xy 93.223207 -242.657537) (xy 93.252583 -242.69797) (xy 93.275273 -242.742502)
			(xy 93.290717 -242.790034) (xy 93.298536 -242.839397) (xy 93.299026 -242.864386) (xy 93.604837 -242.864386)
			(xy 93.608932 -242.813658) (xy 93.621111 -242.764244) (xy 93.641059 -242.717424) (xy 93.66826 -242.67441)
			(xy 93.702008 -242.636316) (xy 93.74143 -242.604129) (xy 93.785504 -242.578683) (xy 93.83309 -242.560636)
			(xy 93.882954 -242.550456) (xy 93.933806 -242.548407) (xy 93.984327 -242.554541) (xy 94.033211 -242.568701)
			(xy 94.07919 -242.590518) (xy 94.121074 -242.619428) (xy 94.157778 -242.654683) (xy 94.188351 -242.695369)
			(xy 94.212002 -242.740432) (xy 94.228118 -242.788706) (xy 94.236282 -242.83894) (xy 94.236794 -242.864386)
			(xy 94.236291 -242.889375) (xy 94.543608 -242.889375) (xy 94.543608 -242.839397) (xy 94.551427 -242.790034)
			(xy 94.566871 -242.742502) (xy 94.589561 -242.69797) (xy 94.618937 -242.657537) (xy 94.654277 -242.622197)
			(xy 94.69471 -242.592821) (xy 94.739242 -242.570131) (xy 94.786774 -242.554687) (xy 94.836137 -242.546868)
			(xy 94.886115 -242.546868) (xy 94.935478 -242.554687) (xy 94.98301 -242.570131) (xy 95.027542 -242.592821)
			(xy 95.067975 -242.622197) (xy 95.103315 -242.657537) (xy 95.132691 -242.69797) (xy 95.155381 -242.742502)
			(xy 95.170825 -242.790034) (xy 95.178644 -242.839397) (xy 95.179134 -242.864386) (xy 95.484691 -242.864386)
			(xy 95.488786 -242.813658) (xy 95.500965 -242.764244) (xy 95.520913 -242.717424) (xy 95.548114 -242.67441)
			(xy 95.581862 -242.636316) (xy 95.621284 -242.604129) (xy 95.665358 -242.578683) (xy 95.712944 -242.560636)
			(xy 95.762808 -242.550456) (xy 95.81366 -242.548407) (xy 95.864181 -242.554541) (xy 95.913065 -242.568701)
			(xy 95.959044 -242.590518) (xy 96.000928 -242.619428) (xy 96.037632 -242.654683) (xy 96.068205 -242.695369)
			(xy 96.091856 -242.740432) (xy 96.107972 -242.788706) (xy 96.116136 -242.83894) (xy 96.116648 -242.864386)
			(xy 96.116136 -242.889832) (xy 96.107972 -242.940066) (xy 96.091856 -242.98834) (xy 96.068205 -243.033403)
			(xy 96.037632 -243.074089) (xy 96.000928 -243.109344) (xy 95.959044 -243.138254) (xy 95.913065 -243.160071)
			(xy 95.864181 -243.174231) (xy 95.81366 -243.180365) (xy 95.762808 -243.178316) (xy 95.712944 -243.168136)
			(xy 95.665358 -243.150089) (xy 95.621284 -243.124643) (xy 95.581862 -243.092456) (xy 95.548114 -243.054362)
			(xy 95.520913 -243.011348) (xy 95.500965 -242.964528) (xy 95.488786 -242.915114) (xy 95.484691 -242.864386)
			(xy 95.179134 -242.864386) (xy 95.178644 -242.889375) (xy 95.170825 -242.938738) (xy 95.155381 -242.98627)
			(xy 95.132691 -243.030802) (xy 95.103315 -243.071235) (xy 95.067975 -243.106575) (xy 95.027542 -243.135951)
			(xy 94.98301 -243.158641) (xy 94.935478 -243.174085) (xy 94.886115 -243.181904) (xy 94.836137 -243.181904)
			(xy 94.786774 -243.174085) (xy 94.739242 -243.158641) (xy 94.69471 -243.135951) (xy 94.654277 -243.106575)
			(xy 94.618937 -243.071235) (xy 94.589561 -243.030802) (xy 94.566871 -242.98627) (xy 94.551427 -242.938738)
			(xy 94.543608 -242.889375) (xy 94.236291 -242.889375) (xy 94.236282 -242.889832) (xy 94.228118 -242.940066)
			(xy 94.212002 -242.98834) (xy 94.188351 -243.033403) (xy 94.157778 -243.074089) (xy 94.121074 -243.109344)
			(xy 94.07919 -243.138254) (xy 94.033211 -243.160071) (xy 93.984327 -243.174231) (xy 93.933806 -243.180365)
			(xy 93.882954 -243.178316) (xy 93.83309 -243.168136) (xy 93.785504 -243.150089) (xy 93.74143 -243.124643)
			(xy 93.702008 -243.092456) (xy 93.66826 -243.054362) (xy 93.641059 -243.011348) (xy 93.621111 -242.964528)
			(xy 93.608932 -242.915114) (xy 93.604837 -242.864386) (xy 93.299026 -242.864386) (xy 93.298536 -242.889375)
			(xy 93.290717 -242.938738) (xy 93.275273 -242.98627) (xy 93.252583 -243.030802) (xy 93.223207 -243.071235)
			(xy 93.187867 -243.106575) (xy 93.147434 -243.135951) (xy 93.102902 -243.158641) (xy 93.05537 -243.174085)
			(xy 93.006007 -243.181904) (xy 92.956029 -243.181904) (xy 92.906666 -243.174085) (xy 92.859134 -243.158641)
			(xy 92.814602 -243.135951) (xy 92.774169 -243.106575) (xy 92.738829 -243.071235) (xy 92.709453 -243.030802)
			(xy 92.686763 -242.98627) (xy 92.671319 -242.938738) (xy 92.6635 -242.889375) (xy 92.356183 -242.889375)
			(xy 92.356174 -242.889832) (xy 92.34801 -242.940066) (xy 92.331894 -242.98834) (xy 92.308243 -243.033403)
			(xy 92.27767 -243.074089) (xy 92.240966 -243.109344) (xy 92.199082 -243.138254) (xy 92.153103 -243.160071)
			(xy 92.104219 -243.174231) (xy 92.053698 -243.180365) (xy 92.002846 -243.178316) (xy 91.952982 -243.168136)
			(xy 91.905396 -243.150089) (xy 91.861322 -243.124643) (xy 91.8219 -243.092456) (xy 91.788152 -243.054362)
			(xy 91.760951 -243.011348) (xy 91.741003 -242.964528) (xy 91.728824 -242.915114) (xy 91.724729 -242.864386)
			(xy 91.416632 -242.864386) (xy 91.41612 -242.889832) (xy 91.407956 -242.940066) (xy 91.39184 -242.98834)
			(xy 91.368189 -243.033403) (xy 91.337616 -243.074089) (xy 91.300912 -243.109344) (xy 91.259028 -243.138254)
			(xy 91.213049 -243.160071) (xy 91.164165 -243.174231) (xy 91.113644 -243.180365) (xy 91.062792 -243.178316)
			(xy 91.012928 -243.168136) (xy 90.965342 -243.150089) (xy 90.921268 -243.124643) (xy 90.881846 -243.092456)
			(xy 90.848098 -243.054362) (xy 90.820897 -243.011348) (xy 90.800949 -242.964528) (xy 90.78877 -242.915114)
			(xy 90.784675 -242.864386) (xy 90.479118 -242.864386) (xy 90.478628 -242.889375) (xy 90.470809 -242.938738)
			(xy 90.455365 -242.98627) (xy 90.432675 -243.030802) (xy 90.403299 -243.071235) (xy 90.367959 -243.106575)
			(xy 90.327526 -243.135951) (xy 90.282994 -243.158641) (xy 90.235462 -243.174085) (xy 90.186099 -243.181904)
			(xy 90.136121 -243.181904) (xy 90.086758 -243.174085) (xy 90.039226 -243.158641) (xy 89.994694 -243.135951)
			(xy 89.954261 -243.106575) (xy 89.918921 -243.071235) (xy 89.889545 -243.030802) (xy 89.866855 -242.98627)
			(xy 89.851411 -242.938738) (xy 89.843592 -242.889375) (xy 89.536275 -242.889375) (xy 89.536266 -242.889832)
			(xy 89.528102 -242.940066) (xy 89.511986 -242.98834) (xy 89.488335 -243.033403) (xy 89.457762 -243.074089)
			(xy 89.421058 -243.109344) (xy 89.379174 -243.138254) (xy 89.333195 -243.160071) (xy 89.284311 -243.174231)
			(xy 89.23379 -243.180365) (xy 89.182938 -243.178316) (xy 89.133074 -243.168136) (xy 89.085488 -243.150089)
			(xy 89.041414 -243.124643) (xy 89.001992 -243.092456) (xy 88.968244 -243.054362) (xy 88.941043 -243.011348)
			(xy 88.921095 -242.964528) (xy 88.908916 -242.915114) (xy 88.904821 -242.864386) (xy 88.59901 -242.864386)
			(xy 88.59852 -242.889375) (xy 88.590701 -242.938738) (xy 88.575257 -242.98627) (xy 88.552567 -243.030802)
			(xy 88.523191 -243.071235) (xy 88.487851 -243.106575) (xy 88.447418 -243.135951) (xy 88.402886 -243.158641)
			(xy 88.355354 -243.174085) (xy 88.305991 -243.181904) (xy 88.256013 -243.181904) (xy 88.20665 -243.174085)
			(xy 88.159118 -243.158641) (xy 88.114586 -243.135951) (xy 88.074153 -243.106575) (xy 88.038813 -243.071235)
			(xy 88.009437 -243.030802) (xy 87.986747 -242.98627) (xy 87.971303 -242.938738) (xy 87.963484 -242.889375)
			(xy 87.656167 -242.889375) (xy 87.656158 -242.889832) (xy 87.647994 -242.940066) (xy 87.631878 -242.98834)
			(xy 87.608227 -243.033403) (xy 87.577654 -243.074089) (xy 87.54095 -243.109344) (xy 87.499066 -243.138254)
			(xy 87.453087 -243.160071) (xy 87.404203 -243.174231) (xy 87.353682 -243.180365) (xy 87.30283 -243.178316)
			(xy 87.252966 -243.168136) (xy 87.20538 -243.150089) (xy 87.161306 -243.124643) (xy 87.121884 -243.092456)
			(xy 87.088136 -243.054362) (xy 87.060935 -243.011348) (xy 87.040987 -242.964528) (xy 87.028808 -242.915114)
			(xy 87.024713 -242.864386) (xy 86.719156 -242.864386) (xy 86.718666 -242.889375) (xy 86.710847 -242.938738)
			(xy 86.695403 -242.98627) (xy 86.672713 -243.030802) (xy 86.643337 -243.071235) (xy 86.607997 -243.106575)
			(xy 86.567564 -243.135951) (xy 86.523032 -243.158641) (xy 86.4755 -243.174085) (xy 86.426137 -243.181904)
			(xy 86.376159 -243.181904) (xy 86.326796 -243.174085) (xy 86.279264 -243.158641) (xy 86.234732 -243.135951)
			(xy 86.194299 -243.106575) (xy 86.158959 -243.071235) (xy 86.129583 -243.030802) (xy 86.106893 -242.98627)
			(xy 86.091449 -242.938738) (xy 86.08363 -242.889375) (xy 85.776313 -242.889375) (xy 85.776304 -242.889832)
			(xy 85.76814 -242.940066) (xy 85.752024 -242.98834) (xy 85.728373 -243.033403) (xy 85.6978 -243.074089)
			(xy 85.661096 -243.109344) (xy 85.619212 -243.138254) (xy 85.573233 -243.160071) (xy 85.524349 -243.174231)
			(xy 85.473828 -243.180365) (xy 85.422976 -243.178316) (xy 85.373112 -243.168136) (xy 85.325526 -243.150089)
			(xy 85.281452 -243.124643) (xy 85.24203 -243.092456) (xy 85.208282 -243.054362) (xy 85.181081 -243.011348)
			(xy 85.161133 -242.964528) (xy 85.148954 -242.915114) (xy 85.144859 -242.864386) (xy 84.836762 -242.864386)
			(xy 84.83625 -242.889832) (xy 84.828086 -242.940066) (xy 84.81197 -242.98834) (xy 84.788319 -243.033403)
			(xy 84.757746 -243.074089) (xy 84.721042 -243.109344) (xy 84.679158 -243.138254) (xy 84.633179 -243.160071)
			(xy 84.584295 -243.174231) (xy 84.533774 -243.180365) (xy 84.482922 -243.178316) (xy 84.433058 -243.168136)
			(xy 84.385472 -243.150089) (xy 84.341398 -243.124643) (xy 84.301976 -243.092456) (xy 84.268228 -243.054362)
			(xy 84.241027 -243.011348) (xy 84.221079 -242.964528) (xy 84.2089 -242.915114) (xy 84.204805 -242.864386)
			(xy 83.898994 -242.864386) (xy 83.898504 -242.889375) (xy 83.890685 -242.938738) (xy 83.875241 -242.98627)
			(xy 83.852551 -243.030802) (xy 83.823175 -243.071235) (xy 83.787835 -243.106575) (xy 83.747402 -243.135951)
			(xy 83.70287 -243.158641) (xy 83.655338 -243.174085) (xy 83.605975 -243.181904) (xy 83.555997 -243.181904)
			(xy 83.506634 -243.174085) (xy 83.459102 -243.158641) (xy 83.41457 -243.135951) (xy 83.374137 -243.106575)
			(xy 83.338797 -243.071235) (xy 83.309421 -243.030802) (xy 83.286731 -242.98627) (xy 83.271287 -242.938738)
			(xy 83.263468 -242.889375) (xy 82.956151 -242.889375) (xy 82.956142 -242.889832) (xy 82.947978 -242.940066)
			(xy 82.931862 -242.98834) (xy 82.908211 -243.033403) (xy 82.877638 -243.074089) (xy 82.840934 -243.109344)
			(xy 82.79905 -243.138254) (xy 82.753071 -243.160071) (xy 82.704187 -243.174231) (xy 82.653666 -243.180365)
			(xy 82.602814 -243.178316) (xy 82.55295 -243.168136) (xy 82.505364 -243.150089) (xy 82.46129 -243.124643)
			(xy 82.421868 -243.092456) (xy 82.38812 -243.054362) (xy 82.360919 -243.011348) (xy 82.340971 -242.964528)
			(xy 82.328792 -242.915114) (xy 82.324697 -242.864386) (xy 82.01914 -242.864386) (xy 82.01865 -242.889375)
			(xy 82.010831 -242.938738) (xy 81.995387 -242.98627) (xy 81.972697 -243.030802) (xy 81.943321 -243.071235)
			(xy 81.907981 -243.106575) (xy 81.867548 -243.135951) (xy 81.823016 -243.158641) (xy 81.775484 -243.174085)
			(xy 81.726121 -243.181904) (xy 81.676143 -243.181904) (xy 81.62678 -243.174085) (xy 81.579248 -243.158641)
			(xy 81.534716 -243.135951) (xy 81.494283 -243.106575) (xy 81.458943 -243.071235) (xy 81.429567 -243.030802)
			(xy 81.406877 -242.98627) (xy 81.391433 -242.938738) (xy 81.383614 -242.889375) (xy 81.076297 -242.889375)
			(xy 81.076288 -242.889832) (xy 81.068124 -242.940066) (xy 81.052008 -242.98834) (xy 81.028357 -243.033403)
			(xy 80.997784 -243.074089) (xy 80.96108 -243.109344) (xy 80.919196 -243.138254) (xy 80.873217 -243.160071)
			(xy 80.824333 -243.174231) (xy 80.773812 -243.180365) (xy 80.72296 -243.178316) (xy 80.673096 -243.168136)
			(xy 80.62551 -243.150089) (xy 80.581436 -243.124643) (xy 80.542014 -243.092456) (xy 80.508266 -243.054362)
			(xy 80.481065 -243.011348) (xy 80.461117 -242.964528) (xy 80.448938 -242.915114) (xy 80.444843 -242.864386)
			(xy 80.138785 -242.864386) (xy 80.138785 -242.889409) (xy 80.130961 -242.938811) (xy 80.115506 -242.986382)
			(xy 80.092799 -243.030949) (xy 80.0634 -243.071415) (xy 80.028033 -243.106785) (xy 79.987569 -243.136186)
			(xy 79.943004 -243.158896) (xy 79.895435 -243.174356) (xy 79.846033 -243.182184) (xy 79.821024 -243.182648)
			(xy 79.796529 -243.1822) (xy 79.748117 -243.174701) (xy 79.701425 -243.159877) (xy 79.679292 -243.149374)
			(xy 79.665839 -243.143252) (xy 79.636724 -243.138233) (xy 79.607389 -243.141751) (xy 79.580287 -243.153514)
			(xy 79.557682 -243.172537) (xy 79.541463 -243.197232) (xy 79.532986 -243.225534) (xy 79.53248 -243.240306)
			(xy 79.53248 -243.699381) (xy 79.97366 -243.699381) (xy 79.97366 -243.649403) (xy 79.981479 -243.60004)
			(xy 79.996923 -243.552508) (xy 80.019613 -243.507976) (xy 80.048989 -243.467543) (xy 80.084329 -243.432203)
			(xy 80.124762 -243.402827) (xy 80.169294 -243.380137) (xy 80.216826 -243.364693) (xy 80.266189 -243.356874)
			(xy 80.316167 -243.356874) (xy 80.36553 -243.364693) (xy 80.413062 -243.380137) (xy 80.457594 -243.402827)
			(xy 80.498027 -243.432203) (xy 80.533367 -243.467543) (xy 80.562743 -243.507976) (xy 80.585433 -243.552508)
			(xy 80.600877 -243.60004) (xy 80.608696 -243.649403) (xy 80.609186 -243.674392) (xy 80.914743 -243.674392)
			(xy 80.918838 -243.623664) (xy 80.931017 -243.57425) (xy 80.950965 -243.52743) (xy 80.978166 -243.484416)
			(xy 81.011914 -243.446322) (xy 81.051336 -243.414135) (xy 81.09541 -243.388689) (xy 81.142996 -243.370642)
			(xy 81.19286 -243.360462) (xy 81.243712 -243.358413) (xy 81.294233 -243.364547) (xy 81.343117 -243.378707)
			(xy 81.389096 -243.400524) (xy 81.43098 -243.429434) (xy 81.467684 -243.464689) (xy 81.498257 -243.505375)
			(xy 81.521908 -243.550438) (xy 81.538024 -243.598712) (xy 81.546188 -243.648946) (xy 81.5467 -243.674392)
			(xy 81.854797 -243.674392) (xy 81.858892 -243.623664) (xy 81.871071 -243.57425) (xy 81.891019 -243.52743)
			(xy 81.91822 -243.484416) (xy 81.951968 -243.446322) (xy 81.99139 -243.414135) (xy 82.035464 -243.388689)
			(xy 82.08305 -243.370642) (xy 82.132914 -243.360462) (xy 82.183766 -243.358413) (xy 82.234287 -243.364547)
			(xy 82.283171 -243.378707) (xy 82.32915 -243.400524) (xy 82.371034 -243.429434) (xy 82.407738 -243.464689)
			(xy 82.438311 -243.505375) (xy 82.461962 -243.550438) (xy 82.478078 -243.598712) (xy 82.486242 -243.648946)
			(xy 82.486754 -243.674392) (xy 82.486251 -243.699381) (xy 82.793568 -243.699381) (xy 82.793568 -243.649403)
			(xy 82.801387 -243.60004) (xy 82.816831 -243.552508) (xy 82.839521 -243.507976) (xy 82.868897 -243.467543)
			(xy 82.904237 -243.432203) (xy 82.94467 -243.402827) (xy 82.989202 -243.380137) (xy 83.036734 -243.364693)
			(xy 83.086097 -243.356874) (xy 83.136075 -243.356874) (xy 83.185438 -243.364693) (xy 83.23297 -243.380137)
			(xy 83.277502 -243.402827) (xy 83.317935 -243.432203) (xy 83.353275 -243.467543) (xy 83.382651 -243.507976)
			(xy 83.405341 -243.552508) (xy 83.420785 -243.60004) (xy 83.428604 -243.649403) (xy 83.429094 -243.674392)
			(xy 83.734905 -243.674392) (xy 83.739 -243.623664) (xy 83.751179 -243.57425) (xy 83.771127 -243.52743)
			(xy 83.798328 -243.484416) (xy 83.832076 -243.446322) (xy 83.871498 -243.414135) (xy 83.915572 -243.388689)
			(xy 83.963158 -243.370642) (xy 84.013022 -243.360462) (xy 84.063874 -243.358413) (xy 84.114395 -243.364547)
			(xy 84.163279 -243.378707) (xy 84.209258 -243.400524) (xy 84.251142 -243.429434) (xy 84.287846 -243.464689)
			(xy 84.318419 -243.505375) (xy 84.34207 -243.550438) (xy 84.358186 -243.598712) (xy 84.36635 -243.648946)
			(xy 84.366862 -243.674392) (xy 84.366359 -243.699381) (xy 84.673422 -243.699381) (xy 84.673422 -243.649403)
			(xy 84.681241 -243.60004) (xy 84.696685 -243.552508) (xy 84.719375 -243.507976) (xy 84.748751 -243.467543)
			(xy 84.784091 -243.432203) (xy 84.824524 -243.402827) (xy 84.869056 -243.380137) (xy 84.916588 -243.364693)
			(xy 84.965951 -243.356874) (xy 85.015929 -243.356874) (xy 85.065292 -243.364693) (xy 85.112824 -243.380137)
			(xy 85.157356 -243.402827) (xy 85.197789 -243.432203) (xy 85.233129 -243.467543) (xy 85.262505 -243.507976)
			(xy 85.285195 -243.552508) (xy 85.300639 -243.60004) (xy 85.308458 -243.649403) (xy 85.308948 -243.674392)
			(xy 85.614759 -243.674392) (xy 85.618854 -243.623664) (xy 85.631033 -243.57425) (xy 85.650981 -243.52743)
			(xy 85.678182 -243.484416) (xy 85.71193 -243.446322) (xy 85.751352 -243.414135) (xy 85.795426 -243.388689)
			(xy 85.843012 -243.370642) (xy 85.892876 -243.360462) (xy 85.943728 -243.358413) (xy 85.994249 -243.364547)
			(xy 86.043133 -243.378707) (xy 86.089112 -243.400524) (xy 86.130996 -243.429434) (xy 86.1677 -243.464689)
			(xy 86.198273 -243.505375) (xy 86.221924 -243.550438) (xy 86.23804 -243.598712) (xy 86.246204 -243.648946)
			(xy 86.246716 -243.674392) (xy 86.246213 -243.699381) (xy 86.55353 -243.699381) (xy 86.55353 -243.649403)
			(xy 86.561349 -243.60004) (xy 86.576793 -243.552508) (xy 86.599483 -243.507976) (xy 86.628859 -243.467543)
			(xy 86.664199 -243.432203) (xy 86.704632 -243.402827) (xy 86.749164 -243.380137) (xy 86.796696 -243.364693)
			(xy 86.846059 -243.356874) (xy 86.896037 -243.356874) (xy 86.9454 -243.364693) (xy 86.992932 -243.380137)
			(xy 87.037464 -243.402827) (xy 87.077897 -243.432203) (xy 87.113237 -243.467543) (xy 87.142613 -243.507976)
			(xy 87.165303 -243.552508) (xy 87.180747 -243.60004) (xy 87.188566 -243.649403) (xy 87.189056 -243.674392)
			(xy 87.494867 -243.674392) (xy 87.498962 -243.623664) (xy 87.511141 -243.57425) (xy 87.531089 -243.52743)
			(xy 87.55829 -243.484416) (xy 87.592038 -243.446322) (xy 87.63146 -243.414135) (xy 87.675534 -243.388689)
			(xy 87.72312 -243.370642) (xy 87.772984 -243.360462) (xy 87.823836 -243.358413) (xy 87.874357 -243.364547)
			(xy 87.923241 -243.378707) (xy 87.96922 -243.400524) (xy 88.011104 -243.429434) (xy 88.047808 -243.464689)
			(xy 88.078381 -243.505375) (xy 88.102032 -243.550438) (xy 88.118148 -243.598712) (xy 88.126312 -243.648946)
			(xy 88.126824 -243.674392) (xy 88.434921 -243.674392) (xy 88.439016 -243.623664) (xy 88.451195 -243.57425)
			(xy 88.471143 -243.52743) (xy 88.498344 -243.484416) (xy 88.532092 -243.446322) (xy 88.571514 -243.414135)
			(xy 88.615588 -243.388689) (xy 88.663174 -243.370642) (xy 88.713038 -243.360462) (xy 88.76389 -243.358413)
			(xy 88.814411 -243.364547) (xy 88.863295 -243.378707) (xy 88.909274 -243.400524) (xy 88.951158 -243.429434)
			(xy 88.987862 -243.464689) (xy 89.018435 -243.505375) (xy 89.042086 -243.550438) (xy 89.058202 -243.598712)
			(xy 89.066366 -243.648946) (xy 89.066878 -243.674392) (xy 89.066375 -243.699381) (xy 89.373438 -243.699381)
			(xy 89.373438 -243.649403) (xy 89.381257 -243.60004) (xy 89.396701 -243.552508) (xy 89.419391 -243.507976)
			(xy 89.448767 -243.467543) (xy 89.484107 -243.432203) (xy 89.52454 -243.402827) (xy 89.569072 -243.380137)
			(xy 89.616604 -243.364693) (xy 89.665967 -243.356874) (xy 89.715945 -243.356874) (xy 89.765308 -243.364693)
			(xy 89.81284 -243.380137) (xy 89.857372 -243.402827) (xy 89.897805 -243.432203) (xy 89.933145 -243.467543)
			(xy 89.962521 -243.507976) (xy 89.985211 -243.552508) (xy 90.000655 -243.60004) (xy 90.008474 -243.649403)
			(xy 90.008964 -243.674392) (xy 90.314775 -243.674392) (xy 90.31887 -243.623664) (xy 90.331049 -243.57425)
			(xy 90.350997 -243.52743) (xy 90.378198 -243.484416) (xy 90.411946 -243.446322) (xy 90.451368 -243.414135)
			(xy 90.495442 -243.388689) (xy 90.543028 -243.370642) (xy 90.592892 -243.360462) (xy 90.643744 -243.358413)
			(xy 90.694265 -243.364547) (xy 90.743149 -243.378707) (xy 90.789128 -243.400524) (xy 90.831012 -243.429434)
			(xy 90.867716 -243.464689) (xy 90.898289 -243.505375) (xy 90.92194 -243.550438) (xy 90.938056 -243.598712)
			(xy 90.94622 -243.648946) (xy 90.946732 -243.674392) (xy 90.946229 -243.699381) (xy 91.253546 -243.699381)
			(xy 91.253546 -243.649403) (xy 91.261365 -243.60004) (xy 91.276809 -243.552508) (xy 91.299499 -243.507976)
			(xy 91.328875 -243.467543) (xy 91.364215 -243.432203) (xy 91.404648 -243.402827) (xy 91.44918 -243.380137)
			(xy 91.496712 -243.364693) (xy 91.546075 -243.356874) (xy 91.596053 -243.356874) (xy 91.645416 -243.364693)
			(xy 91.692948 -243.380137) (xy 91.73748 -243.402827) (xy 91.777913 -243.432203) (xy 91.813253 -243.467543)
			(xy 91.842629 -243.507976) (xy 91.865319 -243.552508) (xy 91.880763 -243.60004) (xy 91.888582 -243.649403)
			(xy 91.889072 -243.674392) (xy 92.194883 -243.674392) (xy 92.198978 -243.623664) (xy 92.211157 -243.57425)
			(xy 92.231105 -243.52743) (xy 92.258306 -243.484416) (xy 92.292054 -243.446322) (xy 92.331476 -243.414135)
			(xy 92.37555 -243.388689) (xy 92.423136 -243.370642) (xy 92.473 -243.360462) (xy 92.523852 -243.358413)
			(xy 92.574373 -243.364547) (xy 92.623257 -243.378707) (xy 92.669236 -243.400524) (xy 92.71112 -243.429434)
			(xy 92.747824 -243.464689) (xy 92.778397 -243.505375) (xy 92.802048 -243.550438) (xy 92.818164 -243.598712)
			(xy 92.826328 -243.648946) (xy 92.82684 -243.674392) (xy 92.826337 -243.699381) (xy 93.1334 -243.699381)
			(xy 93.1334 -243.649403) (xy 93.141219 -243.60004) (xy 93.156663 -243.552508) (xy 93.179353 -243.507976)
			(xy 93.208729 -243.467543) (xy 93.244069 -243.432203) (xy 93.284502 -243.402827) (xy 93.329034 -243.380137)
			(xy 93.376566 -243.364693) (xy 93.425929 -243.356874) (xy 93.475907 -243.356874) (xy 93.52527 -243.364693)
			(xy 93.572802 -243.380137) (xy 93.617334 -243.402827) (xy 93.657767 -243.432203) (xy 93.693107 -243.467543)
			(xy 93.722483 -243.507976) (xy 93.745173 -243.552508) (xy 93.760617 -243.60004) (xy 93.768436 -243.649403)
			(xy 93.768926 -243.674392) (xy 94.074737 -243.674392) (xy 94.078832 -243.623664) (xy 94.091011 -243.57425)
			(xy 94.110959 -243.52743) (xy 94.13816 -243.484416) (xy 94.171908 -243.446322) (xy 94.21133 -243.414135)
			(xy 94.255404 -243.388689) (xy 94.30299 -243.370642) (xy 94.352854 -243.360462) (xy 94.403706 -243.358413)
			(xy 94.454227 -243.364547) (xy 94.503111 -243.378707) (xy 94.54909 -243.400524) (xy 94.590974 -243.429434)
			(xy 94.627678 -243.464689) (xy 94.658251 -243.505375) (xy 94.681902 -243.550438) (xy 94.698018 -243.598712)
			(xy 94.706182 -243.648946) (xy 94.706694 -243.674392) (xy 95.014791 -243.674392) (xy 95.018886 -243.623664)
			(xy 95.031065 -243.57425) (xy 95.051013 -243.52743) (xy 95.078214 -243.484416) (xy 95.111962 -243.446322)
			(xy 95.151384 -243.414135) (xy 95.195458 -243.388689) (xy 95.243044 -243.370642) (xy 95.292908 -243.360462)
			(xy 95.34376 -243.358413) (xy 95.394281 -243.364547) (xy 95.443165 -243.378707) (xy 95.489144 -243.400524)
			(xy 95.531028 -243.429434) (xy 95.567732 -243.464689) (xy 95.598305 -243.505375) (xy 95.621956 -243.550438)
			(xy 95.638072 -243.598712) (xy 95.646236 -243.648946) (xy 95.646748 -243.674392) (xy 95.646236 -243.699838)
			(xy 95.638072 -243.750072) (xy 95.621956 -243.798346) (xy 95.598305 -243.843409) (xy 95.567732 -243.884095)
			(xy 95.531028 -243.91935) (xy 95.489144 -243.94826) (xy 95.443165 -243.970077) (xy 95.394281 -243.984237)
			(xy 95.34376 -243.990371) (xy 95.292908 -243.988322) (xy 95.243044 -243.978142) (xy 95.195458 -243.960095)
			(xy 95.151384 -243.934649) (xy 95.111962 -243.902462) (xy 95.078214 -243.864368) (xy 95.051013 -243.821354)
			(xy 95.031065 -243.774534) (xy 95.018886 -243.72512) (xy 95.014791 -243.674392) (xy 94.706694 -243.674392)
			(xy 94.706182 -243.699838) (xy 94.698018 -243.750072) (xy 94.681902 -243.798346) (xy 94.658251 -243.843409)
			(xy 94.627678 -243.884095) (xy 94.590974 -243.91935) (xy 94.54909 -243.94826) (xy 94.503111 -243.970077)
			(xy 94.454227 -243.984237) (xy 94.403706 -243.990371) (xy 94.352854 -243.988322) (xy 94.30299 -243.978142)
			(xy 94.255404 -243.960095) (xy 94.21133 -243.934649) (xy 94.171908 -243.902462) (xy 94.13816 -243.864368)
			(xy 94.110959 -243.821354) (xy 94.091011 -243.774534) (xy 94.078832 -243.72512) (xy 94.074737 -243.674392)
			(xy 93.768926 -243.674392) (xy 93.768436 -243.699381) (xy 93.760617 -243.748744) (xy 93.745173 -243.796276)
			(xy 93.722483 -243.840808) (xy 93.693107 -243.881241) (xy 93.657767 -243.916581) (xy 93.617334 -243.945957)
			(xy 93.572802 -243.968647) (xy 93.52527 -243.984091) (xy 93.475907 -243.99191) (xy 93.425929 -243.99191)
			(xy 93.376566 -243.984091) (xy 93.329034 -243.968647) (xy 93.284502 -243.945957) (xy 93.244069 -243.916581)
			(xy 93.208729 -243.881241) (xy 93.179353 -243.840808) (xy 93.156663 -243.796276) (xy 93.141219 -243.748744)
			(xy 93.1334 -243.699381) (xy 92.826337 -243.699381) (xy 92.826328 -243.699838) (xy 92.818164 -243.750072)
			(xy 92.802048 -243.798346) (xy 92.778397 -243.843409) (xy 92.747824 -243.884095) (xy 92.71112 -243.91935)
			(xy 92.669236 -243.94826) (xy 92.623257 -243.970077) (xy 92.574373 -243.984237) (xy 92.523852 -243.990371)
			(xy 92.473 -243.988322) (xy 92.423136 -243.978142) (xy 92.37555 -243.960095) (xy 92.331476 -243.934649)
			(xy 92.292054 -243.902462) (xy 92.258306 -243.864368) (xy 92.231105 -243.821354) (xy 92.211157 -243.774534)
			(xy 92.198978 -243.72512) (xy 92.194883 -243.674392) (xy 91.889072 -243.674392) (xy 91.888582 -243.699381)
			(xy 91.880763 -243.748744) (xy 91.865319 -243.796276) (xy 91.842629 -243.840808) (xy 91.813253 -243.881241)
			(xy 91.777913 -243.916581) (xy 91.73748 -243.945957) (xy 91.692948 -243.968647) (xy 91.645416 -243.984091)
			(xy 91.596053 -243.99191) (xy 91.546075 -243.99191) (xy 91.496712 -243.984091) (xy 91.44918 -243.968647)
			(xy 91.404648 -243.945957) (xy 91.364215 -243.916581) (xy 91.328875 -243.881241) (xy 91.299499 -243.840808)
			(xy 91.276809 -243.796276) (xy 91.261365 -243.748744) (xy 91.253546 -243.699381) (xy 90.946229 -243.699381)
			(xy 90.94622 -243.699838) (xy 90.938056 -243.750072) (xy 90.92194 -243.798346) (xy 90.898289 -243.843409)
			(xy 90.867716 -243.884095) (xy 90.831012 -243.91935) (xy 90.789128 -243.94826) (xy 90.743149 -243.970077)
			(xy 90.694265 -243.984237) (xy 90.643744 -243.990371) (xy 90.592892 -243.988322) (xy 90.543028 -243.978142)
			(xy 90.495442 -243.960095) (xy 90.451368 -243.934649) (xy 90.411946 -243.902462) (xy 90.378198 -243.864368)
			(xy 90.350997 -243.821354) (xy 90.331049 -243.774534) (xy 90.31887 -243.72512) (xy 90.314775 -243.674392)
			(xy 90.008964 -243.674392) (xy 90.008474 -243.699381) (xy 90.000655 -243.748744) (xy 89.985211 -243.796276)
			(xy 89.962521 -243.840808) (xy 89.933145 -243.881241) (xy 89.897805 -243.916581) (xy 89.857372 -243.945957)
			(xy 89.81284 -243.968647) (xy 89.765308 -243.984091) (xy 89.715945 -243.99191) (xy 89.665967 -243.99191)
			(xy 89.616604 -243.984091) (xy 89.569072 -243.968647) (xy 89.52454 -243.945957) (xy 89.484107 -243.916581)
			(xy 89.448767 -243.881241) (xy 89.419391 -243.840808) (xy 89.396701 -243.796276) (xy 89.381257 -243.748744)
			(xy 89.373438 -243.699381) (xy 89.066375 -243.699381) (xy 89.066366 -243.699838) (xy 89.058202 -243.750072)
			(xy 89.042086 -243.798346) (xy 89.018435 -243.843409) (xy 88.987862 -243.884095) (xy 88.951158 -243.91935)
			(xy 88.909274 -243.94826) (xy 88.863295 -243.970077) (xy 88.814411 -243.984237) (xy 88.76389 -243.990371)
			(xy 88.713038 -243.988322) (xy 88.663174 -243.978142) (xy 88.615588 -243.960095) (xy 88.571514 -243.934649)
			(xy 88.532092 -243.902462) (xy 88.498344 -243.864368) (xy 88.471143 -243.821354) (xy 88.451195 -243.774534)
			(xy 88.439016 -243.72512) (xy 88.434921 -243.674392) (xy 88.126824 -243.674392) (xy 88.126312 -243.699838)
			(xy 88.118148 -243.750072) (xy 88.102032 -243.798346) (xy 88.078381 -243.843409) (xy 88.047808 -243.884095)
			(xy 88.011104 -243.91935) (xy 87.96922 -243.94826) (xy 87.923241 -243.970077) (xy 87.874357 -243.984237)
			(xy 87.823836 -243.990371) (xy 87.772984 -243.988322) (xy 87.72312 -243.978142) (xy 87.675534 -243.960095)
			(xy 87.63146 -243.934649) (xy 87.592038 -243.902462) (xy 87.55829 -243.864368) (xy 87.531089 -243.821354)
			(xy 87.511141 -243.774534) (xy 87.498962 -243.72512) (xy 87.494867 -243.674392) (xy 87.189056 -243.674392)
			(xy 87.188566 -243.699381) (xy 87.180747 -243.748744) (xy 87.165303 -243.796276) (xy 87.142613 -243.840808)
			(xy 87.113237 -243.881241) (xy 87.077897 -243.916581) (xy 87.037464 -243.945957) (xy 86.992932 -243.968647)
			(xy 86.9454 -243.984091) (xy 86.896037 -243.99191) (xy 86.846059 -243.99191) (xy 86.796696 -243.984091)
			(xy 86.749164 -243.968647) (xy 86.704632 -243.945957) (xy 86.664199 -243.916581) (xy 86.628859 -243.881241)
			(xy 86.599483 -243.840808) (xy 86.576793 -243.796276) (xy 86.561349 -243.748744) (xy 86.55353 -243.699381)
			(xy 86.246213 -243.699381) (xy 86.246204 -243.699838) (xy 86.23804 -243.750072) (xy 86.221924 -243.798346)
			(xy 86.198273 -243.843409) (xy 86.1677 -243.884095) (xy 86.130996 -243.91935) (xy 86.089112 -243.94826)
			(xy 86.043133 -243.970077) (xy 85.994249 -243.984237) (xy 85.943728 -243.990371) (xy 85.892876 -243.988322)
			(xy 85.843012 -243.978142) (xy 85.795426 -243.960095) (xy 85.751352 -243.934649) (xy 85.71193 -243.902462)
			(xy 85.678182 -243.864368) (xy 85.650981 -243.821354) (xy 85.631033 -243.774534) (xy 85.618854 -243.72512)
			(xy 85.614759 -243.674392) (xy 85.308948 -243.674392) (xy 85.308458 -243.699381) (xy 85.300639 -243.748744)
			(xy 85.285195 -243.796276) (xy 85.262505 -243.840808) (xy 85.233129 -243.881241) (xy 85.197789 -243.916581)
			(xy 85.157356 -243.945957) (xy 85.112824 -243.968647) (xy 85.065292 -243.984091) (xy 85.015929 -243.99191)
			(xy 84.965951 -243.99191) (xy 84.916588 -243.984091) (xy 84.869056 -243.968647) (xy 84.824524 -243.945957)
			(xy 84.784091 -243.916581) (xy 84.748751 -243.881241) (xy 84.719375 -243.840808) (xy 84.696685 -243.796276)
			(xy 84.681241 -243.748744) (xy 84.673422 -243.699381) (xy 84.366359 -243.699381) (xy 84.36635 -243.699838)
			(xy 84.358186 -243.750072) (xy 84.34207 -243.798346) (xy 84.318419 -243.843409) (xy 84.287846 -243.884095)
			(xy 84.251142 -243.91935) (xy 84.209258 -243.94826) (xy 84.163279 -243.970077) (xy 84.114395 -243.984237)
			(xy 84.063874 -243.990371) (xy 84.013022 -243.988322) (xy 83.963158 -243.978142) (xy 83.915572 -243.960095)
			(xy 83.871498 -243.934649) (xy 83.832076 -243.902462) (xy 83.798328 -243.864368) (xy 83.771127 -243.821354)
			(xy 83.751179 -243.774534) (xy 83.739 -243.72512) (xy 83.734905 -243.674392) (xy 83.429094 -243.674392)
			(xy 83.428604 -243.699381) (xy 83.420785 -243.748744) (xy 83.405341 -243.796276) (xy 83.382651 -243.840808)
			(xy 83.353275 -243.881241) (xy 83.317935 -243.916581) (xy 83.277502 -243.945957) (xy 83.23297 -243.968647)
			(xy 83.185438 -243.984091) (xy 83.136075 -243.99191) (xy 83.086097 -243.99191) (xy 83.036734 -243.984091)
			(xy 82.989202 -243.968647) (xy 82.94467 -243.945957) (xy 82.904237 -243.916581) (xy 82.868897 -243.881241)
			(xy 82.839521 -243.840808) (xy 82.816831 -243.796276) (xy 82.801387 -243.748744) (xy 82.793568 -243.699381)
			(xy 82.486251 -243.699381) (xy 82.486242 -243.699838) (xy 82.478078 -243.750072) (xy 82.461962 -243.798346)
			(xy 82.438311 -243.843409) (xy 82.407738 -243.884095) (xy 82.371034 -243.91935) (xy 82.32915 -243.94826)
			(xy 82.283171 -243.970077) (xy 82.234287 -243.984237) (xy 82.183766 -243.990371) (xy 82.132914 -243.988322)
			(xy 82.08305 -243.978142) (xy 82.035464 -243.960095) (xy 81.99139 -243.934649) (xy 81.951968 -243.902462)
			(xy 81.91822 -243.864368) (xy 81.891019 -243.821354) (xy 81.871071 -243.774534) (xy 81.858892 -243.72512)
			(xy 81.854797 -243.674392) (xy 81.5467 -243.674392) (xy 81.546188 -243.699838) (xy 81.538024 -243.750072)
			(xy 81.521908 -243.798346) (xy 81.498257 -243.843409) (xy 81.467684 -243.884095) (xy 81.43098 -243.91935)
			(xy 81.389096 -243.94826) (xy 81.343117 -243.970077) (xy 81.294233 -243.984237) (xy 81.243712 -243.990371)
			(xy 81.19286 -243.988322) (xy 81.142996 -243.978142) (xy 81.09541 -243.960095) (xy 81.051336 -243.934649)
			(xy 81.011914 -243.902462) (xy 80.978166 -243.864368) (xy 80.950965 -243.821354) (xy 80.931017 -243.774534)
			(xy 80.918838 -243.72512) (xy 80.914743 -243.674392) (xy 80.609186 -243.674392) (xy 80.608696 -243.699381)
			(xy 80.600877 -243.748744) (xy 80.585433 -243.796276) (xy 80.562743 -243.840808) (xy 80.533367 -243.881241)
			(xy 80.498027 -243.916581) (xy 80.457594 -243.945957) (xy 80.413062 -243.968647) (xy 80.36553 -243.984091)
			(xy 80.316167 -243.99191) (xy 80.266189 -243.99191) (xy 80.216826 -243.984091) (xy 80.169294 -243.968647)
			(xy 80.124762 -243.945957) (xy 80.084329 -243.916581) (xy 80.048989 -243.881241) (xy 80.019613 -243.840808)
			(xy 79.996923 -243.796276) (xy 79.981479 -243.748744) (xy 79.97366 -243.699381) (xy 79.53248 -243.699381)
			(xy 79.53248 -244.484398) (xy 80.444843 -244.484398) (xy 80.448938 -244.43367) (xy 80.461117 -244.384256)
			(xy 80.481065 -244.337436) (xy 80.508266 -244.294422) (xy 80.542014 -244.256328) (xy 80.581436 -244.224141)
			(xy 80.62551 -244.198695) (xy 80.673096 -244.180648) (xy 80.72296 -244.170468) (xy 80.773812 -244.168419)
			(xy 80.824333 -244.174553) (xy 80.873217 -244.188713) (xy 80.919196 -244.21053) (xy 80.96108 -244.23944)
			(xy 80.997784 -244.274695) (xy 81.028357 -244.315381) (xy 81.052008 -244.360444) (xy 81.068124 -244.408718)
			(xy 81.076288 -244.458952) (xy 81.0768 -244.484398) (xy 81.076297 -244.509387) (xy 81.383614 -244.509387)
			(xy 81.383614 -244.459409) (xy 81.391433 -244.410046) (xy 81.406877 -244.362514) (xy 81.429567 -244.317982)
			(xy 81.458943 -244.277549) (xy 81.494283 -244.242209) (xy 81.534716 -244.212833) (xy 81.579248 -244.190143)
			(xy 81.62678 -244.174699) (xy 81.676143 -244.16688) (xy 81.726121 -244.16688) (xy 81.775484 -244.174699)
			(xy 81.823016 -244.190143) (xy 81.867548 -244.212833) (xy 81.907981 -244.242209) (xy 81.943321 -244.277549)
			(xy 81.972697 -244.317982) (xy 81.995387 -244.362514) (xy 82.010831 -244.410046) (xy 82.01865 -244.459409)
			(xy 82.01914 -244.484398) (xy 82.324697 -244.484398) (xy 82.328792 -244.43367) (xy 82.340971 -244.384256)
			(xy 82.360919 -244.337436) (xy 82.38812 -244.294422) (xy 82.421868 -244.256328) (xy 82.46129 -244.224141)
			(xy 82.505364 -244.198695) (xy 82.55295 -244.180648) (xy 82.602814 -244.170468) (xy 82.653666 -244.168419)
			(xy 82.704187 -244.174553) (xy 82.753071 -244.188713) (xy 82.79905 -244.21053) (xy 82.840934 -244.23944)
			(xy 82.877638 -244.274695) (xy 82.908211 -244.315381) (xy 82.931862 -244.360444) (xy 82.947978 -244.408718)
			(xy 82.956142 -244.458952) (xy 82.956654 -244.484398) (xy 82.956151 -244.509387) (xy 83.263468 -244.509387)
			(xy 83.263468 -244.459409) (xy 83.271287 -244.410046) (xy 83.286731 -244.362514) (xy 83.309421 -244.317982)
			(xy 83.338797 -244.277549) (xy 83.374137 -244.242209) (xy 83.41457 -244.212833) (xy 83.459102 -244.190143)
			(xy 83.506634 -244.174699) (xy 83.555997 -244.16688) (xy 83.605975 -244.16688) (xy 83.655338 -244.174699)
			(xy 83.70287 -244.190143) (xy 83.747402 -244.212833) (xy 83.787835 -244.242209) (xy 83.823175 -244.277549)
			(xy 83.852551 -244.317982) (xy 83.875241 -244.362514) (xy 83.890685 -244.410046) (xy 83.898504 -244.459409)
			(xy 83.898994 -244.484398) (xy 84.204805 -244.484398) (xy 84.2089 -244.43367) (xy 84.221079 -244.384256)
			(xy 84.241027 -244.337436) (xy 84.268228 -244.294422) (xy 84.301976 -244.256328) (xy 84.341398 -244.224141)
			(xy 84.385472 -244.198695) (xy 84.433058 -244.180648) (xy 84.482922 -244.170468) (xy 84.533774 -244.168419)
			(xy 84.584295 -244.174553) (xy 84.633179 -244.188713) (xy 84.679158 -244.21053) (xy 84.721042 -244.23944)
			(xy 84.757746 -244.274695) (xy 84.788319 -244.315381) (xy 84.81197 -244.360444) (xy 84.828086 -244.408718)
			(xy 84.83625 -244.458952) (xy 84.836762 -244.484398) (xy 85.144859 -244.484398) (xy 85.148954 -244.43367)
			(xy 85.161133 -244.384256) (xy 85.181081 -244.337436) (xy 85.208282 -244.294422) (xy 85.24203 -244.256328)
			(xy 85.281452 -244.224141) (xy 85.325526 -244.198695) (xy 85.373112 -244.180648) (xy 85.422976 -244.170468)
			(xy 85.473828 -244.168419) (xy 85.524349 -244.174553) (xy 85.573233 -244.188713) (xy 85.619212 -244.21053)
			(xy 85.661096 -244.23944) (xy 85.6978 -244.274695) (xy 85.728373 -244.315381) (xy 85.752024 -244.360444)
			(xy 85.76814 -244.408718) (xy 85.776304 -244.458952) (xy 85.776816 -244.484398) (xy 87.024713 -244.484398)
			(xy 87.028808 -244.43367) (xy 87.040987 -244.384256) (xy 87.060935 -244.337436) (xy 87.088136 -244.294422)
			(xy 87.121884 -244.256328) (xy 87.161306 -244.224141) (xy 87.20538 -244.198695) (xy 87.252966 -244.180648)
			(xy 87.30283 -244.170468) (xy 87.353682 -244.168419) (xy 87.404203 -244.174553) (xy 87.453087 -244.188713)
			(xy 87.499066 -244.21053) (xy 87.54095 -244.23944) (xy 87.577654 -244.274695) (xy 87.608227 -244.315381)
			(xy 87.631878 -244.360444) (xy 87.647994 -244.408718) (xy 87.656158 -244.458952) (xy 87.65667 -244.484398)
			(xy 87.656167 -244.509387) (xy 87.963484 -244.509387) (xy 87.963484 -244.459409) (xy 87.971303 -244.410046)
			(xy 87.986747 -244.362514) (xy 88.009437 -244.317982) (xy 88.038813 -244.277549) (xy 88.074153 -244.242209)
			(xy 88.114586 -244.212833) (xy 88.159118 -244.190143) (xy 88.20665 -244.174699) (xy 88.256013 -244.16688)
			(xy 88.305991 -244.16688) (xy 88.355354 -244.174699) (xy 88.402886 -244.190143) (xy 88.447418 -244.212833)
			(xy 88.487851 -244.242209) (xy 88.523191 -244.277549) (xy 88.552567 -244.317982) (xy 88.575257 -244.362514)
			(xy 88.590701 -244.410046) (xy 88.59852 -244.459409) (xy 88.59901 -244.484398) (xy 88.904821 -244.484398)
			(xy 88.908916 -244.43367) (xy 88.921095 -244.384256) (xy 88.941043 -244.337436) (xy 88.968244 -244.294422)
			(xy 89.001992 -244.256328) (xy 89.041414 -244.224141) (xy 89.085488 -244.198695) (xy 89.133074 -244.180648)
			(xy 89.182938 -244.170468) (xy 89.23379 -244.168419) (xy 89.284311 -244.174553) (xy 89.333195 -244.188713)
			(xy 89.379174 -244.21053) (xy 89.421058 -244.23944) (xy 89.457762 -244.274695) (xy 89.488335 -244.315381)
			(xy 89.511986 -244.360444) (xy 89.528102 -244.408718) (xy 89.536266 -244.458952) (xy 89.536778 -244.484398)
			(xy 89.536275 -244.509387) (xy 89.843592 -244.509387) (xy 89.843592 -244.459409) (xy 89.851411 -244.410046)
			(xy 89.866855 -244.362514) (xy 89.889545 -244.317982) (xy 89.918921 -244.277549) (xy 89.954261 -244.242209)
			(xy 89.994694 -244.212833) (xy 90.039226 -244.190143) (xy 90.086758 -244.174699) (xy 90.136121 -244.16688)
			(xy 90.186099 -244.16688) (xy 90.235462 -244.174699) (xy 90.282994 -244.190143) (xy 90.327526 -244.212833)
			(xy 90.367959 -244.242209) (xy 90.403299 -244.277549) (xy 90.432675 -244.317982) (xy 90.455365 -244.362514)
			(xy 90.470809 -244.410046) (xy 90.478628 -244.459409) (xy 90.479118 -244.484398) (xy 90.784675 -244.484398)
			(xy 90.78877 -244.43367) (xy 90.800949 -244.384256) (xy 90.820897 -244.337436) (xy 90.848098 -244.294422)
			(xy 90.881846 -244.256328) (xy 90.921268 -244.224141) (xy 90.965342 -244.198695) (xy 91.012928 -244.180648)
			(xy 91.062792 -244.170468) (xy 91.113644 -244.168419) (xy 91.164165 -244.174553) (xy 91.213049 -244.188713)
			(xy 91.259028 -244.21053) (xy 91.300912 -244.23944) (xy 91.337616 -244.274695) (xy 91.368189 -244.315381)
			(xy 91.39184 -244.360444) (xy 91.407956 -244.408718) (xy 91.41612 -244.458952) (xy 91.416632 -244.484398)
			(xy 91.724729 -244.484398) (xy 91.728824 -244.43367) (xy 91.741003 -244.384256) (xy 91.760951 -244.337436)
			(xy 91.788152 -244.294422) (xy 91.8219 -244.256328) (xy 91.861322 -244.224141) (xy 91.905396 -244.198695)
			(xy 91.952982 -244.180648) (xy 92.002846 -244.170468) (xy 92.053698 -244.168419) (xy 92.104219 -244.174553)
			(xy 92.153103 -244.188713) (xy 92.199082 -244.21053) (xy 92.240966 -244.23944) (xy 92.27767 -244.274695)
			(xy 92.308243 -244.315381) (xy 92.331894 -244.360444) (xy 92.34801 -244.408718) (xy 92.356174 -244.458952)
			(xy 92.356686 -244.484398) (xy 93.604837 -244.484398) (xy 93.608932 -244.43367) (xy 93.621111 -244.384256)
			(xy 93.641059 -244.337436) (xy 93.66826 -244.294422) (xy 93.702008 -244.256328) (xy 93.74143 -244.224141)
			(xy 93.785504 -244.198695) (xy 93.83309 -244.180648) (xy 93.882954 -244.170468) (xy 93.933806 -244.168419)
			(xy 93.984327 -244.174553) (xy 94.033211 -244.188713) (xy 94.07919 -244.21053) (xy 94.121074 -244.23944)
			(xy 94.157778 -244.274695) (xy 94.188351 -244.315381) (xy 94.212002 -244.360444) (xy 94.228118 -244.408718)
			(xy 94.236282 -244.458952) (xy 94.236794 -244.484398) (xy 94.236291 -244.509387) (xy 94.543608 -244.509387)
			(xy 94.543608 -244.459409) (xy 94.551427 -244.410046) (xy 94.566871 -244.362514) (xy 94.589561 -244.317982)
			(xy 94.618937 -244.277549) (xy 94.654277 -244.242209) (xy 94.69471 -244.212833) (xy 94.739242 -244.190143)
			(xy 94.786774 -244.174699) (xy 94.836137 -244.16688) (xy 94.886115 -244.16688) (xy 94.935478 -244.174699)
			(xy 94.98301 -244.190143) (xy 95.027542 -244.212833) (xy 95.067975 -244.242209) (xy 95.103315 -244.277549)
			(xy 95.132691 -244.317982) (xy 95.155381 -244.362514) (xy 95.170825 -244.410046) (xy 95.178644 -244.459409)
			(xy 95.179134 -244.484398) (xy 95.484691 -244.484398) (xy 95.488786 -244.43367) (xy 95.500965 -244.384256)
			(xy 95.520913 -244.337436) (xy 95.548114 -244.294422) (xy 95.581862 -244.256328) (xy 95.621284 -244.224141)
			(xy 95.665358 -244.198695) (xy 95.712944 -244.180648) (xy 95.762808 -244.170468) (xy 95.81366 -244.168419)
			(xy 95.864181 -244.174553) (xy 95.913065 -244.188713) (xy 95.959044 -244.21053) (xy 96.000928 -244.23944)
			(xy 96.037632 -244.274695) (xy 96.068205 -244.315381) (xy 96.091856 -244.360444) (xy 96.107972 -244.408718)
			(xy 96.116136 -244.458952) (xy 96.116648 -244.484398) (xy 96.116136 -244.509844) (xy 96.107972 -244.560078)
			(xy 96.091856 -244.608352) (xy 96.068205 -244.653415) (xy 96.037632 -244.694101) (xy 96.000928 -244.729356)
			(xy 95.959044 -244.758266) (xy 95.913065 -244.780083) (xy 95.864181 -244.794243) (xy 95.81366 -244.800377)
			(xy 95.762808 -244.798328) (xy 95.712944 -244.788148) (xy 95.665358 -244.770101) (xy 95.621284 -244.744655)
			(xy 95.581862 -244.712468) (xy 95.548114 -244.674374) (xy 95.520913 -244.63136) (xy 95.500965 -244.58454)
			(xy 95.488786 -244.535126) (xy 95.484691 -244.484398) (xy 95.179134 -244.484398) (xy 95.178644 -244.509387)
			(xy 95.170825 -244.55875) (xy 95.155381 -244.606282) (xy 95.132691 -244.650814) (xy 95.103315 -244.691247)
			(xy 95.067975 -244.726587) (xy 95.027542 -244.755963) (xy 94.98301 -244.778653) (xy 94.935478 -244.794097)
			(xy 94.886115 -244.801916) (xy 94.836137 -244.801916) (xy 94.786774 -244.794097) (xy 94.739242 -244.778653)
			(xy 94.69471 -244.755963) (xy 94.654277 -244.726587) (xy 94.618937 -244.691247) (xy 94.589561 -244.650814)
			(xy 94.566871 -244.606282) (xy 94.551427 -244.55875) (xy 94.543608 -244.509387) (xy 94.236291 -244.509387)
			(xy 94.236282 -244.509844) (xy 94.228118 -244.560078) (xy 94.212002 -244.608352) (xy 94.188351 -244.653415)
			(xy 94.157778 -244.694101) (xy 94.121074 -244.729356) (xy 94.07919 -244.758266) (xy 94.033211 -244.780083)
			(xy 93.984327 -244.794243) (xy 93.933806 -244.800377) (xy 93.882954 -244.798328) (xy 93.83309 -244.788148)
			(xy 93.785504 -244.770101) (xy 93.74143 -244.744655) (xy 93.702008 -244.712468) (xy 93.66826 -244.674374)
			(xy 93.641059 -244.63136) (xy 93.621111 -244.58454) (xy 93.608932 -244.535126) (xy 93.604837 -244.484398)
			(xy 92.356686 -244.484398) (xy 92.356174 -244.509844) (xy 92.34801 -244.560078) (xy 92.331894 -244.608352)
			(xy 92.308243 -244.653415) (xy 92.27767 -244.694101) (xy 92.240966 -244.729356) (xy 92.199082 -244.758266)
			(xy 92.153103 -244.780083) (xy 92.104219 -244.794243) (xy 92.053698 -244.800377) (xy 92.002846 -244.798328)
			(xy 91.952982 -244.788148) (xy 91.905396 -244.770101) (xy 91.861322 -244.744655) (xy 91.8219 -244.712468)
			(xy 91.788152 -244.674374) (xy 91.760951 -244.63136) (xy 91.741003 -244.58454) (xy 91.728824 -244.535126)
			(xy 91.724729 -244.484398) (xy 91.416632 -244.484398) (xy 91.41612 -244.509844) (xy 91.407956 -244.560078)
			(xy 91.39184 -244.608352) (xy 91.368189 -244.653415) (xy 91.337616 -244.694101) (xy 91.300912 -244.729356)
			(xy 91.259028 -244.758266) (xy 91.213049 -244.780083) (xy 91.164165 -244.794243) (xy 91.113644 -244.800377)
			(xy 91.062792 -244.798328) (xy 91.012928 -244.788148) (xy 90.965342 -244.770101) (xy 90.921268 -244.744655)
			(xy 90.881846 -244.712468) (xy 90.848098 -244.674374) (xy 90.820897 -244.63136) (xy 90.800949 -244.58454)
			(xy 90.78877 -244.535126) (xy 90.784675 -244.484398) (xy 90.479118 -244.484398) (xy 90.478628 -244.509387)
			(xy 90.470809 -244.55875) (xy 90.455365 -244.606282) (xy 90.432675 -244.650814) (xy 90.403299 -244.691247)
			(xy 90.367959 -244.726587) (xy 90.327526 -244.755963) (xy 90.282994 -244.778653) (xy 90.235462 -244.794097)
			(xy 90.186099 -244.801916) (xy 90.136121 -244.801916) (xy 90.086758 -244.794097) (xy 90.039226 -244.778653)
			(xy 89.994694 -244.755963) (xy 89.954261 -244.726587) (xy 89.918921 -244.691247) (xy 89.889545 -244.650814)
			(xy 89.866855 -244.606282) (xy 89.851411 -244.55875) (xy 89.843592 -244.509387) (xy 89.536275 -244.509387)
			(xy 89.536266 -244.509844) (xy 89.528102 -244.560078) (xy 89.511986 -244.608352) (xy 89.488335 -244.653415)
			(xy 89.457762 -244.694101) (xy 89.421058 -244.729356) (xy 89.379174 -244.758266) (xy 89.333195 -244.780083)
			(xy 89.284311 -244.794243) (xy 89.23379 -244.800377) (xy 89.182938 -244.798328) (xy 89.133074 -244.788148)
			(xy 89.085488 -244.770101) (xy 89.041414 -244.744655) (xy 89.001992 -244.712468) (xy 88.968244 -244.674374)
			(xy 88.941043 -244.63136) (xy 88.921095 -244.58454) (xy 88.908916 -244.535126) (xy 88.904821 -244.484398)
			(xy 88.59901 -244.484398) (xy 88.59852 -244.509387) (xy 88.590701 -244.55875) (xy 88.575257 -244.606282)
			(xy 88.552567 -244.650814) (xy 88.523191 -244.691247) (xy 88.487851 -244.726587) (xy 88.447418 -244.755963)
			(xy 88.402886 -244.778653) (xy 88.355354 -244.794097) (xy 88.305991 -244.801916) (xy 88.256013 -244.801916)
			(xy 88.20665 -244.794097) (xy 88.159118 -244.778653) (xy 88.114586 -244.755963) (xy 88.074153 -244.726587)
			(xy 88.038813 -244.691247) (xy 88.009437 -244.650814) (xy 87.986747 -244.606282) (xy 87.971303 -244.55875)
			(xy 87.963484 -244.509387) (xy 87.656167 -244.509387) (xy 87.656158 -244.509844) (xy 87.647994 -244.560078)
			(xy 87.631878 -244.608352) (xy 87.608227 -244.653415) (xy 87.577654 -244.694101) (xy 87.54095 -244.729356)
			(xy 87.499066 -244.758266) (xy 87.453087 -244.780083) (xy 87.404203 -244.794243) (xy 87.353682 -244.800377)
			(xy 87.30283 -244.798328) (xy 87.252966 -244.788148) (xy 87.20538 -244.770101) (xy 87.161306 -244.744655)
			(xy 87.121884 -244.712468) (xy 87.088136 -244.674374) (xy 87.060935 -244.63136) (xy 87.040987 -244.58454)
			(xy 87.028808 -244.535126) (xy 87.024713 -244.484398) (xy 85.776816 -244.484398) (xy 85.776304 -244.509844)
			(xy 85.76814 -244.560078) (xy 85.752024 -244.608352) (xy 85.728373 -244.653415) (xy 85.6978 -244.694101)
			(xy 85.661096 -244.729356) (xy 85.619212 -244.758266) (xy 85.573233 -244.780083) (xy 85.524349 -244.794243)
			(xy 85.473828 -244.800377) (xy 85.422976 -244.798328) (xy 85.373112 -244.788148) (xy 85.325526 -244.770101)
			(xy 85.281452 -244.744655) (xy 85.24203 -244.712468) (xy 85.208282 -244.674374) (xy 85.181081 -244.63136)
			(xy 85.161133 -244.58454) (xy 85.148954 -244.535126) (xy 85.144859 -244.484398) (xy 84.836762 -244.484398)
			(xy 84.83625 -244.509844) (xy 84.828086 -244.560078) (xy 84.81197 -244.608352) (xy 84.788319 -244.653415)
			(xy 84.757746 -244.694101) (xy 84.721042 -244.729356) (xy 84.679158 -244.758266) (xy 84.633179 -244.780083)
			(xy 84.584295 -244.794243) (xy 84.533774 -244.800377) (xy 84.482922 -244.798328) (xy 84.433058 -244.788148)
			(xy 84.385472 -244.770101) (xy 84.341398 -244.744655) (xy 84.301976 -244.712468) (xy 84.268228 -244.674374)
			(xy 84.241027 -244.63136) (xy 84.221079 -244.58454) (xy 84.2089 -244.535126) (xy 84.204805 -244.484398)
			(xy 83.898994 -244.484398) (xy 83.898504 -244.509387) (xy 83.890685 -244.55875) (xy 83.875241 -244.606282)
			(xy 83.852551 -244.650814) (xy 83.823175 -244.691247) (xy 83.787835 -244.726587) (xy 83.747402 -244.755963)
			(xy 83.70287 -244.778653) (xy 83.655338 -244.794097) (xy 83.605975 -244.801916) (xy 83.555997 -244.801916)
			(xy 83.506634 -244.794097) (xy 83.459102 -244.778653) (xy 83.41457 -244.755963) (xy 83.374137 -244.726587)
			(xy 83.338797 -244.691247) (xy 83.309421 -244.650814) (xy 83.286731 -244.606282) (xy 83.271287 -244.55875)
			(xy 83.263468 -244.509387) (xy 82.956151 -244.509387) (xy 82.956142 -244.509844) (xy 82.947978 -244.560078)
			(xy 82.931862 -244.608352) (xy 82.908211 -244.653415) (xy 82.877638 -244.694101) (xy 82.840934 -244.729356)
			(xy 82.79905 -244.758266) (xy 82.753071 -244.780083) (xy 82.704187 -244.794243) (xy 82.653666 -244.800377)
			(xy 82.602814 -244.798328) (xy 82.55295 -244.788148) (xy 82.505364 -244.770101) (xy 82.46129 -244.744655)
			(xy 82.421868 -244.712468) (xy 82.38812 -244.674374) (xy 82.360919 -244.63136) (xy 82.340971 -244.58454)
			(xy 82.328792 -244.535126) (xy 82.324697 -244.484398) (xy 82.01914 -244.484398) (xy 82.01865 -244.509387)
			(xy 82.010831 -244.55875) (xy 81.995387 -244.606282) (xy 81.972697 -244.650814) (xy 81.943321 -244.691247)
			(xy 81.907981 -244.726587) (xy 81.867548 -244.755963) (xy 81.823016 -244.778653) (xy 81.775484 -244.794097)
			(xy 81.726121 -244.801916) (xy 81.676143 -244.801916) (xy 81.62678 -244.794097) (xy 81.579248 -244.778653)
			(xy 81.534716 -244.755963) (xy 81.494283 -244.726587) (xy 81.458943 -244.691247) (xy 81.429567 -244.650814)
			(xy 81.406877 -244.606282) (xy 81.391433 -244.55875) (xy 81.383614 -244.509387) (xy 81.076297 -244.509387)
			(xy 81.076288 -244.509844) (xy 81.068124 -244.560078) (xy 81.052008 -244.608352) (xy 81.028357 -244.653415)
			(xy 80.997784 -244.694101) (xy 80.96108 -244.729356) (xy 80.919196 -244.758266) (xy 80.873217 -244.780083)
			(xy 80.824333 -244.794243) (xy 80.773812 -244.800377) (xy 80.72296 -244.798328) (xy 80.673096 -244.788148)
			(xy 80.62551 -244.770101) (xy 80.581436 -244.744655) (xy 80.542014 -244.712468) (xy 80.508266 -244.674374)
			(xy 80.481065 -244.63136) (xy 80.461117 -244.58454) (xy 80.448938 -244.535126) (xy 80.444843 -244.484398)
			(xy 79.53248 -244.484398) (xy 79.53248 -245.319393) (xy 79.97366 -245.319393) (xy 79.97366 -245.269415)
			(xy 79.981479 -245.220052) (xy 79.996923 -245.17252) (xy 80.019613 -245.127988) (xy 80.048989 -245.087555)
			(xy 80.084329 -245.052215) (xy 80.124762 -245.022839) (xy 80.169294 -245.000149) (xy 80.216826 -244.984705)
			(xy 80.266189 -244.976886) (xy 80.316167 -244.976886) (xy 80.36553 -244.984705) (xy 80.413062 -245.000149)
			(xy 80.457594 -245.022839) (xy 80.498027 -245.052215) (xy 80.533367 -245.087555) (xy 80.562743 -245.127988)
			(xy 80.585433 -245.17252) (xy 80.600877 -245.220052) (xy 80.608696 -245.269415) (xy 80.609186 -245.294404)
			(xy 80.914743 -245.294404) (xy 80.918838 -245.243676) (xy 80.931017 -245.194262) (xy 80.950965 -245.147442)
			(xy 80.978166 -245.104428) (xy 81.011914 -245.066334) (xy 81.051336 -245.034147) (xy 81.09541 -245.008701)
			(xy 81.142996 -244.990654) (xy 81.19286 -244.980474) (xy 81.243712 -244.978425) (xy 81.294233 -244.984559)
			(xy 81.343117 -244.998719) (xy 81.389096 -245.020536) (xy 81.43098 -245.049446) (xy 81.467684 -245.084701)
			(xy 81.498257 -245.125387) (xy 81.521908 -245.17045) (xy 81.538024 -245.218724) (xy 81.546188 -245.268958)
			(xy 81.5467 -245.294404) (xy 81.854797 -245.294404) (xy 81.858892 -245.243676) (xy 81.871071 -245.194262)
			(xy 81.891019 -245.147442) (xy 81.91822 -245.104428) (xy 81.951968 -245.066334) (xy 81.99139 -245.034147)
			(xy 82.035464 -245.008701) (xy 82.08305 -244.990654) (xy 82.132914 -244.980474) (xy 82.183766 -244.978425)
			(xy 82.234287 -244.984559) (xy 82.283171 -244.998719) (xy 82.32915 -245.020536) (xy 82.371034 -245.049446)
			(xy 82.407738 -245.084701) (xy 82.438311 -245.125387) (xy 82.461962 -245.17045) (xy 82.478078 -245.218724)
			(xy 82.486242 -245.268958) (xy 82.486754 -245.294404) (xy 82.486251 -245.319393) (xy 82.793568 -245.319393)
			(xy 82.793568 -245.269415) (xy 82.801387 -245.220052) (xy 82.816831 -245.17252) (xy 82.839521 -245.127988)
			(xy 82.868897 -245.087555) (xy 82.904237 -245.052215) (xy 82.94467 -245.022839) (xy 82.989202 -245.000149)
			(xy 83.036734 -244.984705) (xy 83.086097 -244.976886) (xy 83.136075 -244.976886) (xy 83.185438 -244.984705)
			(xy 83.23297 -245.000149) (xy 83.277502 -245.022839) (xy 83.317935 -245.052215) (xy 83.353275 -245.087555)
			(xy 83.382651 -245.127988) (xy 83.405341 -245.17252) (xy 83.420785 -245.220052) (xy 83.428604 -245.269415)
			(xy 83.429094 -245.294404) (xy 83.734905 -245.294404) (xy 83.739 -245.243676) (xy 83.751179 -245.194262)
			(xy 83.771127 -245.147442) (xy 83.798328 -245.104428) (xy 83.832076 -245.066334) (xy 83.871498 -245.034147)
			(xy 83.915572 -245.008701) (xy 83.963158 -244.990654) (xy 84.013022 -244.980474) (xy 84.063874 -244.978425)
			(xy 84.114395 -244.984559) (xy 84.163279 -244.998719) (xy 84.209258 -245.020536) (xy 84.251142 -245.049446)
			(xy 84.287846 -245.084701) (xy 84.318419 -245.125387) (xy 84.34207 -245.17045) (xy 84.358186 -245.218724)
			(xy 84.36635 -245.268958) (xy 84.366862 -245.294404) (xy 84.366359 -245.319393) (xy 84.673422 -245.319393)
			(xy 84.673422 -245.269415) (xy 84.681241 -245.220052) (xy 84.696685 -245.17252) (xy 84.719375 -245.127988)
			(xy 84.748751 -245.087555) (xy 84.784091 -245.052215) (xy 84.824524 -245.022839) (xy 84.869056 -245.000149)
			(xy 84.916588 -244.984705) (xy 84.965951 -244.976886) (xy 85.015929 -244.976886) (xy 85.065292 -244.984705)
			(xy 85.112824 -245.000149) (xy 85.157356 -245.022839) (xy 85.197789 -245.052215) (xy 85.233129 -245.087555)
			(xy 85.262505 -245.127988) (xy 85.285195 -245.17252) (xy 85.300639 -245.220052) (xy 85.308458 -245.269415)
			(xy 85.308948 -245.294404) (xy 85.614759 -245.294404) (xy 85.618854 -245.243676) (xy 85.631033 -245.194262)
			(xy 85.650981 -245.147442) (xy 85.678182 -245.104428) (xy 85.71193 -245.066334) (xy 85.751352 -245.034147)
			(xy 85.795426 -245.008701) (xy 85.843012 -244.990654) (xy 85.892876 -244.980474) (xy 85.943728 -244.978425)
			(xy 85.994249 -244.984559) (xy 86.043133 -244.998719) (xy 86.089112 -245.020536) (xy 86.130996 -245.049446)
			(xy 86.1677 -245.084701) (xy 86.198273 -245.125387) (xy 86.221924 -245.17045) (xy 86.23804 -245.218724)
			(xy 86.246204 -245.268958) (xy 86.246716 -245.294404) (xy 86.246213 -245.319393) (xy 86.55353 -245.319393)
			(xy 86.55353 -245.269415) (xy 86.561349 -245.220052) (xy 86.576793 -245.17252) (xy 86.599483 -245.127988)
			(xy 86.628859 -245.087555) (xy 86.664199 -245.052215) (xy 86.704632 -245.022839) (xy 86.749164 -245.000149)
			(xy 86.796696 -244.984705) (xy 86.846059 -244.976886) (xy 86.896037 -244.976886) (xy 86.9454 -244.984705)
			(xy 86.992932 -245.000149) (xy 87.037464 -245.022839) (xy 87.077897 -245.052215) (xy 87.113237 -245.087555)
			(xy 87.142613 -245.127988) (xy 87.165303 -245.17252) (xy 87.180747 -245.220052) (xy 87.188566 -245.269415)
			(xy 87.189056 -245.294404) (xy 87.494867 -245.294404) (xy 87.498962 -245.243676) (xy 87.511141 -245.194262)
			(xy 87.531089 -245.147442) (xy 87.55829 -245.104428) (xy 87.592038 -245.066334) (xy 87.63146 -245.034147)
			(xy 87.675534 -245.008701) (xy 87.72312 -244.990654) (xy 87.772984 -244.980474) (xy 87.823836 -244.978425)
			(xy 87.874357 -244.984559) (xy 87.923241 -244.998719) (xy 87.96922 -245.020536) (xy 88.011104 -245.049446)
			(xy 88.047808 -245.084701) (xy 88.078381 -245.125387) (xy 88.102032 -245.17045) (xy 88.118148 -245.218724)
			(xy 88.126312 -245.268958) (xy 88.126824 -245.294404) (xy 88.434921 -245.294404) (xy 88.439016 -245.243676)
			(xy 88.451195 -245.194262) (xy 88.471143 -245.147442) (xy 88.498344 -245.104428) (xy 88.532092 -245.066334)
			(xy 88.571514 -245.034147) (xy 88.615588 -245.008701) (xy 88.663174 -244.990654) (xy 88.713038 -244.980474)
			(xy 88.76389 -244.978425) (xy 88.814411 -244.984559) (xy 88.863295 -244.998719) (xy 88.909274 -245.020536)
			(xy 88.951158 -245.049446) (xy 88.987862 -245.084701) (xy 89.018435 -245.125387) (xy 89.042086 -245.17045)
			(xy 89.058202 -245.218724) (xy 89.066366 -245.268958) (xy 89.066878 -245.294404) (xy 89.066375 -245.319393)
			(xy 89.373438 -245.319393) (xy 89.373438 -245.269415) (xy 89.381257 -245.220052) (xy 89.396701 -245.17252)
			(xy 89.419391 -245.127988) (xy 89.448767 -245.087555) (xy 89.484107 -245.052215) (xy 89.52454 -245.022839)
			(xy 89.569072 -245.000149) (xy 89.616604 -244.984705) (xy 89.665967 -244.976886) (xy 89.715945 -244.976886)
			(xy 89.765308 -244.984705) (xy 89.81284 -245.000149) (xy 89.857372 -245.022839) (xy 89.897805 -245.052215)
			(xy 89.933145 -245.087555) (xy 89.962521 -245.127988) (xy 89.985211 -245.17252) (xy 90.000655 -245.220052)
			(xy 90.008474 -245.269415) (xy 90.008964 -245.294404) (xy 90.314775 -245.294404) (xy 90.31887 -245.243676)
			(xy 90.331049 -245.194262) (xy 90.350997 -245.147442) (xy 90.378198 -245.104428) (xy 90.411946 -245.066334)
			(xy 90.451368 -245.034147) (xy 90.495442 -245.008701) (xy 90.543028 -244.990654) (xy 90.592892 -244.980474)
			(xy 90.643744 -244.978425) (xy 90.694265 -244.984559) (xy 90.743149 -244.998719) (xy 90.789128 -245.020536)
			(xy 90.831012 -245.049446) (xy 90.867716 -245.084701) (xy 90.898289 -245.125387) (xy 90.92194 -245.17045)
			(xy 90.938056 -245.218724) (xy 90.94622 -245.268958) (xy 90.946732 -245.294404) (xy 90.946229 -245.319393)
			(xy 91.253546 -245.319393) (xy 91.253546 -245.269415) (xy 91.261365 -245.220052) (xy 91.276809 -245.17252)
			(xy 91.299499 -245.127988) (xy 91.328875 -245.087555) (xy 91.364215 -245.052215) (xy 91.404648 -245.022839)
			(xy 91.44918 -245.000149) (xy 91.496712 -244.984705) (xy 91.546075 -244.976886) (xy 91.596053 -244.976886)
			(xy 91.645416 -244.984705) (xy 91.692948 -245.000149) (xy 91.73748 -245.022839) (xy 91.777913 -245.052215)
			(xy 91.813253 -245.087555) (xy 91.842629 -245.127988) (xy 91.865319 -245.17252) (xy 91.880763 -245.220052)
			(xy 91.888582 -245.269415) (xy 91.889072 -245.294404) (xy 92.194883 -245.294404) (xy 92.198978 -245.243676)
			(xy 92.211157 -245.194262) (xy 92.231105 -245.147442) (xy 92.258306 -245.104428) (xy 92.292054 -245.066334)
			(xy 92.331476 -245.034147) (xy 92.37555 -245.008701) (xy 92.423136 -244.990654) (xy 92.473 -244.980474)
			(xy 92.523852 -244.978425) (xy 92.574373 -244.984559) (xy 92.623257 -244.998719) (xy 92.669236 -245.020536)
			(xy 92.71112 -245.049446) (xy 92.747824 -245.084701) (xy 92.778397 -245.125387) (xy 92.802048 -245.17045)
			(xy 92.818164 -245.218724) (xy 92.826328 -245.268958) (xy 92.82684 -245.294404) (xy 92.826337 -245.319393)
			(xy 93.1334 -245.319393) (xy 93.1334 -245.269415) (xy 93.141219 -245.220052) (xy 93.156663 -245.17252)
			(xy 93.179353 -245.127988) (xy 93.208729 -245.087555) (xy 93.244069 -245.052215) (xy 93.284502 -245.022839)
			(xy 93.329034 -245.000149) (xy 93.376566 -244.984705) (xy 93.425929 -244.976886) (xy 93.475907 -244.976886)
			(xy 93.52527 -244.984705) (xy 93.572802 -245.000149) (xy 93.617334 -245.022839) (xy 93.657767 -245.052215)
			(xy 93.693107 -245.087555) (xy 93.722483 -245.127988) (xy 93.745173 -245.17252) (xy 93.760617 -245.220052)
			(xy 93.768436 -245.269415) (xy 93.768926 -245.294404) (xy 94.074737 -245.294404) (xy 94.078832 -245.243676)
			(xy 94.091011 -245.194262) (xy 94.110959 -245.147442) (xy 94.13816 -245.104428) (xy 94.171908 -245.066334)
			(xy 94.21133 -245.034147) (xy 94.255404 -245.008701) (xy 94.30299 -244.990654) (xy 94.352854 -244.980474)
			(xy 94.403706 -244.978425) (xy 94.454227 -244.984559) (xy 94.503111 -244.998719) (xy 94.54909 -245.020536)
			(xy 94.590974 -245.049446) (xy 94.627678 -245.084701) (xy 94.658251 -245.125387) (xy 94.681902 -245.17045)
			(xy 94.698018 -245.218724) (xy 94.706182 -245.268958) (xy 94.706694 -245.294404) (xy 95.014791 -245.294404)
			(xy 95.018886 -245.243676) (xy 95.031065 -245.194262) (xy 95.051013 -245.147442) (xy 95.078214 -245.104428)
			(xy 95.111962 -245.066334) (xy 95.151384 -245.034147) (xy 95.195458 -245.008701) (xy 95.243044 -244.990654)
			(xy 95.292908 -244.980474) (xy 95.34376 -244.978425) (xy 95.394281 -244.984559) (xy 95.443165 -244.998719)
			(xy 95.489144 -245.020536) (xy 95.531028 -245.049446) (xy 95.567732 -245.084701) (xy 95.598305 -245.125387)
			(xy 95.621956 -245.17045) (xy 95.638072 -245.218724) (xy 95.646236 -245.268958) (xy 95.646748 -245.294404)
			(xy 95.646245 -245.319393) (xy 95.953562 -245.319393) (xy 95.953562 -245.269415) (xy 95.961381 -245.220052)
			(xy 95.976825 -245.17252) (xy 95.999515 -245.127988) (xy 96.028891 -245.087555) (xy 96.064231 -245.052215)
			(xy 96.104664 -245.022839) (xy 96.149196 -245.000149) (xy 96.196728 -244.984705) (xy 96.246091 -244.976886)
			(xy 96.296069 -244.976886) (xy 96.345432 -244.984705) (xy 96.392964 -245.000149) (xy 96.437496 -245.022839)
			(xy 96.477929 -245.052215) (xy 96.513269 -245.087555) (xy 96.542645 -245.127988) (xy 96.565335 -245.17252)
			(xy 96.580779 -245.220052) (xy 96.588598 -245.269415) (xy 96.589088 -245.294404) (xy 96.588598 -245.319393)
			(xy 96.580779 -245.368756) (xy 96.565335 -245.416288) (xy 96.542645 -245.46082) (xy 96.513269 -245.501253)
			(xy 96.477929 -245.536593) (xy 96.437496 -245.565969) (xy 96.392964 -245.588659) (xy 96.345432 -245.604103)
			(xy 96.296069 -245.611922) (xy 96.246091 -245.611922) (xy 96.196728 -245.604103) (xy 96.149196 -245.588659)
			(xy 96.104664 -245.565969) (xy 96.064231 -245.536593) (xy 96.028891 -245.501253) (xy 95.999515 -245.46082)
			(xy 95.976825 -245.416288) (xy 95.961381 -245.368756) (xy 95.953562 -245.319393) (xy 95.646245 -245.319393)
			(xy 95.646236 -245.31985) (xy 95.638072 -245.370084) (xy 95.621956 -245.418358) (xy 95.598305 -245.463421)
			(xy 95.567732 -245.504107) (xy 95.531028 -245.539362) (xy 95.489144 -245.568272) (xy 95.443165 -245.590089)
			(xy 95.394281 -245.604249) (xy 95.34376 -245.610383) (xy 95.292908 -245.608334) (xy 95.243044 -245.598154)
			(xy 95.195458 -245.580107) (xy 95.151384 -245.554661) (xy 95.111962 -245.522474) (xy 95.078214 -245.48438)
			(xy 95.051013 -245.441366) (xy 95.031065 -245.394546) (xy 95.018886 -245.345132) (xy 95.014791 -245.294404)
			(xy 94.706694 -245.294404) (xy 94.706182 -245.31985) (xy 94.698018 -245.370084) (xy 94.681902 -245.418358)
			(xy 94.658251 -245.463421) (xy 94.627678 -245.504107) (xy 94.590974 -245.539362) (xy 94.54909 -245.568272)
			(xy 94.503111 -245.590089) (xy 94.454227 -245.604249) (xy 94.403706 -245.610383) (xy 94.352854 -245.608334)
			(xy 94.30299 -245.598154) (xy 94.255404 -245.580107) (xy 94.21133 -245.554661) (xy 94.171908 -245.522474)
			(xy 94.13816 -245.48438) (xy 94.110959 -245.441366) (xy 94.091011 -245.394546) (xy 94.078832 -245.345132)
			(xy 94.074737 -245.294404) (xy 93.768926 -245.294404) (xy 93.768436 -245.319393) (xy 93.760617 -245.368756)
			(xy 93.745173 -245.416288) (xy 93.722483 -245.46082) (xy 93.693107 -245.501253) (xy 93.657767 -245.536593)
			(xy 93.617334 -245.565969) (xy 93.572802 -245.588659) (xy 93.52527 -245.604103) (xy 93.475907 -245.611922)
			(xy 93.425929 -245.611922) (xy 93.376566 -245.604103) (xy 93.329034 -245.588659) (xy 93.284502 -245.565969)
			(xy 93.244069 -245.536593) (xy 93.208729 -245.501253) (xy 93.179353 -245.46082) (xy 93.156663 -245.416288)
			(xy 93.141219 -245.368756) (xy 93.1334 -245.319393) (xy 92.826337 -245.319393) (xy 92.826328 -245.31985)
			(xy 92.818164 -245.370084) (xy 92.802048 -245.418358) (xy 92.778397 -245.463421) (xy 92.747824 -245.504107)
			(xy 92.71112 -245.539362) (xy 92.669236 -245.568272) (xy 92.623257 -245.590089) (xy 92.574373 -245.604249)
			(xy 92.523852 -245.610383) (xy 92.473 -245.608334) (xy 92.423136 -245.598154) (xy 92.37555 -245.580107)
			(xy 92.331476 -245.554661) (xy 92.292054 -245.522474) (xy 92.258306 -245.48438) (xy 92.231105 -245.441366)
			(xy 92.211157 -245.394546) (xy 92.198978 -245.345132) (xy 92.194883 -245.294404) (xy 91.889072 -245.294404)
			(xy 91.888582 -245.319393) (xy 91.880763 -245.368756) (xy 91.865319 -245.416288) (xy 91.842629 -245.46082)
			(xy 91.813253 -245.501253) (xy 91.777913 -245.536593) (xy 91.73748 -245.565969) (xy 91.692948 -245.588659)
			(xy 91.645416 -245.604103) (xy 91.596053 -245.611922) (xy 91.546075 -245.611922) (xy 91.496712 -245.604103)
			(xy 91.44918 -245.588659) (xy 91.404648 -245.565969) (xy 91.364215 -245.536593) (xy 91.328875 -245.501253)
			(xy 91.299499 -245.46082) (xy 91.276809 -245.416288) (xy 91.261365 -245.368756) (xy 91.253546 -245.319393)
			(xy 90.946229 -245.319393) (xy 90.94622 -245.31985) (xy 90.938056 -245.370084) (xy 90.92194 -245.418358)
			(xy 90.898289 -245.463421) (xy 90.867716 -245.504107) (xy 90.831012 -245.539362) (xy 90.789128 -245.568272)
			(xy 90.743149 -245.590089) (xy 90.694265 -245.604249) (xy 90.643744 -245.610383) (xy 90.592892 -245.608334)
			(xy 90.543028 -245.598154) (xy 90.495442 -245.580107) (xy 90.451368 -245.554661) (xy 90.411946 -245.522474)
			(xy 90.378198 -245.48438) (xy 90.350997 -245.441366) (xy 90.331049 -245.394546) (xy 90.31887 -245.345132)
			(xy 90.314775 -245.294404) (xy 90.008964 -245.294404) (xy 90.008474 -245.319393) (xy 90.000655 -245.368756)
			(xy 89.985211 -245.416288) (xy 89.962521 -245.46082) (xy 89.933145 -245.501253) (xy 89.897805 -245.536593)
			(xy 89.857372 -245.565969) (xy 89.81284 -245.588659) (xy 89.765308 -245.604103) (xy 89.715945 -245.611922)
			(xy 89.665967 -245.611922) (xy 89.616604 -245.604103) (xy 89.569072 -245.588659) (xy 89.52454 -245.565969)
			(xy 89.484107 -245.536593) (xy 89.448767 -245.501253) (xy 89.419391 -245.46082) (xy 89.396701 -245.416288)
			(xy 89.381257 -245.368756) (xy 89.373438 -245.319393) (xy 89.066375 -245.319393) (xy 89.066366 -245.31985)
			(xy 89.058202 -245.370084) (xy 89.042086 -245.418358) (xy 89.018435 -245.463421) (xy 88.987862 -245.504107)
			(xy 88.951158 -245.539362) (xy 88.909274 -245.568272) (xy 88.863295 -245.590089) (xy 88.814411 -245.604249)
			(xy 88.76389 -245.610383) (xy 88.713038 -245.608334) (xy 88.663174 -245.598154) (xy 88.615588 -245.580107)
			(xy 88.571514 -245.554661) (xy 88.532092 -245.522474) (xy 88.498344 -245.48438) (xy 88.471143 -245.441366)
			(xy 88.451195 -245.394546) (xy 88.439016 -245.345132) (xy 88.434921 -245.294404) (xy 88.126824 -245.294404)
			(xy 88.126312 -245.31985) (xy 88.118148 -245.370084) (xy 88.102032 -245.418358) (xy 88.078381 -245.463421)
			(xy 88.047808 -245.504107) (xy 88.011104 -245.539362) (xy 87.96922 -245.568272) (xy 87.923241 -245.590089)
			(xy 87.874357 -245.604249) (xy 87.823836 -245.610383) (xy 87.772984 -245.608334) (xy 87.72312 -245.598154)
			(xy 87.675534 -245.580107) (xy 87.63146 -245.554661) (xy 87.592038 -245.522474) (xy 87.55829 -245.48438)
			(xy 87.531089 -245.441366) (xy 87.511141 -245.394546) (xy 87.498962 -245.345132) (xy 87.494867 -245.294404)
			(xy 87.189056 -245.294404) (xy 87.188566 -245.319393) (xy 87.180747 -245.368756) (xy 87.165303 -245.416288)
			(xy 87.142613 -245.46082) (xy 87.113237 -245.501253) (xy 87.077897 -245.536593) (xy 87.037464 -245.565969)
			(xy 86.992932 -245.588659) (xy 86.9454 -245.604103) (xy 86.896037 -245.611922) (xy 86.846059 -245.611922)
			(xy 86.796696 -245.604103) (xy 86.749164 -245.588659) (xy 86.704632 -245.565969) (xy 86.664199 -245.536593)
			(xy 86.628859 -245.501253) (xy 86.599483 -245.46082) (xy 86.576793 -245.416288) (xy 86.561349 -245.368756)
			(xy 86.55353 -245.319393) (xy 86.246213 -245.319393) (xy 86.246204 -245.31985) (xy 86.23804 -245.370084)
			(xy 86.221924 -245.418358) (xy 86.198273 -245.463421) (xy 86.1677 -245.504107) (xy 86.130996 -245.539362)
			(xy 86.089112 -245.568272) (xy 86.043133 -245.590089) (xy 85.994249 -245.604249) (xy 85.943728 -245.610383)
			(xy 85.892876 -245.608334) (xy 85.843012 -245.598154) (xy 85.795426 -245.580107) (xy 85.751352 -245.554661)
			(xy 85.71193 -245.522474) (xy 85.678182 -245.48438) (xy 85.650981 -245.441366) (xy 85.631033 -245.394546)
			(xy 85.618854 -245.345132) (xy 85.614759 -245.294404) (xy 85.308948 -245.294404) (xy 85.308458 -245.319393)
			(xy 85.300639 -245.368756) (xy 85.285195 -245.416288) (xy 85.262505 -245.46082) (xy 85.233129 -245.501253)
			(xy 85.197789 -245.536593) (xy 85.157356 -245.565969) (xy 85.112824 -245.588659) (xy 85.065292 -245.604103)
			(xy 85.015929 -245.611922) (xy 84.965951 -245.611922) (xy 84.916588 -245.604103) (xy 84.869056 -245.588659)
			(xy 84.824524 -245.565969) (xy 84.784091 -245.536593) (xy 84.748751 -245.501253) (xy 84.719375 -245.46082)
			(xy 84.696685 -245.416288) (xy 84.681241 -245.368756) (xy 84.673422 -245.319393) (xy 84.366359 -245.319393)
			(xy 84.36635 -245.31985) (xy 84.358186 -245.370084) (xy 84.34207 -245.418358) (xy 84.318419 -245.463421)
			(xy 84.287846 -245.504107) (xy 84.251142 -245.539362) (xy 84.209258 -245.568272) (xy 84.163279 -245.590089)
			(xy 84.114395 -245.604249) (xy 84.063874 -245.610383) (xy 84.013022 -245.608334) (xy 83.963158 -245.598154)
			(xy 83.915572 -245.580107) (xy 83.871498 -245.554661) (xy 83.832076 -245.522474) (xy 83.798328 -245.48438)
			(xy 83.771127 -245.441366) (xy 83.751179 -245.394546) (xy 83.739 -245.345132) (xy 83.734905 -245.294404)
			(xy 83.429094 -245.294404) (xy 83.428604 -245.319393) (xy 83.420785 -245.368756) (xy 83.405341 -245.416288)
			(xy 83.382651 -245.46082) (xy 83.353275 -245.501253) (xy 83.317935 -245.536593) (xy 83.277502 -245.565969)
			(xy 83.23297 -245.588659) (xy 83.185438 -245.604103) (xy 83.136075 -245.611922) (xy 83.086097 -245.611922)
			(xy 83.036734 -245.604103) (xy 82.989202 -245.588659) (xy 82.94467 -245.565969) (xy 82.904237 -245.536593)
			(xy 82.868897 -245.501253) (xy 82.839521 -245.46082) (xy 82.816831 -245.416288) (xy 82.801387 -245.368756)
			(xy 82.793568 -245.319393) (xy 82.486251 -245.319393) (xy 82.486242 -245.31985) (xy 82.478078 -245.370084)
			(xy 82.461962 -245.418358) (xy 82.438311 -245.463421) (xy 82.407738 -245.504107) (xy 82.371034 -245.539362)
			(xy 82.32915 -245.568272) (xy 82.283171 -245.590089) (xy 82.234287 -245.604249) (xy 82.183766 -245.610383)
			(xy 82.132914 -245.608334) (xy 82.08305 -245.598154) (xy 82.035464 -245.580107) (xy 81.99139 -245.554661)
			(xy 81.951968 -245.522474) (xy 81.91822 -245.48438) (xy 81.891019 -245.441366) (xy 81.871071 -245.394546)
			(xy 81.858892 -245.345132) (xy 81.854797 -245.294404) (xy 81.5467 -245.294404) (xy 81.546188 -245.31985)
			(xy 81.538024 -245.370084) (xy 81.521908 -245.418358) (xy 81.498257 -245.463421) (xy 81.467684 -245.504107)
			(xy 81.43098 -245.539362) (xy 81.389096 -245.568272) (xy 81.343117 -245.590089) (xy 81.294233 -245.604249)
			(xy 81.243712 -245.610383) (xy 81.19286 -245.608334) (xy 81.142996 -245.598154) (xy 81.09541 -245.580107)
			(xy 81.051336 -245.554661) (xy 81.011914 -245.522474) (xy 80.978166 -245.48438) (xy 80.950965 -245.441366)
			(xy 80.931017 -245.394546) (xy 80.918838 -245.345132) (xy 80.914743 -245.294404) (xy 80.609186 -245.294404)
			(xy 80.608696 -245.319393) (xy 80.600877 -245.368756) (xy 80.585433 -245.416288) (xy 80.562743 -245.46082)
			(xy 80.533367 -245.501253) (xy 80.498027 -245.536593) (xy 80.457594 -245.565969) (xy 80.413062 -245.588659)
			(xy 80.36553 -245.604103) (xy 80.316167 -245.611922) (xy 80.266189 -245.611922) (xy 80.216826 -245.604103)
			(xy 80.169294 -245.588659) (xy 80.124762 -245.565969) (xy 80.084329 -245.536593) (xy 80.048989 -245.501253)
			(xy 80.019613 -245.46082) (xy 79.996923 -245.416288) (xy 79.981479 -245.368756) (xy 79.97366 -245.319393)
			(xy 79.53248 -245.319393) (xy 79.53248 -245.72849) (xy 79.53298 -245.743264) (xy 79.541438 -245.771575)
			(xy 79.55765 -245.796278) (xy 79.580257 -245.815303) (xy 79.607366 -245.827058) (xy 79.636706 -245.830558)
			(xy 79.665819 -245.825509) (xy 79.679292 -245.819422) (xy 79.701428 -245.808928) (xy 79.74812 -245.794108)
			(xy 79.79653 -245.786612) (xy 79.821024 -245.786148) (xy 79.846031 -245.78664) (xy 79.895429 -245.794468)
			(xy 79.942995 -245.809926) (xy 79.987557 -245.832634) (xy 80.028018 -245.862034) (xy 80.063382 -245.897401)
			(xy 80.092778 -245.937864) (xy 80.115483 -245.982428) (xy 80.130938 -246.029994) (xy 80.138762 -246.079393)
			(xy 80.138762 -246.10441) (xy 80.444843 -246.10441) (xy 80.448938 -246.053682) (xy 80.461117 -246.004268)
			(xy 80.481065 -245.957448) (xy 80.508266 -245.914434) (xy 80.542014 -245.87634) (xy 80.581436 -245.844153)
			(xy 80.62551 -245.818707) (xy 80.673096 -245.80066) (xy 80.72296 -245.79048) (xy 80.773812 -245.788431)
			(xy 80.824333 -245.794565) (xy 80.873217 -245.808725) (xy 80.919196 -245.830542) (xy 80.96108 -245.859452)
			(xy 80.997784 -245.894707) (xy 81.028357 -245.935393) (xy 81.052008 -245.980456) (xy 81.068124 -246.02873)
			(xy 81.076288 -246.078964) (xy 81.0768 -246.10441) (xy 81.076297 -246.129399) (xy 81.383614 -246.129399)
			(xy 81.383614 -246.079421) (xy 81.391433 -246.030058) (xy 81.406877 -245.982526) (xy 81.429567 -245.937994)
			(xy 81.458943 -245.897561) (xy 81.494283 -245.862221) (xy 81.534716 -245.832845) (xy 81.579248 -245.810155)
			(xy 81.62678 -245.794711) (xy 81.676143 -245.786892) (xy 81.726121 -245.786892) (xy 81.775484 -245.794711)
			(xy 81.823016 -245.810155) (xy 81.867548 -245.832845) (xy 81.907981 -245.862221) (xy 81.943321 -245.897561)
			(xy 81.972697 -245.937994) (xy 81.995387 -245.982526) (xy 82.010831 -246.030058) (xy 82.01865 -246.079421)
			(xy 82.01914 -246.10441) (xy 82.324697 -246.10441) (xy 82.328792 -246.053682) (xy 82.340971 -246.004268)
			(xy 82.360919 -245.957448) (xy 82.38812 -245.914434) (xy 82.421868 -245.87634) (xy 82.46129 -245.844153)
			(xy 82.505364 -245.818707) (xy 82.55295 -245.80066) (xy 82.602814 -245.79048) (xy 82.653666 -245.788431)
			(xy 82.704187 -245.794565) (xy 82.753071 -245.808725) (xy 82.79905 -245.830542) (xy 82.840934 -245.859452)
			(xy 82.877638 -245.894707) (xy 82.908211 -245.935393) (xy 82.931862 -245.980456) (xy 82.947978 -246.02873)
			(xy 82.956142 -246.078964) (xy 82.956654 -246.10441) (xy 82.956151 -246.129399) (xy 83.263468 -246.129399)
			(xy 83.263468 -246.079421) (xy 83.271287 -246.030058) (xy 83.286731 -245.982526) (xy 83.309421 -245.937994)
			(xy 83.338797 -245.897561) (xy 83.374137 -245.862221) (xy 83.41457 -245.832845) (xy 83.459102 -245.810155)
			(xy 83.506634 -245.794711) (xy 83.555997 -245.786892) (xy 83.605975 -245.786892) (xy 83.655338 -245.794711)
			(xy 83.70287 -245.810155) (xy 83.747402 -245.832845) (xy 83.787835 -245.862221) (xy 83.823175 -245.897561)
			(xy 83.852551 -245.937994) (xy 83.875241 -245.982526) (xy 83.890685 -246.030058) (xy 83.898504 -246.079421)
			(xy 83.898994 -246.10441) (xy 84.204805 -246.10441) (xy 84.2089 -246.053682) (xy 84.221079 -246.004268)
			(xy 84.241027 -245.957448) (xy 84.268228 -245.914434) (xy 84.301976 -245.87634) (xy 84.341398 -245.844153)
			(xy 84.385472 -245.818707) (xy 84.433058 -245.80066) (xy 84.482922 -245.79048) (xy 84.533774 -245.788431)
			(xy 84.584295 -245.794565) (xy 84.633179 -245.808725) (xy 84.679158 -245.830542) (xy 84.721042 -245.859452)
			(xy 84.757746 -245.894707) (xy 84.788319 -245.935393) (xy 84.81197 -245.980456) (xy 84.828086 -246.02873)
			(xy 84.83625 -246.078964) (xy 84.836762 -246.10441) (xy 85.144859 -246.10441) (xy 85.148954 -246.053682)
			(xy 85.161133 -246.004268) (xy 85.181081 -245.957448) (xy 85.208282 -245.914434) (xy 85.24203 -245.87634)
			(xy 85.281452 -245.844153) (xy 85.325526 -245.818707) (xy 85.373112 -245.80066) (xy 85.422976 -245.79048)
			(xy 85.473828 -245.788431) (xy 85.524349 -245.794565) (xy 85.573233 -245.808725) (xy 85.619212 -245.830542)
			(xy 85.661096 -245.859452) (xy 85.6978 -245.894707) (xy 85.728373 -245.935393) (xy 85.752024 -245.980456)
			(xy 85.76814 -246.02873) (xy 85.776304 -246.078964) (xy 85.776816 -246.10441) (xy 85.776313 -246.129399)
			(xy 86.08363 -246.129399) (xy 86.08363 -246.079421) (xy 86.091449 -246.030058) (xy 86.106893 -245.982526)
			(xy 86.129583 -245.937994) (xy 86.158959 -245.897561) (xy 86.194299 -245.862221) (xy 86.234732 -245.832845)
			(xy 86.279264 -245.810155) (xy 86.326796 -245.794711) (xy 86.376159 -245.786892) (xy 86.426137 -245.786892)
			(xy 86.4755 -245.794711) (xy 86.523032 -245.810155) (xy 86.567564 -245.832845) (xy 86.607997 -245.862221)
			(xy 86.643337 -245.897561) (xy 86.672713 -245.937994) (xy 86.695403 -245.982526) (xy 86.710847 -246.030058)
			(xy 86.718666 -246.079421) (xy 86.719156 -246.10441) (xy 87.024713 -246.10441) (xy 87.028808 -246.053682)
			(xy 87.040987 -246.004268) (xy 87.060935 -245.957448) (xy 87.088136 -245.914434) (xy 87.121884 -245.87634)
			(xy 87.161306 -245.844153) (xy 87.20538 -245.818707) (xy 87.252966 -245.80066) (xy 87.30283 -245.79048)
			(xy 87.353682 -245.788431) (xy 87.404203 -245.794565) (xy 87.453087 -245.808725) (xy 87.499066 -245.830542)
			(xy 87.54095 -245.859452) (xy 87.577654 -245.894707) (xy 87.608227 -245.935393) (xy 87.631878 -245.980456)
			(xy 87.647994 -246.02873) (xy 87.656158 -246.078964) (xy 87.65667 -246.10441) (xy 87.656167 -246.129399)
			(xy 87.963484 -246.129399) (xy 87.963484 -246.079421) (xy 87.971303 -246.030058) (xy 87.986747 -245.982526)
			(xy 88.009437 -245.937994) (xy 88.038813 -245.897561) (xy 88.074153 -245.862221) (xy 88.114586 -245.832845)
			(xy 88.159118 -245.810155) (xy 88.20665 -245.794711) (xy 88.256013 -245.786892) (xy 88.305991 -245.786892)
			(xy 88.355354 -245.794711) (xy 88.402886 -245.810155) (xy 88.447418 -245.832845) (xy 88.487851 -245.862221)
			(xy 88.523191 -245.897561) (xy 88.552567 -245.937994) (xy 88.575257 -245.982526) (xy 88.590701 -246.030058)
			(xy 88.59852 -246.079421) (xy 88.59901 -246.10441) (xy 88.904821 -246.10441) (xy 88.908916 -246.053682)
			(xy 88.921095 -246.004268) (xy 88.941043 -245.957448) (xy 88.968244 -245.914434) (xy 89.001992 -245.87634)
			(xy 89.041414 -245.844153) (xy 89.085488 -245.818707) (xy 89.133074 -245.80066) (xy 89.182938 -245.79048)
			(xy 89.23379 -245.788431) (xy 89.284311 -245.794565) (xy 89.333195 -245.808725) (xy 89.379174 -245.830542)
			(xy 89.421058 -245.859452) (xy 89.457762 -245.894707) (xy 89.488335 -245.935393) (xy 89.511986 -245.980456)
			(xy 89.528102 -246.02873) (xy 89.536266 -246.078964) (xy 89.536778 -246.10441) (xy 89.536275 -246.129399)
			(xy 89.843592 -246.129399) (xy 89.843592 -246.079421) (xy 89.851411 -246.030058) (xy 89.866855 -245.982526)
			(xy 89.889545 -245.937994) (xy 89.918921 -245.897561) (xy 89.954261 -245.862221) (xy 89.994694 -245.832845)
			(xy 90.039226 -245.810155) (xy 90.086758 -245.794711) (xy 90.136121 -245.786892) (xy 90.186099 -245.786892)
			(xy 90.235462 -245.794711) (xy 90.282994 -245.810155) (xy 90.327526 -245.832845) (xy 90.367959 -245.862221)
			(xy 90.403299 -245.897561) (xy 90.432675 -245.937994) (xy 90.455365 -245.982526) (xy 90.470809 -246.030058)
			(xy 90.478628 -246.079421) (xy 90.479118 -246.10441) (xy 90.784675 -246.10441) (xy 90.78877 -246.053682)
			(xy 90.800949 -246.004268) (xy 90.820897 -245.957448) (xy 90.848098 -245.914434) (xy 90.881846 -245.87634)
			(xy 90.921268 -245.844153) (xy 90.965342 -245.818707) (xy 91.012928 -245.80066) (xy 91.062792 -245.79048)
			(xy 91.113644 -245.788431) (xy 91.164165 -245.794565) (xy 91.213049 -245.808725) (xy 91.259028 -245.830542)
			(xy 91.300912 -245.859452) (xy 91.337616 -245.894707) (xy 91.368189 -245.935393) (xy 91.39184 -245.980456)
			(xy 91.407956 -246.02873) (xy 91.41612 -246.078964) (xy 91.416632 -246.10441) (xy 91.724729 -246.10441)
			(xy 91.728824 -246.053682) (xy 91.741003 -246.004268) (xy 91.760951 -245.957448) (xy 91.788152 -245.914434)
			(xy 91.8219 -245.87634) (xy 91.861322 -245.844153) (xy 91.905396 -245.818707) (xy 91.952982 -245.80066)
			(xy 92.002846 -245.79048) (xy 92.053698 -245.788431) (xy 92.104219 -245.794565) (xy 92.153103 -245.808725)
			(xy 92.199082 -245.830542) (xy 92.240966 -245.859452) (xy 92.27767 -245.894707) (xy 92.308243 -245.935393)
			(xy 92.331894 -245.980456) (xy 92.34801 -246.02873) (xy 92.356174 -246.078964) (xy 92.356686 -246.10441)
			(xy 92.356183 -246.129399) (xy 92.6635 -246.129399) (xy 92.6635 -246.079421) (xy 92.671319 -246.030058)
			(xy 92.686763 -245.982526) (xy 92.709453 -245.937994) (xy 92.738829 -245.897561) (xy 92.774169 -245.862221)
			(xy 92.814602 -245.832845) (xy 92.859134 -245.810155) (xy 92.906666 -245.794711) (xy 92.956029 -245.786892)
			(xy 93.006007 -245.786892) (xy 93.05537 -245.794711) (xy 93.102902 -245.810155) (xy 93.147434 -245.832845)
			(xy 93.187867 -245.862221) (xy 93.223207 -245.897561) (xy 93.252583 -245.937994) (xy 93.275273 -245.982526)
			(xy 93.290717 -246.030058) (xy 93.298536 -246.079421) (xy 93.299026 -246.10441) (xy 93.604837 -246.10441)
			(xy 93.608932 -246.053682) (xy 93.621111 -246.004268) (xy 93.641059 -245.957448) (xy 93.66826 -245.914434)
			(xy 93.702008 -245.87634) (xy 93.74143 -245.844153) (xy 93.785504 -245.818707) (xy 93.83309 -245.80066)
			(xy 93.882954 -245.79048) (xy 93.933806 -245.788431) (xy 93.984327 -245.794565) (xy 94.033211 -245.808725)
			(xy 94.07919 -245.830542) (xy 94.121074 -245.859452) (xy 94.157778 -245.894707) (xy 94.188351 -245.935393)
			(xy 94.212002 -245.980456) (xy 94.228118 -246.02873) (xy 94.236282 -246.078964) (xy 94.236794 -246.10441)
			(xy 94.236291 -246.129399) (xy 94.543608 -246.129399) (xy 94.543608 -246.079421) (xy 94.551427 -246.030058)
			(xy 94.566871 -245.982526) (xy 94.589561 -245.937994) (xy 94.618937 -245.897561) (xy 94.654277 -245.862221)
			(xy 94.69471 -245.832845) (xy 94.739242 -245.810155) (xy 94.786774 -245.794711) (xy 94.836137 -245.786892)
			(xy 94.886115 -245.786892) (xy 94.935478 -245.794711) (xy 94.98301 -245.810155) (xy 95.027542 -245.832845)
			(xy 95.067975 -245.862221) (xy 95.103315 -245.897561) (xy 95.132691 -245.937994) (xy 95.155381 -245.982526)
			(xy 95.170825 -246.030058) (xy 95.178644 -246.079421) (xy 95.179134 -246.10441) (xy 95.484691 -246.10441)
			(xy 95.488786 -246.053682) (xy 95.500965 -246.004268) (xy 95.520913 -245.957448) (xy 95.548114 -245.914434)
			(xy 95.581862 -245.87634) (xy 95.621284 -245.844153) (xy 95.665358 -245.818707) (xy 95.712944 -245.80066)
			(xy 95.762808 -245.79048) (xy 95.81366 -245.788431) (xy 95.864181 -245.794565) (xy 95.913065 -245.808725)
			(xy 95.959044 -245.830542) (xy 96.000928 -245.859452) (xy 96.037632 -245.894707) (xy 96.068205 -245.935393)
			(xy 96.091856 -245.980456) (xy 96.107972 -246.02873) (xy 96.116136 -246.078964) (xy 96.116648 -246.10441)
			(xy 96.116136 -246.129856) (xy 96.107972 -246.18009) (xy 96.091856 -246.228364) (xy 96.068205 -246.273427)
			(xy 96.037632 -246.314113) (xy 96.000928 -246.349368) (xy 95.959044 -246.378278) (xy 95.913065 -246.400095)
			(xy 95.864181 -246.414255) (xy 95.81366 -246.420389) (xy 95.762808 -246.41834) (xy 95.712944 -246.40816)
			(xy 95.665358 -246.390113) (xy 95.621284 -246.364667) (xy 95.581862 -246.33248) (xy 95.548114 -246.294386)
			(xy 95.520913 -246.251372) (xy 95.500965 -246.204552) (xy 95.488786 -246.155138) (xy 95.484691 -246.10441)
			(xy 95.179134 -246.10441) (xy 95.178644 -246.129399) (xy 95.170825 -246.178762) (xy 95.155381 -246.226294)
			(xy 95.132691 -246.270826) (xy 95.103315 -246.311259) (xy 95.067975 -246.346599) (xy 95.027542 -246.375975)
			(xy 94.98301 -246.398665) (xy 94.935478 -246.414109) (xy 94.886115 -246.421928) (xy 94.836137 -246.421928)
			(xy 94.786774 -246.414109) (xy 94.739242 -246.398665) (xy 94.69471 -246.375975) (xy 94.654277 -246.346599)
			(xy 94.618937 -246.311259) (xy 94.589561 -246.270826) (xy 94.566871 -246.226294) (xy 94.551427 -246.178762)
			(xy 94.543608 -246.129399) (xy 94.236291 -246.129399) (xy 94.236282 -246.129856) (xy 94.228118 -246.18009)
			(xy 94.212002 -246.228364) (xy 94.188351 -246.273427) (xy 94.157778 -246.314113) (xy 94.121074 -246.349368)
			(xy 94.07919 -246.378278) (xy 94.033211 -246.400095) (xy 93.984327 -246.414255) (xy 93.933806 -246.420389)
			(xy 93.882954 -246.41834) (xy 93.83309 -246.40816) (xy 93.785504 -246.390113) (xy 93.74143 -246.364667)
			(xy 93.702008 -246.33248) (xy 93.66826 -246.294386) (xy 93.641059 -246.251372) (xy 93.621111 -246.204552)
			(xy 93.608932 -246.155138) (xy 93.604837 -246.10441) (xy 93.299026 -246.10441) (xy 93.298536 -246.129399)
			(xy 93.290717 -246.178762) (xy 93.275273 -246.226294) (xy 93.252583 -246.270826) (xy 93.223207 -246.311259)
			(xy 93.187867 -246.346599) (xy 93.147434 -246.375975) (xy 93.102902 -246.398665) (xy 93.05537 -246.414109)
			(xy 93.006007 -246.421928) (xy 92.956029 -246.421928) (xy 92.906666 -246.414109) (xy 92.859134 -246.398665)
			(xy 92.814602 -246.375975) (xy 92.774169 -246.346599) (xy 92.738829 -246.311259) (xy 92.709453 -246.270826)
			(xy 92.686763 -246.226294) (xy 92.671319 -246.178762) (xy 92.6635 -246.129399) (xy 92.356183 -246.129399)
			(xy 92.356174 -246.129856) (xy 92.34801 -246.18009) (xy 92.331894 -246.228364) (xy 92.308243 -246.273427)
			(xy 92.27767 -246.314113) (xy 92.240966 -246.349368) (xy 92.199082 -246.378278) (xy 92.153103 -246.400095)
			(xy 92.104219 -246.414255) (xy 92.053698 -246.420389) (xy 92.002846 -246.41834) (xy 91.952982 -246.40816)
			(xy 91.905396 -246.390113) (xy 91.861322 -246.364667) (xy 91.8219 -246.33248) (xy 91.788152 -246.294386)
			(xy 91.760951 -246.251372) (xy 91.741003 -246.204552) (xy 91.728824 -246.155138) (xy 91.724729 -246.10441)
			(xy 91.416632 -246.10441) (xy 91.41612 -246.129856) (xy 91.407956 -246.18009) (xy 91.39184 -246.228364)
			(xy 91.368189 -246.273427) (xy 91.337616 -246.314113) (xy 91.300912 -246.349368) (xy 91.259028 -246.378278)
			(xy 91.213049 -246.400095) (xy 91.164165 -246.414255) (xy 91.113644 -246.420389) (xy 91.062792 -246.41834)
			(xy 91.012928 -246.40816) (xy 90.965342 -246.390113) (xy 90.921268 -246.364667) (xy 90.881846 -246.33248)
			(xy 90.848098 -246.294386) (xy 90.820897 -246.251372) (xy 90.800949 -246.204552) (xy 90.78877 -246.155138)
			(xy 90.784675 -246.10441) (xy 90.479118 -246.10441) (xy 90.478628 -246.129399) (xy 90.470809 -246.178762)
			(xy 90.455365 -246.226294) (xy 90.432675 -246.270826) (xy 90.403299 -246.311259) (xy 90.367959 -246.346599)
			(xy 90.327526 -246.375975) (xy 90.282994 -246.398665) (xy 90.235462 -246.414109) (xy 90.186099 -246.421928)
			(xy 90.136121 -246.421928) (xy 90.086758 -246.414109) (xy 90.039226 -246.398665) (xy 89.994694 -246.375975)
			(xy 89.954261 -246.346599) (xy 89.918921 -246.311259) (xy 89.889545 -246.270826) (xy 89.866855 -246.226294)
			(xy 89.851411 -246.178762) (xy 89.843592 -246.129399) (xy 89.536275 -246.129399) (xy 89.536266 -246.129856)
			(xy 89.528102 -246.18009) (xy 89.511986 -246.228364) (xy 89.488335 -246.273427) (xy 89.457762 -246.314113)
			(xy 89.421058 -246.349368) (xy 89.379174 -246.378278) (xy 89.333195 -246.400095) (xy 89.284311 -246.414255)
			(xy 89.23379 -246.420389) (xy 89.182938 -246.41834) (xy 89.133074 -246.40816) (xy 89.085488 -246.390113)
			(xy 89.041414 -246.364667) (xy 89.001992 -246.33248) (xy 88.968244 -246.294386) (xy 88.941043 -246.251372)
			(xy 88.921095 -246.204552) (xy 88.908916 -246.155138) (xy 88.904821 -246.10441) (xy 88.59901 -246.10441)
			(xy 88.59852 -246.129399) (xy 88.590701 -246.178762) (xy 88.575257 -246.226294) (xy 88.552567 -246.270826)
			(xy 88.523191 -246.311259) (xy 88.487851 -246.346599) (xy 88.447418 -246.375975) (xy 88.402886 -246.398665)
			(xy 88.355354 -246.414109) (xy 88.305991 -246.421928) (xy 88.256013 -246.421928) (xy 88.20665 -246.414109)
			(xy 88.159118 -246.398665) (xy 88.114586 -246.375975) (xy 88.074153 -246.346599) (xy 88.038813 -246.311259)
			(xy 88.009437 -246.270826) (xy 87.986747 -246.226294) (xy 87.971303 -246.178762) (xy 87.963484 -246.129399)
			(xy 87.656167 -246.129399) (xy 87.656158 -246.129856) (xy 87.647994 -246.18009) (xy 87.631878 -246.228364)
			(xy 87.608227 -246.273427) (xy 87.577654 -246.314113) (xy 87.54095 -246.349368) (xy 87.499066 -246.378278)
			(xy 87.453087 -246.400095) (xy 87.404203 -246.414255) (xy 87.353682 -246.420389) (xy 87.30283 -246.41834)
			(xy 87.252966 -246.40816) (xy 87.20538 -246.390113) (xy 87.161306 -246.364667) (xy 87.121884 -246.33248)
			(xy 87.088136 -246.294386) (xy 87.060935 -246.251372) (xy 87.040987 -246.204552) (xy 87.028808 -246.155138)
			(xy 87.024713 -246.10441) (xy 86.719156 -246.10441) (xy 86.718666 -246.129399) (xy 86.710847 -246.178762)
			(xy 86.695403 -246.226294) (xy 86.672713 -246.270826) (xy 86.643337 -246.311259) (xy 86.607997 -246.346599)
			(xy 86.567564 -246.375975) (xy 86.523032 -246.398665) (xy 86.4755 -246.414109) (xy 86.426137 -246.421928)
			(xy 86.376159 -246.421928) (xy 86.326796 -246.414109) (xy 86.279264 -246.398665) (xy 86.234732 -246.375975)
			(xy 86.194299 -246.346599) (xy 86.158959 -246.311259) (xy 86.129583 -246.270826) (xy 86.106893 -246.226294)
			(xy 86.091449 -246.178762) (xy 86.08363 -246.129399) (xy 85.776313 -246.129399) (xy 85.776304 -246.129856)
			(xy 85.76814 -246.18009) (xy 85.752024 -246.228364) (xy 85.728373 -246.273427) (xy 85.6978 -246.314113)
			(xy 85.661096 -246.349368) (xy 85.619212 -246.378278) (xy 85.573233 -246.400095) (xy 85.524349 -246.414255)
			(xy 85.473828 -246.420389) (xy 85.422976 -246.41834) (xy 85.373112 -246.40816) (xy 85.325526 -246.390113)
			(xy 85.281452 -246.364667) (xy 85.24203 -246.33248) (xy 85.208282 -246.294386) (xy 85.181081 -246.251372)
			(xy 85.161133 -246.204552) (xy 85.148954 -246.155138) (xy 85.144859 -246.10441) (xy 84.836762 -246.10441)
			(xy 84.83625 -246.129856) (xy 84.828086 -246.18009) (xy 84.81197 -246.228364) (xy 84.788319 -246.273427)
			(xy 84.757746 -246.314113) (xy 84.721042 -246.349368) (xy 84.679158 -246.378278) (xy 84.633179 -246.400095)
			(xy 84.584295 -246.414255) (xy 84.533774 -246.420389) (xy 84.482922 -246.41834) (xy 84.433058 -246.40816)
			(xy 84.385472 -246.390113) (xy 84.341398 -246.364667) (xy 84.301976 -246.33248) (xy 84.268228 -246.294386)
			(xy 84.241027 -246.251372) (xy 84.221079 -246.204552) (xy 84.2089 -246.155138) (xy 84.204805 -246.10441)
			(xy 83.898994 -246.10441) (xy 83.898504 -246.129399) (xy 83.890685 -246.178762) (xy 83.875241 -246.226294)
			(xy 83.852551 -246.270826) (xy 83.823175 -246.311259) (xy 83.787835 -246.346599) (xy 83.747402 -246.375975)
			(xy 83.70287 -246.398665) (xy 83.655338 -246.414109) (xy 83.605975 -246.421928) (xy 83.555997 -246.421928)
			(xy 83.506634 -246.414109) (xy 83.459102 -246.398665) (xy 83.41457 -246.375975) (xy 83.374137 -246.346599)
			(xy 83.338797 -246.311259) (xy 83.309421 -246.270826) (xy 83.286731 -246.226294) (xy 83.271287 -246.178762)
			(xy 83.263468 -246.129399) (xy 82.956151 -246.129399) (xy 82.956142 -246.129856) (xy 82.947978 -246.18009)
			(xy 82.931862 -246.228364) (xy 82.908211 -246.273427) (xy 82.877638 -246.314113) (xy 82.840934 -246.349368)
			(xy 82.79905 -246.378278) (xy 82.753071 -246.400095) (xy 82.704187 -246.414255) (xy 82.653666 -246.420389)
			(xy 82.602814 -246.41834) (xy 82.55295 -246.40816) (xy 82.505364 -246.390113) (xy 82.46129 -246.364667)
			(xy 82.421868 -246.33248) (xy 82.38812 -246.294386) (xy 82.360919 -246.251372) (xy 82.340971 -246.204552)
			(xy 82.328792 -246.155138) (xy 82.324697 -246.10441) (xy 82.01914 -246.10441) (xy 82.01865 -246.129399)
			(xy 82.010831 -246.178762) (xy 81.995387 -246.226294) (xy 81.972697 -246.270826) (xy 81.943321 -246.311259)
			(xy 81.907981 -246.346599) (xy 81.867548 -246.375975) (xy 81.823016 -246.398665) (xy 81.775484 -246.414109)
			(xy 81.726121 -246.421928) (xy 81.676143 -246.421928) (xy 81.62678 -246.414109) (xy 81.579248 -246.398665)
			(xy 81.534716 -246.375975) (xy 81.494283 -246.346599) (xy 81.458943 -246.311259) (xy 81.429567 -246.270826)
			(xy 81.406877 -246.226294) (xy 81.391433 -246.178762) (xy 81.383614 -246.129399) (xy 81.076297 -246.129399)
			(xy 81.076288 -246.129856) (xy 81.068124 -246.18009) (xy 81.052008 -246.228364) (xy 81.028357 -246.273427)
			(xy 80.997784 -246.314113) (xy 80.96108 -246.349368) (xy 80.919196 -246.378278) (xy 80.873217 -246.400095)
			(xy 80.824333 -246.414255) (xy 80.773812 -246.420389) (xy 80.72296 -246.41834) (xy 80.673096 -246.40816)
			(xy 80.62551 -246.390113) (xy 80.581436 -246.364667) (xy 80.542014 -246.33248) (xy 80.508266 -246.294386)
			(xy 80.481065 -246.251372) (xy 80.461117 -246.204552) (xy 80.448938 -246.155138) (xy 80.444843 -246.10441)
			(xy 80.138762 -246.10441) (xy 80.138762 -246.129407) (xy 80.130938 -246.178806) (xy 80.115483 -246.226372)
			(xy 80.092778 -246.270936) (xy 80.063382 -246.311399) (xy 80.028018 -246.346766) (xy 79.987557 -246.376166)
			(xy 79.942995 -246.398874) (xy 79.895429 -246.414332) (xy 79.846031 -246.42216) (xy 79.821024 -246.422672)
			(xy 79.796529 -246.422224) (xy 79.748117 -246.414726) (xy 79.701424 -246.399903) (xy 79.679292 -246.389398)
			(xy 79.66584 -246.383275) (xy 79.636726 -246.378254) (xy 79.607393 -246.381772) (xy 79.580293 -246.393536)
			(xy 79.55769 -246.41256) (xy 79.541476 -246.437256) (xy 79.533004 -246.465559) (xy 79.53248 -246.48033)
			(xy 79.53248 -246.914416) (xy 80.914743 -246.914416) (xy 80.918838 -246.863688) (xy 80.931017 -246.814274)
			(xy 80.950965 -246.767454) (xy 80.978166 -246.72444) (xy 81.011914 -246.686346) (xy 81.051336 -246.654159)
			(xy 81.09541 -246.628713) (xy 81.142996 -246.610666) (xy 81.19286 -246.600486) (xy 81.243712 -246.598437)
			(xy 81.294233 -246.604571) (xy 81.343117 -246.618731) (xy 81.389096 -246.640548) (xy 81.43098 -246.669458)
			(xy 81.467684 -246.704713) (xy 81.498257 -246.745399) (xy 81.521908 -246.790462) (xy 81.538024 -246.838736)
			(xy 81.546188 -246.88897) (xy 81.5467 -246.914416) (xy 81.854797 -246.914416) (xy 81.858892 -246.863688)
			(xy 81.871071 -246.814274) (xy 81.891019 -246.767454) (xy 81.91822 -246.72444) (xy 81.951968 -246.686346)
			(xy 81.99139 -246.654159) (xy 82.035464 -246.628713) (xy 82.08305 -246.610666) (xy 82.132914 -246.600486)
			(xy 82.183766 -246.598437) (xy 82.234287 -246.604571) (xy 82.283171 -246.618731) (xy 82.32915 -246.640548)
			(xy 82.371034 -246.669458) (xy 82.407738 -246.704713) (xy 82.438311 -246.745399) (xy 82.461962 -246.790462)
			(xy 82.478078 -246.838736) (xy 82.486242 -246.88897) (xy 82.486754 -246.914416) (xy 82.486251 -246.939405)
			(xy 82.793568 -246.939405) (xy 82.793568 -246.889427) (xy 82.801387 -246.840064) (xy 82.816831 -246.792532)
			(xy 82.839521 -246.748) (xy 82.868897 -246.707567) (xy 82.904237 -246.672227) (xy 82.94467 -246.642851)
			(xy 82.989202 -246.620161) (xy 83.036734 -246.604717) (xy 83.086097 -246.596898) (xy 83.136075 -246.596898)
			(xy 83.185438 -246.604717) (xy 83.23297 -246.620161) (xy 83.277502 -246.642851) (xy 83.317935 -246.672227)
			(xy 83.353275 -246.707567) (xy 83.382651 -246.748) (xy 83.405341 -246.792532) (xy 83.420785 -246.840064)
			(xy 83.428604 -246.889427) (xy 83.429094 -246.914416) (xy 83.734905 -246.914416) (xy 83.739 -246.863688)
			(xy 83.751179 -246.814274) (xy 83.771127 -246.767454) (xy 83.798328 -246.72444) (xy 83.832076 -246.686346)
			(xy 83.871498 -246.654159) (xy 83.915572 -246.628713) (xy 83.963158 -246.610666) (xy 84.013022 -246.600486)
			(xy 84.063874 -246.598437) (xy 84.114395 -246.604571) (xy 84.163279 -246.618731) (xy 84.209258 -246.640548)
			(xy 84.251142 -246.669458) (xy 84.287846 -246.704713) (xy 84.318419 -246.745399) (xy 84.34207 -246.790462)
			(xy 84.358186 -246.838736) (xy 84.36635 -246.88897) (xy 84.366862 -246.914416) (xy 84.366359 -246.939405)
			(xy 84.673422 -246.939405) (xy 84.673422 -246.889427) (xy 84.681241 -246.840064) (xy 84.696685 -246.792532)
			(xy 84.719375 -246.748) (xy 84.748751 -246.707567) (xy 84.784091 -246.672227) (xy 84.824524 -246.642851)
			(xy 84.869056 -246.620161) (xy 84.916588 -246.604717) (xy 84.965951 -246.596898) (xy 85.015929 -246.596898)
			(xy 85.065292 -246.604717) (xy 85.112824 -246.620161) (xy 85.157356 -246.642851) (xy 85.197789 -246.672227)
			(xy 85.233129 -246.707567) (xy 85.262505 -246.748) (xy 85.285195 -246.792532) (xy 85.300639 -246.840064)
			(xy 85.308458 -246.889427) (xy 85.308948 -246.914416) (xy 85.614759 -246.914416) (xy 85.618854 -246.863688)
			(xy 85.631033 -246.814274) (xy 85.650981 -246.767454) (xy 85.678182 -246.72444) (xy 85.71193 -246.686346)
			(xy 85.751352 -246.654159) (xy 85.795426 -246.628713) (xy 85.843012 -246.610666) (xy 85.892876 -246.600486)
			(xy 85.943728 -246.598437) (xy 85.994249 -246.604571) (xy 86.043133 -246.618731) (xy 86.089112 -246.640548)
			(xy 86.130996 -246.669458) (xy 86.1677 -246.704713) (xy 86.198273 -246.745399) (xy 86.221924 -246.790462)
			(xy 86.23804 -246.838736) (xy 86.246204 -246.88897) (xy 86.246716 -246.914416) (xy 87.494867 -246.914416)
			(xy 87.498962 -246.863688) (xy 87.511141 -246.814274) (xy 87.531089 -246.767454) (xy 87.55829 -246.72444)
			(xy 87.592038 -246.686346) (xy 87.63146 -246.654159) (xy 87.675534 -246.628713) (xy 87.72312 -246.610666)
			(xy 87.772984 -246.600486) (xy 87.823836 -246.598437) (xy 87.874357 -246.604571) (xy 87.923241 -246.618731)
			(xy 87.96922 -246.640548) (xy 88.011104 -246.669458) (xy 88.047808 -246.704713) (xy 88.078381 -246.745399)
			(xy 88.102032 -246.790462) (xy 88.118148 -246.838736) (xy 88.126312 -246.88897) (xy 88.126824 -246.914416)
			(xy 88.434921 -246.914416) (xy 88.439016 -246.863688) (xy 88.451195 -246.814274) (xy 88.471143 -246.767454)
			(xy 88.498344 -246.72444) (xy 88.532092 -246.686346) (xy 88.571514 -246.654159) (xy 88.615588 -246.628713)
			(xy 88.663174 -246.610666) (xy 88.713038 -246.600486) (xy 88.76389 -246.598437) (xy 88.814411 -246.604571)
			(xy 88.863295 -246.618731) (xy 88.909274 -246.640548) (xy 88.951158 -246.669458) (xy 88.987862 -246.704713)
			(xy 89.018435 -246.745399) (xy 89.042086 -246.790462) (xy 89.058202 -246.838736) (xy 89.066366 -246.88897)
			(xy 89.066878 -246.914416) (xy 89.066375 -246.939405) (xy 89.373438 -246.939405) (xy 89.373438 -246.889427)
			(xy 89.381257 -246.840064) (xy 89.396701 -246.792532) (xy 89.419391 -246.748) (xy 89.448767 -246.707567)
			(xy 89.484107 -246.672227) (xy 89.52454 -246.642851) (xy 89.569072 -246.620161) (xy 89.616604 -246.604717)
			(xy 89.665967 -246.596898) (xy 89.715945 -246.596898) (xy 89.765308 -246.604717) (xy 89.81284 -246.620161)
			(xy 89.857372 -246.642851) (xy 89.897805 -246.672227) (xy 89.933145 -246.707567) (xy 89.962521 -246.748)
			(xy 89.985211 -246.792532) (xy 90.000655 -246.840064) (xy 90.008474 -246.889427) (xy 90.008964 -246.914416)
			(xy 90.314775 -246.914416) (xy 90.31887 -246.863688) (xy 90.331049 -246.814274) (xy 90.350997 -246.767454)
			(xy 90.378198 -246.72444) (xy 90.411946 -246.686346) (xy 90.451368 -246.654159) (xy 90.495442 -246.628713)
			(xy 90.543028 -246.610666) (xy 90.592892 -246.600486) (xy 90.643744 -246.598437) (xy 90.694265 -246.604571)
			(xy 90.743149 -246.618731) (xy 90.789128 -246.640548) (xy 90.831012 -246.669458) (xy 90.867716 -246.704713)
			(xy 90.898289 -246.745399) (xy 90.92194 -246.790462) (xy 90.938056 -246.838736) (xy 90.94622 -246.88897)
			(xy 90.946732 -246.914416) (xy 90.946229 -246.939405) (xy 91.253546 -246.939405) (xy 91.253546 -246.889427)
			(xy 91.261365 -246.840064) (xy 91.276809 -246.792532) (xy 91.299499 -246.748) (xy 91.328875 -246.707567)
			(xy 91.364215 -246.672227) (xy 91.404648 -246.642851) (xy 91.44918 -246.620161) (xy 91.496712 -246.604717)
			(xy 91.546075 -246.596898) (xy 91.596053 -246.596898) (xy 91.645416 -246.604717) (xy 91.692948 -246.620161)
			(xy 91.73748 -246.642851) (xy 91.777913 -246.672227) (xy 91.813253 -246.707567) (xy 91.842629 -246.748)
			(xy 91.865319 -246.792532) (xy 91.880763 -246.840064) (xy 91.888582 -246.889427) (xy 91.889072 -246.914416)
			(xy 92.194883 -246.914416) (xy 92.198978 -246.863688) (xy 92.211157 -246.814274) (xy 92.231105 -246.767454)
			(xy 92.258306 -246.72444) (xy 92.292054 -246.686346) (xy 92.331476 -246.654159) (xy 92.37555 -246.628713)
			(xy 92.423136 -246.610666) (xy 92.473 -246.600486) (xy 92.523852 -246.598437) (xy 92.574373 -246.604571)
			(xy 92.623257 -246.618731) (xy 92.669236 -246.640548) (xy 92.71112 -246.669458) (xy 92.747824 -246.704713)
			(xy 92.778397 -246.745399) (xy 92.802048 -246.790462) (xy 92.818164 -246.838736) (xy 92.826328 -246.88897)
			(xy 92.82684 -246.914416) (xy 94.074737 -246.914416) (xy 94.078832 -246.863688) (xy 94.091011 -246.814274)
			(xy 94.110959 -246.767454) (xy 94.13816 -246.72444) (xy 94.171908 -246.686346) (xy 94.21133 -246.654159)
			(xy 94.255404 -246.628713) (xy 94.30299 -246.610666) (xy 94.352854 -246.600486) (xy 94.403706 -246.598437)
			(xy 94.454227 -246.604571) (xy 94.503111 -246.618731) (xy 94.54909 -246.640548) (xy 94.590974 -246.669458)
			(xy 94.627678 -246.704713) (xy 94.658251 -246.745399) (xy 94.681902 -246.790462) (xy 94.698018 -246.838736)
			(xy 94.706182 -246.88897) (xy 94.706694 -246.914416) (xy 95.014791 -246.914416) (xy 95.018886 -246.863688)
			(xy 95.031065 -246.814274) (xy 95.051013 -246.767454) (xy 95.078214 -246.72444) (xy 95.111962 -246.686346)
			(xy 95.151384 -246.654159) (xy 95.195458 -246.628713) (xy 95.243044 -246.610666) (xy 95.292908 -246.600486)
			(xy 95.34376 -246.598437) (xy 95.394281 -246.604571) (xy 95.443165 -246.618731) (xy 95.489144 -246.640548)
			(xy 95.531028 -246.669458) (xy 95.567732 -246.704713) (xy 95.598305 -246.745399) (xy 95.621956 -246.790462)
			(xy 95.638072 -246.838736) (xy 95.646236 -246.88897) (xy 95.646748 -246.914416) (xy 95.646236 -246.939862)
			(xy 95.638072 -246.990096) (xy 95.621956 -247.03837) (xy 95.598305 -247.083433) (xy 95.567732 -247.124119)
			(xy 95.531028 -247.159374) (xy 95.489144 -247.188284) (xy 95.443165 -247.210101) (xy 95.394281 -247.224261)
			(xy 95.34376 -247.230395) (xy 95.292908 -247.228346) (xy 95.243044 -247.218166) (xy 95.195458 -247.200119)
			(xy 95.151384 -247.174673) (xy 95.111962 -247.142486) (xy 95.078214 -247.104392) (xy 95.051013 -247.061378)
			(xy 95.031065 -247.014558) (xy 95.018886 -246.965144) (xy 95.014791 -246.914416) (xy 94.706694 -246.914416)
			(xy 94.706182 -246.939862) (xy 94.698018 -246.990096) (xy 94.681902 -247.03837) (xy 94.658251 -247.083433)
			(xy 94.627678 -247.124119) (xy 94.590974 -247.159374) (xy 94.54909 -247.188284) (xy 94.503111 -247.210101)
			(xy 94.454227 -247.224261) (xy 94.403706 -247.230395) (xy 94.352854 -247.228346) (xy 94.30299 -247.218166)
			(xy 94.255404 -247.200119) (xy 94.21133 -247.174673) (xy 94.171908 -247.142486) (xy 94.13816 -247.104392)
			(xy 94.110959 -247.061378) (xy 94.091011 -247.014558) (xy 94.078832 -246.965144) (xy 94.074737 -246.914416)
			(xy 92.82684 -246.914416) (xy 92.826328 -246.939862) (xy 92.818164 -246.990096) (xy 92.802048 -247.03837)
			(xy 92.778397 -247.083433) (xy 92.747824 -247.124119) (xy 92.71112 -247.159374) (xy 92.669236 -247.188284)
			(xy 92.623257 -247.210101) (xy 92.574373 -247.224261) (xy 92.523852 -247.230395) (xy 92.473 -247.228346)
			(xy 92.423136 -247.218166) (xy 92.37555 -247.200119) (xy 92.331476 -247.174673) (xy 92.292054 -247.142486)
			(xy 92.258306 -247.104392) (xy 92.231105 -247.061378) (xy 92.211157 -247.014558) (xy 92.198978 -246.965144)
			(xy 92.194883 -246.914416) (xy 91.889072 -246.914416) (xy 91.888582 -246.939405) (xy 91.880763 -246.988768)
			(xy 91.865319 -247.0363) (xy 91.842629 -247.080832) (xy 91.813253 -247.121265) (xy 91.777913 -247.156605)
			(xy 91.73748 -247.185981) (xy 91.692948 -247.208671) (xy 91.645416 -247.224115) (xy 91.596053 -247.231934)
			(xy 91.546075 -247.231934) (xy 91.496712 -247.224115) (xy 91.44918 -247.208671) (xy 91.404648 -247.185981)
			(xy 91.364215 -247.156605) (xy 91.328875 -247.121265) (xy 91.299499 -247.080832) (xy 91.276809 -247.0363)
			(xy 91.261365 -246.988768) (xy 91.253546 -246.939405) (xy 90.946229 -246.939405) (xy 90.94622 -246.939862)
			(xy 90.938056 -246.990096) (xy 90.92194 -247.03837) (xy 90.898289 -247.083433) (xy 90.867716 -247.124119)
			(xy 90.831012 -247.159374) (xy 90.789128 -247.188284) (xy 90.743149 -247.210101) (xy 90.694265 -247.224261)
			(xy 90.643744 -247.230395) (xy 90.592892 -247.228346) (xy 90.543028 -247.218166) (xy 90.495442 -247.200119)
			(xy 90.451368 -247.174673) (xy 90.411946 -247.142486) (xy 90.378198 -247.104392) (xy 90.350997 -247.061378)
			(xy 90.331049 -247.014558) (xy 90.31887 -246.965144) (xy 90.314775 -246.914416) (xy 90.008964 -246.914416)
			(xy 90.008474 -246.939405) (xy 90.000655 -246.988768) (xy 89.985211 -247.0363) (xy 89.962521 -247.080832)
			(xy 89.933145 -247.121265) (xy 89.897805 -247.156605) (xy 89.857372 -247.185981) (xy 89.81284 -247.208671)
			(xy 89.765308 -247.224115) (xy 89.715945 -247.231934) (xy 89.665967 -247.231934) (xy 89.616604 -247.224115)
			(xy 89.569072 -247.208671) (xy 89.52454 -247.185981) (xy 89.484107 -247.156605) (xy 89.448767 -247.121265)
			(xy 89.419391 -247.080832) (xy 89.396701 -247.0363) (xy 89.381257 -246.988768) (xy 89.373438 -246.939405)
			(xy 89.066375 -246.939405) (xy 89.066366 -246.939862) (xy 89.058202 -246.990096) (xy 89.042086 -247.03837)
			(xy 89.018435 -247.083433) (xy 88.987862 -247.124119) (xy 88.951158 -247.159374) (xy 88.909274 -247.188284)
			(xy 88.863295 -247.210101) (xy 88.814411 -247.224261) (xy 88.76389 -247.230395) (xy 88.713038 -247.228346)
			(xy 88.663174 -247.218166) (xy 88.615588 -247.200119) (xy 88.571514 -247.174673) (xy 88.532092 -247.142486)
			(xy 88.498344 -247.104392) (xy 88.471143 -247.061378) (xy 88.451195 -247.014558) (xy 88.439016 -246.965144)
			(xy 88.434921 -246.914416) (xy 88.126824 -246.914416) (xy 88.126312 -246.939862) (xy 88.118148 -246.990096)
			(xy 88.102032 -247.03837) (xy 88.078381 -247.083433) (xy 88.047808 -247.124119) (xy 88.011104 -247.159374)
			(xy 87.96922 -247.188284) (xy 87.923241 -247.210101) (xy 87.874357 -247.224261) (xy 87.823836 -247.230395)
			(xy 87.772984 -247.228346) (xy 87.72312 -247.218166) (xy 87.675534 -247.200119) (xy 87.63146 -247.174673)
			(xy 87.592038 -247.142486) (xy 87.55829 -247.104392) (xy 87.531089 -247.061378) (xy 87.511141 -247.014558)
			(xy 87.498962 -246.965144) (xy 87.494867 -246.914416) (xy 86.246716 -246.914416) (xy 86.246204 -246.939862)
			(xy 86.23804 -246.990096) (xy 86.221924 -247.03837) (xy 86.198273 -247.083433) (xy 86.1677 -247.124119)
			(xy 86.130996 -247.159374) (xy 86.089112 -247.188284) (xy 86.043133 -247.210101) (xy 85.994249 -247.224261)
			(xy 85.943728 -247.230395) (xy 85.892876 -247.228346) (xy 85.843012 -247.218166) (xy 85.795426 -247.200119)
			(xy 85.751352 -247.174673) (xy 85.71193 -247.142486) (xy 85.678182 -247.104392) (xy 85.650981 -247.061378)
			(xy 85.631033 -247.014558) (xy 85.618854 -246.965144) (xy 85.614759 -246.914416) (xy 85.308948 -246.914416)
			(xy 85.308458 -246.939405) (xy 85.300639 -246.988768) (xy 85.285195 -247.0363) (xy 85.262505 -247.080832)
			(xy 85.233129 -247.121265) (xy 85.197789 -247.156605) (xy 85.157356 -247.185981) (xy 85.112824 -247.208671)
			(xy 85.065292 -247.224115) (xy 85.015929 -247.231934) (xy 84.965951 -247.231934) (xy 84.916588 -247.224115)
			(xy 84.869056 -247.208671) (xy 84.824524 -247.185981) (xy 84.784091 -247.156605) (xy 84.748751 -247.121265)
			(xy 84.719375 -247.080832) (xy 84.696685 -247.0363) (xy 84.681241 -246.988768) (xy 84.673422 -246.939405)
			(xy 84.366359 -246.939405) (xy 84.36635 -246.939862) (xy 84.358186 -246.990096) (xy 84.34207 -247.03837)
			(xy 84.318419 -247.083433) (xy 84.287846 -247.124119) (xy 84.251142 -247.159374) (xy 84.209258 -247.188284)
			(xy 84.163279 -247.210101) (xy 84.114395 -247.224261) (xy 84.063874 -247.230395) (xy 84.013022 -247.228346)
			(xy 83.963158 -247.218166) (xy 83.915572 -247.200119) (xy 83.871498 -247.174673) (xy 83.832076 -247.142486)
			(xy 83.798328 -247.104392) (xy 83.771127 -247.061378) (xy 83.751179 -247.014558) (xy 83.739 -246.965144)
			(xy 83.734905 -246.914416) (xy 83.429094 -246.914416) (xy 83.428604 -246.939405) (xy 83.420785 -246.988768)
			(xy 83.405341 -247.0363) (xy 83.382651 -247.080832) (xy 83.353275 -247.121265) (xy 83.317935 -247.156605)
			(xy 83.277502 -247.185981) (xy 83.23297 -247.208671) (xy 83.185438 -247.224115) (xy 83.136075 -247.231934)
			(xy 83.086097 -247.231934) (xy 83.036734 -247.224115) (xy 82.989202 -247.208671) (xy 82.94467 -247.185981)
			(xy 82.904237 -247.156605) (xy 82.868897 -247.121265) (xy 82.839521 -247.080832) (xy 82.816831 -247.0363)
			(xy 82.801387 -246.988768) (xy 82.793568 -246.939405) (xy 82.486251 -246.939405) (xy 82.486242 -246.939862)
			(xy 82.478078 -246.990096) (xy 82.461962 -247.03837) (xy 82.438311 -247.083433) (xy 82.407738 -247.124119)
			(xy 82.371034 -247.159374) (xy 82.32915 -247.188284) (xy 82.283171 -247.210101) (xy 82.234287 -247.224261)
			(xy 82.183766 -247.230395) (xy 82.132914 -247.228346) (xy 82.08305 -247.218166) (xy 82.035464 -247.200119)
			(xy 81.99139 -247.174673) (xy 81.951968 -247.142486) (xy 81.91822 -247.104392) (xy 81.891019 -247.061378)
			(xy 81.871071 -247.014558) (xy 81.858892 -246.965144) (xy 81.854797 -246.914416) (xy 81.5467 -246.914416)
			(xy 81.546188 -246.939862) (xy 81.538024 -246.990096) (xy 81.521908 -247.03837) (xy 81.498257 -247.083433)
			(xy 81.467684 -247.124119) (xy 81.43098 -247.159374) (xy 81.389096 -247.188284) (xy 81.343117 -247.210101)
			(xy 81.294233 -247.224261) (xy 81.243712 -247.230395) (xy 81.19286 -247.228346) (xy 81.142996 -247.218166)
			(xy 81.09541 -247.200119) (xy 81.051336 -247.174673) (xy 81.011914 -247.142486) (xy 80.978166 -247.104392)
			(xy 80.950965 -247.061378) (xy 80.931017 -247.014558) (xy 80.918838 -246.965144) (xy 80.914743 -246.914416)
			(xy 79.53248 -246.914416) (xy 79.53248 -247.348502) (xy 79.532981 -247.363275) (xy 79.541442 -247.391582)
			(xy 79.557654 -247.416282) (xy 79.58026 -247.435305) (xy 79.607367 -247.447058) (xy 79.636704 -247.450558)
			(xy 79.665815 -247.44551) (xy 79.679292 -247.439434) (xy 79.701428 -247.428939) (xy 79.74812 -247.414119)
			(xy 79.79653 -247.406623) (xy 79.821024 -247.40616) (xy 79.84603 -247.406652) (xy 79.895426 -247.414479)
			(xy 79.94299 -247.429937) (xy 79.98755 -247.452644) (xy 80.02801 -247.482043) (xy 80.063373 -247.517408)
			(xy 80.092768 -247.55787) (xy 80.115472 -247.602432) (xy 80.130926 -247.649997) (xy 80.13875 -247.699394)
			(xy 80.13875 -247.724422) (xy 80.444843 -247.724422) (xy 80.448938 -247.673694) (xy 80.461117 -247.62428)
			(xy 80.481065 -247.57746) (xy 80.508266 -247.534446) (xy 80.542014 -247.496352) (xy 80.581436 -247.464165)
			(xy 80.62551 -247.438719) (xy 80.673096 -247.420672) (xy 80.72296 -247.410492) (xy 80.773812 -247.408443)
			(xy 80.824333 -247.414577) (xy 80.873217 -247.428737) (xy 80.919196 -247.450554) (xy 80.96108 -247.479464)
			(xy 80.997784 -247.514719) (xy 81.028357 -247.555405) (xy 81.052008 -247.600468) (xy 81.068124 -247.648742)
			(xy 81.076288 -247.698976) (xy 81.0768 -247.724422) (xy 81.076297 -247.749411) (xy 81.383614 -247.749411)
			(xy 81.383614 -247.699433) (xy 81.391433 -247.65007) (xy 81.406877 -247.602538) (xy 81.429567 -247.558006)
			(xy 81.458943 -247.517573) (xy 81.494283 -247.482233) (xy 81.534716 -247.452857) (xy 81.579248 -247.430167)
			(xy 81.62678 -247.414723) (xy 81.676143 -247.406904) (xy 81.726121 -247.406904) (xy 81.775484 -247.414723)
			(xy 81.823016 -247.430167) (xy 81.867548 -247.452857) (xy 81.907981 -247.482233) (xy 81.943321 -247.517573)
			(xy 81.972697 -247.558006) (xy 81.995387 -247.602538) (xy 82.010831 -247.65007) (xy 82.01865 -247.699433)
			(xy 82.01914 -247.724422) (xy 82.324697 -247.724422) (xy 82.328792 -247.673694) (xy 82.340971 -247.62428)
			(xy 82.360919 -247.57746) (xy 82.38812 -247.534446) (xy 82.421868 -247.496352) (xy 82.46129 -247.464165)
			(xy 82.505364 -247.438719) (xy 82.55295 -247.420672) (xy 82.602814 -247.410492) (xy 82.653666 -247.408443)
			(xy 82.704187 -247.414577) (xy 82.753071 -247.428737) (xy 82.79905 -247.450554) (xy 82.840934 -247.479464)
			(xy 82.877638 -247.514719) (xy 82.908211 -247.555405) (xy 82.931862 -247.600468) (xy 82.947978 -247.648742)
			(xy 82.956142 -247.698976) (xy 82.956654 -247.724422) (xy 82.956151 -247.749411) (xy 83.263468 -247.749411)
			(xy 83.263468 -247.699433) (xy 83.271287 -247.65007) (xy 83.286731 -247.602538) (xy 83.309421 -247.558006)
			(xy 83.338797 -247.517573) (xy 83.374137 -247.482233) (xy 83.41457 -247.452857) (xy 83.459102 -247.430167)
			(xy 83.506634 -247.414723) (xy 83.555997 -247.406904) (xy 83.605975 -247.406904) (xy 83.655338 -247.414723)
			(xy 83.70287 -247.430167) (xy 83.747402 -247.452857) (xy 83.787835 -247.482233) (xy 83.823175 -247.517573)
			(xy 83.852551 -247.558006) (xy 83.875241 -247.602538) (xy 83.890685 -247.65007) (xy 83.898504 -247.699433)
			(xy 83.898994 -247.724422) (xy 84.204805 -247.724422) (xy 84.2089 -247.673694) (xy 84.221079 -247.62428)
			(xy 84.241027 -247.57746) (xy 84.268228 -247.534446) (xy 84.301976 -247.496352) (xy 84.341398 -247.464165)
			(xy 84.385472 -247.438719) (xy 84.433058 -247.420672) (xy 84.482922 -247.410492) (xy 84.533774 -247.408443)
			(xy 84.584295 -247.414577) (xy 84.633179 -247.428737) (xy 84.679158 -247.450554) (xy 84.721042 -247.479464)
			(xy 84.757746 -247.514719) (xy 84.788319 -247.555405) (xy 84.81197 -247.600468) (xy 84.828086 -247.648742)
			(xy 84.83625 -247.698976) (xy 84.836762 -247.724422) (xy 85.144859 -247.724422) (xy 85.148954 -247.673694)
			(xy 85.161133 -247.62428) (xy 85.181081 -247.57746) (xy 85.208282 -247.534446) (xy 85.24203 -247.496352)
			(xy 85.281452 -247.464165) (xy 85.325526 -247.438719) (xy 85.373112 -247.420672) (xy 85.422976 -247.410492)
			(xy 85.473828 -247.408443) (xy 85.524349 -247.414577) (xy 85.573233 -247.428737) (xy 85.619212 -247.450554)
			(xy 85.661096 -247.479464) (xy 85.6978 -247.514719) (xy 85.728373 -247.555405) (xy 85.752024 -247.600468)
			(xy 85.76814 -247.648742) (xy 85.776304 -247.698976) (xy 85.776816 -247.724422) (xy 85.776313 -247.749411)
			(xy 86.08363 -247.749411) (xy 86.08363 -247.699433) (xy 86.091449 -247.65007) (xy 86.106893 -247.602538)
			(xy 86.129583 -247.558006) (xy 86.158959 -247.517573) (xy 86.194299 -247.482233) (xy 86.234732 -247.452857)
			(xy 86.279264 -247.430167) (xy 86.326796 -247.414723) (xy 86.376159 -247.406904) (xy 86.426137 -247.406904)
			(xy 86.4755 -247.414723) (xy 86.523032 -247.430167) (xy 86.567564 -247.452857) (xy 86.607997 -247.482233)
			(xy 86.643337 -247.517573) (xy 86.672713 -247.558006) (xy 86.695403 -247.602538) (xy 86.710847 -247.65007)
			(xy 86.718666 -247.699433) (xy 86.719156 -247.724422) (xy 87.024713 -247.724422) (xy 87.028808 -247.673694)
			(xy 87.040987 -247.62428) (xy 87.060935 -247.57746) (xy 87.088136 -247.534446) (xy 87.121884 -247.496352)
			(xy 87.161306 -247.464165) (xy 87.20538 -247.438719) (xy 87.252966 -247.420672) (xy 87.30283 -247.410492)
			(xy 87.353682 -247.408443) (xy 87.404203 -247.414577) (xy 87.453087 -247.428737) (xy 87.499066 -247.450554)
			(xy 87.54095 -247.479464) (xy 87.577654 -247.514719) (xy 87.608227 -247.555405) (xy 87.631878 -247.600468)
			(xy 87.647994 -247.648742) (xy 87.656158 -247.698976) (xy 87.65667 -247.724422) (xy 87.656167 -247.749411)
			(xy 87.963484 -247.749411) (xy 87.963484 -247.699433) (xy 87.971303 -247.65007) (xy 87.986747 -247.602538)
			(xy 88.009437 -247.558006) (xy 88.038813 -247.517573) (xy 88.074153 -247.482233) (xy 88.114586 -247.452857)
			(xy 88.159118 -247.430167) (xy 88.20665 -247.414723) (xy 88.256013 -247.406904) (xy 88.305991 -247.406904)
			(xy 88.355354 -247.414723) (xy 88.402886 -247.430167) (xy 88.447418 -247.452857) (xy 88.487851 -247.482233)
			(xy 88.523191 -247.517573) (xy 88.552567 -247.558006) (xy 88.575257 -247.602538) (xy 88.590701 -247.65007)
			(xy 88.59852 -247.699433) (xy 88.59901 -247.724422) (xy 88.904821 -247.724422) (xy 88.908916 -247.673694)
			(xy 88.921095 -247.62428) (xy 88.941043 -247.57746) (xy 88.968244 -247.534446) (xy 89.001992 -247.496352)
			(xy 89.041414 -247.464165) (xy 89.085488 -247.438719) (xy 89.133074 -247.420672) (xy 89.182938 -247.410492)
			(xy 89.23379 -247.408443) (xy 89.284311 -247.414577) (xy 89.333195 -247.428737) (xy 89.379174 -247.450554)
			(xy 89.421058 -247.479464) (xy 89.457762 -247.514719) (xy 89.488335 -247.555405) (xy 89.511986 -247.600468)
			(xy 89.528102 -247.648742) (xy 89.536266 -247.698976) (xy 89.536778 -247.724422) (xy 89.536275 -247.749411)
			(xy 89.843592 -247.749411) (xy 89.843592 -247.699433) (xy 89.851411 -247.65007) (xy 89.866855 -247.602538)
			(xy 89.889545 -247.558006) (xy 89.918921 -247.517573) (xy 89.954261 -247.482233) (xy 89.994694 -247.452857)
			(xy 90.039226 -247.430167) (xy 90.086758 -247.414723) (xy 90.136121 -247.406904) (xy 90.186099 -247.406904)
			(xy 90.235462 -247.414723) (xy 90.282994 -247.430167) (xy 90.327526 -247.452857) (xy 90.367959 -247.482233)
			(xy 90.403299 -247.517573) (xy 90.432675 -247.558006) (xy 90.455365 -247.602538) (xy 90.470809 -247.65007)
			(xy 90.478628 -247.699433) (xy 90.479118 -247.724422) (xy 90.784675 -247.724422) (xy 90.78877 -247.673694)
			(xy 90.800949 -247.62428) (xy 90.820897 -247.57746) (xy 90.848098 -247.534446) (xy 90.881846 -247.496352)
			(xy 90.921268 -247.464165) (xy 90.965342 -247.438719) (xy 91.012928 -247.420672) (xy 91.062792 -247.410492)
			(xy 91.113644 -247.408443) (xy 91.164165 -247.414577) (xy 91.213049 -247.428737) (xy 91.259028 -247.450554)
			(xy 91.300912 -247.479464) (xy 91.337616 -247.514719) (xy 91.368189 -247.555405) (xy 91.39184 -247.600468)
			(xy 91.407956 -247.648742) (xy 91.41612 -247.698976) (xy 91.416632 -247.724422) (xy 91.724729 -247.724422)
			(xy 91.728824 -247.673694) (xy 91.741003 -247.62428) (xy 91.760951 -247.57746) (xy 91.788152 -247.534446)
			(xy 91.8219 -247.496352) (xy 91.861322 -247.464165) (xy 91.905396 -247.438719) (xy 91.952982 -247.420672)
			(xy 92.002846 -247.410492) (xy 92.053698 -247.408443) (xy 92.104219 -247.414577) (xy 92.153103 -247.428737)
			(xy 92.199082 -247.450554) (xy 92.240966 -247.479464) (xy 92.27767 -247.514719) (xy 92.308243 -247.555405)
			(xy 92.331894 -247.600468) (xy 92.34801 -247.648742) (xy 92.356174 -247.698976) (xy 92.356686 -247.724422)
			(xy 92.356183 -247.749411) (xy 92.6635 -247.749411) (xy 92.6635 -247.699433) (xy 92.671319 -247.65007)
			(xy 92.686763 -247.602538) (xy 92.709453 -247.558006) (xy 92.738829 -247.517573) (xy 92.774169 -247.482233)
			(xy 92.814602 -247.452857) (xy 92.859134 -247.430167) (xy 92.906666 -247.414723) (xy 92.956029 -247.406904)
			(xy 93.006007 -247.406904) (xy 93.05537 -247.414723) (xy 93.102902 -247.430167) (xy 93.147434 -247.452857)
			(xy 93.187867 -247.482233) (xy 93.223207 -247.517573) (xy 93.252583 -247.558006) (xy 93.275273 -247.602538)
			(xy 93.290717 -247.65007) (xy 93.298536 -247.699433) (xy 93.299026 -247.724422) (xy 93.604837 -247.724422)
			(xy 93.608932 -247.673694) (xy 93.621111 -247.62428) (xy 93.641059 -247.57746) (xy 93.66826 -247.534446)
			(xy 93.702008 -247.496352) (xy 93.74143 -247.464165) (xy 93.785504 -247.438719) (xy 93.83309 -247.420672)
			(xy 93.882954 -247.410492) (xy 93.933806 -247.408443) (xy 93.984327 -247.414577) (xy 94.033211 -247.428737)
			(xy 94.07919 -247.450554) (xy 94.121074 -247.479464) (xy 94.157778 -247.514719) (xy 94.188351 -247.555405)
			(xy 94.212002 -247.600468) (xy 94.228118 -247.648742) (xy 94.236282 -247.698976) (xy 94.236794 -247.724422)
			(xy 94.236291 -247.749411) (xy 94.543608 -247.749411) (xy 94.543608 -247.699433) (xy 94.551427 -247.65007)
			(xy 94.566871 -247.602538) (xy 94.589561 -247.558006) (xy 94.618937 -247.517573) (xy 94.654277 -247.482233)
			(xy 94.69471 -247.452857) (xy 94.739242 -247.430167) (xy 94.786774 -247.414723) (xy 94.836137 -247.406904)
			(xy 94.886115 -247.406904) (xy 94.935478 -247.414723) (xy 94.98301 -247.430167) (xy 95.027542 -247.452857)
			(xy 95.067975 -247.482233) (xy 95.103315 -247.517573) (xy 95.132691 -247.558006) (xy 95.155381 -247.602538)
			(xy 95.170825 -247.65007) (xy 95.178644 -247.699433) (xy 95.179134 -247.724422) (xy 95.484691 -247.724422)
			(xy 95.488786 -247.673694) (xy 95.500965 -247.62428) (xy 95.520913 -247.57746) (xy 95.548114 -247.534446)
			(xy 95.581862 -247.496352) (xy 95.621284 -247.464165) (xy 95.665358 -247.438719) (xy 95.712944 -247.420672)
			(xy 95.762808 -247.410492) (xy 95.81366 -247.408443) (xy 95.864181 -247.414577) (xy 95.913065 -247.428737)
			(xy 95.959044 -247.450554) (xy 96.000928 -247.479464) (xy 96.037632 -247.514719) (xy 96.068205 -247.555405)
			(xy 96.091856 -247.600468) (xy 96.107972 -247.648742) (xy 96.116136 -247.698976) (xy 96.116648 -247.724422)
			(xy 96.116136 -247.749868) (xy 96.107972 -247.800102) (xy 96.091856 -247.848376) (xy 96.068205 -247.893439)
			(xy 96.037632 -247.934125) (xy 96.000928 -247.96938) (xy 95.959044 -247.99829) (xy 95.913065 -248.020107)
			(xy 95.864181 -248.034267) (xy 95.81366 -248.040401) (xy 95.762808 -248.038352) (xy 95.712944 -248.028172)
			(xy 95.665358 -248.010125) (xy 95.621284 -247.984679) (xy 95.581862 -247.952492) (xy 95.548114 -247.914398)
			(xy 95.520913 -247.871384) (xy 95.500965 -247.824564) (xy 95.488786 -247.77515) (xy 95.484691 -247.724422)
			(xy 95.179134 -247.724422) (xy 95.178644 -247.749411) (xy 95.170825 -247.798774) (xy 95.155381 -247.846306)
			(xy 95.132691 -247.890838) (xy 95.103315 -247.931271) (xy 95.067975 -247.966611) (xy 95.027542 -247.995987)
			(xy 94.98301 -248.018677) (xy 94.935478 -248.034121) (xy 94.886115 -248.04194) (xy 94.836137 -248.04194)
			(xy 94.786774 -248.034121) (xy 94.739242 -248.018677) (xy 94.69471 -247.995987) (xy 94.654277 -247.966611)
			(xy 94.618937 -247.931271) (xy 94.589561 -247.890838) (xy 94.566871 -247.846306) (xy 94.551427 -247.798774)
			(xy 94.543608 -247.749411) (xy 94.236291 -247.749411) (xy 94.236282 -247.749868) (xy 94.228118 -247.800102)
			(xy 94.212002 -247.848376) (xy 94.188351 -247.893439) (xy 94.157778 -247.934125) (xy 94.121074 -247.96938)
			(xy 94.07919 -247.99829) (xy 94.033211 -248.020107) (xy 93.984327 -248.034267) (xy 93.933806 -248.040401)
			(xy 93.882954 -248.038352) (xy 93.83309 -248.028172) (xy 93.785504 -248.010125) (xy 93.74143 -247.984679)
			(xy 93.702008 -247.952492) (xy 93.66826 -247.914398) (xy 93.641059 -247.871384) (xy 93.621111 -247.824564)
			(xy 93.608932 -247.77515) (xy 93.604837 -247.724422) (xy 93.299026 -247.724422) (xy 93.298536 -247.749411)
			(xy 93.290717 -247.798774) (xy 93.275273 -247.846306) (xy 93.252583 -247.890838) (xy 93.223207 -247.931271)
			(xy 93.187867 -247.966611) (xy 93.147434 -247.995987) (xy 93.102902 -248.018677) (xy 93.05537 -248.034121)
			(xy 93.006007 -248.04194) (xy 92.956029 -248.04194) (xy 92.906666 -248.034121) (xy 92.859134 -248.018677)
			(xy 92.814602 -247.995987) (xy 92.774169 -247.966611) (xy 92.738829 -247.931271) (xy 92.709453 -247.890838)
			(xy 92.686763 -247.846306) (xy 92.671319 -247.798774) (xy 92.6635 -247.749411) (xy 92.356183 -247.749411)
			(xy 92.356174 -247.749868) (xy 92.34801 -247.800102) (xy 92.331894 -247.848376) (xy 92.308243 -247.893439)
			(xy 92.27767 -247.934125) (xy 92.240966 -247.96938) (xy 92.199082 -247.99829) (xy 92.153103 -248.020107)
			(xy 92.104219 -248.034267) (xy 92.053698 -248.040401) (xy 92.002846 -248.038352) (xy 91.952982 -248.028172)
			(xy 91.905396 -248.010125) (xy 91.861322 -247.984679) (xy 91.8219 -247.952492) (xy 91.788152 -247.914398)
			(xy 91.760951 -247.871384) (xy 91.741003 -247.824564) (xy 91.728824 -247.77515) (xy 91.724729 -247.724422)
			(xy 91.416632 -247.724422) (xy 91.41612 -247.749868) (xy 91.407956 -247.800102) (xy 91.39184 -247.848376)
			(xy 91.368189 -247.893439) (xy 91.337616 -247.934125) (xy 91.300912 -247.96938) (xy 91.259028 -247.99829)
			(xy 91.213049 -248.020107) (xy 91.164165 -248.034267) (xy 91.113644 -248.040401) (xy 91.062792 -248.038352)
			(xy 91.012928 -248.028172) (xy 90.965342 -248.010125) (xy 90.921268 -247.984679) (xy 90.881846 -247.952492)
			(xy 90.848098 -247.914398) (xy 90.820897 -247.871384) (xy 90.800949 -247.824564) (xy 90.78877 -247.77515)
			(xy 90.784675 -247.724422) (xy 90.479118 -247.724422) (xy 90.478628 -247.749411) (xy 90.470809 -247.798774)
			(xy 90.455365 -247.846306) (xy 90.432675 -247.890838) (xy 90.403299 -247.931271) (xy 90.367959 -247.966611)
			(xy 90.327526 -247.995987) (xy 90.282994 -248.018677) (xy 90.235462 -248.034121) (xy 90.186099 -248.04194)
			(xy 90.136121 -248.04194) (xy 90.086758 -248.034121) (xy 90.039226 -248.018677) (xy 89.994694 -247.995987)
			(xy 89.954261 -247.966611) (xy 89.918921 -247.931271) (xy 89.889545 -247.890838) (xy 89.866855 -247.846306)
			(xy 89.851411 -247.798774) (xy 89.843592 -247.749411) (xy 89.536275 -247.749411) (xy 89.536266 -247.749868)
			(xy 89.528102 -247.800102) (xy 89.511986 -247.848376) (xy 89.488335 -247.893439) (xy 89.457762 -247.934125)
			(xy 89.421058 -247.96938) (xy 89.379174 -247.99829) (xy 89.333195 -248.020107) (xy 89.284311 -248.034267)
			(xy 89.23379 -248.040401) (xy 89.182938 -248.038352) (xy 89.133074 -248.028172) (xy 89.085488 -248.010125)
			(xy 89.041414 -247.984679) (xy 89.001992 -247.952492) (xy 88.968244 -247.914398) (xy 88.941043 -247.871384)
			(xy 88.921095 -247.824564) (xy 88.908916 -247.77515) (xy 88.904821 -247.724422) (xy 88.59901 -247.724422)
			(xy 88.59852 -247.749411) (xy 88.590701 -247.798774) (xy 88.575257 -247.846306) (xy 88.552567 -247.890838)
			(xy 88.523191 -247.931271) (xy 88.487851 -247.966611) (xy 88.447418 -247.995987) (xy 88.402886 -248.018677)
			(xy 88.355354 -248.034121) (xy 88.305991 -248.04194) (xy 88.256013 -248.04194) (xy 88.20665 -248.034121)
			(xy 88.159118 -248.018677) (xy 88.114586 -247.995987) (xy 88.074153 -247.966611) (xy 88.038813 -247.931271)
			(xy 88.009437 -247.890838) (xy 87.986747 -247.846306) (xy 87.971303 -247.798774) (xy 87.963484 -247.749411)
			(xy 87.656167 -247.749411) (xy 87.656158 -247.749868) (xy 87.647994 -247.800102) (xy 87.631878 -247.848376)
			(xy 87.608227 -247.893439) (xy 87.577654 -247.934125) (xy 87.54095 -247.96938) (xy 87.499066 -247.99829)
			(xy 87.453087 -248.020107) (xy 87.404203 -248.034267) (xy 87.353682 -248.040401) (xy 87.30283 -248.038352)
			(xy 87.252966 -248.028172) (xy 87.20538 -248.010125) (xy 87.161306 -247.984679) (xy 87.121884 -247.952492)
			(xy 87.088136 -247.914398) (xy 87.060935 -247.871384) (xy 87.040987 -247.824564) (xy 87.028808 -247.77515)
			(xy 87.024713 -247.724422) (xy 86.719156 -247.724422) (xy 86.718666 -247.749411) (xy 86.710847 -247.798774)
			(xy 86.695403 -247.846306) (xy 86.672713 -247.890838) (xy 86.643337 -247.931271) (xy 86.607997 -247.966611)
			(xy 86.567564 -247.995987) (xy 86.523032 -248.018677) (xy 86.4755 -248.034121) (xy 86.426137 -248.04194)
			(xy 86.376159 -248.04194) (xy 86.326796 -248.034121) (xy 86.279264 -248.018677) (xy 86.234732 -247.995987)
			(xy 86.194299 -247.966611) (xy 86.158959 -247.931271) (xy 86.129583 -247.890838) (xy 86.106893 -247.846306)
			(xy 86.091449 -247.798774) (xy 86.08363 -247.749411) (xy 85.776313 -247.749411) (xy 85.776304 -247.749868)
			(xy 85.76814 -247.800102) (xy 85.752024 -247.848376) (xy 85.728373 -247.893439) (xy 85.6978 -247.934125)
			(xy 85.661096 -247.96938) (xy 85.619212 -247.99829) (xy 85.573233 -248.020107) (xy 85.524349 -248.034267)
			(xy 85.473828 -248.040401) (xy 85.422976 -248.038352) (xy 85.373112 -248.028172) (xy 85.325526 -248.010125)
			(xy 85.281452 -247.984679) (xy 85.24203 -247.952492) (xy 85.208282 -247.914398) (xy 85.181081 -247.871384)
			(xy 85.161133 -247.824564) (xy 85.148954 -247.77515) (xy 85.144859 -247.724422) (xy 84.836762 -247.724422)
			(xy 84.83625 -247.749868) (xy 84.828086 -247.800102) (xy 84.81197 -247.848376) (xy 84.788319 -247.893439)
			(xy 84.757746 -247.934125) (xy 84.721042 -247.96938) (xy 84.679158 -247.99829) (xy 84.633179 -248.020107)
			(xy 84.584295 -248.034267) (xy 84.533774 -248.040401) (xy 84.482922 -248.038352) (xy 84.433058 -248.028172)
			(xy 84.385472 -248.010125) (xy 84.341398 -247.984679) (xy 84.301976 -247.952492) (xy 84.268228 -247.914398)
			(xy 84.241027 -247.871384) (xy 84.221079 -247.824564) (xy 84.2089 -247.77515) (xy 84.204805 -247.724422)
			(xy 83.898994 -247.724422) (xy 83.898504 -247.749411) (xy 83.890685 -247.798774) (xy 83.875241 -247.846306)
			(xy 83.852551 -247.890838) (xy 83.823175 -247.931271) (xy 83.787835 -247.966611) (xy 83.747402 -247.995987)
			(xy 83.70287 -248.018677) (xy 83.655338 -248.034121) (xy 83.605975 -248.04194) (xy 83.555997 -248.04194)
			(xy 83.506634 -248.034121) (xy 83.459102 -248.018677) (xy 83.41457 -247.995987) (xy 83.374137 -247.966611)
			(xy 83.338797 -247.931271) (xy 83.309421 -247.890838) (xy 83.286731 -247.846306) (xy 83.271287 -247.798774)
			(xy 83.263468 -247.749411) (xy 82.956151 -247.749411) (xy 82.956142 -247.749868) (xy 82.947978 -247.800102)
			(xy 82.931862 -247.848376) (xy 82.908211 -247.893439) (xy 82.877638 -247.934125) (xy 82.840934 -247.96938)
			(xy 82.79905 -247.99829) (xy 82.753071 -248.020107) (xy 82.704187 -248.034267) (xy 82.653666 -248.040401)
			(xy 82.602814 -248.038352) (xy 82.55295 -248.028172) (xy 82.505364 -248.010125) (xy 82.46129 -247.984679)
			(xy 82.421868 -247.952492) (xy 82.38812 -247.914398) (xy 82.360919 -247.871384) (xy 82.340971 -247.824564)
			(xy 82.328792 -247.77515) (xy 82.324697 -247.724422) (xy 82.01914 -247.724422) (xy 82.01865 -247.749411)
			(xy 82.010831 -247.798774) (xy 81.995387 -247.846306) (xy 81.972697 -247.890838) (xy 81.943321 -247.931271)
			(xy 81.907981 -247.966611) (xy 81.867548 -247.995987) (xy 81.823016 -248.018677) (xy 81.775484 -248.034121)
			(xy 81.726121 -248.04194) (xy 81.676143 -248.04194) (xy 81.62678 -248.034121) (xy 81.579248 -248.018677)
			(xy 81.534716 -247.995987) (xy 81.494283 -247.966611) (xy 81.458943 -247.931271) (xy 81.429567 -247.890838)
			(xy 81.406877 -247.846306) (xy 81.391433 -247.798774) (xy 81.383614 -247.749411) (xy 81.076297 -247.749411)
			(xy 81.076288 -247.749868) (xy 81.068124 -247.800102) (xy 81.052008 -247.848376) (xy 81.028357 -247.893439)
			(xy 80.997784 -247.934125) (xy 80.96108 -247.96938) (xy 80.919196 -247.99829) (xy 80.873217 -248.020107)
			(xy 80.824333 -248.034267) (xy 80.773812 -248.040401) (xy 80.72296 -248.038352) (xy 80.673096 -248.028172)
			(xy 80.62551 -248.010125) (xy 80.581436 -247.984679) (xy 80.542014 -247.952492) (xy 80.508266 -247.914398)
			(xy 80.481065 -247.871384) (xy 80.461117 -247.824564) (xy 80.448938 -247.77515) (xy 80.444843 -247.724422)
			(xy 80.13875 -247.724422) (xy 80.13875 -247.749406) (xy 80.130926 -247.798803) (xy 80.115472 -247.846368)
			(xy 80.092768 -247.89093) (xy 80.063373 -247.931392) (xy 80.02801 -247.966757) (xy 79.98755 -247.996156)
			(xy 79.94299 -248.018863) (xy 79.895426 -248.034321) (xy 79.84603 -248.042148) (xy 79.821024 -248.042684)
			(xy 79.796529 -248.042236) (xy 79.748117 -248.034738) (xy 79.701424 -248.019915) (xy 79.679292 -248.00941)
			(xy 79.66584 -248.003287) (xy 79.636728 -247.998265) (xy 79.607395 -248.001783) (xy 79.580296 -248.013546)
			(xy 79.557695 -248.032572) (xy 79.541482 -248.057268) (xy 79.533013 -248.085571) (xy 79.53248 -248.100342)
			(xy 79.53248 -248.559417) (xy 79.97366 -248.559417) (xy 79.97366 -248.509439) (xy 79.981479 -248.460076)
			(xy 79.996923 -248.412544) (xy 80.019613 -248.368012) (xy 80.048989 -248.327579) (xy 80.084329 -248.292239)
			(xy 80.124762 -248.262863) (xy 80.169294 -248.240173) (xy 80.216826 -248.224729) (xy 80.266189 -248.21691)
			(xy 80.316167 -248.21691) (xy 80.36553 -248.224729) (xy 80.413062 -248.240173) (xy 80.457594 -248.262863)
			(xy 80.498027 -248.292239) (xy 80.533367 -248.327579) (xy 80.562743 -248.368012) (xy 80.585433 -248.412544)
			(xy 80.600877 -248.460076) (xy 80.608696 -248.509439) (xy 80.609186 -248.534428) (xy 80.914743 -248.534428)
			(xy 80.918838 -248.4837) (xy 80.931017 -248.434286) (xy 80.950965 -248.387466) (xy 80.978166 -248.344452)
			(xy 81.011914 -248.306358) (xy 81.051336 -248.274171) (xy 81.09541 -248.248725) (xy 81.142996 -248.230678)
			(xy 81.19286 -248.220498) (xy 81.243712 -248.218449) (xy 81.294233 -248.224583) (xy 81.343117 -248.238743)
			(xy 81.389096 -248.26056) (xy 81.43098 -248.28947) (xy 81.467684 -248.324725) (xy 81.498257 -248.365411)
			(xy 81.521908 -248.410474) (xy 81.538024 -248.458748) (xy 81.546188 -248.508982) (xy 81.5467 -248.534428)
			(xy 81.854797 -248.534428) (xy 81.858892 -248.4837) (xy 81.871071 -248.434286) (xy 81.891019 -248.387466)
			(xy 81.91822 -248.344452) (xy 81.951968 -248.306358) (xy 81.99139 -248.274171) (xy 82.035464 -248.248725)
			(xy 82.08305 -248.230678) (xy 82.132914 -248.220498) (xy 82.183766 -248.218449) (xy 82.234287 -248.224583)
			(xy 82.283171 -248.238743) (xy 82.32915 -248.26056) (xy 82.371034 -248.28947) (xy 82.407738 -248.324725)
			(xy 82.438311 -248.365411) (xy 82.461962 -248.410474) (xy 82.478078 -248.458748) (xy 82.486242 -248.508982)
			(xy 82.486754 -248.534428) (xy 82.486251 -248.559417) (xy 82.793568 -248.559417) (xy 82.793568 -248.509439)
			(xy 82.801387 -248.460076) (xy 82.816831 -248.412544) (xy 82.839521 -248.368012) (xy 82.868897 -248.327579)
			(xy 82.904237 -248.292239) (xy 82.94467 -248.262863) (xy 82.989202 -248.240173) (xy 83.036734 -248.224729)
			(xy 83.086097 -248.21691) (xy 83.136075 -248.21691) (xy 83.185438 -248.224729) (xy 83.23297 -248.240173)
			(xy 83.277502 -248.262863) (xy 83.317935 -248.292239) (xy 83.353275 -248.327579) (xy 83.382651 -248.368012)
			(xy 83.405341 -248.412544) (xy 83.420785 -248.460076) (xy 83.428604 -248.509439) (xy 83.429094 -248.534428)
			(xy 83.734905 -248.534428) (xy 83.739 -248.4837) (xy 83.751179 -248.434286) (xy 83.771127 -248.387466)
			(xy 83.798328 -248.344452) (xy 83.832076 -248.306358) (xy 83.871498 -248.274171) (xy 83.915572 -248.248725)
			(xy 83.963158 -248.230678) (xy 84.013022 -248.220498) (xy 84.063874 -248.218449) (xy 84.114395 -248.224583)
			(xy 84.163279 -248.238743) (xy 84.209258 -248.26056) (xy 84.251142 -248.28947) (xy 84.287846 -248.324725)
			(xy 84.318419 -248.365411) (xy 84.34207 -248.410474) (xy 84.358186 -248.458748) (xy 84.36635 -248.508982)
			(xy 84.366862 -248.534428) (xy 84.366359 -248.559417) (xy 84.673422 -248.559417) (xy 84.673422 -248.509439)
			(xy 84.681241 -248.460076) (xy 84.696685 -248.412544) (xy 84.719375 -248.368012) (xy 84.748751 -248.327579)
			(xy 84.784091 -248.292239) (xy 84.824524 -248.262863) (xy 84.869056 -248.240173) (xy 84.916588 -248.224729)
			(xy 84.965951 -248.21691) (xy 85.015929 -248.21691) (xy 85.065292 -248.224729) (xy 85.112824 -248.240173)
			(xy 85.157356 -248.262863) (xy 85.197789 -248.292239) (xy 85.233129 -248.327579) (xy 85.262505 -248.368012)
			(xy 85.285195 -248.412544) (xy 85.300639 -248.460076) (xy 85.308458 -248.509439) (xy 85.308948 -248.534428)
			(xy 85.614759 -248.534428) (xy 85.618854 -248.4837) (xy 85.631033 -248.434286) (xy 85.650981 -248.387466)
			(xy 85.678182 -248.344452) (xy 85.71193 -248.306358) (xy 85.751352 -248.274171) (xy 85.795426 -248.248725)
			(xy 85.843012 -248.230678) (xy 85.892876 -248.220498) (xy 85.943728 -248.218449) (xy 85.994249 -248.224583)
			(xy 86.043133 -248.238743) (xy 86.089112 -248.26056) (xy 86.130996 -248.28947) (xy 86.1677 -248.324725)
			(xy 86.198273 -248.365411) (xy 86.221924 -248.410474) (xy 86.23804 -248.458748) (xy 86.246204 -248.508982)
			(xy 86.246716 -248.534428) (xy 86.246213 -248.559417) (xy 86.55353 -248.559417) (xy 86.55353 -248.509439)
			(xy 86.561349 -248.460076) (xy 86.576793 -248.412544) (xy 86.599483 -248.368012) (xy 86.628859 -248.327579)
			(xy 86.664199 -248.292239) (xy 86.704632 -248.262863) (xy 86.749164 -248.240173) (xy 86.796696 -248.224729)
			(xy 86.846059 -248.21691) (xy 86.896037 -248.21691) (xy 86.9454 -248.224729) (xy 86.992932 -248.240173)
			(xy 87.037464 -248.262863) (xy 87.077897 -248.292239) (xy 87.113237 -248.327579) (xy 87.142613 -248.368012)
			(xy 87.165303 -248.412544) (xy 87.180747 -248.460076) (xy 87.188566 -248.509439) (xy 87.189056 -248.534428)
			(xy 87.494867 -248.534428) (xy 87.498962 -248.4837) (xy 87.511141 -248.434286) (xy 87.531089 -248.387466)
			(xy 87.55829 -248.344452) (xy 87.592038 -248.306358) (xy 87.63146 -248.274171) (xy 87.675534 -248.248725)
			(xy 87.72312 -248.230678) (xy 87.772984 -248.220498) (xy 87.823836 -248.218449) (xy 87.874357 -248.224583)
			(xy 87.923241 -248.238743) (xy 87.96922 -248.26056) (xy 88.011104 -248.28947) (xy 88.047808 -248.324725)
			(xy 88.078381 -248.365411) (xy 88.102032 -248.410474) (xy 88.118148 -248.458748) (xy 88.126312 -248.508982)
			(xy 88.126824 -248.534428) (xy 88.434921 -248.534428) (xy 88.439016 -248.4837) (xy 88.451195 -248.434286)
			(xy 88.471143 -248.387466) (xy 88.498344 -248.344452) (xy 88.532092 -248.306358) (xy 88.571514 -248.274171)
			(xy 88.615588 -248.248725) (xy 88.663174 -248.230678) (xy 88.713038 -248.220498) (xy 88.76389 -248.218449)
			(xy 88.814411 -248.224583) (xy 88.863295 -248.238743) (xy 88.909274 -248.26056) (xy 88.951158 -248.28947)
			(xy 88.987862 -248.324725) (xy 89.018435 -248.365411) (xy 89.042086 -248.410474) (xy 89.058202 -248.458748)
			(xy 89.066366 -248.508982) (xy 89.066878 -248.534428) (xy 89.066375 -248.559417) (xy 89.373438 -248.559417)
			(xy 89.373438 -248.509439) (xy 89.381257 -248.460076) (xy 89.396701 -248.412544) (xy 89.419391 -248.368012)
			(xy 89.448767 -248.327579) (xy 89.484107 -248.292239) (xy 89.52454 -248.262863) (xy 89.569072 -248.240173)
			(xy 89.616604 -248.224729) (xy 89.665967 -248.21691) (xy 89.715945 -248.21691) (xy 89.765308 -248.224729)
			(xy 89.81284 -248.240173) (xy 89.857372 -248.262863) (xy 89.897805 -248.292239) (xy 89.933145 -248.327579)
			(xy 89.962521 -248.368012) (xy 89.985211 -248.412544) (xy 90.000655 -248.460076) (xy 90.008474 -248.509439)
			(xy 90.008964 -248.534428) (xy 90.314775 -248.534428) (xy 90.31887 -248.4837) (xy 90.331049 -248.434286)
			(xy 90.350997 -248.387466) (xy 90.378198 -248.344452) (xy 90.411946 -248.306358) (xy 90.451368 -248.274171)
			(xy 90.495442 -248.248725) (xy 90.543028 -248.230678) (xy 90.592892 -248.220498) (xy 90.643744 -248.218449)
			(xy 90.694265 -248.224583) (xy 90.743149 -248.238743) (xy 90.789128 -248.26056) (xy 90.831012 -248.28947)
			(xy 90.867716 -248.324725) (xy 90.898289 -248.365411) (xy 90.92194 -248.410474) (xy 90.938056 -248.458748)
			(xy 90.94622 -248.508982) (xy 90.946732 -248.534428) (xy 90.946229 -248.559417) (xy 91.253546 -248.559417)
			(xy 91.253546 -248.509439) (xy 91.261365 -248.460076) (xy 91.276809 -248.412544) (xy 91.299499 -248.368012)
			(xy 91.328875 -248.327579) (xy 91.364215 -248.292239) (xy 91.404648 -248.262863) (xy 91.44918 -248.240173)
			(xy 91.496712 -248.224729) (xy 91.546075 -248.21691) (xy 91.596053 -248.21691) (xy 91.645416 -248.224729)
			(xy 91.692948 -248.240173) (xy 91.73748 -248.262863) (xy 91.777913 -248.292239) (xy 91.813253 -248.327579)
			(xy 91.842629 -248.368012) (xy 91.865319 -248.412544) (xy 91.880763 -248.460076) (xy 91.888582 -248.509439)
			(xy 91.889072 -248.534428) (xy 92.194883 -248.534428) (xy 92.198978 -248.4837) (xy 92.211157 -248.434286)
			(xy 92.231105 -248.387466) (xy 92.258306 -248.344452) (xy 92.292054 -248.306358) (xy 92.331476 -248.274171)
			(xy 92.37555 -248.248725) (xy 92.423136 -248.230678) (xy 92.473 -248.220498) (xy 92.523852 -248.218449)
			(xy 92.574373 -248.224583) (xy 92.623257 -248.238743) (xy 92.669236 -248.26056) (xy 92.71112 -248.28947)
			(xy 92.747824 -248.324725) (xy 92.778397 -248.365411) (xy 92.802048 -248.410474) (xy 92.818164 -248.458748)
			(xy 92.826328 -248.508982) (xy 92.82684 -248.534428) (xy 92.826337 -248.559417) (xy 93.1334 -248.559417)
			(xy 93.1334 -248.509439) (xy 93.141219 -248.460076) (xy 93.156663 -248.412544) (xy 93.179353 -248.368012)
			(xy 93.208729 -248.327579) (xy 93.244069 -248.292239) (xy 93.284502 -248.262863) (xy 93.329034 -248.240173)
			(xy 93.376566 -248.224729) (xy 93.425929 -248.21691) (xy 93.475907 -248.21691) (xy 93.52527 -248.224729)
			(xy 93.572802 -248.240173) (xy 93.617334 -248.262863) (xy 93.657767 -248.292239) (xy 93.693107 -248.327579)
			(xy 93.722483 -248.368012) (xy 93.745173 -248.412544) (xy 93.760617 -248.460076) (xy 93.768436 -248.509439)
			(xy 93.768926 -248.534428) (xy 94.074737 -248.534428) (xy 94.078832 -248.4837) (xy 94.091011 -248.434286)
			(xy 94.110959 -248.387466) (xy 94.13816 -248.344452) (xy 94.171908 -248.306358) (xy 94.21133 -248.274171)
			(xy 94.255404 -248.248725) (xy 94.30299 -248.230678) (xy 94.352854 -248.220498) (xy 94.403706 -248.218449)
			(xy 94.454227 -248.224583) (xy 94.503111 -248.238743) (xy 94.54909 -248.26056) (xy 94.590974 -248.28947)
			(xy 94.627678 -248.324725) (xy 94.658251 -248.365411) (xy 94.681902 -248.410474) (xy 94.698018 -248.458748)
			(xy 94.706182 -248.508982) (xy 94.706694 -248.534428) (xy 95.014791 -248.534428) (xy 95.018886 -248.4837)
			(xy 95.031065 -248.434286) (xy 95.051013 -248.387466) (xy 95.078214 -248.344452) (xy 95.111962 -248.306358)
			(xy 95.151384 -248.274171) (xy 95.195458 -248.248725) (xy 95.243044 -248.230678) (xy 95.292908 -248.220498)
			(xy 95.34376 -248.218449) (xy 95.394281 -248.224583) (xy 95.443165 -248.238743) (xy 95.489144 -248.26056)
			(xy 95.531028 -248.28947) (xy 95.567732 -248.324725) (xy 95.598305 -248.365411) (xy 95.621956 -248.410474)
			(xy 95.638072 -248.458748) (xy 95.646236 -248.508982) (xy 95.646748 -248.534428) (xy 95.646236 -248.559874)
			(xy 95.638072 -248.610108) (xy 95.621956 -248.658382) (xy 95.598305 -248.703445) (xy 95.567732 -248.744131)
			(xy 95.531028 -248.779386) (xy 95.489144 -248.808296) (xy 95.443165 -248.830113) (xy 95.394281 -248.844273)
			(xy 95.34376 -248.850407) (xy 95.292908 -248.848358) (xy 95.243044 -248.838178) (xy 95.195458 -248.820131)
			(xy 95.151384 -248.794685) (xy 95.111962 -248.762498) (xy 95.078214 -248.724404) (xy 95.051013 -248.68139)
			(xy 95.031065 -248.63457) (xy 95.018886 -248.585156) (xy 95.014791 -248.534428) (xy 94.706694 -248.534428)
			(xy 94.706182 -248.559874) (xy 94.698018 -248.610108) (xy 94.681902 -248.658382) (xy 94.658251 -248.703445)
			(xy 94.627678 -248.744131) (xy 94.590974 -248.779386) (xy 94.54909 -248.808296) (xy 94.503111 -248.830113)
			(xy 94.454227 -248.844273) (xy 94.403706 -248.850407) (xy 94.352854 -248.848358) (xy 94.30299 -248.838178)
			(xy 94.255404 -248.820131) (xy 94.21133 -248.794685) (xy 94.171908 -248.762498) (xy 94.13816 -248.724404)
			(xy 94.110959 -248.68139) (xy 94.091011 -248.63457) (xy 94.078832 -248.585156) (xy 94.074737 -248.534428)
			(xy 93.768926 -248.534428) (xy 93.768436 -248.559417) (xy 93.760617 -248.60878) (xy 93.745173 -248.656312)
			(xy 93.722483 -248.700844) (xy 93.693107 -248.741277) (xy 93.657767 -248.776617) (xy 93.617334 -248.805993)
			(xy 93.572802 -248.828683) (xy 93.52527 -248.844127) (xy 93.475907 -248.851946) (xy 93.425929 -248.851946)
			(xy 93.376566 -248.844127) (xy 93.329034 -248.828683) (xy 93.284502 -248.805993) (xy 93.244069 -248.776617)
			(xy 93.208729 -248.741277) (xy 93.179353 -248.700844) (xy 93.156663 -248.656312) (xy 93.141219 -248.60878)
			(xy 93.1334 -248.559417) (xy 92.826337 -248.559417) (xy 92.826328 -248.559874) (xy 92.818164 -248.610108)
			(xy 92.802048 -248.658382) (xy 92.778397 -248.703445) (xy 92.747824 -248.744131) (xy 92.71112 -248.779386)
			(xy 92.669236 -248.808296) (xy 92.623257 -248.830113) (xy 92.574373 -248.844273) (xy 92.523852 -248.850407)
			(xy 92.473 -248.848358) (xy 92.423136 -248.838178) (xy 92.37555 -248.820131) (xy 92.331476 -248.794685)
			(xy 92.292054 -248.762498) (xy 92.258306 -248.724404) (xy 92.231105 -248.68139) (xy 92.211157 -248.63457)
			(xy 92.198978 -248.585156) (xy 92.194883 -248.534428) (xy 91.889072 -248.534428) (xy 91.888582 -248.559417)
			(xy 91.880763 -248.60878) (xy 91.865319 -248.656312) (xy 91.842629 -248.700844) (xy 91.813253 -248.741277)
			(xy 91.777913 -248.776617) (xy 91.73748 -248.805993) (xy 91.692948 -248.828683) (xy 91.645416 -248.844127)
			(xy 91.596053 -248.851946) (xy 91.546075 -248.851946) (xy 91.496712 -248.844127) (xy 91.44918 -248.828683)
			(xy 91.404648 -248.805993) (xy 91.364215 -248.776617) (xy 91.328875 -248.741277) (xy 91.299499 -248.700844)
			(xy 91.276809 -248.656312) (xy 91.261365 -248.60878) (xy 91.253546 -248.559417) (xy 90.946229 -248.559417)
			(xy 90.94622 -248.559874) (xy 90.938056 -248.610108) (xy 90.92194 -248.658382) (xy 90.898289 -248.703445)
			(xy 90.867716 -248.744131) (xy 90.831012 -248.779386) (xy 90.789128 -248.808296) (xy 90.743149 -248.830113)
			(xy 90.694265 -248.844273) (xy 90.643744 -248.850407) (xy 90.592892 -248.848358) (xy 90.543028 -248.838178)
			(xy 90.495442 -248.820131) (xy 90.451368 -248.794685) (xy 90.411946 -248.762498) (xy 90.378198 -248.724404)
			(xy 90.350997 -248.68139) (xy 90.331049 -248.63457) (xy 90.31887 -248.585156) (xy 90.314775 -248.534428)
			(xy 90.008964 -248.534428) (xy 90.008474 -248.559417) (xy 90.000655 -248.60878) (xy 89.985211 -248.656312)
			(xy 89.962521 -248.700844) (xy 89.933145 -248.741277) (xy 89.897805 -248.776617) (xy 89.857372 -248.805993)
			(xy 89.81284 -248.828683) (xy 89.765308 -248.844127) (xy 89.715945 -248.851946) (xy 89.665967 -248.851946)
			(xy 89.616604 -248.844127) (xy 89.569072 -248.828683) (xy 89.52454 -248.805993) (xy 89.484107 -248.776617)
			(xy 89.448767 -248.741277) (xy 89.419391 -248.700844) (xy 89.396701 -248.656312) (xy 89.381257 -248.60878)
			(xy 89.373438 -248.559417) (xy 89.066375 -248.559417) (xy 89.066366 -248.559874) (xy 89.058202 -248.610108)
			(xy 89.042086 -248.658382) (xy 89.018435 -248.703445) (xy 88.987862 -248.744131) (xy 88.951158 -248.779386)
			(xy 88.909274 -248.808296) (xy 88.863295 -248.830113) (xy 88.814411 -248.844273) (xy 88.76389 -248.850407)
			(xy 88.713038 -248.848358) (xy 88.663174 -248.838178) (xy 88.615588 -248.820131) (xy 88.571514 -248.794685)
			(xy 88.532092 -248.762498) (xy 88.498344 -248.724404) (xy 88.471143 -248.68139) (xy 88.451195 -248.63457)
			(xy 88.439016 -248.585156) (xy 88.434921 -248.534428) (xy 88.126824 -248.534428) (xy 88.126312 -248.559874)
			(xy 88.118148 -248.610108) (xy 88.102032 -248.658382) (xy 88.078381 -248.703445) (xy 88.047808 -248.744131)
			(xy 88.011104 -248.779386) (xy 87.96922 -248.808296) (xy 87.923241 -248.830113) (xy 87.874357 -248.844273)
			(xy 87.823836 -248.850407) (xy 87.772984 -248.848358) (xy 87.72312 -248.838178) (xy 87.675534 -248.820131)
			(xy 87.63146 -248.794685) (xy 87.592038 -248.762498) (xy 87.55829 -248.724404) (xy 87.531089 -248.68139)
			(xy 87.511141 -248.63457) (xy 87.498962 -248.585156) (xy 87.494867 -248.534428) (xy 87.189056 -248.534428)
			(xy 87.188566 -248.559417) (xy 87.180747 -248.60878) (xy 87.165303 -248.656312) (xy 87.142613 -248.700844)
			(xy 87.113237 -248.741277) (xy 87.077897 -248.776617) (xy 87.037464 -248.805993) (xy 86.992932 -248.828683)
			(xy 86.9454 -248.844127) (xy 86.896037 -248.851946) (xy 86.846059 -248.851946) (xy 86.796696 -248.844127)
			(xy 86.749164 -248.828683) (xy 86.704632 -248.805993) (xy 86.664199 -248.776617) (xy 86.628859 -248.741277)
			(xy 86.599483 -248.700844) (xy 86.576793 -248.656312) (xy 86.561349 -248.60878) (xy 86.55353 -248.559417)
			(xy 86.246213 -248.559417) (xy 86.246204 -248.559874) (xy 86.23804 -248.610108) (xy 86.221924 -248.658382)
			(xy 86.198273 -248.703445) (xy 86.1677 -248.744131) (xy 86.130996 -248.779386) (xy 86.089112 -248.808296)
			(xy 86.043133 -248.830113) (xy 85.994249 -248.844273) (xy 85.943728 -248.850407) (xy 85.892876 -248.848358)
			(xy 85.843012 -248.838178) (xy 85.795426 -248.820131) (xy 85.751352 -248.794685) (xy 85.71193 -248.762498)
			(xy 85.678182 -248.724404) (xy 85.650981 -248.68139) (xy 85.631033 -248.63457) (xy 85.618854 -248.585156)
			(xy 85.614759 -248.534428) (xy 85.308948 -248.534428) (xy 85.308458 -248.559417) (xy 85.300639 -248.60878)
			(xy 85.285195 -248.656312) (xy 85.262505 -248.700844) (xy 85.233129 -248.741277) (xy 85.197789 -248.776617)
			(xy 85.157356 -248.805993) (xy 85.112824 -248.828683) (xy 85.065292 -248.844127) (xy 85.015929 -248.851946)
			(xy 84.965951 -248.851946) (xy 84.916588 -248.844127) (xy 84.869056 -248.828683) (xy 84.824524 -248.805993)
			(xy 84.784091 -248.776617) (xy 84.748751 -248.741277) (xy 84.719375 -248.700844) (xy 84.696685 -248.656312)
			(xy 84.681241 -248.60878) (xy 84.673422 -248.559417) (xy 84.366359 -248.559417) (xy 84.36635 -248.559874)
			(xy 84.358186 -248.610108) (xy 84.34207 -248.658382) (xy 84.318419 -248.703445) (xy 84.287846 -248.744131)
			(xy 84.251142 -248.779386) (xy 84.209258 -248.808296) (xy 84.163279 -248.830113) (xy 84.114395 -248.844273)
			(xy 84.063874 -248.850407) (xy 84.013022 -248.848358) (xy 83.963158 -248.838178) (xy 83.915572 -248.820131)
			(xy 83.871498 -248.794685) (xy 83.832076 -248.762498) (xy 83.798328 -248.724404) (xy 83.771127 -248.68139)
			(xy 83.751179 -248.63457) (xy 83.739 -248.585156) (xy 83.734905 -248.534428) (xy 83.429094 -248.534428)
			(xy 83.428604 -248.559417) (xy 83.420785 -248.60878) (xy 83.405341 -248.656312) (xy 83.382651 -248.700844)
			(xy 83.353275 -248.741277) (xy 83.317935 -248.776617) (xy 83.277502 -248.805993) (xy 83.23297 -248.828683)
			(xy 83.185438 -248.844127) (xy 83.136075 -248.851946) (xy 83.086097 -248.851946) (xy 83.036734 -248.844127)
			(xy 82.989202 -248.828683) (xy 82.94467 -248.805993) (xy 82.904237 -248.776617) (xy 82.868897 -248.741277)
			(xy 82.839521 -248.700844) (xy 82.816831 -248.656312) (xy 82.801387 -248.60878) (xy 82.793568 -248.559417)
			(xy 82.486251 -248.559417) (xy 82.486242 -248.559874) (xy 82.478078 -248.610108) (xy 82.461962 -248.658382)
			(xy 82.438311 -248.703445) (xy 82.407738 -248.744131) (xy 82.371034 -248.779386) (xy 82.32915 -248.808296)
			(xy 82.283171 -248.830113) (xy 82.234287 -248.844273) (xy 82.183766 -248.850407) (xy 82.132914 -248.848358)
			(xy 82.08305 -248.838178) (xy 82.035464 -248.820131) (xy 81.99139 -248.794685) (xy 81.951968 -248.762498)
			(xy 81.91822 -248.724404) (xy 81.891019 -248.68139) (xy 81.871071 -248.63457) (xy 81.858892 -248.585156)
			(xy 81.854797 -248.534428) (xy 81.5467 -248.534428) (xy 81.546188 -248.559874) (xy 81.538024 -248.610108)
			(xy 81.521908 -248.658382) (xy 81.498257 -248.703445) (xy 81.467684 -248.744131) (xy 81.43098 -248.779386)
			(xy 81.389096 -248.808296) (xy 81.343117 -248.830113) (xy 81.294233 -248.844273) (xy 81.243712 -248.850407)
			(xy 81.19286 -248.848358) (xy 81.142996 -248.838178) (xy 81.09541 -248.820131) (xy 81.051336 -248.794685)
			(xy 81.011914 -248.762498) (xy 80.978166 -248.724404) (xy 80.950965 -248.68139) (xy 80.931017 -248.63457)
			(xy 80.918838 -248.585156) (xy 80.914743 -248.534428) (xy 80.609186 -248.534428) (xy 80.608696 -248.559417)
			(xy 80.600877 -248.60878) (xy 80.585433 -248.656312) (xy 80.562743 -248.700844) (xy 80.533367 -248.741277)
			(xy 80.498027 -248.776617) (xy 80.457594 -248.805993) (xy 80.413062 -248.828683) (xy 80.36553 -248.844127)
			(xy 80.316167 -248.851946) (xy 80.266189 -248.851946) (xy 80.216826 -248.844127) (xy 80.169294 -248.828683)
			(xy 80.124762 -248.805993) (xy 80.084329 -248.776617) (xy 80.048989 -248.741277) (xy 80.019613 -248.700844)
			(xy 79.996923 -248.656312) (xy 79.981479 -248.60878) (xy 79.97366 -248.559417) (xy 79.53248 -248.559417)
			(xy 79.53248 -249.369423) (xy 80.44356 -249.369423) (xy 80.44356 -249.319445) (xy 80.451379 -249.270082)
			(xy 80.466823 -249.22255) (xy 80.489513 -249.178018) (xy 80.518889 -249.137585) (xy 80.554229 -249.102245)
			(xy 80.594662 -249.072869) (xy 80.639194 -249.050179) (xy 80.686726 -249.034735) (xy 80.736089 -249.026916)
			(xy 80.786067 -249.026916) (xy 80.83543 -249.034735) (xy 80.882962 -249.050179) (xy 80.927494 -249.072869)
			(xy 80.967927 -249.102245) (xy 81.003267 -249.137585) (xy 81.032643 -249.178018) (xy 81.055333 -249.22255)
			(xy 81.070777 -249.270082) (xy 81.078596 -249.319445) (xy 81.079086 -249.344434) (xy 81.078596 -249.369423)
			(xy 81.383614 -249.369423) (xy 81.383614 -249.319445) (xy 81.391433 -249.270082) (xy 81.406877 -249.22255)
			(xy 81.429567 -249.178018) (xy 81.458943 -249.137585) (xy 81.494283 -249.102245) (xy 81.534716 -249.072869)
			(xy 81.579248 -249.050179) (xy 81.62678 -249.034735) (xy 81.676143 -249.026916) (xy 81.726121 -249.026916)
			(xy 81.775484 -249.034735) (xy 81.823016 -249.050179) (xy 81.867548 -249.072869) (xy 81.907981 -249.102245)
			(xy 81.943321 -249.137585) (xy 81.972697 -249.178018) (xy 81.995387 -249.22255) (xy 82.010831 -249.270082)
			(xy 82.01865 -249.319445) (xy 82.01914 -249.344434) (xy 82.324697 -249.344434) (xy 82.328792 -249.293706)
			(xy 82.340971 -249.244292) (xy 82.360919 -249.197472) (xy 82.38812 -249.154458) (xy 82.421868 -249.116364)
			(xy 82.46129 -249.084177) (xy 82.505364 -249.058731) (xy 82.55295 -249.040684) (xy 82.602814 -249.030504)
			(xy 82.653666 -249.028455) (xy 82.704187 -249.034589) (xy 82.753071 -249.048749) (xy 82.79905 -249.070566)
			(xy 82.840934 -249.099476) (xy 82.877638 -249.134731) (xy 82.908211 -249.175417) (xy 82.931862 -249.22048)
			(xy 82.947978 -249.268754) (xy 82.956142 -249.318988) (xy 82.956654 -249.344434) (xy 82.956151 -249.369423)
			(xy 83.263468 -249.369423) (xy 83.263468 -249.319445) (xy 83.271287 -249.270082) (xy 83.286731 -249.22255)
			(xy 83.309421 -249.178018) (xy 83.338797 -249.137585) (xy 83.374137 -249.102245) (xy 83.41457 -249.072869)
			(xy 83.459102 -249.050179) (xy 83.506634 -249.034735) (xy 83.555997 -249.026916) (xy 83.605975 -249.026916)
			(xy 83.655338 -249.034735) (xy 83.70287 -249.050179) (xy 83.747402 -249.072869) (xy 83.787835 -249.102245)
			(xy 83.823175 -249.137585) (xy 83.852551 -249.178018) (xy 83.875241 -249.22255) (xy 83.890685 -249.270082)
			(xy 83.898504 -249.319445) (xy 83.898994 -249.344434) (xy 83.898504 -249.369423) (xy 84.203522 -249.369423)
			(xy 84.203522 -249.319445) (xy 84.211341 -249.270082) (xy 84.226785 -249.22255) (xy 84.249475 -249.178018)
			(xy 84.278851 -249.137585) (xy 84.314191 -249.102245) (xy 84.354624 -249.072869) (xy 84.399156 -249.050179)
			(xy 84.446688 -249.034735) (xy 84.496051 -249.026916) (xy 84.546029 -249.026916) (xy 84.595392 -249.034735)
			(xy 84.642924 -249.050179) (xy 84.687456 -249.072869) (xy 84.727889 -249.102245) (xy 84.763229 -249.137585)
			(xy 84.792605 -249.178018) (xy 84.815295 -249.22255) (xy 84.830739 -249.270082) (xy 84.838558 -249.319445)
			(xy 84.839048 -249.344434) (xy 85.144859 -249.344434) (xy 85.148954 -249.293706) (xy 85.161133 -249.244292)
			(xy 85.181081 -249.197472) (xy 85.208282 -249.154458) (xy 85.24203 -249.116364) (xy 85.281452 -249.084177)
			(xy 85.325526 -249.058731) (xy 85.373112 -249.040684) (xy 85.422976 -249.030504) (xy 85.473828 -249.028455)
			(xy 85.524349 -249.034589) (xy 85.573233 -249.048749) (xy 85.619212 -249.070566) (xy 85.661096 -249.099476)
			(xy 85.6978 -249.134731) (xy 85.728373 -249.175417) (xy 85.752024 -249.22048) (xy 85.76814 -249.268754)
			(xy 85.776304 -249.318988) (xy 85.776816 -249.344434) (xy 85.776313 -249.369423) (xy 87.02343 -249.369423)
			(xy 87.02343 -249.319445) (xy 87.031249 -249.270082) (xy 87.046693 -249.22255) (xy 87.069383 -249.178018)
			(xy 87.098759 -249.137585) (xy 87.134099 -249.102245) (xy 87.174532 -249.072869) (xy 87.219064 -249.050179)
			(xy 87.266596 -249.034735) (xy 87.315959 -249.026916) (xy 87.365937 -249.026916) (xy 87.4153 -249.034735)
			(xy 87.462832 -249.050179) (xy 87.507364 -249.072869) (xy 87.547797 -249.102245) (xy 87.583137 -249.137585)
			(xy 87.612513 -249.178018) (xy 87.635203 -249.22255) (xy 87.650647 -249.270082) (xy 87.658466 -249.319445)
			(xy 87.658956 -249.344434) (xy 87.658466 -249.369423) (xy 87.963484 -249.369423) (xy 87.963484 -249.319445)
			(xy 87.971303 -249.270082) (xy 87.986747 -249.22255) (xy 88.009437 -249.178018) (xy 88.038813 -249.137585)
			(xy 88.074153 -249.102245) (xy 88.114586 -249.072869) (xy 88.159118 -249.050179) (xy 88.20665 -249.034735)
			(xy 88.256013 -249.026916) (xy 88.305991 -249.026916) (xy 88.355354 -249.034735) (xy 88.402886 -249.050179)
			(xy 88.447418 -249.072869) (xy 88.487851 -249.102245) (xy 88.523191 -249.137585) (xy 88.552567 -249.178018)
			(xy 88.575257 -249.22255) (xy 88.590701 -249.270082) (xy 88.59852 -249.319445) (xy 88.59901 -249.344434)
			(xy 88.904821 -249.344434) (xy 88.908916 -249.293706) (xy 88.921095 -249.244292) (xy 88.941043 -249.197472)
			(xy 88.968244 -249.154458) (xy 89.001992 -249.116364) (xy 89.041414 -249.084177) (xy 89.085488 -249.058731)
			(xy 89.133074 -249.040684) (xy 89.182938 -249.030504) (xy 89.23379 -249.028455) (xy 89.284311 -249.034589)
			(xy 89.333195 -249.048749) (xy 89.379174 -249.070566) (xy 89.421058 -249.099476) (xy 89.457762 -249.134731)
			(xy 89.488335 -249.175417) (xy 89.511986 -249.22048) (xy 89.528102 -249.268754) (xy 89.536266 -249.318988)
			(xy 89.536778 -249.344434) (xy 89.536275 -249.369423) (xy 89.843592 -249.369423) (xy 89.843592 -249.319445)
			(xy 89.851411 -249.270082) (xy 89.866855 -249.22255) (xy 89.889545 -249.178018) (xy 89.918921 -249.137585)
			(xy 89.954261 -249.102245) (xy 89.994694 -249.072869) (xy 90.039226 -249.050179) (xy 90.086758 -249.034735)
			(xy 90.136121 -249.026916) (xy 90.186099 -249.026916) (xy 90.235462 -249.034735) (xy 90.282994 -249.050179)
			(xy 90.327526 -249.072869) (xy 90.367959 -249.102245) (xy 90.403299 -249.137585) (xy 90.432675 -249.178018)
			(xy 90.455365 -249.22255) (xy 90.470809 -249.270082) (xy 90.478628 -249.319445) (xy 90.479118 -249.344434)
			(xy 90.478628 -249.369423) (xy 90.783392 -249.369423) (xy 90.783392 -249.319445) (xy 90.791211 -249.270082)
			(xy 90.806655 -249.22255) (xy 90.829345 -249.178018) (xy 90.858721 -249.137585) (xy 90.894061 -249.102245)
			(xy 90.934494 -249.072869) (xy 90.979026 -249.050179) (xy 91.026558 -249.034735) (xy 91.075921 -249.026916)
			(xy 91.125899 -249.026916) (xy 91.175262 -249.034735) (xy 91.222794 -249.050179) (xy 91.267326 -249.072869)
			(xy 91.307759 -249.102245) (xy 91.343099 -249.137585) (xy 91.372475 -249.178018) (xy 91.395165 -249.22255)
			(xy 91.410609 -249.270082) (xy 91.418428 -249.319445) (xy 91.418918 -249.344434) (xy 91.724729 -249.344434)
			(xy 91.728824 -249.293706) (xy 91.741003 -249.244292) (xy 91.760951 -249.197472) (xy 91.788152 -249.154458)
			(xy 91.8219 -249.116364) (xy 91.861322 -249.084177) (xy 91.905396 -249.058731) (xy 91.952982 -249.040684)
			(xy 92.002846 -249.030504) (xy 92.053698 -249.028455) (xy 92.104219 -249.034589) (xy 92.153103 -249.048749)
			(xy 92.199082 -249.070566) (xy 92.240966 -249.099476) (xy 92.27767 -249.134731) (xy 92.308243 -249.175417)
			(xy 92.331894 -249.22048) (xy 92.34801 -249.268754) (xy 92.356174 -249.318988) (xy 92.356686 -249.344434)
			(xy 92.356183 -249.369423) (xy 93.603554 -249.369423) (xy 93.603554 -249.319445) (xy 93.611373 -249.270082)
			(xy 93.626817 -249.22255) (xy 93.649507 -249.178018) (xy 93.678883 -249.137585) (xy 93.714223 -249.102245)
			(xy 93.754656 -249.072869) (xy 93.799188 -249.050179) (xy 93.84672 -249.034735) (xy 93.896083 -249.026916)
			(xy 93.946061 -249.026916) (xy 93.995424 -249.034735) (xy 94.042956 -249.050179) (xy 94.087488 -249.072869)
			(xy 94.127921 -249.102245) (xy 94.163261 -249.137585) (xy 94.192637 -249.178018) (xy 94.215327 -249.22255)
			(xy 94.230771 -249.270082) (xy 94.23859 -249.319445) (xy 94.23908 -249.344434) (xy 94.23859 -249.369423)
			(xy 94.543608 -249.369423) (xy 94.543608 -249.319445) (xy 94.551427 -249.270082) (xy 94.566871 -249.22255)
			(xy 94.589561 -249.178018) (xy 94.618937 -249.137585) (xy 94.654277 -249.102245) (xy 94.69471 -249.072869)
			(xy 94.739242 -249.050179) (xy 94.786774 -249.034735) (xy 94.836137 -249.026916) (xy 94.886115 -249.026916)
			(xy 94.935478 -249.034735) (xy 94.98301 -249.050179) (xy 95.027542 -249.072869) (xy 95.067975 -249.102245)
			(xy 95.103315 -249.137585) (xy 95.132691 -249.178018) (xy 95.155381 -249.22255) (xy 95.170825 -249.270082)
			(xy 95.178644 -249.319445) (xy 95.179134 -249.344434) (xy 95.178644 -249.369423) (xy 95.170825 -249.418786)
			(xy 95.155381 -249.466318) (xy 95.132691 -249.51085) (xy 95.103315 -249.551283) (xy 95.067975 -249.586623)
			(xy 95.027542 -249.615999) (xy 94.98301 -249.638689) (xy 94.935478 -249.654133) (xy 94.886115 -249.661952)
			(xy 94.836137 -249.661952) (xy 94.786774 -249.654133) (xy 94.739242 -249.638689) (xy 94.69471 -249.615999)
			(xy 94.654277 -249.586623) (xy 94.618937 -249.551283) (xy 94.589561 -249.51085) (xy 94.566871 -249.466318)
			(xy 94.551427 -249.418786) (xy 94.543608 -249.369423) (xy 94.23859 -249.369423) (xy 94.230771 -249.418786)
			(xy 94.215327 -249.466318) (xy 94.192637 -249.51085) (xy 94.163261 -249.551283) (xy 94.127921 -249.586623)
			(xy 94.087488 -249.615999) (xy 94.042956 -249.638689) (xy 93.995424 -249.654133) (xy 93.946061 -249.661952)
			(xy 93.896083 -249.661952) (xy 93.84672 -249.654133) (xy 93.799188 -249.638689) (xy 93.754656 -249.615999)
			(xy 93.714223 -249.586623) (xy 93.678883 -249.551283) (xy 93.649507 -249.51085) (xy 93.626817 -249.466318)
			(xy 93.611373 -249.418786) (xy 93.603554 -249.369423) (xy 92.356183 -249.369423) (xy 92.356174 -249.36988)
			(xy 92.34801 -249.420114) (xy 92.331894 -249.468388) (xy 92.308243 -249.513451) (xy 92.27767 -249.554137)
			(xy 92.240966 -249.589392) (xy 92.199082 -249.618302) (xy 92.153103 -249.640119) (xy 92.104219 -249.654279)
			(xy 92.053698 -249.660413) (xy 92.002846 -249.658364) (xy 91.952982 -249.648184) (xy 91.905396 -249.630137)
			(xy 91.861322 -249.604691) (xy 91.8219 -249.572504) (xy 91.788152 -249.53441) (xy 91.760951 -249.491396)
			(xy 91.741003 -249.444576) (xy 91.728824 -249.395162) (xy 91.724729 -249.344434) (xy 91.418918 -249.344434)
			(xy 91.418428 -249.369423) (xy 91.410609 -249.418786) (xy 91.395165 -249.466318) (xy 91.372475 -249.51085)
			(xy 91.343099 -249.551283) (xy 91.307759 -249.586623) (xy 91.267326 -249.615999) (xy 91.222794 -249.638689)
			(xy 91.175262 -249.654133) (xy 91.125899 -249.661952) (xy 91.075921 -249.661952) (xy 91.026558 -249.654133)
			(xy 90.979026 -249.638689) (xy 90.934494 -249.615999) (xy 90.894061 -249.586623) (xy 90.858721 -249.551283)
			(xy 90.829345 -249.51085) (xy 90.806655 -249.466318) (xy 90.791211 -249.418786) (xy 90.783392 -249.369423)
			(xy 90.478628 -249.369423) (xy 90.470809 -249.418786) (xy 90.455365 -249.466318) (xy 90.432675 -249.51085)
			(xy 90.403299 -249.551283) (xy 90.367959 -249.586623) (xy 90.327526 -249.615999) (xy 90.282994 -249.638689)
			(xy 90.235462 -249.654133) (xy 90.186099 -249.661952) (xy 90.136121 -249.661952) (xy 90.086758 -249.654133)
			(xy 90.039226 -249.638689) (xy 89.994694 -249.615999) (xy 89.954261 -249.586623) (xy 89.918921 -249.551283)
			(xy 89.889545 -249.51085) (xy 89.866855 -249.466318) (xy 89.851411 -249.418786) (xy 89.843592 -249.369423)
			(xy 89.536275 -249.369423) (xy 89.536266 -249.36988) (xy 89.528102 -249.420114) (xy 89.511986 -249.468388)
			(xy 89.488335 -249.513451) (xy 89.457762 -249.554137) (xy 89.421058 -249.589392) (xy 89.379174 -249.618302)
			(xy 89.333195 -249.640119) (xy 89.284311 -249.654279) (xy 89.23379 -249.660413) (xy 89.182938 -249.658364)
			(xy 89.133074 -249.648184) (xy 89.085488 -249.630137) (xy 89.041414 -249.604691) (xy 89.001992 -249.572504)
			(xy 88.968244 -249.53441) (xy 88.941043 -249.491396) (xy 88.921095 -249.444576) (xy 88.908916 -249.395162)
			(xy 88.904821 -249.344434) (xy 88.59901 -249.344434) (xy 88.59852 -249.369423) (xy 88.590701 -249.418786)
			(xy 88.575257 -249.466318) (xy 88.552567 -249.51085) (xy 88.523191 -249.551283) (xy 88.487851 -249.586623)
			(xy 88.447418 -249.615999) (xy 88.402886 -249.638689) (xy 88.355354 -249.654133) (xy 88.305991 -249.661952)
			(xy 88.256013 -249.661952) (xy 88.20665 -249.654133) (xy 88.159118 -249.638689) (xy 88.114586 -249.615999)
			(xy 88.074153 -249.586623) (xy 88.038813 -249.551283) (xy 88.009437 -249.51085) (xy 87.986747 -249.466318)
			(xy 87.971303 -249.418786) (xy 87.963484 -249.369423) (xy 87.658466 -249.369423) (xy 87.650647 -249.418786)
			(xy 87.635203 -249.466318) (xy 87.612513 -249.51085) (xy 87.583137 -249.551283) (xy 87.547797 -249.586623)
			(xy 87.507364 -249.615999) (xy 87.462832 -249.638689) (xy 87.4153 -249.654133) (xy 87.365937 -249.661952)
			(xy 87.315959 -249.661952) (xy 87.266596 -249.654133) (xy 87.219064 -249.638689) (xy 87.174532 -249.615999)
			(xy 87.134099 -249.586623) (xy 87.098759 -249.551283) (xy 87.069383 -249.51085) (xy 87.046693 -249.466318)
			(xy 87.031249 -249.418786) (xy 87.02343 -249.369423) (xy 85.776313 -249.369423) (xy 85.776304 -249.36988)
			(xy 85.76814 -249.420114) (xy 85.752024 -249.468388) (xy 85.728373 -249.513451) (xy 85.6978 -249.554137)
			(xy 85.661096 -249.589392) (xy 85.619212 -249.618302) (xy 85.573233 -249.640119) (xy 85.524349 -249.654279)
			(xy 85.473828 -249.660413) (xy 85.422976 -249.658364) (xy 85.373112 -249.648184) (xy 85.325526 -249.630137)
			(xy 85.281452 -249.604691) (xy 85.24203 -249.572504) (xy 85.208282 -249.53441) (xy 85.181081 -249.491396)
			(xy 85.161133 -249.444576) (xy 85.148954 -249.395162) (xy 85.144859 -249.344434) (xy 84.839048 -249.344434)
			(xy 84.838558 -249.369423) (xy 84.830739 -249.418786) (xy 84.815295 -249.466318) (xy 84.792605 -249.51085)
			(xy 84.763229 -249.551283) (xy 84.727889 -249.586623) (xy 84.687456 -249.615999) (xy 84.642924 -249.638689)
			(xy 84.595392 -249.654133) (xy 84.546029 -249.661952) (xy 84.496051 -249.661952) (xy 84.446688 -249.654133)
			(xy 84.399156 -249.638689) (xy 84.354624 -249.615999) (xy 84.314191 -249.586623) (xy 84.278851 -249.551283)
			(xy 84.249475 -249.51085) (xy 84.226785 -249.466318) (xy 84.211341 -249.418786) (xy 84.203522 -249.369423)
			(xy 83.898504 -249.369423) (xy 83.890685 -249.418786) (xy 83.875241 -249.466318) (xy 83.852551 -249.51085)
			(xy 83.823175 -249.551283) (xy 83.787835 -249.586623) (xy 83.747402 -249.615999) (xy 83.70287 -249.638689)
			(xy 83.655338 -249.654133) (xy 83.605975 -249.661952) (xy 83.555997 -249.661952) (xy 83.506634 -249.654133)
			(xy 83.459102 -249.638689) (xy 83.41457 -249.615999) (xy 83.374137 -249.586623) (xy 83.338797 -249.551283)
			(xy 83.309421 -249.51085) (xy 83.286731 -249.466318) (xy 83.271287 -249.418786) (xy 83.263468 -249.369423)
			(xy 82.956151 -249.369423) (xy 82.956142 -249.36988) (xy 82.947978 -249.420114) (xy 82.931862 -249.468388)
			(xy 82.908211 -249.513451) (xy 82.877638 -249.554137) (xy 82.840934 -249.589392) (xy 82.79905 -249.618302)
			(xy 82.753071 -249.640119) (xy 82.704187 -249.654279) (xy 82.653666 -249.660413) (xy 82.602814 -249.658364)
			(xy 82.55295 -249.648184) (xy 82.505364 -249.630137) (xy 82.46129 -249.604691) (xy 82.421868 -249.572504)
			(xy 82.38812 -249.53441) (xy 82.360919 -249.491396) (xy 82.340971 -249.444576) (xy 82.328792 -249.395162)
			(xy 82.324697 -249.344434) (xy 82.01914 -249.344434) (xy 82.01865 -249.369423) (xy 82.010831 -249.418786)
			(xy 81.995387 -249.466318) (xy 81.972697 -249.51085) (xy 81.943321 -249.551283) (xy 81.907981 -249.586623)
			(xy 81.867548 -249.615999) (xy 81.823016 -249.638689) (xy 81.775484 -249.654133) (xy 81.726121 -249.661952)
			(xy 81.676143 -249.661952) (xy 81.62678 -249.654133) (xy 81.579248 -249.638689) (xy 81.534716 -249.615999)
			(xy 81.494283 -249.586623) (xy 81.458943 -249.551283) (xy 81.429567 -249.51085) (xy 81.406877 -249.466318)
			(xy 81.391433 -249.418786) (xy 81.383614 -249.369423) (xy 81.078596 -249.369423) (xy 81.070777 -249.418786)
			(xy 81.055333 -249.466318) (xy 81.032643 -249.51085) (xy 81.003267 -249.551283) (xy 80.967927 -249.586623)
			(xy 80.927494 -249.615999) (xy 80.882962 -249.638689) (xy 80.83543 -249.654133) (xy 80.786067 -249.661952)
			(xy 80.736089 -249.661952) (xy 80.686726 -249.654133) (xy 80.639194 -249.638689) (xy 80.594662 -249.615999)
			(xy 80.554229 -249.586623) (xy 80.518889 -249.551283) (xy 80.489513 -249.51085) (xy 80.466823 -249.466318)
			(xy 80.451379 -249.418786) (xy 80.44356 -249.369423) (xy 79.53248 -249.369423) (xy 79.53248 -249.867674)
			(xy 79.532734 -249.873008) (xy 79.534046 -249.881662) (xy 79.541704 -249.897386) (xy 79.54772 -249.903742)
			(xy 79.551276 -249.907044) (xy 79.571 -249.923647) (xy 79.605322 -249.962114) (xy 79.632995 -250.005611)
			(xy 79.653293 -250.052999) (xy 79.665687 -250.103041) (xy 79.669852 -250.154425) (xy 79.667821 -250.179429)
			(xy 79.97366 -250.179429) (xy 79.97366 -250.129451) (xy 79.981479 -250.080088) (xy 79.996923 -250.032556)
			(xy 80.019613 -249.988024) (xy 80.048989 -249.947591) (xy 80.084329 -249.912251) (xy 80.124762 -249.882875)
			(xy 80.169294 -249.860185) (xy 80.216826 -249.844741) (xy 80.266189 -249.836922) (xy 80.316167 -249.836922)
			(xy 80.36553 -249.844741) (xy 80.413062 -249.860185) (xy 80.457594 -249.882875) (xy 80.498027 -249.912251)
			(xy 80.533367 -249.947591) (xy 80.562743 -249.988024) (xy 80.585433 -250.032556) (xy 80.600877 -250.080088)
			(xy 80.608696 -250.129451) (xy 80.609186 -250.15444) (xy 80.608696 -250.179429) (xy 80.91346 -250.179429)
			(xy 80.91346 -250.129451) (xy 80.921279 -250.080088) (xy 80.936723 -250.032556) (xy 80.959413 -249.988024)
			(xy 80.988789 -249.947591) (xy 81.024129 -249.912251) (xy 81.064562 -249.882875) (xy 81.109094 -249.860185)
			(xy 81.156626 -249.844741) (xy 81.205989 -249.836922) (xy 81.255967 -249.836922) (xy 81.30533 -249.844741)
			(xy 81.352862 -249.860185) (xy 81.397394 -249.882875) (xy 81.437827 -249.912251) (xy 81.473167 -249.947591)
			(xy 81.502543 -249.988024) (xy 81.525233 -250.032556) (xy 81.540677 -250.080088) (xy 81.548496 -250.129451)
			(xy 81.548986 -250.15444) (xy 81.854797 -250.15444) (xy 81.858892 -250.103712) (xy 81.871071 -250.054298)
			(xy 81.891019 -250.007478) (xy 81.91822 -249.964464) (xy 81.951968 -249.92637) (xy 81.99139 -249.894183)
			(xy 82.035464 -249.868737) (xy 82.08305 -249.85069) (xy 82.132914 -249.84051) (xy 82.183766 -249.838461)
			(xy 82.234287 -249.844595) (xy 82.283171 -249.858755) (xy 82.32915 -249.880572) (xy 82.371034 -249.909482)
			(xy 82.407738 -249.944737) (xy 82.438311 -249.985423) (xy 82.461962 -250.030486) (xy 82.478078 -250.07876)
			(xy 82.486242 -250.128994) (xy 82.486754 -250.15444) (xy 82.486251 -250.179429) (xy 82.793568 -250.179429)
			(xy 82.793568 -250.129451) (xy 82.801387 -250.080088) (xy 82.816831 -250.032556) (xy 82.839521 -249.988024)
			(xy 82.868897 -249.947591) (xy 82.904237 -249.912251) (xy 82.94467 -249.882875) (xy 82.989202 -249.860185)
			(xy 83.036734 -249.844741) (xy 83.086097 -249.836922) (xy 83.136075 -249.836922) (xy 83.185438 -249.844741)
			(xy 83.23297 -249.860185) (xy 83.277502 -249.882875) (xy 83.317935 -249.912251) (xy 83.353275 -249.947591)
			(xy 83.382651 -249.988024) (xy 83.405341 -250.032556) (xy 83.420785 -250.080088) (xy 83.428604 -250.129451)
			(xy 83.429094 -250.15444) (xy 83.428604 -250.179429) (xy 83.733622 -250.179429) (xy 83.733622 -250.129451)
			(xy 83.741441 -250.080088) (xy 83.756885 -250.032556) (xy 83.779575 -249.988024) (xy 83.808951 -249.947591)
			(xy 83.844291 -249.912251) (xy 83.884724 -249.882875) (xy 83.929256 -249.860185) (xy 83.976788 -249.844741)
			(xy 84.026151 -249.836922) (xy 84.076129 -249.836922) (xy 84.125492 -249.844741) (xy 84.173024 -249.860185)
			(xy 84.217556 -249.882875) (xy 84.257989 -249.912251) (xy 84.293329 -249.947591) (xy 84.322705 -249.988024)
			(xy 84.345395 -250.032556) (xy 84.360839 -250.080088) (xy 84.368658 -250.129451) (xy 84.369148 -250.15444)
			(xy 84.368658 -250.179429) (xy 84.673422 -250.179429) (xy 84.673422 -250.129451) (xy 84.681241 -250.080088)
			(xy 84.696685 -250.032556) (xy 84.719375 -249.988024) (xy 84.748751 -249.947591) (xy 84.784091 -249.912251)
			(xy 84.824524 -249.882875) (xy 84.869056 -249.860185) (xy 84.916588 -249.844741) (xy 84.965951 -249.836922)
			(xy 85.015929 -249.836922) (xy 85.065292 -249.844741) (xy 85.112824 -249.860185) (xy 85.157356 -249.882875)
			(xy 85.197789 -249.912251) (xy 85.233129 -249.947591) (xy 85.262505 -249.988024) (xy 85.285195 -250.032556)
			(xy 85.300639 -250.080088) (xy 85.308458 -250.129451) (xy 85.308948 -250.15444) (xy 85.614759 -250.15444)
			(xy 85.618854 -250.103712) (xy 85.631033 -250.054298) (xy 85.650981 -250.007478) (xy 85.678182 -249.964464)
			(xy 85.71193 -249.92637) (xy 85.751352 -249.894183) (xy 85.795426 -249.868737) (xy 85.843012 -249.85069)
			(xy 85.892876 -249.84051) (xy 85.943728 -249.838461) (xy 85.994249 -249.844595) (xy 86.043133 -249.858755)
			(xy 86.089112 -249.880572) (xy 86.130996 -249.909482) (xy 86.1677 -249.944737) (xy 86.198273 -249.985423)
			(xy 86.221924 -250.030486) (xy 86.23804 -250.07876) (xy 86.246204 -250.128994) (xy 86.246716 -250.15444)
			(xy 86.246213 -250.179429) (xy 86.55353 -250.179429) (xy 86.55353 -250.129451) (xy 86.561349 -250.080088)
			(xy 86.576793 -250.032556) (xy 86.599483 -249.988024) (xy 86.628859 -249.947591) (xy 86.664199 -249.912251)
			(xy 86.704632 -249.882875) (xy 86.749164 -249.860185) (xy 86.796696 -249.844741) (xy 86.846059 -249.836922)
			(xy 86.896037 -249.836922) (xy 86.9454 -249.844741) (xy 86.992932 -249.860185) (xy 87.037464 -249.882875)
			(xy 87.077897 -249.912251) (xy 87.113237 -249.947591) (xy 87.142613 -249.988024) (xy 87.165303 -250.032556)
			(xy 87.180747 -250.080088) (xy 87.188566 -250.129451) (xy 87.189056 -250.15444) (xy 87.188566 -250.179429)
			(xy 87.493584 -250.179429) (xy 87.493584 -250.129451) (xy 87.501403 -250.080088) (xy 87.516847 -250.032556)
			(xy 87.539537 -249.988024) (xy 87.568913 -249.947591) (xy 87.604253 -249.912251) (xy 87.644686 -249.882875)
			(xy 87.689218 -249.860185) (xy 87.73675 -249.844741) (xy 87.786113 -249.836922) (xy 87.836091 -249.836922)
			(xy 87.885454 -249.844741) (xy 87.932986 -249.860185) (xy 87.977518 -249.882875) (xy 88.017951 -249.912251)
			(xy 88.053291 -249.947591) (xy 88.082667 -249.988024) (xy 88.105357 -250.032556) (xy 88.120801 -250.080088)
			(xy 88.12862 -250.129451) (xy 88.12911 -250.15444) (xy 88.434921 -250.15444) (xy 88.439016 -250.103712)
			(xy 88.451195 -250.054298) (xy 88.471143 -250.007478) (xy 88.498344 -249.964464) (xy 88.532092 -249.92637)
			(xy 88.571514 -249.894183) (xy 88.615588 -249.868737) (xy 88.663174 -249.85069) (xy 88.713038 -249.84051)
			(xy 88.76389 -249.838461) (xy 88.814411 -249.844595) (xy 88.863295 -249.858755) (xy 88.909274 -249.880572)
			(xy 88.951158 -249.909482) (xy 88.987862 -249.944737) (xy 89.018435 -249.985423) (xy 89.042086 -250.030486)
			(xy 89.058202 -250.07876) (xy 89.066366 -250.128994) (xy 89.066878 -250.15444) (xy 89.066375 -250.179429)
			(xy 89.373438 -250.179429) (xy 89.373438 -250.129451) (xy 89.381257 -250.080088) (xy 89.396701 -250.032556)
			(xy 89.419391 -249.988024) (xy 89.448767 -249.947591) (xy 89.484107 -249.912251) (xy 89.52454 -249.882875)
			(xy 89.569072 -249.860185) (xy 89.616604 -249.844741) (xy 89.665967 -249.836922) (xy 89.715945 -249.836922)
			(xy 89.765308 -249.844741) (xy 89.81284 -249.860185) (xy 89.857372 -249.882875) (xy 89.897805 -249.912251)
			(xy 89.933145 -249.947591) (xy 89.962521 -249.988024) (xy 89.985211 -250.032556) (xy 90.000655 -250.080088)
			(xy 90.008474 -250.129451) (xy 90.008964 -250.15444) (xy 90.008474 -250.179429) (xy 90.313492 -250.179429)
			(xy 90.313492 -250.129451) (xy 90.321311 -250.080088) (xy 90.336755 -250.032556) (xy 90.359445 -249.988024)
			(xy 90.388821 -249.947591) (xy 90.424161 -249.912251) (xy 90.464594 -249.882875) (xy 90.509126 -249.860185)
			(xy 90.556658 -249.844741) (xy 90.606021 -249.836922) (xy 90.655999 -249.836922) (xy 90.705362 -249.844741)
			(xy 90.752894 -249.860185) (xy 90.797426 -249.882875) (xy 90.837859 -249.912251) (xy 90.873199 -249.947591)
			(xy 90.902575 -249.988024) (xy 90.925265 -250.032556) (xy 90.940709 -250.080088) (xy 90.948528 -250.129451)
			(xy 90.949018 -250.15444) (xy 90.948528 -250.179429) (xy 91.253546 -250.179429) (xy 91.253546 -250.129451)
			(xy 91.261365 -250.080088) (xy 91.276809 -250.032556) (xy 91.299499 -249.988024) (xy 91.328875 -249.947591)
			(xy 91.364215 -249.912251) (xy 91.404648 -249.882875) (xy 91.44918 -249.860185) (xy 91.496712 -249.844741)
			(xy 91.546075 -249.836922) (xy 91.596053 -249.836922) (xy 91.645416 -249.844741) (xy 91.692948 -249.860185)
			(xy 91.73748 -249.882875) (xy 91.777913 -249.912251) (xy 91.813253 -249.947591) (xy 91.842629 -249.988024)
			(xy 91.865319 -250.032556) (xy 91.880763 -250.080088) (xy 91.888582 -250.129451) (xy 91.889072 -250.15444)
			(xy 92.194883 -250.15444) (xy 92.198978 -250.103712) (xy 92.211157 -250.054298) (xy 92.231105 -250.007478)
			(xy 92.258306 -249.964464) (xy 92.292054 -249.92637) (xy 92.331476 -249.894183) (xy 92.37555 -249.868737)
			(xy 92.423136 -249.85069) (xy 92.473 -249.84051) (xy 92.523852 -249.838461) (xy 92.574373 -249.844595)
			(xy 92.623257 -249.858755) (xy 92.669236 -249.880572) (xy 92.71112 -249.909482) (xy 92.747824 -249.944737)
			(xy 92.778397 -249.985423) (xy 92.802048 -250.030486) (xy 92.818164 -250.07876) (xy 92.826328 -250.128994)
			(xy 92.82684 -250.15444) (xy 92.826337 -250.179429) (xy 93.1334 -250.179429) (xy 93.1334 -250.129451)
			(xy 93.141219 -250.080088) (xy 93.156663 -250.032556) (xy 93.179353 -249.988024) (xy 93.208729 -249.947591)
			(xy 93.244069 -249.912251) (xy 93.284502 -249.882875) (xy 93.329034 -249.860185) (xy 93.376566 -249.844741)
			(xy 93.425929 -249.836922) (xy 93.475907 -249.836922) (xy 93.52527 -249.844741) (xy 93.572802 -249.860185)
			(xy 93.617334 -249.882875) (xy 93.657767 -249.912251) (xy 93.693107 -249.947591) (xy 93.722483 -249.988024)
			(xy 93.745173 -250.032556) (xy 93.760617 -250.080088) (xy 93.768436 -250.129451) (xy 93.768926 -250.15444)
			(xy 93.768436 -250.179429) (xy 94.073454 -250.179429) (xy 94.073454 -250.129451) (xy 94.081273 -250.080088)
			(xy 94.096717 -250.032556) (xy 94.119407 -249.988024) (xy 94.148783 -249.947591) (xy 94.184123 -249.912251)
			(xy 94.224556 -249.882875) (xy 94.269088 -249.860185) (xy 94.31662 -249.844741) (xy 94.365983 -249.836922)
			(xy 94.415961 -249.836922) (xy 94.465324 -249.844741) (xy 94.512856 -249.860185) (xy 94.557388 -249.882875)
			(xy 94.597821 -249.912251) (xy 94.633161 -249.947591) (xy 94.662537 -249.988024) (xy 94.685227 -250.032556)
			(xy 94.700671 -250.080088) (xy 94.70849 -250.129451) (xy 94.70898 -250.15444) (xy 95.014791 -250.15444)
			(xy 95.018886 -250.103712) (xy 95.031065 -250.054298) (xy 95.051013 -250.007478) (xy 95.078214 -249.964464)
			(xy 95.111962 -249.92637) (xy 95.151384 -249.894183) (xy 95.195458 -249.868737) (xy 95.243044 -249.85069)
			(xy 95.292908 -249.84051) (xy 95.34376 -249.838461) (xy 95.394281 -249.844595) (xy 95.443165 -249.858755)
			(xy 95.489144 -249.880572) (xy 95.531028 -249.909482) (xy 95.567732 -249.944737) (xy 95.598305 -249.985423)
			(xy 95.621956 -250.030486) (xy 95.638072 -250.07876) (xy 95.646236 -250.128994) (xy 95.646748 -250.15444)
			(xy 95.646236 -250.179886) (xy 95.638072 -250.23012) (xy 95.621956 -250.278394) (xy 95.598305 -250.323457)
			(xy 95.567732 -250.364143) (xy 95.531028 -250.399398) (xy 95.489144 -250.428308) (xy 95.443165 -250.450125)
			(xy 95.394281 -250.464285) (xy 95.34376 -250.470419) (xy 95.292908 -250.46837) (xy 95.243044 -250.45819)
			(xy 95.195458 -250.440143) (xy 95.151384 -250.414697) (xy 95.111962 -250.38251) (xy 95.078214 -250.344416)
			(xy 95.051013 -250.301402) (xy 95.031065 -250.254582) (xy 95.018886 -250.205168) (xy 95.014791 -250.15444)
			(xy 94.70898 -250.15444) (xy 94.70849 -250.179429) (xy 94.700671 -250.228792) (xy 94.685227 -250.276324)
			(xy 94.662537 -250.320856) (xy 94.633161 -250.361289) (xy 94.597821 -250.396629) (xy 94.557388 -250.426005)
			(xy 94.512856 -250.448695) (xy 94.465324 -250.464139) (xy 94.415961 -250.471958) (xy 94.365983 -250.471958)
			(xy 94.31662 -250.464139) (xy 94.269088 -250.448695) (xy 94.224556 -250.426005) (xy 94.184123 -250.396629)
			(xy 94.148783 -250.361289) (xy 94.119407 -250.320856) (xy 94.096717 -250.276324) (xy 94.081273 -250.228792)
			(xy 94.073454 -250.179429) (xy 93.768436 -250.179429) (xy 93.760617 -250.228792) (xy 93.745173 -250.276324)
			(xy 93.722483 -250.320856) (xy 93.693107 -250.361289) (xy 93.657767 -250.396629) (xy 93.617334 -250.426005)
			(xy 93.572802 -250.448695) (xy 93.52527 -250.464139) (xy 93.475907 -250.471958) (xy 93.425929 -250.471958)
			(xy 93.376566 -250.464139) (xy 93.329034 -250.448695) (xy 93.284502 -250.426005) (xy 93.244069 -250.396629)
			(xy 93.208729 -250.361289) (xy 93.179353 -250.320856) (xy 93.156663 -250.276324) (xy 93.141219 -250.228792)
			(xy 93.1334 -250.179429) (xy 92.826337 -250.179429) (xy 92.826328 -250.179886) (xy 92.818164 -250.23012)
			(xy 92.802048 -250.278394) (xy 92.778397 -250.323457) (xy 92.747824 -250.364143) (xy 92.71112 -250.399398)
			(xy 92.669236 -250.428308) (xy 92.623257 -250.450125) (xy 92.574373 -250.464285) (xy 92.523852 -250.470419)
			(xy 92.473 -250.46837) (xy 92.423136 -250.45819) (xy 92.37555 -250.440143) (xy 92.331476 -250.414697)
			(xy 92.292054 -250.38251) (xy 92.258306 -250.344416) (xy 92.231105 -250.301402) (xy 92.211157 -250.254582)
			(xy 92.198978 -250.205168) (xy 92.194883 -250.15444) (xy 91.889072 -250.15444) (xy 91.888582 -250.179429)
			(xy 91.880763 -250.228792) (xy 91.865319 -250.276324) (xy 91.842629 -250.320856) (xy 91.813253 -250.361289)
			(xy 91.777913 -250.396629) (xy 91.73748 -250.426005) (xy 91.692948 -250.448695) (xy 91.645416 -250.464139)
			(xy 91.596053 -250.471958) (xy 91.546075 -250.471958) (xy 91.496712 -250.464139) (xy 91.44918 -250.448695)
			(xy 91.404648 -250.426005) (xy 91.364215 -250.396629) (xy 91.328875 -250.361289) (xy 91.299499 -250.320856)
			(xy 91.276809 -250.276324) (xy 91.261365 -250.228792) (xy 91.253546 -250.179429) (xy 90.948528 -250.179429)
			(xy 90.940709 -250.228792) (xy 90.925265 -250.276324) (xy 90.902575 -250.320856) (xy 90.873199 -250.361289)
			(xy 90.837859 -250.396629) (xy 90.797426 -250.426005) (xy 90.752894 -250.448695) (xy 90.705362 -250.464139)
			(xy 90.655999 -250.471958) (xy 90.606021 -250.471958) (xy 90.556658 -250.464139) (xy 90.509126 -250.448695)
			(xy 90.464594 -250.426005) (xy 90.424161 -250.396629) (xy 90.388821 -250.361289) (xy 90.359445 -250.320856)
			(xy 90.336755 -250.276324) (xy 90.321311 -250.228792) (xy 90.313492 -250.179429) (xy 90.008474 -250.179429)
			(xy 90.000655 -250.228792) (xy 89.985211 -250.276324) (xy 89.962521 -250.320856) (xy 89.933145 -250.361289)
			(xy 89.897805 -250.396629) (xy 89.857372 -250.426005) (xy 89.81284 -250.448695) (xy 89.765308 -250.464139)
			(xy 89.715945 -250.471958) (xy 89.665967 -250.471958) (xy 89.616604 -250.464139) (xy 89.569072 -250.448695)
			(xy 89.52454 -250.426005) (xy 89.484107 -250.396629) (xy 89.448767 -250.361289) (xy 89.419391 -250.320856)
			(xy 89.396701 -250.276324) (xy 89.381257 -250.228792) (xy 89.373438 -250.179429) (xy 89.066375 -250.179429)
			(xy 89.066366 -250.179886) (xy 89.058202 -250.23012) (xy 89.042086 -250.278394) (xy 89.018435 -250.323457)
			(xy 88.987862 -250.364143) (xy 88.951158 -250.399398) (xy 88.909274 -250.428308) (xy 88.863295 -250.450125)
			(xy 88.814411 -250.464285) (xy 88.76389 -250.470419) (xy 88.713038 -250.46837) (xy 88.663174 -250.45819)
			(xy 88.615588 -250.440143) (xy 88.571514 -250.414697) (xy 88.532092 -250.38251) (xy 88.498344 -250.344416)
			(xy 88.471143 -250.301402) (xy 88.451195 -250.254582) (xy 88.439016 -250.205168) (xy 88.434921 -250.15444)
			(xy 88.12911 -250.15444) (xy 88.12862 -250.179429) (xy 88.120801 -250.228792) (xy 88.105357 -250.276324)
			(xy 88.082667 -250.320856) (xy 88.053291 -250.361289) (xy 88.017951 -250.396629) (xy 87.977518 -250.426005)
			(xy 87.932986 -250.448695) (xy 87.885454 -250.464139) (xy 87.836091 -250.471958) (xy 87.786113 -250.471958)
			(xy 87.73675 -250.464139) (xy 87.689218 -250.448695) (xy 87.644686 -250.426005) (xy 87.604253 -250.396629)
			(xy 87.568913 -250.361289) (xy 87.539537 -250.320856) (xy 87.516847 -250.276324) (xy 87.501403 -250.228792)
			(xy 87.493584 -250.179429) (xy 87.188566 -250.179429) (xy 87.180747 -250.228792) (xy 87.165303 -250.276324)
			(xy 87.142613 -250.320856) (xy 87.113237 -250.361289) (xy 87.077897 -250.396629) (xy 87.037464 -250.426005)
			(xy 86.992932 -250.448695) (xy 86.9454 -250.464139) (xy 86.896037 -250.471958) (xy 86.846059 -250.471958)
			(xy 86.796696 -250.464139) (xy 86.749164 -250.448695) (xy 86.704632 -250.426005) (xy 86.664199 -250.396629)
			(xy 86.628859 -250.361289) (xy 86.599483 -250.320856) (xy 86.576793 -250.276324) (xy 86.561349 -250.228792)
			(xy 86.55353 -250.179429) (xy 86.246213 -250.179429) (xy 86.246204 -250.179886) (xy 86.23804 -250.23012)
			(xy 86.221924 -250.278394) (xy 86.198273 -250.323457) (xy 86.1677 -250.364143) (xy 86.130996 -250.399398)
			(xy 86.089112 -250.428308) (xy 86.043133 -250.450125) (xy 85.994249 -250.464285) (xy 85.943728 -250.470419)
			(xy 85.892876 -250.46837) (xy 85.843012 -250.45819) (xy 85.795426 -250.440143) (xy 85.751352 -250.414697)
			(xy 85.71193 -250.38251) (xy 85.678182 -250.344416) (xy 85.650981 -250.301402) (xy 85.631033 -250.254582)
			(xy 85.618854 -250.205168) (xy 85.614759 -250.15444) (xy 85.308948 -250.15444) (xy 85.308458 -250.179429)
			(xy 85.300639 -250.228792) (xy 85.285195 -250.276324) (xy 85.262505 -250.320856) (xy 85.233129 -250.361289)
			(xy 85.197789 -250.396629) (xy 85.157356 -250.426005) (xy 85.112824 -250.448695) (xy 85.065292 -250.464139)
			(xy 85.015929 -250.471958) (xy 84.965951 -250.471958) (xy 84.916588 -250.464139) (xy 84.869056 -250.448695)
			(xy 84.824524 -250.426005) (xy 84.784091 -250.396629) (xy 84.748751 -250.361289) (xy 84.719375 -250.320856)
			(xy 84.696685 -250.276324) (xy 84.681241 -250.228792) (xy 84.673422 -250.179429) (xy 84.368658 -250.179429)
			(xy 84.360839 -250.228792) (xy 84.345395 -250.276324) (xy 84.322705 -250.320856) (xy 84.293329 -250.361289)
			(xy 84.257989 -250.396629) (xy 84.217556 -250.426005) (xy 84.173024 -250.448695) (xy 84.125492 -250.464139)
			(xy 84.076129 -250.471958) (xy 84.026151 -250.471958) (xy 83.976788 -250.464139) (xy 83.929256 -250.448695)
			(xy 83.884724 -250.426005) (xy 83.844291 -250.396629) (xy 83.808951 -250.361289) (xy 83.779575 -250.320856)
			(xy 83.756885 -250.276324) (xy 83.741441 -250.228792) (xy 83.733622 -250.179429) (xy 83.428604 -250.179429)
			(xy 83.420785 -250.228792) (xy 83.405341 -250.276324) (xy 83.382651 -250.320856) (xy 83.353275 -250.361289)
			(xy 83.317935 -250.396629) (xy 83.277502 -250.426005) (xy 83.23297 -250.448695) (xy 83.185438 -250.464139)
			(xy 83.136075 -250.471958) (xy 83.086097 -250.471958) (xy 83.036734 -250.464139) (xy 82.989202 -250.448695)
			(xy 82.94467 -250.426005) (xy 82.904237 -250.396629) (xy 82.868897 -250.361289) (xy 82.839521 -250.320856)
			(xy 82.816831 -250.276324) (xy 82.801387 -250.228792) (xy 82.793568 -250.179429) (xy 82.486251 -250.179429)
			(xy 82.486242 -250.179886) (xy 82.478078 -250.23012) (xy 82.461962 -250.278394) (xy 82.438311 -250.323457)
			(xy 82.407738 -250.364143) (xy 82.371034 -250.399398) (xy 82.32915 -250.428308) (xy 82.283171 -250.450125)
			(xy 82.234287 -250.464285) (xy 82.183766 -250.470419) (xy 82.132914 -250.46837) (xy 82.08305 -250.45819)
			(xy 82.035464 -250.440143) (xy 81.99139 -250.414697) (xy 81.951968 -250.38251) (xy 81.91822 -250.344416)
			(xy 81.891019 -250.301402) (xy 81.871071 -250.254582) (xy 81.858892 -250.205168) (xy 81.854797 -250.15444)
			(xy 81.548986 -250.15444) (xy 81.548496 -250.179429) (xy 81.540677 -250.228792) (xy 81.525233 -250.276324)
			(xy 81.502543 -250.320856) (xy 81.473167 -250.361289) (xy 81.437827 -250.396629) (xy 81.397394 -250.426005)
			(xy 81.352862 -250.448695) (xy 81.30533 -250.464139) (xy 81.255967 -250.471958) (xy 81.205989 -250.471958)
			(xy 81.156626 -250.464139) (xy 81.109094 -250.448695) (xy 81.064562 -250.426005) (xy 81.024129 -250.396629)
			(xy 80.988789 -250.361289) (xy 80.959413 -250.320856) (xy 80.936723 -250.276324) (xy 80.921279 -250.228792)
			(xy 80.91346 -250.179429) (xy 80.608696 -250.179429) (xy 80.600877 -250.228792) (xy 80.585433 -250.276324)
			(xy 80.562743 -250.320856) (xy 80.533367 -250.361289) (xy 80.498027 -250.396629) (xy 80.457594 -250.426005)
			(xy 80.413062 -250.448695) (xy 80.36553 -250.464139) (xy 80.316167 -250.471958) (xy 80.266189 -250.471958)
			(xy 80.216826 -250.464139) (xy 80.169294 -250.448695) (xy 80.124762 -250.426005) (xy 80.084329 -250.396629)
			(xy 80.048989 -250.361289) (xy 80.019613 -250.320856) (xy 79.996923 -250.276324) (xy 79.981479 -250.228792)
			(xy 79.97366 -250.179429) (xy 79.667821 -250.179429) (xy 79.665679 -250.205809) (xy 79.653277 -250.255848)
			(xy 79.632971 -250.303234) (xy 79.605292 -250.346726) (xy 79.570963 -250.385188) (xy 79.551276 -250.401836)
			(xy 79.54772 -250.405138) (xy 79.541719 -250.411508) (xy 79.534043 -250.427221) (xy 79.532734 -250.435872)
			(xy 79.53248 -250.441206) (xy 79.53248 -250.588526) (xy 79.532971 -250.603307) (xy 79.54142 -250.631634)
			(xy 79.55763 -250.656354) (xy 79.580242 -250.675394) (xy 79.607362 -250.687157) (xy 79.636714 -250.690657)
			(xy 79.66584 -250.685602) (xy 79.679292 -250.679458) (xy 79.701429 -250.668966) (xy 79.748121 -250.654149)
			(xy 79.796531 -250.646655) (xy 79.821024 -250.646184) (xy 79.846028 -250.646676) (xy 79.895421 -250.654503)
			(xy 79.942981 -250.669959) (xy 79.987538 -250.692665) (xy 80.027994 -250.722061) (xy 80.063354 -250.757424)
			(xy 80.092748 -250.797883) (xy 80.11545 -250.842441) (xy 80.130903 -250.890003) (xy 80.138726 -250.939396)
			(xy 80.138726 -250.989404) (xy 80.138721 -250.989435) (xy 80.44356 -250.989435) (xy 80.44356 -250.939457)
			(xy 80.451379 -250.890094) (xy 80.466823 -250.842562) (xy 80.489513 -250.79803) (xy 80.518889 -250.757597)
			(xy 80.554229 -250.722257) (xy 80.594662 -250.692881) (xy 80.639194 -250.670191) (xy 80.686726 -250.654747)
			(xy 80.736089 -250.646928) (xy 80.786067 -250.646928) (xy 80.83543 -250.654747) (xy 80.882962 -250.670191)
			(xy 80.927494 -250.692881) (xy 80.967927 -250.722257) (xy 81.003267 -250.757597) (xy 81.032643 -250.79803)
			(xy 81.055333 -250.842562) (xy 81.070777 -250.890094) (xy 81.078596 -250.939457) (xy 81.079086 -250.964446)
			(xy 81.078596 -250.989435) (xy 81.383614 -250.989435) (xy 81.383614 -250.939457) (xy 81.391433 -250.890094)
			(xy 81.406877 -250.842562) (xy 81.429567 -250.79803) (xy 81.458943 -250.757597) (xy 81.494283 -250.722257)
			(xy 81.534716 -250.692881) (xy 81.579248 -250.670191) (xy 81.62678 -250.654747) (xy 81.676143 -250.646928)
			(xy 81.726121 -250.646928) (xy 81.775484 -250.654747) (xy 81.823016 -250.670191) (xy 81.867548 -250.692881)
			(xy 81.907981 -250.722257) (xy 81.943321 -250.757597) (xy 81.972697 -250.79803) (xy 81.995387 -250.842562)
			(xy 82.010831 -250.890094) (xy 82.01865 -250.939457) (xy 82.01914 -250.964446) (xy 82.324697 -250.964446)
			(xy 82.328792 -250.913718) (xy 82.340971 -250.864304) (xy 82.360919 -250.817484) (xy 82.38812 -250.77447)
			(xy 82.421868 -250.736376) (xy 82.46129 -250.704189) (xy 82.505364 -250.678743) (xy 82.55295 -250.660696)
			(xy 82.602814 -250.650516) (xy 82.653666 -250.648467) (xy 82.704187 -250.654601) (xy 82.753071 -250.668761)
			(xy 82.79905 -250.690578) (xy 82.840934 -250.719488) (xy 82.877638 -250.754743) (xy 82.908211 -250.795429)
			(xy 82.931862 -250.840492) (xy 82.947978 -250.888766) (xy 82.956142 -250.939) (xy 82.956654 -250.964446)
			(xy 82.956151 -250.989435) (xy 83.263468 -250.989435) (xy 83.263468 -250.939457) (xy 83.271287 -250.890094)
			(xy 83.286731 -250.842562) (xy 83.309421 -250.79803) (xy 83.338797 -250.757597) (xy 83.374137 -250.722257)
			(xy 83.41457 -250.692881) (xy 83.459102 -250.670191) (xy 83.506634 -250.654747) (xy 83.555997 -250.646928)
			(xy 83.605975 -250.646928) (xy 83.655338 -250.654747) (xy 83.70287 -250.670191) (xy 83.747402 -250.692881)
			(xy 83.787835 -250.722257) (xy 83.823175 -250.757597) (xy 83.852551 -250.79803) (xy 83.875241 -250.842562)
			(xy 83.890685 -250.890094) (xy 83.898504 -250.939457) (xy 83.898994 -250.964446) (xy 83.898504 -250.989435)
			(xy 84.203522 -250.989435) (xy 84.203522 -250.939457) (xy 84.211341 -250.890094) (xy 84.226785 -250.842562)
			(xy 84.249475 -250.79803) (xy 84.278851 -250.757597) (xy 84.314191 -250.722257) (xy 84.354624 -250.692881)
			(xy 84.399156 -250.670191) (xy 84.446688 -250.654747) (xy 84.496051 -250.646928) (xy 84.546029 -250.646928)
			(xy 84.595392 -250.654747) (xy 84.642924 -250.670191) (xy 84.687456 -250.692881) (xy 84.727889 -250.722257)
			(xy 84.763229 -250.757597) (xy 84.792605 -250.79803) (xy 84.815295 -250.842562) (xy 84.830739 -250.890094)
			(xy 84.838558 -250.939457) (xy 84.839048 -250.964446) (xy 85.144859 -250.964446) (xy 85.148954 -250.913718)
			(xy 85.161133 -250.864304) (xy 85.181081 -250.817484) (xy 85.208282 -250.77447) (xy 85.24203 -250.736376)
			(xy 85.281452 -250.704189) (xy 85.325526 -250.678743) (xy 85.373112 -250.660696) (xy 85.422976 -250.650516)
			(xy 85.473828 -250.648467) (xy 85.524349 -250.654601) (xy 85.573233 -250.668761) (xy 85.619212 -250.690578)
			(xy 85.661096 -250.719488) (xy 85.6978 -250.754743) (xy 85.728373 -250.795429) (xy 85.752024 -250.840492)
			(xy 85.76814 -250.888766) (xy 85.776304 -250.939) (xy 85.776816 -250.964446) (xy 85.776313 -250.989435)
			(xy 86.08363 -250.989435) (xy 86.08363 -250.939457) (xy 86.091449 -250.890094) (xy 86.106893 -250.842562)
			(xy 86.129583 -250.79803) (xy 86.158959 -250.757597) (xy 86.194299 -250.722257) (xy 86.234732 -250.692881)
			(xy 86.279264 -250.670191) (xy 86.326796 -250.654747) (xy 86.376159 -250.646928) (xy 86.426137 -250.646928)
			(xy 86.4755 -250.654747) (xy 86.523032 -250.670191) (xy 86.567564 -250.692881) (xy 86.607997 -250.722257)
			(xy 86.643337 -250.757597) (xy 86.672713 -250.79803) (xy 86.695403 -250.842562) (xy 86.710847 -250.890094)
			(xy 86.718666 -250.939457) (xy 86.719156 -250.964446) (xy 86.718666 -250.989435) (xy 87.02343 -250.989435)
			(xy 87.02343 -250.939457) (xy 87.031249 -250.890094) (xy 87.046693 -250.842562) (xy 87.069383 -250.79803)
			(xy 87.098759 -250.757597) (xy 87.134099 -250.722257) (xy 87.174532 -250.692881) (xy 87.219064 -250.670191)
			(xy 87.266596 -250.654747) (xy 87.315959 -250.646928) (xy 87.365937 -250.646928) (xy 87.4153 -250.654747)
			(xy 87.462832 -250.670191) (xy 87.507364 -250.692881) (xy 87.547797 -250.722257) (xy 87.583137 -250.757597)
			(xy 87.612513 -250.79803) (xy 87.635203 -250.842562) (xy 87.650647 -250.890094) (xy 87.658466 -250.939457)
			(xy 87.658956 -250.964446) (xy 87.658466 -250.989435) (xy 87.963484 -250.989435) (xy 87.963484 -250.939457)
			(xy 87.971303 -250.890094) (xy 87.986747 -250.842562) (xy 88.009437 -250.79803) (xy 88.038813 -250.757597)
			(xy 88.074153 -250.722257) (xy 88.114586 -250.692881) (xy 88.159118 -250.670191) (xy 88.20665 -250.654747)
			(xy 88.256013 -250.646928) (xy 88.305991 -250.646928) (xy 88.355354 -250.654747) (xy 88.402886 -250.670191)
			(xy 88.447418 -250.692881) (xy 88.487851 -250.722257) (xy 88.523191 -250.757597) (xy 88.552567 -250.79803)
			(xy 88.575257 -250.842562) (xy 88.590701 -250.890094) (xy 88.59852 -250.939457) (xy 88.59901 -250.964446)
			(xy 88.904821 -250.964446) (xy 88.908916 -250.913718) (xy 88.921095 -250.864304) (xy 88.941043 -250.817484)
			(xy 88.968244 -250.77447) (xy 89.001992 -250.736376) (xy 89.041414 -250.704189) (xy 89.085488 -250.678743)
			(xy 89.133074 -250.660696) (xy 89.182938 -250.650516) (xy 89.23379 -250.648467) (xy 89.284311 -250.654601)
			(xy 89.333195 -250.668761) (xy 89.379174 -250.690578) (xy 89.421058 -250.719488) (xy 89.457762 -250.754743)
			(xy 89.488335 -250.795429) (xy 89.511986 -250.840492) (xy 89.528102 -250.888766) (xy 89.536266 -250.939)
			(xy 89.536778 -250.964446) (xy 89.536275 -250.989435) (xy 89.843592 -250.989435) (xy 89.843592 -250.939457)
			(xy 89.851411 -250.890094) (xy 89.866855 -250.842562) (xy 89.889545 -250.79803) (xy 89.918921 -250.757597)
			(xy 89.954261 -250.722257) (xy 89.994694 -250.692881) (xy 90.039226 -250.670191) (xy 90.086758 -250.654747)
			(xy 90.136121 -250.646928) (xy 90.186099 -250.646928) (xy 90.235462 -250.654747) (xy 90.282994 -250.670191)
			(xy 90.327526 -250.692881) (xy 90.367959 -250.722257) (xy 90.403299 -250.757597) (xy 90.432675 -250.79803)
			(xy 90.455365 -250.842562) (xy 90.470809 -250.890094) (xy 90.478628 -250.939457) (xy 90.479118 -250.964446)
			(xy 90.478628 -250.989435) (xy 90.783646 -250.989435) (xy 90.783646 -250.939457) (xy 90.791465 -250.890094)
			(xy 90.806909 -250.842562) (xy 90.829599 -250.79803) (xy 90.858975 -250.757597) (xy 90.894315 -250.722257)
			(xy 90.934748 -250.692881) (xy 90.97928 -250.670191) (xy 91.026812 -250.654747) (xy 91.076175 -250.646928)
			(xy 91.126153 -250.646928) (xy 91.175516 -250.654747) (xy 91.223048 -250.670191) (xy 91.26758 -250.692881)
			(xy 91.308013 -250.722257) (xy 91.343353 -250.757597) (xy 91.372729 -250.79803) (xy 91.395419 -250.842562)
			(xy 91.410863 -250.890094) (xy 91.418682 -250.939457) (xy 91.419172 -250.964446) (xy 91.724729 -250.964446)
			(xy 91.728824 -250.913718) (xy 91.741003 -250.864304) (xy 91.760951 -250.817484) (xy 91.788152 -250.77447)
			(xy 91.8219 -250.736376) (xy 91.861322 -250.704189) (xy 91.905396 -250.678743) (xy 91.952982 -250.660696)
			(xy 92.002846 -250.650516) (xy 92.053698 -250.648467) (xy 92.104219 -250.654601) (xy 92.153103 -250.668761)
			(xy 92.199082 -250.690578) (xy 92.240966 -250.719488) (xy 92.27767 -250.754743) (xy 92.308243 -250.795429)
			(xy 92.331894 -250.840492) (xy 92.34801 -250.888766) (xy 92.356174 -250.939) (xy 92.356686 -250.964446)
			(xy 92.356183 -250.989435) (xy 92.6635 -250.989435) (xy 92.6635 -250.939457) (xy 92.671319 -250.890094)
			(xy 92.686763 -250.842562) (xy 92.709453 -250.79803) (xy 92.738829 -250.757597) (xy 92.774169 -250.722257)
			(xy 92.814602 -250.692881) (xy 92.859134 -250.670191) (xy 92.906666 -250.654747) (xy 92.956029 -250.646928)
			(xy 93.006007 -250.646928) (xy 93.05537 -250.654747) (xy 93.102902 -250.670191) (xy 93.147434 -250.692881)
			(xy 93.187867 -250.722257) (xy 93.223207 -250.757597) (xy 93.252583 -250.79803) (xy 93.275273 -250.842562)
			(xy 93.290717 -250.890094) (xy 93.298536 -250.939457) (xy 93.299026 -250.964446) (xy 93.298536 -250.989435)
			(xy 93.603554 -250.989435) (xy 93.603554 -250.939457) (xy 93.611373 -250.890094) (xy 93.626817 -250.842562)
			(xy 93.649507 -250.79803) (xy 93.678883 -250.757597) (xy 93.714223 -250.722257) (xy 93.754656 -250.692881)
			(xy 93.799188 -250.670191) (xy 93.84672 -250.654747) (xy 93.896083 -250.646928) (xy 93.946061 -250.646928)
			(xy 93.995424 -250.654747) (xy 94.042956 -250.670191) (xy 94.087488 -250.692881) (xy 94.127921 -250.722257)
			(xy 94.163261 -250.757597) (xy 94.192637 -250.79803) (xy 94.215327 -250.842562) (xy 94.230771 -250.890094)
			(xy 94.23859 -250.939457) (xy 94.23908 -250.964446) (xy 94.23859 -250.989435) (xy 94.543608 -250.989435)
			(xy 94.543608 -250.939457) (xy 94.551427 -250.890094) (xy 94.566871 -250.842562) (xy 94.589561 -250.79803)
			(xy 94.618937 -250.757597) (xy 94.654277 -250.722257) (xy 94.69471 -250.692881) (xy 94.739242 -250.670191)
			(xy 94.786774 -250.654747) (xy 94.836137 -250.646928) (xy 94.886115 -250.646928) (xy 94.935478 -250.654747)
			(xy 94.98301 -250.670191) (xy 95.027542 -250.692881) (xy 95.067975 -250.722257) (xy 95.103315 -250.757597)
			(xy 95.132691 -250.79803) (xy 95.155381 -250.842562) (xy 95.170825 -250.890094) (xy 95.178644 -250.939457)
			(xy 95.179134 -250.964446) (xy 95.178644 -250.989435) (xy 95.170825 -251.038798) (xy 95.155381 -251.08633)
			(xy 95.132691 -251.130862) (xy 95.103315 -251.171295) (xy 95.067975 -251.206635) (xy 95.027542 -251.236011)
			(xy 94.98301 -251.258701) (xy 94.935478 -251.274145) (xy 94.886115 -251.281964) (xy 94.836137 -251.281964)
			(xy 94.786774 -251.274145) (xy 94.739242 -251.258701) (xy 94.69471 -251.236011) (xy 94.654277 -251.206635)
			(xy 94.618937 -251.171295) (xy 94.589561 -251.130862) (xy 94.566871 -251.08633) (xy 94.551427 -251.038798)
			(xy 94.543608 -250.989435) (xy 94.23859 -250.989435) (xy 94.230771 -251.038798) (xy 94.215327 -251.08633)
			(xy 94.192637 -251.130862) (xy 94.163261 -251.171295) (xy 94.127921 -251.206635) (xy 94.087488 -251.236011)
			(xy 94.042956 -251.258701) (xy 93.995424 -251.274145) (xy 93.946061 -251.281964) (xy 93.896083 -251.281964)
			(xy 93.84672 -251.274145) (xy 93.799188 -251.258701) (xy 93.754656 -251.236011) (xy 93.714223 -251.206635)
			(xy 93.678883 -251.171295) (xy 93.649507 -251.130862) (xy 93.626817 -251.08633) (xy 93.611373 -251.038798)
			(xy 93.603554 -250.989435) (xy 93.298536 -250.989435) (xy 93.290717 -251.038798) (xy 93.275273 -251.08633)
			(xy 93.252583 -251.130862) (xy 93.223207 -251.171295) (xy 93.187867 -251.206635) (xy 93.147434 -251.236011)
			(xy 93.102902 -251.258701) (xy 93.05537 -251.274145) (xy 93.006007 -251.281964) (xy 92.956029 -251.281964)
			(xy 92.906666 -251.274145) (xy 92.859134 -251.258701) (xy 92.814602 -251.236011) (xy 92.774169 -251.206635)
			(xy 92.738829 -251.171295) (xy 92.709453 -251.130862) (xy 92.686763 -251.08633) (xy 92.671319 -251.038798)
			(xy 92.6635 -250.989435) (xy 92.356183 -250.989435) (xy 92.356174 -250.989892) (xy 92.34801 -251.040126)
			(xy 92.331894 -251.0884) (xy 92.308243 -251.133463) (xy 92.27767 -251.174149) (xy 92.240966 -251.209404)
			(xy 92.199082 -251.238314) (xy 92.153103 -251.260131) (xy 92.104219 -251.274291) (xy 92.053698 -251.280425)
			(xy 92.002846 -251.278376) (xy 91.952982 -251.268196) (xy 91.905396 -251.250149) (xy 91.861322 -251.224703)
			(xy 91.8219 -251.192516) (xy 91.788152 -251.154422) (xy 91.760951 -251.111408) (xy 91.741003 -251.064588)
			(xy 91.728824 -251.015174) (xy 91.724729 -250.964446) (xy 91.419172 -250.964446) (xy 91.418682 -250.989435)
			(xy 91.410863 -251.038798) (xy 91.395419 -251.08633) (xy 91.372729 -251.130862) (xy 91.343353 -251.171295)
			(xy 91.308013 -251.206635) (xy 91.26758 -251.236011) (xy 91.223048 -251.258701) (xy 91.175516 -251.274145)
			(xy 91.126153 -251.281964) (xy 91.076175 -251.281964) (xy 91.026812 -251.274145) (xy 90.97928 -251.258701)
			(xy 90.934748 -251.236011) (xy 90.894315 -251.206635) (xy 90.858975 -251.171295) (xy 90.829599 -251.130862)
			(xy 90.806909 -251.08633) (xy 90.791465 -251.038798) (xy 90.783646 -250.989435) (xy 90.478628 -250.989435)
			(xy 90.470809 -251.038798) (xy 90.455365 -251.08633) (xy 90.432675 -251.130862) (xy 90.403299 -251.171295)
			(xy 90.367959 -251.206635) (xy 90.327526 -251.236011) (xy 90.282994 -251.258701) (xy 90.235462 -251.274145)
			(xy 90.186099 -251.281964) (xy 90.136121 -251.281964) (xy 90.086758 -251.274145) (xy 90.039226 -251.258701)
			(xy 89.994694 -251.236011) (xy 89.954261 -251.206635) (xy 89.918921 -251.171295) (xy 89.889545 -251.130862)
			(xy 89.866855 -251.08633) (xy 89.851411 -251.038798) (xy 89.843592 -250.989435) (xy 89.536275 -250.989435)
			(xy 89.536266 -250.989892) (xy 89.528102 -251.040126) (xy 89.511986 -251.0884) (xy 89.488335 -251.133463)
			(xy 89.457762 -251.174149) (xy 89.421058 -251.209404) (xy 89.379174 -251.238314) (xy 89.333195 -251.260131)
			(xy 89.284311 -251.274291) (xy 89.23379 -251.280425) (xy 89.182938 -251.278376) (xy 89.133074 -251.268196)
			(xy 89.085488 -251.250149) (xy 89.041414 -251.224703) (xy 89.001992 -251.192516) (xy 88.968244 -251.154422)
			(xy 88.941043 -251.111408) (xy 88.921095 -251.064588) (xy 88.908916 -251.015174) (xy 88.904821 -250.964446)
			(xy 88.59901 -250.964446) (xy 88.59852 -250.989435) (xy 88.590701 -251.038798) (xy 88.575257 -251.08633)
			(xy 88.552567 -251.130862) (xy 88.523191 -251.171295) (xy 88.487851 -251.206635) (xy 88.447418 -251.236011)
			(xy 88.402886 -251.258701) (xy 88.355354 -251.274145) (xy 88.305991 -251.281964) (xy 88.256013 -251.281964)
			(xy 88.20665 -251.274145) (xy 88.159118 -251.258701) (xy 88.114586 -251.236011) (xy 88.074153 -251.206635)
			(xy 88.038813 -251.171295) (xy 88.009437 -251.130862) (xy 87.986747 -251.08633) (xy 87.971303 -251.038798)
			(xy 87.963484 -250.989435) (xy 87.658466 -250.989435) (xy 87.650647 -251.038798) (xy 87.635203 -251.08633)
			(xy 87.612513 -251.130862) (xy 87.583137 -251.171295) (xy 87.547797 -251.206635) (xy 87.507364 -251.236011)
			(xy 87.462832 -251.258701) (xy 87.4153 -251.274145) (xy 87.365937 -251.281964) (xy 87.315959 -251.281964)
			(xy 87.266596 -251.274145) (xy 87.219064 -251.258701) (xy 87.174532 -251.236011) (xy 87.134099 -251.206635)
			(xy 87.098759 -251.171295) (xy 87.069383 -251.130862) (xy 87.046693 -251.08633) (xy 87.031249 -251.038798)
			(xy 87.02343 -250.989435) (xy 86.718666 -250.989435) (xy 86.710847 -251.038798) (xy 86.695403 -251.08633)
			(xy 86.672713 -251.130862) (xy 86.643337 -251.171295) (xy 86.607997 -251.206635) (xy 86.567564 -251.236011)
			(xy 86.523032 -251.258701) (xy 86.4755 -251.274145) (xy 86.426137 -251.281964) (xy 86.376159 -251.281964)
			(xy 86.326796 -251.274145) (xy 86.279264 -251.258701) (xy 86.234732 -251.236011) (xy 86.194299 -251.206635)
			(xy 86.158959 -251.171295) (xy 86.129583 -251.130862) (xy 86.106893 -251.08633) (xy 86.091449 -251.038798)
			(xy 86.08363 -250.989435) (xy 85.776313 -250.989435) (xy 85.776304 -250.989892) (xy 85.76814 -251.040126)
			(xy 85.752024 -251.0884) (xy 85.728373 -251.133463) (xy 85.6978 -251.174149) (xy 85.661096 -251.209404)
			(xy 85.619212 -251.238314) (xy 85.573233 -251.260131) (xy 85.524349 -251.274291) (xy 85.473828 -251.280425)
			(xy 85.422976 -251.278376) (xy 85.373112 -251.268196) (xy 85.325526 -251.250149) (xy 85.281452 -251.224703)
			(xy 85.24203 -251.192516) (xy 85.208282 -251.154422) (xy 85.181081 -251.111408) (xy 85.161133 -251.064588)
			(xy 85.148954 -251.015174) (xy 85.144859 -250.964446) (xy 84.839048 -250.964446) (xy 84.838558 -250.989435)
			(xy 84.830739 -251.038798) (xy 84.815295 -251.08633) (xy 84.792605 -251.130862) (xy 84.763229 -251.171295)
			(xy 84.727889 -251.206635) (xy 84.687456 -251.236011) (xy 84.642924 -251.258701) (xy 84.595392 -251.274145)
			(xy 84.546029 -251.281964) (xy 84.496051 -251.281964) (xy 84.446688 -251.274145) (xy 84.399156 -251.258701)
			(xy 84.354624 -251.236011) (xy 84.314191 -251.206635) (xy 84.278851 -251.171295) (xy 84.249475 -251.130862)
			(xy 84.226785 -251.08633) (xy 84.211341 -251.038798) (xy 84.203522 -250.989435) (xy 83.898504 -250.989435)
			(xy 83.890685 -251.038798) (xy 83.875241 -251.08633) (xy 83.852551 -251.130862) (xy 83.823175 -251.171295)
			(xy 83.787835 -251.206635) (xy 83.747402 -251.236011) (xy 83.70287 -251.258701) (xy 83.655338 -251.274145)
			(xy 83.605975 -251.281964) (xy 83.555997 -251.281964) (xy 83.506634 -251.274145) (xy 83.459102 -251.258701)
			(xy 83.41457 -251.236011) (xy 83.374137 -251.206635) (xy 83.338797 -251.171295) (xy 83.309421 -251.130862)
			(xy 83.286731 -251.08633) (xy 83.271287 -251.038798) (xy 83.263468 -250.989435) (xy 82.956151 -250.989435)
			(xy 82.956142 -250.989892) (xy 82.947978 -251.040126) (xy 82.931862 -251.0884) (xy 82.908211 -251.133463)
			(xy 82.877638 -251.174149) (xy 82.840934 -251.209404) (xy 82.79905 -251.238314) (xy 82.753071 -251.260131)
			(xy 82.704187 -251.274291) (xy 82.653666 -251.280425) (xy 82.602814 -251.278376) (xy 82.55295 -251.268196)
			(xy 82.505364 -251.250149) (xy 82.46129 -251.224703) (xy 82.421868 -251.192516) (xy 82.38812 -251.154422)
			(xy 82.360919 -251.111408) (xy 82.340971 -251.064588) (xy 82.328792 -251.015174) (xy 82.324697 -250.964446)
			(xy 82.01914 -250.964446) (xy 82.01865 -250.989435) (xy 82.010831 -251.038798) (xy 81.995387 -251.08633)
			(xy 81.972697 -251.130862) (xy 81.943321 -251.171295) (xy 81.907981 -251.206635) (xy 81.867548 -251.236011)
			(xy 81.823016 -251.258701) (xy 81.775484 -251.274145) (xy 81.726121 -251.281964) (xy 81.676143 -251.281964)
			(xy 81.62678 -251.274145) (xy 81.579248 -251.258701) (xy 81.534716 -251.236011) (xy 81.494283 -251.206635)
			(xy 81.458943 -251.171295) (xy 81.429567 -251.130862) (xy 81.406877 -251.08633) (xy 81.391433 -251.038798)
			(xy 81.383614 -250.989435) (xy 81.078596 -250.989435) (xy 81.070777 -251.038798) (xy 81.055333 -251.08633)
			(xy 81.032643 -251.130862) (xy 81.003267 -251.171295) (xy 80.967927 -251.206635) (xy 80.927494 -251.236011)
			(xy 80.882962 -251.258701) (xy 80.83543 -251.274145) (xy 80.786067 -251.281964) (xy 80.736089 -251.281964)
			(xy 80.686726 -251.274145) (xy 80.639194 -251.258701) (xy 80.594662 -251.236011) (xy 80.554229 -251.206635)
			(xy 80.518889 -251.171295) (xy 80.489513 -251.130862) (xy 80.466823 -251.08633) (xy 80.451379 -251.038798)
			(xy 80.44356 -250.989435) (xy 80.138721 -250.989435) (xy 80.130903 -251.038797) (xy 80.11545 -251.086359)
			(xy 80.092748 -251.130917) (xy 80.063354 -251.171376) (xy 80.027994 -251.206739) (xy 79.987538 -251.236135)
			(xy 79.942981 -251.258841) (xy 79.895421 -251.274297) (xy 79.846028 -251.282124) (xy 79.821024 -251.282708)
			(xy 79.796529 -251.282261) (xy 79.748117 -251.274763) (xy 79.701423 -251.259941) (xy 79.679292 -251.249434)
			(xy 79.665841 -251.24331) (xy 79.63673 -251.238287) (xy 79.607399 -251.241805) (xy 79.580302 -251.253569)
			(xy 79.557703 -251.272595) (xy 79.541495 -251.297293) (xy 79.533032 -251.325596) (xy 79.53248 -251.340366)
			(xy 79.53248 -251.774452) (xy 80.914743 -251.774452) (xy 80.918838 -251.723724) (xy 80.931017 -251.67431)
			(xy 80.950965 -251.62749) (xy 80.978166 -251.584476) (xy 81.011914 -251.546382) (xy 81.051336 -251.514195)
			(xy 81.09541 -251.488749) (xy 81.142996 -251.470702) (xy 81.19286 -251.460522) (xy 81.243712 -251.458473)
			(xy 81.294233 -251.464607) (xy 81.343117 -251.478767) (xy 81.389096 -251.500584) (xy 81.43098 -251.529494)
			(xy 81.467684 -251.564749) (xy 81.498257 -251.605435) (xy 81.521908 -251.650498) (xy 81.538024 -251.698772)
			(xy 81.546188 -251.749006) (xy 81.5467 -251.774452) (xy 81.546197 -251.799441) (xy 81.853514 -251.799441)
			(xy 81.853514 -251.749463) (xy 81.861333 -251.7001) (xy 81.876777 -251.652568) (xy 81.899467 -251.608036)
			(xy 81.928843 -251.567603) (xy 81.964183 -251.532263) (xy 82.004616 -251.502887) (xy 82.049148 -251.480197)
			(xy 82.09668 -251.464753) (xy 82.146043 -251.456934) (xy 82.196021 -251.456934) (xy 82.245384 -251.464753)
			(xy 82.292916 -251.480197) (xy 82.337448 -251.502887) (xy 82.377881 -251.532263) (xy 82.413221 -251.567603)
			(xy 82.442597 -251.608036) (xy 82.465287 -251.652568) (xy 82.480731 -251.7001) (xy 82.48855 -251.749463)
			(xy 82.48904 -251.774452) (xy 82.48855 -251.799441) (xy 82.793568 -251.799441) (xy 82.793568 -251.749463)
			(xy 82.801387 -251.7001) (xy 82.816831 -251.652568) (xy 82.839521 -251.608036) (xy 82.868897 -251.567603)
			(xy 82.904237 -251.532263) (xy 82.94467 -251.502887) (xy 82.989202 -251.480197) (xy 83.036734 -251.464753)
			(xy 83.086097 -251.456934) (xy 83.136075 -251.456934) (xy 83.185438 -251.464753) (xy 83.23297 -251.480197)
			(xy 83.277502 -251.502887) (xy 83.317935 -251.532263) (xy 83.353275 -251.567603) (xy 83.382651 -251.608036)
			(xy 83.405341 -251.652568) (xy 83.420785 -251.7001) (xy 83.428604 -251.749463) (xy 83.429094 -251.774452)
			(xy 83.734905 -251.774452) (xy 83.739 -251.723724) (xy 83.751179 -251.67431) (xy 83.771127 -251.62749)
			(xy 83.798328 -251.584476) (xy 83.832076 -251.546382) (xy 83.871498 -251.514195) (xy 83.915572 -251.488749)
			(xy 83.963158 -251.470702) (xy 84.013022 -251.460522) (xy 84.063874 -251.458473) (xy 84.114395 -251.464607)
			(xy 84.163279 -251.478767) (xy 84.209258 -251.500584) (xy 84.251142 -251.529494) (xy 84.287846 -251.564749)
			(xy 84.318419 -251.605435) (xy 84.34207 -251.650498) (xy 84.358186 -251.698772) (xy 84.36635 -251.749006)
			(xy 84.366862 -251.774452) (xy 84.366359 -251.799441) (xy 84.673422 -251.799441) (xy 84.673422 -251.749463)
			(xy 84.681241 -251.7001) (xy 84.696685 -251.652568) (xy 84.719375 -251.608036) (xy 84.748751 -251.567603)
			(xy 84.784091 -251.532263) (xy 84.824524 -251.502887) (xy 84.869056 -251.480197) (xy 84.916588 -251.464753)
			(xy 84.965951 -251.456934) (xy 85.015929 -251.456934) (xy 85.065292 -251.464753) (xy 85.112824 -251.480197)
			(xy 85.157356 -251.502887) (xy 85.197789 -251.532263) (xy 85.233129 -251.567603) (xy 85.262505 -251.608036)
			(xy 85.285195 -251.652568) (xy 85.300639 -251.7001) (xy 85.308458 -251.749463) (xy 85.308948 -251.774452)
			(xy 85.308458 -251.799441) (xy 85.613476 -251.799441) (xy 85.613476 -251.749463) (xy 85.621295 -251.7001)
			(xy 85.636739 -251.652568) (xy 85.659429 -251.608036) (xy 85.688805 -251.567603) (xy 85.724145 -251.532263)
			(xy 85.764578 -251.502887) (xy 85.80911 -251.480197) (xy 85.856642 -251.464753) (xy 85.906005 -251.456934)
			(xy 85.955983 -251.456934) (xy 86.005346 -251.464753) (xy 86.052878 -251.480197) (xy 86.09741 -251.502887)
			(xy 86.137843 -251.532263) (xy 86.173183 -251.567603) (xy 86.202559 -251.608036) (xy 86.225249 -251.652568)
			(xy 86.240693 -251.7001) (xy 86.248512 -251.749463) (xy 86.249002 -251.774452) (xy 87.494867 -251.774452)
			(xy 87.498962 -251.723724) (xy 87.511141 -251.67431) (xy 87.531089 -251.62749) (xy 87.55829 -251.584476)
			(xy 87.592038 -251.546382) (xy 87.63146 -251.514195) (xy 87.675534 -251.488749) (xy 87.72312 -251.470702)
			(xy 87.772984 -251.460522) (xy 87.823836 -251.458473) (xy 87.874357 -251.464607) (xy 87.923241 -251.478767)
			(xy 87.96922 -251.500584) (xy 88.011104 -251.529494) (xy 88.047808 -251.564749) (xy 88.078381 -251.605435)
			(xy 88.102032 -251.650498) (xy 88.118148 -251.698772) (xy 88.126312 -251.749006) (xy 88.126824 -251.774452)
			(xy 88.126321 -251.799441) (xy 88.433638 -251.799441) (xy 88.433638 -251.749463) (xy 88.441457 -251.7001)
			(xy 88.456901 -251.652568) (xy 88.479591 -251.608036) (xy 88.508967 -251.567603) (xy 88.544307 -251.532263)
			(xy 88.58474 -251.502887) (xy 88.629272 -251.480197) (xy 88.676804 -251.464753) (xy 88.726167 -251.456934)
			(xy 88.776145 -251.456934) (xy 88.825508 -251.464753) (xy 88.87304 -251.480197) (xy 88.917572 -251.502887)
			(xy 88.958005 -251.532263) (xy 88.993345 -251.567603) (xy 89.022721 -251.608036) (xy 89.045411 -251.652568)
			(xy 89.060855 -251.7001) (xy 89.068674 -251.749463) (xy 89.069164 -251.774452) (xy 89.068674 -251.799441)
			(xy 89.373438 -251.799441) (xy 89.373438 -251.749463) (xy 89.381257 -251.7001) (xy 89.396701 -251.652568)
			(xy 89.419391 -251.608036) (xy 89.448767 -251.567603) (xy 89.484107 -251.532263) (xy 89.52454 -251.502887)
			(xy 89.569072 -251.480197) (xy 89.616604 -251.464753) (xy 89.665967 -251.456934) (xy 89.715945 -251.456934)
			(xy 89.765308 -251.464753) (xy 89.81284 -251.480197) (xy 89.857372 -251.502887) (xy 89.897805 -251.532263)
			(xy 89.933145 -251.567603) (xy 89.962521 -251.608036) (xy 89.985211 -251.652568) (xy 90.000655 -251.7001)
			(xy 90.008474 -251.749463) (xy 90.008964 -251.774452) (xy 90.314775 -251.774452) (xy 90.31887 -251.723724)
			(xy 90.331049 -251.67431) (xy 90.350997 -251.62749) (xy 90.378198 -251.584476) (xy 90.411946 -251.546382)
			(xy 90.451368 -251.514195) (xy 90.495442 -251.488749) (xy 90.543028 -251.470702) (xy 90.592892 -251.460522)
			(xy 90.643744 -251.458473) (xy 90.694265 -251.464607) (xy 90.743149 -251.478767) (xy 90.789128 -251.500584)
			(xy 90.831012 -251.529494) (xy 90.867716 -251.564749) (xy 90.898289 -251.605435) (xy 90.92194 -251.650498)
			(xy 90.938056 -251.698772) (xy 90.94622 -251.749006) (xy 90.946732 -251.774452) (xy 90.946229 -251.799441)
			(xy 91.253546 -251.799441) (xy 91.253546 -251.749463) (xy 91.261365 -251.7001) (xy 91.276809 -251.652568)
			(xy 91.299499 -251.608036) (xy 91.328875 -251.567603) (xy 91.364215 -251.532263) (xy 91.404648 -251.502887)
			(xy 91.44918 -251.480197) (xy 91.496712 -251.464753) (xy 91.546075 -251.456934) (xy 91.596053 -251.456934)
			(xy 91.645416 -251.464753) (xy 91.692948 -251.480197) (xy 91.73748 -251.502887) (xy 91.777913 -251.532263)
			(xy 91.813253 -251.567603) (xy 91.842629 -251.608036) (xy 91.865319 -251.652568) (xy 91.880763 -251.7001)
			(xy 91.888582 -251.749463) (xy 91.889072 -251.774452) (xy 91.888582 -251.799441) (xy 92.1936 -251.799441)
			(xy 92.1936 -251.749463) (xy 92.201419 -251.7001) (xy 92.216863 -251.652568) (xy 92.239553 -251.608036)
			(xy 92.268929 -251.567603) (xy 92.304269 -251.532263) (xy 92.344702 -251.502887) (xy 92.389234 -251.480197)
			(xy 92.436766 -251.464753) (xy 92.486129 -251.456934) (xy 92.536107 -251.456934) (xy 92.58547 -251.464753)
			(xy 92.633002 -251.480197) (xy 92.677534 -251.502887) (xy 92.717967 -251.532263) (xy 92.753307 -251.567603)
			(xy 92.782683 -251.608036) (xy 92.805373 -251.652568) (xy 92.820817 -251.7001) (xy 92.828636 -251.749463)
			(xy 92.829126 -251.774452) (xy 94.074737 -251.774452) (xy 94.078832 -251.723724) (xy 94.091011 -251.67431)
			(xy 94.110959 -251.62749) (xy 94.13816 -251.584476) (xy 94.171908 -251.546382) (xy 94.21133 -251.514195)
			(xy 94.255404 -251.488749) (xy 94.30299 -251.470702) (xy 94.352854 -251.460522) (xy 94.403706 -251.458473)
			(xy 94.454227 -251.464607) (xy 94.503111 -251.478767) (xy 94.54909 -251.500584) (xy 94.590974 -251.529494)
			(xy 94.627678 -251.564749) (xy 94.658251 -251.605435) (xy 94.681902 -251.650498) (xy 94.698018 -251.698772)
			(xy 94.706182 -251.749006) (xy 94.706694 -251.774452) (xy 94.706191 -251.799441) (xy 95.013508 -251.799441)
			(xy 95.013508 -251.749463) (xy 95.021327 -251.7001) (xy 95.036771 -251.652568) (xy 95.059461 -251.608036)
			(xy 95.088837 -251.567603) (xy 95.124177 -251.532263) (xy 95.16461 -251.502887) (xy 95.209142 -251.480197)
			(xy 95.256674 -251.464753) (xy 95.306037 -251.456934) (xy 95.356015 -251.456934) (xy 95.405378 -251.464753)
			(xy 95.45291 -251.480197) (xy 95.497442 -251.502887) (xy 95.537875 -251.532263) (xy 95.573215 -251.567603)
			(xy 95.602591 -251.608036) (xy 95.625281 -251.652568) (xy 95.640725 -251.7001) (xy 95.648544 -251.749463)
			(xy 95.649034 -251.774452) (xy 95.648544 -251.799441) (xy 95.640725 -251.848804) (xy 95.625281 -251.896336)
			(xy 95.602591 -251.940868) (xy 95.573215 -251.981301) (xy 95.537875 -252.016641) (xy 95.497442 -252.046017)
			(xy 95.45291 -252.068707) (xy 95.405378 -252.084151) (xy 95.356015 -252.09197) (xy 95.306037 -252.09197)
			(xy 95.256674 -252.084151) (xy 95.209142 -252.068707) (xy 95.16461 -252.046017) (xy 95.124177 -252.016641)
			(xy 95.088837 -251.981301) (xy 95.059461 -251.940868) (xy 95.036771 -251.896336) (xy 95.021327 -251.848804)
			(xy 95.013508 -251.799441) (xy 94.706191 -251.799441) (xy 94.706182 -251.799898) (xy 94.698018 -251.850132)
			(xy 94.681902 -251.898406) (xy 94.658251 -251.943469) (xy 94.627678 -251.984155) (xy 94.590974 -252.01941)
			(xy 94.54909 -252.04832) (xy 94.503111 -252.070137) (xy 94.454227 -252.084297) (xy 94.403706 -252.090431)
			(xy 94.352854 -252.088382) (xy 94.30299 -252.078202) (xy 94.255404 -252.060155) (xy 94.21133 -252.034709)
			(xy 94.171908 -252.002522) (xy 94.13816 -251.964428) (xy 94.110959 -251.921414) (xy 94.091011 -251.874594)
			(xy 94.078832 -251.82518) (xy 94.074737 -251.774452) (xy 92.829126 -251.774452) (xy 92.828636 -251.799441)
			(xy 92.820817 -251.848804) (xy 92.805373 -251.896336) (xy 92.782683 -251.940868) (xy 92.753307 -251.981301)
			(xy 92.717967 -252.016641) (xy 92.677534 -252.046017) (xy 92.633002 -252.068707) (xy 92.58547 -252.084151)
			(xy 92.536107 -252.09197) (xy 92.486129 -252.09197) (xy 92.436766 -252.084151) (xy 92.389234 -252.068707)
			(xy 92.344702 -252.046017) (xy 92.304269 -252.016641) (xy 92.268929 -251.981301) (xy 92.239553 -251.940868)
			(xy 92.216863 -251.896336) (xy 92.201419 -251.848804) (xy 92.1936 -251.799441) (xy 91.888582 -251.799441)
			(xy 91.880763 -251.848804) (xy 91.865319 -251.896336) (xy 91.842629 -251.940868) (xy 91.813253 -251.981301)
			(xy 91.777913 -252.016641) (xy 91.73748 -252.046017) (xy 91.692948 -252.068707) (xy 91.645416 -252.084151)
			(xy 91.596053 -252.09197) (xy 91.546075 -252.09197) (xy 91.496712 -252.084151) (xy 91.44918 -252.068707)
			(xy 91.404648 -252.046017) (xy 91.364215 -252.016641) (xy 91.328875 -251.981301) (xy 91.299499 -251.940868)
			(xy 91.276809 -251.896336) (xy 91.261365 -251.848804) (xy 91.253546 -251.799441) (xy 90.946229 -251.799441)
			(xy 90.94622 -251.799898) (xy 90.938056 -251.850132) (xy 90.92194 -251.898406) (xy 90.898289 -251.943469)
			(xy 90.867716 -251.984155) (xy 90.831012 -252.01941) (xy 90.789128 -252.04832) (xy 90.743149 -252.070137)
			(xy 90.694265 -252.084297) (xy 90.643744 -252.090431) (xy 90.592892 -252.088382) (xy 90.543028 -252.078202)
			(xy 90.495442 -252.060155) (xy 90.451368 -252.034709) (xy 90.411946 -252.002522) (xy 90.378198 -251.964428)
			(xy 90.350997 -251.921414) (xy 90.331049 -251.874594) (xy 90.31887 -251.82518) (xy 90.314775 -251.774452)
			(xy 90.008964 -251.774452) (xy 90.008474 -251.799441) (xy 90.000655 -251.848804) (xy 89.985211 -251.896336)
			(xy 89.962521 -251.940868) (xy 89.933145 -251.981301) (xy 89.897805 -252.016641) (xy 89.857372 -252.046017)
			(xy 89.81284 -252.068707) (xy 89.765308 -252.084151) (xy 89.715945 -252.09197) (xy 89.665967 -252.09197)
			(xy 89.616604 -252.084151) (xy 89.569072 -252.068707) (xy 89.52454 -252.046017) (xy 89.484107 -252.016641)
			(xy 89.448767 -251.981301) (xy 89.419391 -251.940868) (xy 89.396701 -251.896336) (xy 89.381257 -251.848804)
			(xy 89.373438 -251.799441) (xy 89.068674 -251.799441) (xy 89.060855 -251.848804) (xy 89.045411 -251.896336)
			(xy 89.022721 -251.940868) (xy 88.993345 -251.981301) (xy 88.958005 -252.016641) (xy 88.917572 -252.046017)
			(xy 88.87304 -252.068707) (xy 88.825508 -252.084151) (xy 88.776145 -252.09197) (xy 88.726167 -252.09197)
			(xy 88.676804 -252.084151) (xy 88.629272 -252.068707) (xy 88.58474 -252.046017) (xy 88.544307 -252.016641)
			(xy 88.508967 -251.981301) (xy 88.479591 -251.940868) (xy 88.456901 -251.896336) (xy 88.441457 -251.848804)
			(xy 88.433638 -251.799441) (xy 88.126321 -251.799441) (xy 88.126312 -251.799898) (xy 88.118148 -251.850132)
			(xy 88.102032 -251.898406) (xy 88.078381 -251.943469) (xy 88.047808 -251.984155) (xy 88.011104 -252.01941)
			(xy 87.96922 -252.04832) (xy 87.923241 -252.070137) (xy 87.874357 -252.084297) (xy 87.823836 -252.090431)
			(xy 87.772984 -252.088382) (xy 87.72312 -252.078202) (xy 87.675534 -252.060155) (xy 87.63146 -252.034709)
			(xy 87.592038 -252.002522) (xy 87.55829 -251.964428) (xy 87.531089 -251.921414) (xy 87.511141 -251.874594)
			(xy 87.498962 -251.82518) (xy 87.494867 -251.774452) (xy 86.249002 -251.774452) (xy 86.248512 -251.799441)
			(xy 86.240693 -251.848804) (xy 86.225249 -251.896336) (xy 86.202559 -251.940868) (xy 86.173183 -251.981301)
			(xy 86.137843 -252.016641) (xy 86.09741 -252.046017) (xy 86.052878 -252.068707) (xy 86.005346 -252.084151)
			(xy 85.955983 -252.09197) (xy 85.906005 -252.09197) (xy 85.856642 -252.084151) (xy 85.80911 -252.068707)
			(xy 85.764578 -252.046017) (xy 85.724145 -252.016641) (xy 85.688805 -251.981301) (xy 85.659429 -251.940868)
			(xy 85.636739 -251.896336) (xy 85.621295 -251.848804) (xy 85.613476 -251.799441) (xy 85.308458 -251.799441)
			(xy 85.300639 -251.848804) (xy 85.285195 -251.896336) (xy 85.262505 -251.940868) (xy 85.233129 -251.981301)
			(xy 85.197789 -252.016641) (xy 85.157356 -252.046017) (xy 85.112824 -252.068707) (xy 85.065292 -252.084151)
			(xy 85.015929 -252.09197) (xy 84.965951 -252.09197) (xy 84.916588 -252.084151) (xy 84.869056 -252.068707)
			(xy 84.824524 -252.046017) (xy 84.784091 -252.016641) (xy 84.748751 -251.981301) (xy 84.719375 -251.940868)
			(xy 84.696685 -251.896336) (xy 84.681241 -251.848804) (xy 84.673422 -251.799441) (xy 84.366359 -251.799441)
			(xy 84.36635 -251.799898) (xy 84.358186 -251.850132) (xy 84.34207 -251.898406) (xy 84.318419 -251.943469)
			(xy 84.287846 -251.984155) (xy 84.251142 -252.01941) (xy 84.209258 -252.04832) (xy 84.163279 -252.070137)
			(xy 84.114395 -252.084297) (xy 84.063874 -252.090431) (xy 84.013022 -252.088382) (xy 83.963158 -252.078202)
			(xy 83.915572 -252.060155) (xy 83.871498 -252.034709) (xy 83.832076 -252.002522) (xy 83.798328 -251.964428)
			(xy 83.771127 -251.921414) (xy 83.751179 -251.874594) (xy 83.739 -251.82518) (xy 83.734905 -251.774452)
			(xy 83.429094 -251.774452) (xy 83.428604 -251.799441) (xy 83.420785 -251.848804) (xy 83.405341 -251.896336)
			(xy 83.382651 -251.940868) (xy 83.353275 -251.981301) (xy 83.317935 -252.016641) (xy 83.277502 -252.046017)
			(xy 83.23297 -252.068707) (xy 83.185438 -252.084151) (xy 83.136075 -252.09197) (xy 83.086097 -252.09197)
			(xy 83.036734 -252.084151) (xy 82.989202 -252.068707) (xy 82.94467 -252.046017) (xy 82.904237 -252.016641)
			(xy 82.868897 -251.981301) (xy 82.839521 -251.940868) (xy 82.816831 -251.896336) (xy 82.801387 -251.848804)
			(xy 82.793568 -251.799441) (xy 82.48855 -251.799441) (xy 82.480731 -251.848804) (xy 82.465287 -251.896336)
			(xy 82.442597 -251.940868) (xy 82.413221 -251.981301) (xy 82.377881 -252.016641) (xy 82.337448 -252.046017)
			(xy 82.292916 -252.068707) (xy 82.245384 -252.084151) (xy 82.196021 -252.09197) (xy 82.146043 -252.09197)
			(xy 82.09668 -252.084151) (xy 82.049148 -252.068707) (xy 82.004616 -252.046017) (xy 81.964183 -252.016641)
			(xy 81.928843 -251.981301) (xy 81.899467 -251.940868) (xy 81.876777 -251.896336) (xy 81.861333 -251.848804)
			(xy 81.853514 -251.799441) (xy 81.546197 -251.799441) (xy 81.546188 -251.799898) (xy 81.538024 -251.850132)
			(xy 81.521908 -251.898406) (xy 81.498257 -251.943469) (xy 81.467684 -251.984155) (xy 81.43098 -252.01941)
			(xy 81.389096 -252.04832) (xy 81.343117 -252.070137) (xy 81.294233 -252.084297) (xy 81.243712 -252.090431)
			(xy 81.19286 -252.088382) (xy 81.142996 -252.078202) (xy 81.09541 -252.060155) (xy 81.051336 -252.034709)
			(xy 81.011914 -252.002522) (xy 80.978166 -251.964428) (xy 80.950965 -251.921414) (xy 80.931017 -251.874594)
			(xy 80.918838 -251.82518) (xy 80.914743 -251.774452) (xy 79.53248 -251.774452) (xy 79.53248 -252.208538)
			(xy 79.532973 -252.223317) (xy 79.541423 -252.251642) (xy 79.557633 -252.276359) (xy 79.580245 -252.295396)
			(xy 79.607363 -252.307157) (xy 79.636713 -252.310657) (xy 79.665836 -252.305603) (xy 79.679292 -252.29947)
			(xy 79.701429 -252.288977) (xy 79.748121 -252.27416) (xy 79.796531 -252.266665) (xy 79.821024 -252.266196)
			(xy 79.846035 -252.266689) (xy 79.895441 -252.274517) (xy 79.943015 -252.289978) (xy 79.987584 -252.31269)
			(xy 80.028051 -252.342094) (xy 80.063421 -252.377467) (xy 80.092823 -252.417937) (xy 80.115531 -252.462508)
			(xy 80.130988 -252.510082) (xy 80.138813 -252.559489) (xy 80.138813 -252.584458) (xy 80.444843 -252.584458)
			(xy 80.448938 -252.53373) (xy 80.461117 -252.484316) (xy 80.481065 -252.437496) (xy 80.508266 -252.394482)
			(xy 80.542014 -252.356388) (xy 80.581436 -252.324201) (xy 80.62551 -252.298755) (xy 80.673096 -252.280708)
			(xy 80.72296 -252.270528) (xy 80.773812 -252.268479) (xy 80.824333 -252.274613) (xy 80.873217 -252.288773)
			(xy 80.919196 -252.31059) (xy 80.96108 -252.3395) (xy 80.997784 -252.374755) (xy 81.028357 -252.415441)
			(xy 81.052008 -252.460504) (xy 81.068124 -252.508778) (xy 81.076288 -252.559012) (xy 81.0768 -252.584458)
			(xy 81.076297 -252.609447) (xy 81.383614 -252.609447) (xy 81.383614 -252.559469) (xy 81.391433 -252.510106)
			(xy 81.406877 -252.462574) (xy 81.429567 -252.418042) (xy 81.458943 -252.377609) (xy 81.494283 -252.342269)
			(xy 81.534716 -252.312893) (xy 81.579248 -252.290203) (xy 81.62678 -252.274759) (xy 81.676143 -252.26694)
			(xy 81.726121 -252.26694) (xy 81.775484 -252.274759) (xy 81.823016 -252.290203) (xy 81.867548 -252.312893)
			(xy 81.907981 -252.342269) (xy 81.943321 -252.377609) (xy 81.972697 -252.418042) (xy 81.995387 -252.462574)
			(xy 82.010831 -252.510106) (xy 82.01865 -252.559469) (xy 82.01914 -252.584458) (xy 82.324697 -252.584458)
			(xy 82.328792 -252.53373) (xy 82.340971 -252.484316) (xy 82.360919 -252.437496) (xy 82.38812 -252.394482)
			(xy 82.421868 -252.356388) (xy 82.46129 -252.324201) (xy 82.505364 -252.298755) (xy 82.55295 -252.280708)
			(xy 82.602814 -252.270528) (xy 82.653666 -252.268479) (xy 82.704187 -252.274613) (xy 82.753071 -252.288773)
			(xy 82.79905 -252.31059) (xy 82.840934 -252.3395) (xy 82.877638 -252.374755) (xy 82.908211 -252.415441)
			(xy 82.931862 -252.460504) (xy 82.947978 -252.508778) (xy 82.956142 -252.559012) (xy 82.956654 -252.584458)
			(xy 82.956151 -252.609447) (xy 83.263468 -252.609447) (xy 83.263468 -252.559469) (xy 83.271287 -252.510106)
			(xy 83.286731 -252.462574) (xy 83.309421 -252.418042) (xy 83.338797 -252.377609) (xy 83.374137 -252.342269)
			(xy 83.41457 -252.312893) (xy 83.459102 -252.290203) (xy 83.506634 -252.274759) (xy 83.555997 -252.26694)
			(xy 83.605975 -252.26694) (xy 83.655338 -252.274759) (xy 83.70287 -252.290203) (xy 83.747402 -252.312893)
			(xy 83.787835 -252.342269) (xy 83.823175 -252.377609) (xy 83.852551 -252.418042) (xy 83.875241 -252.462574)
			(xy 83.890685 -252.510106) (xy 83.898504 -252.559469) (xy 83.898994 -252.584458) (xy 84.204805 -252.584458)
			(xy 84.2089 -252.53373) (xy 84.221079 -252.484316) (xy 84.241027 -252.437496) (xy 84.268228 -252.394482)
			(xy 84.301976 -252.356388) (xy 84.341398 -252.324201) (xy 84.385472 -252.298755) (xy 84.433058 -252.280708)
			(xy 84.482922 -252.270528) (xy 84.533774 -252.268479) (xy 84.584295 -252.274613) (xy 84.633179 -252.288773)
			(xy 84.679158 -252.31059) (xy 84.721042 -252.3395) (xy 84.757746 -252.374755) (xy 84.788319 -252.415441)
			(xy 84.81197 -252.460504) (xy 84.828086 -252.508778) (xy 84.83625 -252.559012) (xy 84.836762 -252.584458)
			(xy 85.144859 -252.584458) (xy 85.148954 -252.53373) (xy 85.161133 -252.484316) (xy 85.181081 -252.437496)
			(xy 85.208282 -252.394482) (xy 85.24203 -252.356388) (xy 85.281452 -252.324201) (xy 85.325526 -252.298755)
			(xy 85.373112 -252.280708) (xy 85.422976 -252.270528) (xy 85.473828 -252.268479) (xy 85.524349 -252.274613)
			(xy 85.573233 -252.288773) (xy 85.619212 -252.31059) (xy 85.661096 -252.3395) (xy 85.6978 -252.374755)
			(xy 85.728373 -252.415441) (xy 85.752024 -252.460504) (xy 85.76814 -252.508778) (xy 85.776304 -252.559012)
			(xy 85.776816 -252.584458) (xy 85.776313 -252.609447) (xy 86.08363 -252.609447) (xy 86.08363 -252.559469)
			(xy 86.091449 -252.510106) (xy 86.106893 -252.462574) (xy 86.129583 -252.418042) (xy 86.158959 -252.377609)
			(xy 86.194299 -252.342269) (xy 86.234732 -252.312893) (xy 86.279264 -252.290203) (xy 86.326796 -252.274759)
			(xy 86.376159 -252.26694) (xy 86.426137 -252.26694) (xy 86.4755 -252.274759) (xy 86.523032 -252.290203)
			(xy 86.567564 -252.312893) (xy 86.607997 -252.342269) (xy 86.643337 -252.377609) (xy 86.672713 -252.418042)
			(xy 86.695403 -252.462574) (xy 86.710847 -252.510106) (xy 86.718666 -252.559469) (xy 86.719156 -252.584458)
			(xy 87.024713 -252.584458) (xy 87.028808 -252.53373) (xy 87.040987 -252.484316) (xy 87.060935 -252.437496)
			(xy 87.088136 -252.394482) (xy 87.121884 -252.356388) (xy 87.161306 -252.324201) (xy 87.20538 -252.298755)
			(xy 87.252966 -252.280708) (xy 87.30283 -252.270528) (xy 87.353682 -252.268479) (xy 87.404203 -252.274613)
			(xy 87.453087 -252.288773) (xy 87.499066 -252.31059) (xy 87.54095 -252.3395) (xy 87.577654 -252.374755)
			(xy 87.608227 -252.415441) (xy 87.631878 -252.460504) (xy 87.647994 -252.508778) (xy 87.656158 -252.559012)
			(xy 87.65667 -252.584458) (xy 87.656167 -252.609447) (xy 87.963484 -252.609447) (xy 87.963484 -252.559469)
			(xy 87.971303 -252.510106) (xy 87.986747 -252.462574) (xy 88.009437 -252.418042) (xy 88.038813 -252.377609)
			(xy 88.074153 -252.342269) (xy 88.114586 -252.312893) (xy 88.159118 -252.290203) (xy 88.20665 -252.274759)
			(xy 88.256013 -252.26694) (xy 88.305991 -252.26694) (xy 88.355354 -252.274759) (xy 88.402886 -252.290203)
			(xy 88.447418 -252.312893) (xy 88.487851 -252.342269) (xy 88.523191 -252.377609) (xy 88.552567 -252.418042)
			(xy 88.575257 -252.462574) (xy 88.590701 -252.510106) (xy 88.59852 -252.559469) (xy 88.59901 -252.584458)
			(xy 88.904821 -252.584458) (xy 88.908916 -252.53373) (xy 88.921095 -252.484316) (xy 88.941043 -252.437496)
			(xy 88.968244 -252.394482) (xy 89.001992 -252.356388) (xy 89.041414 -252.324201) (xy 89.085488 -252.298755)
			(xy 89.133074 -252.280708) (xy 89.182938 -252.270528) (xy 89.23379 -252.268479) (xy 89.284311 -252.274613)
			(xy 89.333195 -252.288773) (xy 89.379174 -252.31059) (xy 89.421058 -252.3395) (xy 89.457762 -252.374755)
			(xy 89.488335 -252.415441) (xy 89.511986 -252.460504) (xy 89.528102 -252.508778) (xy 89.536266 -252.559012)
			(xy 89.536778 -252.584458) (xy 89.536275 -252.609447) (xy 89.843592 -252.609447) (xy 89.843592 -252.559469)
			(xy 89.851411 -252.510106) (xy 89.866855 -252.462574) (xy 89.889545 -252.418042) (xy 89.918921 -252.377609)
			(xy 89.954261 -252.342269) (xy 89.994694 -252.312893) (xy 90.039226 -252.290203) (xy 90.086758 -252.274759)
			(xy 90.136121 -252.26694) (xy 90.186099 -252.26694) (xy 90.235462 -252.274759) (xy 90.282994 -252.290203)
			(xy 90.327526 -252.312893) (xy 90.367959 -252.342269) (xy 90.403299 -252.377609) (xy 90.432675 -252.418042)
			(xy 90.455365 -252.462574) (xy 90.470809 -252.510106) (xy 90.478628 -252.559469) (xy 90.479118 -252.584458)
			(xy 90.784675 -252.584458) (xy 90.78877 -252.53373) (xy 90.800949 -252.484316) (xy 90.820897 -252.437496)
			(xy 90.848098 -252.394482) (xy 90.881846 -252.356388) (xy 90.921268 -252.324201) (xy 90.965342 -252.298755)
			(xy 91.012928 -252.280708) (xy 91.062792 -252.270528) (xy 91.113644 -252.268479) (xy 91.164165 -252.274613)
			(xy 91.213049 -252.288773) (xy 91.259028 -252.31059) (xy 91.300912 -252.3395) (xy 91.337616 -252.374755)
			(xy 91.368189 -252.415441) (xy 91.39184 -252.460504) (xy 91.407956 -252.508778) (xy 91.41612 -252.559012)
			(xy 91.416632 -252.584458) (xy 91.724729 -252.584458) (xy 91.728824 -252.53373) (xy 91.741003 -252.484316)
			(xy 91.760951 -252.437496) (xy 91.788152 -252.394482) (xy 91.8219 -252.356388) (xy 91.861322 -252.324201)
			(xy 91.905396 -252.298755) (xy 91.952982 -252.280708) (xy 92.002846 -252.270528) (xy 92.053698 -252.268479)
			(xy 92.104219 -252.274613) (xy 92.153103 -252.288773) (xy 92.199082 -252.31059) (xy 92.240966 -252.3395)
			(xy 92.27767 -252.374755) (xy 92.308243 -252.415441) (xy 92.331894 -252.460504) (xy 92.34801 -252.508778)
			(xy 92.356174 -252.559012) (xy 92.356686 -252.584458) (xy 92.356183 -252.609447) (xy 92.6635 -252.609447)
			(xy 92.6635 -252.559469) (xy 92.671319 -252.510106) (xy 92.686763 -252.462574) (xy 92.709453 -252.418042)
			(xy 92.738829 -252.377609) (xy 92.774169 -252.342269) (xy 92.814602 -252.312893) (xy 92.859134 -252.290203)
			(xy 92.906666 -252.274759) (xy 92.956029 -252.26694) (xy 93.006007 -252.26694) (xy 93.05537 -252.274759)
			(xy 93.102902 -252.290203) (xy 93.147434 -252.312893) (xy 93.187867 -252.342269) (xy 93.223207 -252.377609)
			(xy 93.252583 -252.418042) (xy 93.275273 -252.462574) (xy 93.290717 -252.510106) (xy 93.298536 -252.559469)
			(xy 93.299026 -252.584458) (xy 93.604837 -252.584458) (xy 93.608932 -252.53373) (xy 93.621111 -252.484316)
			(xy 93.641059 -252.437496) (xy 93.66826 -252.394482) (xy 93.702008 -252.356388) (xy 93.74143 -252.324201)
			(xy 93.785504 -252.298755) (xy 93.83309 -252.280708) (xy 93.882954 -252.270528) (xy 93.933806 -252.268479)
			(xy 93.984327 -252.274613) (xy 94.033211 -252.288773) (xy 94.07919 -252.31059) (xy 94.121074 -252.3395)
			(xy 94.157778 -252.374755) (xy 94.188351 -252.415441) (xy 94.212002 -252.460504) (xy 94.228118 -252.508778)
			(xy 94.236282 -252.559012) (xy 94.236794 -252.584458) (xy 94.236291 -252.609447) (xy 94.543608 -252.609447)
			(xy 94.543608 -252.559469) (xy 94.551427 -252.510106) (xy 94.566871 -252.462574) (xy 94.589561 -252.418042)
			(xy 94.618937 -252.377609) (xy 94.654277 -252.342269) (xy 94.69471 -252.312893) (xy 94.739242 -252.290203)
			(xy 94.786774 -252.274759) (xy 94.836137 -252.26694) (xy 94.886115 -252.26694) (xy 94.935478 -252.274759)
			(xy 94.98301 -252.290203) (xy 95.027542 -252.312893) (xy 95.067975 -252.342269) (xy 95.103315 -252.377609)
			(xy 95.132691 -252.418042) (xy 95.155381 -252.462574) (xy 95.170825 -252.510106) (xy 95.178644 -252.559469)
			(xy 95.179134 -252.584458) (xy 95.178644 -252.609447) (xy 95.170825 -252.65881) (xy 95.155381 -252.706342)
			(xy 95.132691 -252.750874) (xy 95.103315 -252.791307) (xy 95.067975 -252.826647) (xy 95.027542 -252.856023)
			(xy 94.98301 -252.878713) (xy 94.935478 -252.894157) (xy 94.886115 -252.901976) (xy 94.836137 -252.901976)
			(xy 94.786774 -252.894157) (xy 94.739242 -252.878713) (xy 94.69471 -252.856023) (xy 94.654277 -252.826647)
			(xy 94.618937 -252.791307) (xy 94.589561 -252.750874) (xy 94.566871 -252.706342) (xy 94.551427 -252.65881)
			(xy 94.543608 -252.609447) (xy 94.236291 -252.609447) (xy 94.236282 -252.609904) (xy 94.228118 -252.660138)
			(xy 94.212002 -252.708412) (xy 94.188351 -252.753475) (xy 94.157778 -252.794161) (xy 94.121074 -252.829416)
			(xy 94.07919 -252.858326) (xy 94.033211 -252.880143) (xy 93.984327 -252.894303) (xy 93.933806 -252.900437)
			(xy 93.882954 -252.898388) (xy 93.83309 -252.888208) (xy 93.785504 -252.870161) (xy 93.74143 -252.844715)
			(xy 93.702008 -252.812528) (xy 93.66826 -252.774434) (xy 93.641059 -252.73142) (xy 93.621111 -252.6846)
			(xy 93.608932 -252.635186) (xy 93.604837 -252.584458) (xy 93.299026 -252.584458) (xy 93.298536 -252.609447)
			(xy 93.290717 -252.65881) (xy 93.275273 -252.706342) (xy 93.252583 -252.750874) (xy 93.223207 -252.791307)
			(xy 93.187867 -252.826647) (xy 93.147434 -252.856023) (xy 93.102902 -252.878713) (xy 93.05537 -252.894157)
			(xy 93.006007 -252.901976) (xy 92.956029 -252.901976) (xy 92.906666 -252.894157) (xy 92.859134 -252.878713)
			(xy 92.814602 -252.856023) (xy 92.774169 -252.826647) (xy 92.738829 -252.791307) (xy 92.709453 -252.750874)
			(xy 92.686763 -252.706342) (xy 92.671319 -252.65881) (xy 92.6635 -252.609447) (xy 92.356183 -252.609447)
			(xy 92.356174 -252.609904) (xy 92.34801 -252.660138) (xy 92.331894 -252.708412) (xy 92.308243 -252.753475)
			(xy 92.27767 -252.794161) (xy 92.240966 -252.829416) (xy 92.199082 -252.858326) (xy 92.153103 -252.880143)
			(xy 92.104219 -252.894303) (xy 92.053698 -252.900437) (xy 92.002846 -252.898388) (xy 91.952982 -252.888208)
			(xy 91.905396 -252.870161) (xy 91.861322 -252.844715) (xy 91.8219 -252.812528) (xy 91.788152 -252.774434)
			(xy 91.760951 -252.73142) (xy 91.741003 -252.6846) (xy 91.728824 -252.635186) (xy 91.724729 -252.584458)
			(xy 91.416632 -252.584458) (xy 91.41612 -252.609904) (xy 91.407956 -252.660138) (xy 91.39184 -252.708412)
			(xy 91.368189 -252.753475) (xy 91.337616 -252.794161) (xy 91.300912 -252.829416) (xy 91.259028 -252.858326)
			(xy 91.213049 -252.880143) (xy 91.164165 -252.894303) (xy 91.113644 -252.900437) (xy 91.062792 -252.898388)
			(xy 91.012928 -252.888208) (xy 90.965342 -252.870161) (xy 90.921268 -252.844715) (xy 90.881846 -252.812528)
			(xy 90.848098 -252.774434) (xy 90.820897 -252.73142) (xy 90.800949 -252.6846) (xy 90.78877 -252.635186)
			(xy 90.784675 -252.584458) (xy 90.479118 -252.584458) (xy 90.478628 -252.609447) (xy 90.470809 -252.65881)
			(xy 90.455365 -252.706342) (xy 90.432675 -252.750874) (xy 90.403299 -252.791307) (xy 90.367959 -252.826647)
			(xy 90.327526 -252.856023) (xy 90.282994 -252.878713) (xy 90.235462 -252.894157) (xy 90.186099 -252.901976)
			(xy 90.136121 -252.901976) (xy 90.086758 -252.894157) (xy 90.039226 -252.878713) (xy 89.994694 -252.856023)
			(xy 89.954261 -252.826647) (xy 89.918921 -252.791307) (xy 89.889545 -252.750874) (xy 89.866855 -252.706342)
			(xy 89.851411 -252.65881) (xy 89.843592 -252.609447) (xy 89.536275 -252.609447) (xy 89.536266 -252.609904)
			(xy 89.528102 -252.660138) (xy 89.511986 -252.708412) (xy 89.488335 -252.753475) (xy 89.457762 -252.794161)
			(xy 89.421058 -252.829416) (xy 89.379174 -252.858326) (xy 89.333195 -252.880143) (xy 89.284311 -252.894303)
			(xy 89.23379 -252.900437) (xy 89.182938 -252.898388) (xy 89.133074 -252.888208) (xy 89.085488 -252.870161)
			(xy 89.041414 -252.844715) (xy 89.001992 -252.812528) (xy 88.968244 -252.774434) (xy 88.941043 -252.73142)
			(xy 88.921095 -252.6846) (xy 88.908916 -252.635186) (xy 88.904821 -252.584458) (xy 88.59901 -252.584458)
			(xy 88.59852 -252.609447) (xy 88.590701 -252.65881) (xy 88.575257 -252.706342) (xy 88.552567 -252.750874)
			(xy 88.523191 -252.791307) (xy 88.487851 -252.826647) (xy 88.447418 -252.856023) (xy 88.402886 -252.878713)
			(xy 88.355354 -252.894157) (xy 88.305991 -252.901976) (xy 88.256013 -252.901976) (xy 88.20665 -252.894157)
			(xy 88.159118 -252.878713) (xy 88.114586 -252.856023) (xy 88.074153 -252.826647) (xy 88.038813 -252.791307)
			(xy 88.009437 -252.750874) (xy 87.986747 -252.706342) (xy 87.971303 -252.65881) (xy 87.963484 -252.609447)
			(xy 87.656167 -252.609447) (xy 87.656158 -252.609904) (xy 87.647994 -252.660138) (xy 87.631878 -252.708412)
			(xy 87.608227 -252.753475) (xy 87.577654 -252.794161) (xy 87.54095 -252.829416) (xy 87.499066 -252.858326)
			(xy 87.453087 -252.880143) (xy 87.404203 -252.894303) (xy 87.353682 -252.900437) (xy 87.30283 -252.898388)
			(xy 87.252966 -252.888208) (xy 87.20538 -252.870161) (xy 87.161306 -252.844715) (xy 87.121884 -252.812528)
			(xy 87.088136 -252.774434) (xy 87.060935 -252.73142) (xy 87.040987 -252.6846) (xy 87.028808 -252.635186)
			(xy 87.024713 -252.584458) (xy 86.719156 -252.584458) (xy 86.718666 -252.609447) (xy 86.710847 -252.65881)
			(xy 86.695403 -252.706342) (xy 86.672713 -252.750874) (xy 86.643337 -252.791307) (xy 86.607997 -252.826647)
			(xy 86.567564 -252.856023) (xy 86.523032 -252.878713) (xy 86.4755 -252.894157) (xy 86.426137 -252.901976)
			(xy 86.376159 -252.901976) (xy 86.326796 -252.894157) (xy 86.279264 -252.878713) (xy 86.234732 -252.856023)
			(xy 86.194299 -252.826647) (xy 86.158959 -252.791307) (xy 86.129583 -252.750874) (xy 86.106893 -252.706342)
			(xy 86.091449 -252.65881) (xy 86.08363 -252.609447) (xy 85.776313 -252.609447) (xy 85.776304 -252.609904)
			(xy 85.76814 -252.660138) (xy 85.752024 -252.708412) (xy 85.728373 -252.753475) (xy 85.6978 -252.794161)
			(xy 85.661096 -252.829416) (xy 85.619212 -252.858326) (xy 85.573233 -252.880143) (xy 85.524349 -252.894303)
			(xy 85.473828 -252.900437) (xy 85.422976 -252.898388) (xy 85.373112 -252.888208) (xy 85.325526 -252.870161)
			(xy 85.281452 -252.844715) (xy 85.24203 -252.812528) (xy 85.208282 -252.774434) (xy 85.181081 -252.73142)
			(xy 85.161133 -252.6846) (xy 85.148954 -252.635186) (xy 85.144859 -252.584458) (xy 84.836762 -252.584458)
			(xy 84.83625 -252.609904) (xy 84.828086 -252.660138) (xy 84.81197 -252.708412) (xy 84.788319 -252.753475)
			(xy 84.757746 -252.794161) (xy 84.721042 -252.829416) (xy 84.679158 -252.858326) (xy 84.633179 -252.880143)
			(xy 84.584295 -252.894303) (xy 84.533774 -252.900437) (xy 84.482922 -252.898388) (xy 84.433058 -252.888208)
			(xy 84.385472 -252.870161) (xy 84.341398 -252.844715) (xy 84.301976 -252.812528) (xy 84.268228 -252.774434)
			(xy 84.241027 -252.73142) (xy 84.221079 -252.6846) (xy 84.2089 -252.635186) (xy 84.204805 -252.584458)
			(xy 83.898994 -252.584458) (xy 83.898504 -252.609447) (xy 83.890685 -252.65881) (xy 83.875241 -252.706342)
			(xy 83.852551 -252.750874) (xy 83.823175 -252.791307) (xy 83.787835 -252.826647) (xy 83.747402 -252.856023)
			(xy 83.70287 -252.878713) (xy 83.655338 -252.894157) (xy 83.605975 -252.901976) (xy 83.555997 -252.901976)
			(xy 83.506634 -252.894157) (xy 83.459102 -252.878713) (xy 83.41457 -252.856023) (xy 83.374137 -252.826647)
			(xy 83.338797 -252.791307) (xy 83.309421 -252.750874) (xy 83.286731 -252.706342) (xy 83.271287 -252.65881)
			(xy 83.263468 -252.609447) (xy 82.956151 -252.609447) (xy 82.956142 -252.609904) (xy 82.947978 -252.660138)
			(xy 82.931862 -252.708412) (xy 82.908211 -252.753475) (xy 82.877638 -252.794161) (xy 82.840934 -252.829416)
			(xy 82.79905 -252.858326) (xy 82.753071 -252.880143) (xy 82.704187 -252.894303) (xy 82.653666 -252.900437)
			(xy 82.602814 -252.898388) (xy 82.55295 -252.888208) (xy 82.505364 -252.870161) (xy 82.46129 -252.844715)
			(xy 82.421868 -252.812528) (xy 82.38812 -252.774434) (xy 82.360919 -252.73142) (xy 82.340971 -252.6846)
			(xy 82.328792 -252.635186) (xy 82.324697 -252.584458) (xy 82.01914 -252.584458) (xy 82.01865 -252.609447)
			(xy 82.010831 -252.65881) (xy 81.995387 -252.706342) (xy 81.972697 -252.750874) (xy 81.943321 -252.791307)
			(xy 81.907981 -252.826647) (xy 81.867548 -252.856023) (xy 81.823016 -252.878713) (xy 81.775484 -252.894157)
			(xy 81.726121 -252.901976) (xy 81.676143 -252.901976) (xy 81.62678 -252.894157) (xy 81.579248 -252.878713)
			(xy 81.534716 -252.856023) (xy 81.494283 -252.826647) (xy 81.458943 -252.791307) (xy 81.429567 -252.750874)
			(xy 81.406877 -252.706342) (xy 81.391433 -252.65881) (xy 81.383614 -252.609447) (xy 81.076297 -252.609447)
			(xy 81.076288 -252.609904) (xy 81.068124 -252.660138) (xy 81.052008 -252.708412) (xy 81.028357 -252.753475)
			(xy 80.997784 -252.794161) (xy 80.96108 -252.829416) (xy 80.919196 -252.858326) (xy 80.873217 -252.880143)
			(xy 80.824333 -252.894303) (xy 80.773812 -252.900437) (xy 80.72296 -252.898388) (xy 80.673096 -252.888208)
			(xy 80.62551 -252.870161) (xy 80.581436 -252.844715) (xy 80.542014 -252.812528) (xy 80.508266 -252.774434)
			(xy 80.481065 -252.73142) (xy 80.461117 -252.6846) (xy 80.448938 -252.635186) (xy 80.444843 -252.584458)
			(xy 80.138813 -252.584458) (xy 80.138813 -252.609511) (xy 80.130988 -252.658918) (xy 80.115531 -252.706492)
			(xy 80.092823 -252.751063) (xy 80.063421 -252.791533) (xy 80.028051 -252.826906) (xy 79.987584 -252.85631)
			(xy 79.943015 -252.879022) (xy 79.895441 -252.894483) (xy 79.846035 -252.902311) (xy 79.821024 -252.90272)
			(xy 79.796529 -252.902273) (xy 79.748117 -252.894775) (xy 79.701423 -252.879954) (xy 79.679292 -252.869446)
			(xy 79.665842 -252.863322) (xy 79.636732 -252.858298) (xy 79.607401 -252.861815) (xy 79.580304 -252.87358)
			(xy 79.557707 -252.892607) (xy 79.541501 -252.917305) (xy 79.533041 -252.945608) (xy 79.53248 -252.960378)
			(xy 79.53248 -253.419453) (xy 79.97366 -253.419453) (xy 79.97366 -253.369475) (xy 79.981479 -253.320112)
			(xy 79.996923 -253.27258) (xy 80.019613 -253.228048) (xy 80.048989 -253.187615) (xy 80.084329 -253.152275)
			(xy 80.124762 -253.122899) (xy 80.169294 -253.100209) (xy 80.216826 -253.084765) (xy 80.266189 -253.076946)
			(xy 80.316167 -253.076946) (xy 80.36553 -253.084765) (xy 80.413062 -253.100209) (xy 80.457594 -253.122899)
			(xy 80.498027 -253.152275) (xy 80.533367 -253.187615) (xy 80.562743 -253.228048) (xy 80.585433 -253.27258)
			(xy 80.600877 -253.320112) (xy 80.608696 -253.369475) (xy 80.609186 -253.394464) (xy 80.914743 -253.394464)
			(xy 80.918838 -253.343736) (xy 80.931017 -253.294322) (xy 80.950965 -253.247502) (xy 80.978166 -253.204488)
			(xy 81.011914 -253.166394) (xy 81.051336 -253.134207) (xy 81.09541 -253.108761) (xy 81.142996 -253.090714)
			(xy 81.19286 -253.080534) (xy 81.243712 -253.078485) (xy 81.294233 -253.084619) (xy 81.343117 -253.098779)
			(xy 81.389096 -253.120596) (xy 81.43098 -253.149506) (xy 81.467684 -253.184761) (xy 81.498257 -253.225447)
			(xy 81.521908 -253.27051) (xy 81.538024 -253.318784) (xy 81.546188 -253.369018) (xy 81.5467 -253.394464)
			(xy 81.854797 -253.394464) (xy 81.858892 -253.343736) (xy 81.871071 -253.294322) (xy 81.891019 -253.247502)
			(xy 81.91822 -253.204488) (xy 81.951968 -253.166394) (xy 81.99139 -253.134207) (xy 82.035464 -253.108761)
			(xy 82.08305 -253.090714) (xy 82.132914 -253.080534) (xy 82.183766 -253.078485) (xy 82.234287 -253.084619)
			(xy 82.283171 -253.098779) (xy 82.32915 -253.120596) (xy 82.371034 -253.149506) (xy 82.407738 -253.184761)
			(xy 82.438311 -253.225447) (xy 82.461962 -253.27051) (xy 82.478078 -253.318784) (xy 82.486242 -253.369018)
			(xy 82.486754 -253.394464) (xy 82.486251 -253.419453) (xy 82.793568 -253.419453) (xy 82.793568 -253.369475)
			(xy 82.801387 -253.320112) (xy 82.816831 -253.27258) (xy 82.839521 -253.228048) (xy 82.868897 -253.187615)
			(xy 82.904237 -253.152275) (xy 82.94467 -253.122899) (xy 82.989202 -253.100209) (xy 83.036734 -253.084765)
			(xy 83.086097 -253.076946) (xy 83.136075 -253.076946) (xy 83.185438 -253.084765) (xy 83.23297 -253.100209)
			(xy 83.277502 -253.122899) (xy 83.317935 -253.152275) (xy 83.353275 -253.187615) (xy 83.382651 -253.228048)
			(xy 83.405341 -253.27258) (xy 83.420785 -253.320112) (xy 83.428604 -253.369475) (xy 83.429094 -253.394464)
			(xy 83.734905 -253.394464) (xy 83.739 -253.343736) (xy 83.751179 -253.294322) (xy 83.771127 -253.247502)
			(xy 83.798328 -253.204488) (xy 83.832076 -253.166394) (xy 83.871498 -253.134207) (xy 83.915572 -253.108761)
			(xy 83.963158 -253.090714) (xy 84.013022 -253.080534) (xy 84.063874 -253.078485) (xy 84.114395 -253.084619)
			(xy 84.163279 -253.098779) (xy 84.209258 -253.120596) (xy 84.251142 -253.149506) (xy 84.287846 -253.184761)
			(xy 84.318419 -253.225447) (xy 84.34207 -253.27051) (xy 84.358186 -253.318784) (xy 84.36635 -253.369018)
			(xy 84.366862 -253.394464) (xy 84.366359 -253.419453) (xy 84.673422 -253.419453) (xy 84.673422 -253.369475)
			(xy 84.681241 -253.320112) (xy 84.696685 -253.27258) (xy 84.719375 -253.228048) (xy 84.748751 -253.187615)
			(xy 84.784091 -253.152275) (xy 84.824524 -253.122899) (xy 84.869056 -253.100209) (xy 84.916588 -253.084765)
			(xy 84.965951 -253.076946) (xy 85.015929 -253.076946) (xy 85.065292 -253.084765) (xy 85.112824 -253.100209)
			(xy 85.157356 -253.122899) (xy 85.197789 -253.152275) (xy 85.233129 -253.187615) (xy 85.262505 -253.228048)
			(xy 85.285195 -253.27258) (xy 85.300639 -253.320112) (xy 85.308458 -253.369475) (xy 85.308948 -253.394464)
			(xy 85.614759 -253.394464) (xy 85.618854 -253.343736) (xy 85.631033 -253.294322) (xy 85.650981 -253.247502)
			(xy 85.678182 -253.204488) (xy 85.71193 -253.166394) (xy 85.751352 -253.134207) (xy 85.795426 -253.108761)
			(xy 85.843012 -253.090714) (xy 85.892876 -253.080534) (xy 85.943728 -253.078485) (xy 85.994249 -253.084619)
			(xy 86.043133 -253.098779) (xy 86.089112 -253.120596) (xy 86.130996 -253.149506) (xy 86.1677 -253.184761)
			(xy 86.198273 -253.225447) (xy 86.221924 -253.27051) (xy 86.23804 -253.318784) (xy 86.246204 -253.369018)
			(xy 86.246716 -253.394464) (xy 86.246213 -253.419453) (xy 86.55353 -253.419453) (xy 86.55353 -253.369475)
			(xy 86.561349 -253.320112) (xy 86.576793 -253.27258) (xy 86.599483 -253.228048) (xy 86.628859 -253.187615)
			(xy 86.664199 -253.152275) (xy 86.704632 -253.122899) (xy 86.749164 -253.100209) (xy 86.796696 -253.084765)
			(xy 86.846059 -253.076946) (xy 86.896037 -253.076946) (xy 86.9454 -253.084765) (xy 86.992932 -253.100209)
			(xy 87.037464 -253.122899) (xy 87.077897 -253.152275) (xy 87.113237 -253.187615) (xy 87.142613 -253.228048)
			(xy 87.165303 -253.27258) (xy 87.180747 -253.320112) (xy 87.188566 -253.369475) (xy 87.189056 -253.394464)
			(xy 87.494867 -253.394464) (xy 87.498962 -253.343736) (xy 87.511141 -253.294322) (xy 87.531089 -253.247502)
			(xy 87.55829 -253.204488) (xy 87.592038 -253.166394) (xy 87.63146 -253.134207) (xy 87.675534 -253.108761)
			(xy 87.72312 -253.090714) (xy 87.772984 -253.080534) (xy 87.823836 -253.078485) (xy 87.874357 -253.084619)
			(xy 87.923241 -253.098779) (xy 87.96922 -253.120596) (xy 88.011104 -253.149506) (xy 88.047808 -253.184761)
			(xy 88.078381 -253.225447) (xy 88.102032 -253.27051) (xy 88.118148 -253.318784) (xy 88.126312 -253.369018)
			(xy 88.126824 -253.394464) (xy 88.434921 -253.394464) (xy 88.439016 -253.343736) (xy 88.451195 -253.294322)
			(xy 88.471143 -253.247502) (xy 88.498344 -253.204488) (xy 88.532092 -253.166394) (xy 88.571514 -253.134207)
			(xy 88.615588 -253.108761) (xy 88.663174 -253.090714) (xy 88.713038 -253.080534) (xy 88.76389 -253.078485)
			(xy 88.814411 -253.084619) (xy 88.863295 -253.098779) (xy 88.909274 -253.120596) (xy 88.951158 -253.149506)
			(xy 88.987862 -253.184761) (xy 89.018435 -253.225447) (xy 89.042086 -253.27051) (xy 89.058202 -253.318784)
			(xy 89.066366 -253.369018) (xy 89.066878 -253.394464) (xy 89.066375 -253.419453) (xy 89.373438 -253.419453)
			(xy 89.373438 -253.369475) (xy 89.381257 -253.320112) (xy 89.396701 -253.27258) (xy 89.419391 -253.228048)
			(xy 89.448767 -253.187615) (xy 89.484107 -253.152275) (xy 89.52454 -253.122899) (xy 89.569072 -253.100209)
			(xy 89.616604 -253.084765) (xy 89.665967 -253.076946) (xy 89.715945 -253.076946) (xy 89.765308 -253.084765)
			(xy 89.81284 -253.100209) (xy 89.857372 -253.122899) (xy 89.897805 -253.152275) (xy 89.933145 -253.187615)
			(xy 89.962521 -253.228048) (xy 89.985211 -253.27258) (xy 90.000655 -253.320112) (xy 90.008474 -253.369475)
			(xy 90.008964 -253.394464) (xy 90.314775 -253.394464) (xy 90.31887 -253.343736) (xy 90.331049 -253.294322)
			(xy 90.350997 -253.247502) (xy 90.378198 -253.204488) (xy 90.411946 -253.166394) (xy 90.451368 -253.134207)
			(xy 90.495442 -253.108761) (xy 90.543028 -253.090714) (xy 90.592892 -253.080534) (xy 90.643744 -253.078485)
			(xy 90.694265 -253.084619) (xy 90.743149 -253.098779) (xy 90.789128 -253.120596) (xy 90.831012 -253.149506)
			(xy 90.867716 -253.184761) (xy 90.898289 -253.225447) (xy 90.92194 -253.27051) (xy 90.938056 -253.318784)
			(xy 90.94622 -253.369018) (xy 90.946732 -253.394464) (xy 90.946229 -253.419453) (xy 91.253546 -253.419453)
			(xy 91.253546 -253.369475) (xy 91.261365 -253.320112) (xy 91.276809 -253.27258) (xy 91.299499 -253.228048)
			(xy 91.328875 -253.187615) (xy 91.364215 -253.152275) (xy 91.404648 -253.122899) (xy 91.44918 -253.100209)
			(xy 91.496712 -253.084765) (xy 91.546075 -253.076946) (xy 91.596053 -253.076946) (xy 91.645416 -253.084765)
			(xy 91.692948 -253.100209) (xy 91.73748 -253.122899) (xy 91.777913 -253.152275) (xy 91.813253 -253.187615)
			(xy 91.842629 -253.228048) (xy 91.865319 -253.27258) (xy 91.880763 -253.320112) (xy 91.888582 -253.369475)
			(xy 91.889072 -253.394464) (xy 92.194883 -253.394464) (xy 92.198978 -253.343736) (xy 92.211157 -253.294322)
			(xy 92.231105 -253.247502) (xy 92.258306 -253.204488) (xy 92.292054 -253.166394) (xy 92.331476 -253.134207)
			(xy 92.37555 -253.108761) (xy 92.423136 -253.090714) (xy 92.473 -253.080534) (xy 92.523852 -253.078485)
			(xy 92.574373 -253.084619) (xy 92.623257 -253.098779) (xy 92.669236 -253.120596) (xy 92.71112 -253.149506)
			(xy 92.747824 -253.184761) (xy 92.778397 -253.225447) (xy 92.802048 -253.27051) (xy 92.818164 -253.318784)
			(xy 92.826328 -253.369018) (xy 92.82684 -253.394464) (xy 92.826337 -253.419453) (xy 93.1334 -253.419453)
			(xy 93.1334 -253.369475) (xy 93.141219 -253.320112) (xy 93.156663 -253.27258) (xy 93.179353 -253.228048)
			(xy 93.208729 -253.187615) (xy 93.244069 -253.152275) (xy 93.284502 -253.122899) (xy 93.329034 -253.100209)
			(xy 93.376566 -253.084765) (xy 93.425929 -253.076946) (xy 93.475907 -253.076946) (xy 93.52527 -253.084765)
			(xy 93.572802 -253.100209) (xy 93.617334 -253.122899) (xy 93.657767 -253.152275) (xy 93.693107 -253.187615)
			(xy 93.722483 -253.228048) (xy 93.745173 -253.27258) (xy 93.760617 -253.320112) (xy 93.768436 -253.369475)
			(xy 93.768926 -253.394464) (xy 94.074737 -253.394464) (xy 94.078832 -253.343736) (xy 94.091011 -253.294322)
			(xy 94.110959 -253.247502) (xy 94.13816 -253.204488) (xy 94.171908 -253.166394) (xy 94.21133 -253.134207)
			(xy 94.255404 -253.108761) (xy 94.30299 -253.090714) (xy 94.352854 -253.080534) (xy 94.403706 -253.078485)
			(xy 94.454227 -253.084619) (xy 94.503111 -253.098779) (xy 94.54909 -253.120596) (xy 94.590974 -253.149506)
			(xy 94.627678 -253.184761) (xy 94.658251 -253.225447) (xy 94.681902 -253.27051) (xy 94.698018 -253.318784)
			(xy 94.706182 -253.369018) (xy 94.706694 -253.394464) (xy 95.014791 -253.394464) (xy 95.018886 -253.343736)
			(xy 95.031065 -253.294322) (xy 95.051013 -253.247502) (xy 95.078214 -253.204488) (xy 95.111962 -253.166394)
			(xy 95.151384 -253.134207) (xy 95.195458 -253.108761) (xy 95.243044 -253.090714) (xy 95.292908 -253.080534)
			(xy 95.34376 -253.078485) (xy 95.394281 -253.084619) (xy 95.443165 -253.098779) (xy 95.489144 -253.120596)
			(xy 95.531028 -253.149506) (xy 95.567732 -253.184761) (xy 95.598305 -253.225447) (xy 95.621956 -253.27051)
			(xy 95.638072 -253.318784) (xy 95.646236 -253.369018) (xy 95.646748 -253.394464) (xy 95.646236 -253.41991)
			(xy 95.638072 -253.470144) (xy 95.621956 -253.518418) (xy 95.598305 -253.563481) (xy 95.567732 -253.604167)
			(xy 95.531028 -253.639422) (xy 95.489144 -253.668332) (xy 95.443165 -253.690149) (xy 95.394281 -253.704309)
			(xy 95.34376 -253.710443) (xy 95.292908 -253.708394) (xy 95.243044 -253.698214) (xy 95.195458 -253.680167)
			(xy 95.151384 -253.654721) (xy 95.111962 -253.622534) (xy 95.078214 -253.58444) (xy 95.051013 -253.541426)
			(xy 95.031065 -253.494606) (xy 95.018886 -253.445192) (xy 95.014791 -253.394464) (xy 94.706694 -253.394464)
			(xy 94.706182 -253.41991) (xy 94.698018 -253.470144) (xy 94.681902 -253.518418) (xy 94.658251 -253.563481)
			(xy 94.627678 -253.604167) (xy 94.590974 -253.639422) (xy 94.54909 -253.668332) (xy 94.503111 -253.690149)
			(xy 94.454227 -253.704309) (xy 94.403706 -253.710443) (xy 94.352854 -253.708394) (xy 94.30299 -253.698214)
			(xy 94.255404 -253.680167) (xy 94.21133 -253.654721) (xy 94.171908 -253.622534) (xy 94.13816 -253.58444)
			(xy 94.110959 -253.541426) (xy 94.091011 -253.494606) (xy 94.078832 -253.445192) (xy 94.074737 -253.394464)
			(xy 93.768926 -253.394464) (xy 93.768436 -253.419453) (xy 93.760617 -253.468816) (xy 93.745173 -253.516348)
			(xy 93.722483 -253.56088) (xy 93.693107 -253.601313) (xy 93.657767 -253.636653) (xy 93.617334 -253.666029)
			(xy 93.572802 -253.688719) (xy 93.52527 -253.704163) (xy 93.475907 -253.711982) (xy 93.425929 -253.711982)
			(xy 93.376566 -253.704163) (xy 93.329034 -253.688719) (xy 93.284502 -253.666029) (xy 93.244069 -253.636653)
			(xy 93.208729 -253.601313) (xy 93.179353 -253.56088) (xy 93.156663 -253.516348) (xy 93.141219 -253.468816)
			(xy 93.1334 -253.419453) (xy 92.826337 -253.419453) (xy 92.826328 -253.41991) (xy 92.818164 -253.470144)
			(xy 92.802048 -253.518418) (xy 92.778397 -253.563481) (xy 92.747824 -253.604167) (xy 92.71112 -253.639422)
			(xy 92.669236 -253.668332) (xy 92.623257 -253.690149) (xy 92.574373 -253.704309) (xy 92.523852 -253.710443)
			(xy 92.473 -253.708394) (xy 92.423136 -253.698214) (xy 92.37555 -253.680167) (xy 92.331476 -253.654721)
			(xy 92.292054 -253.622534) (xy 92.258306 -253.58444) (xy 92.231105 -253.541426) (xy 92.211157 -253.494606)
			(xy 92.198978 -253.445192) (xy 92.194883 -253.394464) (xy 91.889072 -253.394464) (xy 91.888582 -253.419453)
			(xy 91.880763 -253.468816) (xy 91.865319 -253.516348) (xy 91.842629 -253.56088) (xy 91.813253 -253.601313)
			(xy 91.777913 -253.636653) (xy 91.73748 -253.666029) (xy 91.692948 -253.688719) (xy 91.645416 -253.704163)
			(xy 91.596053 -253.711982) (xy 91.546075 -253.711982) (xy 91.496712 -253.704163) (xy 91.44918 -253.688719)
			(xy 91.404648 -253.666029) (xy 91.364215 -253.636653) (xy 91.328875 -253.601313) (xy 91.299499 -253.56088)
			(xy 91.276809 -253.516348) (xy 91.261365 -253.468816) (xy 91.253546 -253.419453) (xy 90.946229 -253.419453)
			(xy 90.94622 -253.41991) (xy 90.938056 -253.470144) (xy 90.92194 -253.518418) (xy 90.898289 -253.563481)
			(xy 90.867716 -253.604167) (xy 90.831012 -253.639422) (xy 90.789128 -253.668332) (xy 90.743149 -253.690149)
			(xy 90.694265 -253.704309) (xy 90.643744 -253.710443) (xy 90.592892 -253.708394) (xy 90.543028 -253.698214)
			(xy 90.495442 -253.680167) (xy 90.451368 -253.654721) (xy 90.411946 -253.622534) (xy 90.378198 -253.58444)
			(xy 90.350997 -253.541426) (xy 90.331049 -253.494606) (xy 90.31887 -253.445192) (xy 90.314775 -253.394464)
			(xy 90.008964 -253.394464) (xy 90.008474 -253.419453) (xy 90.000655 -253.468816) (xy 89.985211 -253.516348)
			(xy 89.962521 -253.56088) (xy 89.933145 -253.601313) (xy 89.897805 -253.636653) (xy 89.857372 -253.666029)
			(xy 89.81284 -253.688719) (xy 89.765308 -253.704163) (xy 89.715945 -253.711982) (xy 89.665967 -253.711982)
			(xy 89.616604 -253.704163) (xy 89.569072 -253.688719) (xy 89.52454 -253.666029) (xy 89.484107 -253.636653)
			(xy 89.448767 -253.601313) (xy 89.419391 -253.56088) (xy 89.396701 -253.516348) (xy 89.381257 -253.468816)
			(xy 89.373438 -253.419453) (xy 89.066375 -253.419453) (xy 89.066366 -253.41991) (xy 89.058202 -253.470144)
			(xy 89.042086 -253.518418) (xy 89.018435 -253.563481) (xy 88.987862 -253.604167) (xy 88.951158 -253.639422)
			(xy 88.909274 -253.668332) (xy 88.863295 -253.690149) (xy 88.814411 -253.704309) (xy 88.76389 -253.710443)
			(xy 88.713038 -253.708394) (xy 88.663174 -253.698214) (xy 88.615588 -253.680167) (xy 88.571514 -253.654721)
			(xy 88.532092 -253.622534) (xy 88.498344 -253.58444) (xy 88.471143 -253.541426) (xy 88.451195 -253.494606)
			(xy 88.439016 -253.445192) (xy 88.434921 -253.394464) (xy 88.126824 -253.394464) (xy 88.126312 -253.41991)
			(xy 88.118148 -253.470144) (xy 88.102032 -253.518418) (xy 88.078381 -253.563481) (xy 88.047808 -253.604167)
			(xy 88.011104 -253.639422) (xy 87.96922 -253.668332) (xy 87.923241 -253.690149) (xy 87.874357 -253.704309)
			(xy 87.823836 -253.710443) (xy 87.772984 -253.708394) (xy 87.72312 -253.698214) (xy 87.675534 -253.680167)
			(xy 87.63146 -253.654721) (xy 87.592038 -253.622534) (xy 87.55829 -253.58444) (xy 87.531089 -253.541426)
			(xy 87.511141 -253.494606) (xy 87.498962 -253.445192) (xy 87.494867 -253.394464) (xy 87.189056 -253.394464)
			(xy 87.188566 -253.419453) (xy 87.180747 -253.468816) (xy 87.165303 -253.516348) (xy 87.142613 -253.56088)
			(xy 87.113237 -253.601313) (xy 87.077897 -253.636653) (xy 87.037464 -253.666029) (xy 86.992932 -253.688719)
			(xy 86.9454 -253.704163) (xy 86.896037 -253.711982) (xy 86.846059 -253.711982) (xy 86.796696 -253.704163)
			(xy 86.749164 -253.688719) (xy 86.704632 -253.666029) (xy 86.664199 -253.636653) (xy 86.628859 -253.601313)
			(xy 86.599483 -253.56088) (xy 86.576793 -253.516348) (xy 86.561349 -253.468816) (xy 86.55353 -253.419453)
			(xy 86.246213 -253.419453) (xy 86.246204 -253.41991) (xy 86.23804 -253.470144) (xy 86.221924 -253.518418)
			(xy 86.198273 -253.563481) (xy 86.1677 -253.604167) (xy 86.130996 -253.639422) (xy 86.089112 -253.668332)
			(xy 86.043133 -253.690149) (xy 85.994249 -253.704309) (xy 85.943728 -253.710443) (xy 85.892876 -253.708394)
			(xy 85.843012 -253.698214) (xy 85.795426 -253.680167) (xy 85.751352 -253.654721) (xy 85.71193 -253.622534)
			(xy 85.678182 -253.58444) (xy 85.650981 -253.541426) (xy 85.631033 -253.494606) (xy 85.618854 -253.445192)
			(xy 85.614759 -253.394464) (xy 85.308948 -253.394464) (xy 85.308458 -253.419453) (xy 85.300639 -253.468816)
			(xy 85.285195 -253.516348) (xy 85.262505 -253.56088) (xy 85.233129 -253.601313) (xy 85.197789 -253.636653)
			(xy 85.157356 -253.666029) (xy 85.112824 -253.688719) (xy 85.065292 -253.704163) (xy 85.015929 -253.711982)
			(xy 84.965951 -253.711982) (xy 84.916588 -253.704163) (xy 84.869056 -253.688719) (xy 84.824524 -253.666029)
			(xy 84.784091 -253.636653) (xy 84.748751 -253.601313) (xy 84.719375 -253.56088) (xy 84.696685 -253.516348)
			(xy 84.681241 -253.468816) (xy 84.673422 -253.419453) (xy 84.366359 -253.419453) (xy 84.36635 -253.41991)
			(xy 84.358186 -253.470144) (xy 84.34207 -253.518418) (xy 84.318419 -253.563481) (xy 84.287846 -253.604167)
			(xy 84.251142 -253.639422) (xy 84.209258 -253.668332) (xy 84.163279 -253.690149) (xy 84.114395 -253.704309)
			(xy 84.063874 -253.710443) (xy 84.013022 -253.708394) (xy 83.963158 -253.698214) (xy 83.915572 -253.680167)
			(xy 83.871498 -253.654721) (xy 83.832076 -253.622534) (xy 83.798328 -253.58444) (xy 83.771127 -253.541426)
			(xy 83.751179 -253.494606) (xy 83.739 -253.445192) (xy 83.734905 -253.394464) (xy 83.429094 -253.394464)
			(xy 83.428604 -253.419453) (xy 83.420785 -253.468816) (xy 83.405341 -253.516348) (xy 83.382651 -253.56088)
			(xy 83.353275 -253.601313) (xy 83.317935 -253.636653) (xy 83.277502 -253.666029) (xy 83.23297 -253.688719)
			(xy 83.185438 -253.704163) (xy 83.136075 -253.711982) (xy 83.086097 -253.711982) (xy 83.036734 -253.704163)
			(xy 82.989202 -253.688719) (xy 82.94467 -253.666029) (xy 82.904237 -253.636653) (xy 82.868897 -253.601313)
			(xy 82.839521 -253.56088) (xy 82.816831 -253.516348) (xy 82.801387 -253.468816) (xy 82.793568 -253.419453)
			(xy 82.486251 -253.419453) (xy 82.486242 -253.41991) (xy 82.478078 -253.470144) (xy 82.461962 -253.518418)
			(xy 82.438311 -253.563481) (xy 82.407738 -253.604167) (xy 82.371034 -253.639422) (xy 82.32915 -253.668332)
			(xy 82.283171 -253.690149) (xy 82.234287 -253.704309) (xy 82.183766 -253.710443) (xy 82.132914 -253.708394)
			(xy 82.08305 -253.698214) (xy 82.035464 -253.680167) (xy 81.99139 -253.654721) (xy 81.951968 -253.622534)
			(xy 81.91822 -253.58444) (xy 81.891019 -253.541426) (xy 81.871071 -253.494606) (xy 81.858892 -253.445192)
			(xy 81.854797 -253.394464) (xy 81.5467 -253.394464) (xy 81.546188 -253.41991) (xy 81.538024 -253.470144)
			(xy 81.521908 -253.518418) (xy 81.498257 -253.563481) (xy 81.467684 -253.604167) (xy 81.43098 -253.639422)
			(xy 81.389096 -253.668332) (xy 81.343117 -253.690149) (xy 81.294233 -253.704309) (xy 81.243712 -253.710443)
			(xy 81.19286 -253.708394) (xy 81.142996 -253.698214) (xy 81.09541 -253.680167) (xy 81.051336 -253.654721)
			(xy 81.011914 -253.622534) (xy 80.978166 -253.58444) (xy 80.950965 -253.541426) (xy 80.931017 -253.494606)
			(xy 80.918838 -253.445192) (xy 80.914743 -253.394464) (xy 80.609186 -253.394464) (xy 80.608696 -253.419453)
			(xy 80.600877 -253.468816) (xy 80.585433 -253.516348) (xy 80.562743 -253.56088) (xy 80.533367 -253.601313)
			(xy 80.498027 -253.636653) (xy 80.457594 -253.666029) (xy 80.413062 -253.688719) (xy 80.36553 -253.704163)
			(xy 80.316167 -253.711982) (xy 80.266189 -253.711982) (xy 80.216826 -253.704163) (xy 80.169294 -253.688719)
			(xy 80.124762 -253.666029) (xy 80.084329 -253.636653) (xy 80.048989 -253.601313) (xy 80.019613 -253.56088)
			(xy 79.996923 -253.516348) (xy 79.981479 -253.468816) (xy 79.97366 -253.419453) (xy 79.53248 -253.419453)
			(xy 79.53248 -254.20447) (xy 80.444843 -254.20447) (xy 80.448938 -254.153742) (xy 80.461117 -254.104328)
			(xy 80.481065 -254.057508) (xy 80.508266 -254.014494) (xy 80.542014 -253.9764) (xy 80.581436 -253.944213)
			(xy 80.62551 -253.918767) (xy 80.673096 -253.90072) (xy 80.72296 -253.89054) (xy 80.773812 -253.888491)
			(xy 80.824333 -253.894625) (xy 80.873217 -253.908785) (xy 80.919196 -253.930602) (xy 80.96108 -253.959512)
			(xy 80.997784 -253.994767) (xy 81.028357 -254.035453) (xy 81.052008 -254.080516) (xy 81.068124 -254.12879)
			(xy 81.076288 -254.179024) (xy 81.0768 -254.20447) (xy 81.076297 -254.229459) (xy 81.383614 -254.229459)
			(xy 81.383614 -254.179481) (xy 81.391433 -254.130118) (xy 81.406877 -254.082586) (xy 81.429567 -254.038054)
			(xy 81.458943 -253.997621) (xy 81.494283 -253.962281) (xy 81.534716 -253.932905) (xy 81.579248 -253.910215)
			(xy 81.62678 -253.894771) (xy 81.676143 -253.886952) (xy 81.726121 -253.886952) (xy 81.775484 -253.894771)
			(xy 81.823016 -253.910215) (xy 81.867548 -253.932905) (xy 81.907981 -253.962281) (xy 81.943321 -253.997621)
			(xy 81.972697 -254.038054) (xy 81.995387 -254.082586) (xy 82.010831 -254.130118) (xy 82.01865 -254.179481)
			(xy 82.01914 -254.20447) (xy 82.324697 -254.20447) (xy 82.328792 -254.153742) (xy 82.340971 -254.104328)
			(xy 82.360919 -254.057508) (xy 82.38812 -254.014494) (xy 82.421868 -253.9764) (xy 82.46129 -253.944213)
			(xy 82.505364 -253.918767) (xy 82.55295 -253.90072) (xy 82.602814 -253.89054) (xy 82.653666 -253.888491)
			(xy 82.704187 -253.894625) (xy 82.753071 -253.908785) (xy 82.79905 -253.930602) (xy 82.840934 -253.959512)
			(xy 82.877638 -253.994767) (xy 82.908211 -254.035453) (xy 82.931862 -254.080516) (xy 82.947978 -254.12879)
			(xy 82.956142 -254.179024) (xy 82.956654 -254.20447) (xy 82.956151 -254.229459) (xy 83.263468 -254.229459)
			(xy 83.263468 -254.179481) (xy 83.271287 -254.130118) (xy 83.286731 -254.082586) (xy 83.309421 -254.038054)
			(xy 83.338797 -253.997621) (xy 83.374137 -253.962281) (xy 83.41457 -253.932905) (xy 83.459102 -253.910215)
			(xy 83.506634 -253.894771) (xy 83.555997 -253.886952) (xy 83.605975 -253.886952) (xy 83.655338 -253.894771)
			(xy 83.70287 -253.910215) (xy 83.747402 -253.932905) (xy 83.787835 -253.962281) (xy 83.823175 -253.997621)
			(xy 83.852551 -254.038054) (xy 83.875241 -254.082586) (xy 83.890685 -254.130118) (xy 83.898504 -254.179481)
			(xy 83.898994 -254.20447) (xy 84.204805 -254.20447) (xy 84.2089 -254.153742) (xy 84.221079 -254.104328)
			(xy 84.241027 -254.057508) (xy 84.268228 -254.014494) (xy 84.301976 -253.9764) (xy 84.341398 -253.944213)
			(xy 84.385472 -253.918767) (xy 84.433058 -253.90072) (xy 84.482922 -253.89054) (xy 84.533774 -253.888491)
			(xy 84.584295 -253.894625) (xy 84.633179 -253.908785) (xy 84.679158 -253.930602) (xy 84.721042 -253.959512)
			(xy 84.757746 -253.994767) (xy 84.788319 -254.035453) (xy 84.81197 -254.080516) (xy 84.828086 -254.12879)
			(xy 84.83625 -254.179024) (xy 84.836762 -254.20447) (xy 85.144859 -254.20447) (xy 85.148954 -254.153742)
			(xy 85.161133 -254.104328) (xy 85.181081 -254.057508) (xy 85.208282 -254.014494) (xy 85.24203 -253.9764)
			(xy 85.281452 -253.944213) (xy 85.325526 -253.918767) (xy 85.373112 -253.90072) (xy 85.422976 -253.89054)
			(xy 85.473828 -253.888491) (xy 85.524349 -253.894625) (xy 85.573233 -253.908785) (xy 85.619212 -253.930602)
			(xy 85.661096 -253.959512) (xy 85.6978 -253.994767) (xy 85.728373 -254.035453) (xy 85.752024 -254.080516)
			(xy 85.76814 -254.12879) (xy 85.776304 -254.179024) (xy 85.776816 -254.20447) (xy 87.024713 -254.20447)
			(xy 87.028808 -254.153742) (xy 87.040987 -254.104328) (xy 87.060935 -254.057508) (xy 87.088136 -254.014494)
			(xy 87.121884 -253.9764) (xy 87.161306 -253.944213) (xy 87.20538 -253.918767) (xy 87.252966 -253.90072)
			(xy 87.30283 -253.89054) (xy 87.353682 -253.888491) (xy 87.404203 -253.894625) (xy 87.453087 -253.908785)
			(xy 87.499066 -253.930602) (xy 87.54095 -253.959512) (xy 87.577654 -253.994767) (xy 87.608227 -254.035453)
			(xy 87.631878 -254.080516) (xy 87.647994 -254.12879) (xy 87.656158 -254.179024) (xy 87.65667 -254.20447)
			(xy 87.656167 -254.229459) (xy 87.963484 -254.229459) (xy 87.963484 -254.179481) (xy 87.971303 -254.130118)
			(xy 87.986747 -254.082586) (xy 88.009437 -254.038054) (xy 88.038813 -253.997621) (xy 88.074153 -253.962281)
			(xy 88.114586 -253.932905) (xy 88.159118 -253.910215) (xy 88.20665 -253.894771) (xy 88.256013 -253.886952)
			(xy 88.305991 -253.886952) (xy 88.355354 -253.894771) (xy 88.402886 -253.910215) (xy 88.447418 -253.932905)
			(xy 88.487851 -253.962281) (xy 88.523191 -253.997621) (xy 88.552567 -254.038054) (xy 88.575257 -254.082586)
			(xy 88.590701 -254.130118) (xy 88.59852 -254.179481) (xy 88.59901 -254.20447) (xy 88.904821 -254.20447)
			(xy 88.908916 -254.153742) (xy 88.921095 -254.104328) (xy 88.941043 -254.057508) (xy 88.968244 -254.014494)
			(xy 89.001992 -253.9764) (xy 89.041414 -253.944213) (xy 89.085488 -253.918767) (xy 89.133074 -253.90072)
			(xy 89.182938 -253.89054) (xy 89.23379 -253.888491) (xy 89.284311 -253.894625) (xy 89.333195 -253.908785)
			(xy 89.379174 -253.930602) (xy 89.421058 -253.959512) (xy 89.457762 -253.994767) (xy 89.488335 -254.035453)
			(xy 89.511986 -254.080516) (xy 89.528102 -254.12879) (xy 89.536266 -254.179024) (xy 89.536778 -254.20447)
			(xy 89.536275 -254.229459) (xy 89.843592 -254.229459) (xy 89.843592 -254.179481) (xy 89.851411 -254.130118)
			(xy 89.866855 -254.082586) (xy 89.889545 -254.038054) (xy 89.918921 -253.997621) (xy 89.954261 -253.962281)
			(xy 89.994694 -253.932905) (xy 90.039226 -253.910215) (xy 90.086758 -253.894771) (xy 90.136121 -253.886952)
			(xy 90.186099 -253.886952) (xy 90.235462 -253.894771) (xy 90.282994 -253.910215) (xy 90.327526 -253.932905)
			(xy 90.367959 -253.962281) (xy 90.403299 -253.997621) (xy 90.432675 -254.038054) (xy 90.455365 -254.082586)
			(xy 90.470809 -254.130118) (xy 90.478628 -254.179481) (xy 90.479118 -254.20447) (xy 90.784675 -254.20447)
			(xy 90.78877 -254.153742) (xy 90.800949 -254.104328) (xy 90.820897 -254.057508) (xy 90.848098 -254.014494)
			(xy 90.881846 -253.9764) (xy 90.921268 -253.944213) (xy 90.965342 -253.918767) (xy 91.012928 -253.90072)
			(xy 91.062792 -253.89054) (xy 91.113644 -253.888491) (xy 91.164165 -253.894625) (xy 91.213049 -253.908785)
			(xy 91.259028 -253.930602) (xy 91.300912 -253.959512) (xy 91.337616 -253.994767) (xy 91.368189 -254.035453)
			(xy 91.39184 -254.080516) (xy 91.407956 -254.12879) (xy 91.41612 -254.179024) (xy 91.416632 -254.20447)
			(xy 91.724729 -254.20447) (xy 91.728824 -254.153742) (xy 91.741003 -254.104328) (xy 91.760951 -254.057508)
			(xy 91.788152 -254.014494) (xy 91.8219 -253.9764) (xy 91.861322 -253.944213) (xy 91.905396 -253.918767)
			(xy 91.952982 -253.90072) (xy 92.002846 -253.89054) (xy 92.053698 -253.888491) (xy 92.104219 -253.894625)
			(xy 92.153103 -253.908785) (xy 92.199082 -253.930602) (xy 92.240966 -253.959512) (xy 92.27767 -253.994767)
			(xy 92.308243 -254.035453) (xy 92.331894 -254.080516) (xy 92.34801 -254.12879) (xy 92.356174 -254.179024)
			(xy 92.356686 -254.20447) (xy 93.604837 -254.20447) (xy 93.608932 -254.153742) (xy 93.621111 -254.104328)
			(xy 93.641059 -254.057508) (xy 93.66826 -254.014494) (xy 93.702008 -253.9764) (xy 93.74143 -253.944213)
			(xy 93.785504 -253.918767) (xy 93.83309 -253.90072) (xy 93.882954 -253.89054) (xy 93.933806 -253.888491)
			(xy 93.984327 -253.894625) (xy 94.033211 -253.908785) (xy 94.07919 -253.930602) (xy 94.121074 -253.959512)
			(xy 94.157778 -253.994767) (xy 94.188351 -254.035453) (xy 94.212002 -254.080516) (xy 94.228118 -254.12879)
			(xy 94.236282 -254.179024) (xy 94.236794 -254.20447) (xy 94.236291 -254.229459) (xy 94.543608 -254.229459)
			(xy 94.543608 -254.179481) (xy 94.551427 -254.130118) (xy 94.566871 -254.082586) (xy 94.589561 -254.038054)
			(xy 94.618937 -253.997621) (xy 94.654277 -253.962281) (xy 94.69471 -253.932905) (xy 94.739242 -253.910215)
			(xy 94.786774 -253.894771) (xy 94.836137 -253.886952) (xy 94.886115 -253.886952) (xy 94.935478 -253.894771)
			(xy 94.98301 -253.910215) (xy 95.027542 -253.932905) (xy 95.067975 -253.962281) (xy 95.103315 -253.997621)
			(xy 95.132691 -254.038054) (xy 95.155381 -254.082586) (xy 95.170825 -254.130118) (xy 95.178644 -254.179481)
			(xy 95.179134 -254.20447) (xy 95.178644 -254.229459) (xy 95.170825 -254.278822) (xy 95.155381 -254.326354)
			(xy 95.132691 -254.370886) (xy 95.103315 -254.411319) (xy 95.067975 -254.446659) (xy 95.027542 -254.476035)
			(xy 94.98301 -254.498725) (xy 94.935478 -254.514169) (xy 94.886115 -254.521988) (xy 94.836137 -254.521988)
			(xy 94.786774 -254.514169) (xy 94.739242 -254.498725) (xy 94.69471 -254.476035) (xy 94.654277 -254.446659)
			(xy 94.618937 -254.411319) (xy 94.589561 -254.370886) (xy 94.566871 -254.326354) (xy 94.551427 -254.278822)
			(xy 94.543608 -254.229459) (xy 94.236291 -254.229459) (xy 94.236282 -254.229916) (xy 94.228118 -254.28015)
			(xy 94.212002 -254.328424) (xy 94.188351 -254.373487) (xy 94.157778 -254.414173) (xy 94.121074 -254.449428)
			(xy 94.07919 -254.478338) (xy 94.033211 -254.500155) (xy 93.984327 -254.514315) (xy 93.933806 -254.520449)
			(xy 93.882954 -254.5184) (xy 93.83309 -254.50822) (xy 93.785504 -254.490173) (xy 93.74143 -254.464727)
			(xy 93.702008 -254.43254) (xy 93.66826 -254.394446) (xy 93.641059 -254.351432) (xy 93.621111 -254.304612)
			(xy 93.608932 -254.255198) (xy 93.604837 -254.20447) (xy 92.356686 -254.20447) (xy 92.356174 -254.229916)
			(xy 92.34801 -254.28015) (xy 92.331894 -254.328424) (xy 92.308243 -254.373487) (xy 92.27767 -254.414173)
			(xy 92.240966 -254.449428) (xy 92.199082 -254.478338) (xy 92.153103 -254.500155) (xy 92.104219 -254.514315)
			(xy 92.053698 -254.520449) (xy 92.002846 -254.5184) (xy 91.952982 -254.50822) (xy 91.905396 -254.490173)
			(xy 91.861322 -254.464727) (xy 91.8219 -254.43254) (xy 91.788152 -254.394446) (xy 91.760951 -254.351432)
			(xy 91.741003 -254.304612) (xy 91.728824 -254.255198) (xy 91.724729 -254.20447) (xy 91.416632 -254.20447)
			(xy 91.41612 -254.229916) (xy 91.407956 -254.28015) (xy 91.39184 -254.328424) (xy 91.368189 -254.373487)
			(xy 91.337616 -254.414173) (xy 91.300912 -254.449428) (xy 91.259028 -254.478338) (xy 91.213049 -254.500155)
			(xy 91.164165 -254.514315) (xy 91.113644 -254.520449) (xy 91.062792 -254.5184) (xy 91.012928 -254.50822)
			(xy 90.965342 -254.490173) (xy 90.921268 -254.464727) (xy 90.881846 -254.43254) (xy 90.848098 -254.394446)
			(xy 90.820897 -254.351432) (xy 90.800949 -254.304612) (xy 90.78877 -254.255198) (xy 90.784675 -254.20447)
			(xy 90.479118 -254.20447) (xy 90.478628 -254.229459) (xy 90.470809 -254.278822) (xy 90.455365 -254.326354)
			(xy 90.432675 -254.370886) (xy 90.403299 -254.411319) (xy 90.367959 -254.446659) (xy 90.327526 -254.476035)
			(xy 90.282994 -254.498725) (xy 90.235462 -254.514169) (xy 90.186099 -254.521988) (xy 90.136121 -254.521988)
			(xy 90.086758 -254.514169) (xy 90.039226 -254.498725) (xy 89.994694 -254.476035) (xy 89.954261 -254.446659)
			(xy 89.918921 -254.411319) (xy 89.889545 -254.370886) (xy 89.866855 -254.326354) (xy 89.851411 -254.278822)
			(xy 89.843592 -254.229459) (xy 89.536275 -254.229459) (xy 89.536266 -254.229916) (xy 89.528102 -254.28015)
			(xy 89.511986 -254.328424) (xy 89.488335 -254.373487) (xy 89.457762 -254.414173) (xy 89.421058 -254.449428)
			(xy 89.379174 -254.478338) (xy 89.333195 -254.500155) (xy 89.284311 -254.514315) (xy 89.23379 -254.520449)
			(xy 89.182938 -254.5184) (xy 89.133074 -254.50822) (xy 89.085488 -254.490173) (xy 89.041414 -254.464727)
			(xy 89.001992 -254.43254) (xy 88.968244 -254.394446) (xy 88.941043 -254.351432) (xy 88.921095 -254.304612)
			(xy 88.908916 -254.255198) (xy 88.904821 -254.20447) (xy 88.59901 -254.20447) (xy 88.59852 -254.229459)
			(xy 88.590701 -254.278822) (xy 88.575257 -254.326354) (xy 88.552567 -254.370886) (xy 88.523191 -254.411319)
			(xy 88.487851 -254.446659) (xy 88.447418 -254.476035) (xy 88.402886 -254.498725) (xy 88.355354 -254.514169)
			(xy 88.305991 -254.521988) (xy 88.256013 -254.521988) (xy 88.20665 -254.514169) (xy 88.159118 -254.498725)
			(xy 88.114586 -254.476035) (xy 88.074153 -254.446659) (xy 88.038813 -254.411319) (xy 88.009437 -254.370886)
			(xy 87.986747 -254.326354) (xy 87.971303 -254.278822) (xy 87.963484 -254.229459) (xy 87.656167 -254.229459)
			(xy 87.656158 -254.229916) (xy 87.647994 -254.28015) (xy 87.631878 -254.328424) (xy 87.608227 -254.373487)
			(xy 87.577654 -254.414173) (xy 87.54095 -254.449428) (xy 87.499066 -254.478338) (xy 87.453087 -254.500155)
			(xy 87.404203 -254.514315) (xy 87.353682 -254.520449) (xy 87.30283 -254.5184) (xy 87.252966 -254.50822)
			(xy 87.20538 -254.490173) (xy 87.161306 -254.464727) (xy 87.121884 -254.43254) (xy 87.088136 -254.394446)
			(xy 87.060935 -254.351432) (xy 87.040987 -254.304612) (xy 87.028808 -254.255198) (xy 87.024713 -254.20447)
			(xy 85.776816 -254.20447) (xy 85.776304 -254.229916) (xy 85.76814 -254.28015) (xy 85.752024 -254.328424)
			(xy 85.728373 -254.373487) (xy 85.6978 -254.414173) (xy 85.661096 -254.449428) (xy 85.619212 -254.478338)
			(xy 85.573233 -254.500155) (xy 85.524349 -254.514315) (xy 85.473828 -254.520449) (xy 85.422976 -254.5184)
			(xy 85.373112 -254.50822) (xy 85.325526 -254.490173) (xy 85.281452 -254.464727) (xy 85.24203 -254.43254)
			(xy 85.208282 -254.394446) (xy 85.181081 -254.351432) (xy 85.161133 -254.304612) (xy 85.148954 -254.255198)
			(xy 85.144859 -254.20447) (xy 84.836762 -254.20447) (xy 84.83625 -254.229916) (xy 84.828086 -254.28015)
			(xy 84.81197 -254.328424) (xy 84.788319 -254.373487) (xy 84.757746 -254.414173) (xy 84.721042 -254.449428)
			(xy 84.679158 -254.478338) (xy 84.633179 -254.500155) (xy 84.584295 -254.514315) (xy 84.533774 -254.520449)
			(xy 84.482922 -254.5184) (xy 84.433058 -254.50822) (xy 84.385472 -254.490173) (xy 84.341398 -254.464727)
			(xy 84.301976 -254.43254) (xy 84.268228 -254.394446) (xy 84.241027 -254.351432) (xy 84.221079 -254.304612)
			(xy 84.2089 -254.255198) (xy 84.204805 -254.20447) (xy 83.898994 -254.20447) (xy 83.898504 -254.229459)
			(xy 83.890685 -254.278822) (xy 83.875241 -254.326354) (xy 83.852551 -254.370886) (xy 83.823175 -254.411319)
			(xy 83.787835 -254.446659) (xy 83.747402 -254.476035) (xy 83.70287 -254.498725) (xy 83.655338 -254.514169)
			(xy 83.605975 -254.521988) (xy 83.555997 -254.521988) (xy 83.506634 -254.514169) (xy 83.459102 -254.498725)
			(xy 83.41457 -254.476035) (xy 83.374137 -254.446659) (xy 83.338797 -254.411319) (xy 83.309421 -254.370886)
			(xy 83.286731 -254.326354) (xy 83.271287 -254.278822) (xy 83.263468 -254.229459) (xy 82.956151 -254.229459)
			(xy 82.956142 -254.229916) (xy 82.947978 -254.28015) (xy 82.931862 -254.328424) (xy 82.908211 -254.373487)
			(xy 82.877638 -254.414173) (xy 82.840934 -254.449428) (xy 82.79905 -254.478338) (xy 82.753071 -254.500155)
			(xy 82.704187 -254.514315) (xy 82.653666 -254.520449) (xy 82.602814 -254.5184) (xy 82.55295 -254.50822)
			(xy 82.505364 -254.490173) (xy 82.46129 -254.464727) (xy 82.421868 -254.43254) (xy 82.38812 -254.394446)
			(xy 82.360919 -254.351432) (xy 82.340971 -254.304612) (xy 82.328792 -254.255198) (xy 82.324697 -254.20447)
			(xy 82.01914 -254.20447) (xy 82.01865 -254.229459) (xy 82.010831 -254.278822) (xy 81.995387 -254.326354)
			(xy 81.972697 -254.370886) (xy 81.943321 -254.411319) (xy 81.907981 -254.446659) (xy 81.867548 -254.476035)
			(xy 81.823016 -254.498725) (xy 81.775484 -254.514169) (xy 81.726121 -254.521988) (xy 81.676143 -254.521988)
			(xy 81.62678 -254.514169) (xy 81.579248 -254.498725) (xy 81.534716 -254.476035) (xy 81.494283 -254.446659)
			(xy 81.458943 -254.411319) (xy 81.429567 -254.370886) (xy 81.406877 -254.326354) (xy 81.391433 -254.278822)
			(xy 81.383614 -254.229459) (xy 81.076297 -254.229459) (xy 81.076288 -254.229916) (xy 81.068124 -254.28015)
			(xy 81.052008 -254.328424) (xy 81.028357 -254.373487) (xy 80.997784 -254.414173) (xy 80.96108 -254.449428)
			(xy 80.919196 -254.478338) (xy 80.873217 -254.500155) (xy 80.824333 -254.514315) (xy 80.773812 -254.520449)
			(xy 80.72296 -254.5184) (xy 80.673096 -254.50822) (xy 80.62551 -254.490173) (xy 80.581436 -254.464727)
			(xy 80.542014 -254.43254) (xy 80.508266 -254.394446) (xy 80.481065 -254.351432) (xy 80.461117 -254.304612)
			(xy 80.448938 -254.255198) (xy 80.444843 -254.20447) (xy 79.53248 -254.20447) (xy 79.53248 -255.039465)
			(xy 79.97366 -255.039465) (xy 79.97366 -254.989487) (xy 79.981479 -254.940124) (xy 79.996923 -254.892592)
			(xy 80.019613 -254.84806) (xy 80.048989 -254.807627) (xy 80.084329 -254.772287) (xy 80.124762 -254.742911)
			(xy 80.169294 -254.720221) (xy 80.216826 -254.704777) (xy 80.266189 -254.696958) (xy 80.316167 -254.696958)
			(xy 80.36553 -254.704777) (xy 80.413062 -254.720221) (xy 80.457594 -254.742911) (xy 80.498027 -254.772287)
			(xy 80.533367 -254.807627) (xy 80.562743 -254.84806) (xy 80.585433 -254.892592) (xy 80.600877 -254.940124)
			(xy 80.608696 -254.989487) (xy 80.609186 -255.014476) (xy 80.914743 -255.014476) (xy 80.918838 -254.963748)
			(xy 80.931017 -254.914334) (xy 80.950965 -254.867514) (xy 80.978166 -254.8245) (xy 81.011914 -254.786406)
			(xy 81.051336 -254.754219) (xy 81.09541 -254.728773) (xy 81.142996 -254.710726) (xy 81.19286 -254.700546)
			(xy 81.243712 -254.698497) (xy 81.294233 -254.704631) (xy 81.343117 -254.718791) (xy 81.389096 -254.740608)
			(xy 81.43098 -254.769518) (xy 81.467684 -254.804773) (xy 81.498257 -254.845459) (xy 81.521908 -254.890522)
			(xy 81.538024 -254.938796) (xy 81.546188 -254.98903) (xy 81.5467 -255.014476) (xy 81.854797 -255.014476)
			(xy 81.858892 -254.963748) (xy 81.871071 -254.914334) (xy 81.891019 -254.867514) (xy 81.91822 -254.8245)
			(xy 81.951968 -254.786406) (xy 81.99139 -254.754219) (xy 82.035464 -254.728773) (xy 82.08305 -254.710726)
			(xy 82.132914 -254.700546) (xy 82.183766 -254.698497) (xy 82.234287 -254.704631) (xy 82.283171 -254.718791)
			(xy 82.32915 -254.740608) (xy 82.371034 -254.769518) (xy 82.407738 -254.804773) (xy 82.438311 -254.845459)
			(xy 82.461962 -254.890522) (xy 82.478078 -254.938796) (xy 82.486242 -254.98903) (xy 82.486754 -255.014476)
			(xy 82.486251 -255.039465) (xy 82.793568 -255.039465) (xy 82.793568 -254.989487) (xy 82.801387 -254.940124)
			(xy 82.816831 -254.892592) (xy 82.839521 -254.84806) (xy 82.868897 -254.807627) (xy 82.904237 -254.772287)
			(xy 82.94467 -254.742911) (xy 82.989202 -254.720221) (xy 83.036734 -254.704777) (xy 83.086097 -254.696958)
			(xy 83.136075 -254.696958) (xy 83.185438 -254.704777) (xy 83.23297 -254.720221) (xy 83.277502 -254.742911)
			(xy 83.317935 -254.772287) (xy 83.353275 -254.807627) (xy 83.382651 -254.84806) (xy 83.405341 -254.892592)
			(xy 83.420785 -254.940124) (xy 83.428604 -254.989487) (xy 83.429094 -255.014476) (xy 83.734905 -255.014476)
			(xy 83.739 -254.963748) (xy 83.751179 -254.914334) (xy 83.771127 -254.867514) (xy 83.798328 -254.8245)
			(xy 83.832076 -254.786406) (xy 83.871498 -254.754219) (xy 83.915572 -254.728773) (xy 83.963158 -254.710726)
			(xy 84.013022 -254.700546) (xy 84.063874 -254.698497) (xy 84.114395 -254.704631) (xy 84.163279 -254.718791)
			(xy 84.209258 -254.740608) (xy 84.251142 -254.769518) (xy 84.287846 -254.804773) (xy 84.318419 -254.845459)
			(xy 84.34207 -254.890522) (xy 84.358186 -254.938796) (xy 84.36635 -254.98903) (xy 84.366862 -255.014476)
			(xy 84.366359 -255.039465) (xy 84.673422 -255.039465) (xy 84.673422 -254.989487) (xy 84.681241 -254.940124)
			(xy 84.696685 -254.892592) (xy 84.719375 -254.84806) (xy 84.748751 -254.807627) (xy 84.784091 -254.772287)
			(xy 84.824524 -254.742911) (xy 84.869056 -254.720221) (xy 84.916588 -254.704777) (xy 84.965951 -254.696958)
			(xy 85.015929 -254.696958) (xy 85.065292 -254.704777) (xy 85.112824 -254.720221) (xy 85.157356 -254.742911)
			(xy 85.197789 -254.772287) (xy 85.233129 -254.807627) (xy 85.262505 -254.84806) (xy 85.285195 -254.892592)
			(xy 85.300639 -254.940124) (xy 85.308458 -254.989487) (xy 85.308948 -255.014476) (xy 85.614759 -255.014476)
			(xy 85.618854 -254.963748) (xy 85.631033 -254.914334) (xy 85.650981 -254.867514) (xy 85.678182 -254.8245)
			(xy 85.71193 -254.786406) (xy 85.751352 -254.754219) (xy 85.795426 -254.728773) (xy 85.843012 -254.710726)
			(xy 85.892876 -254.700546) (xy 85.943728 -254.698497) (xy 85.994249 -254.704631) (xy 86.043133 -254.718791)
			(xy 86.089112 -254.740608) (xy 86.130996 -254.769518) (xy 86.1677 -254.804773) (xy 86.198273 -254.845459)
			(xy 86.221924 -254.890522) (xy 86.23804 -254.938796) (xy 86.246204 -254.98903) (xy 86.246716 -255.014476)
			(xy 86.246213 -255.039465) (xy 86.55353 -255.039465) (xy 86.55353 -254.989487) (xy 86.561349 -254.940124)
			(xy 86.576793 -254.892592) (xy 86.599483 -254.84806) (xy 86.628859 -254.807627) (xy 86.664199 -254.772287)
			(xy 86.704632 -254.742911) (xy 86.749164 -254.720221) (xy 86.796696 -254.704777) (xy 86.846059 -254.696958)
			(xy 86.896037 -254.696958) (xy 86.9454 -254.704777) (xy 86.992932 -254.720221) (xy 87.037464 -254.742911)
			(xy 87.077897 -254.772287) (xy 87.113237 -254.807627) (xy 87.142613 -254.84806) (xy 87.165303 -254.892592)
			(xy 87.180747 -254.940124) (xy 87.188566 -254.989487) (xy 87.189056 -255.014476) (xy 87.494867 -255.014476)
			(xy 87.498962 -254.963748) (xy 87.511141 -254.914334) (xy 87.531089 -254.867514) (xy 87.55829 -254.8245)
			(xy 87.592038 -254.786406) (xy 87.63146 -254.754219) (xy 87.675534 -254.728773) (xy 87.72312 -254.710726)
			(xy 87.772984 -254.700546) (xy 87.823836 -254.698497) (xy 87.874357 -254.704631) (xy 87.923241 -254.718791)
			(xy 87.96922 -254.740608) (xy 88.011104 -254.769518) (xy 88.047808 -254.804773) (xy 88.078381 -254.845459)
			(xy 88.102032 -254.890522) (xy 88.118148 -254.938796) (xy 88.126312 -254.98903) (xy 88.126824 -255.014476)
			(xy 88.434921 -255.014476) (xy 88.439016 -254.963748) (xy 88.451195 -254.914334) (xy 88.471143 -254.867514)
			(xy 88.498344 -254.8245) (xy 88.532092 -254.786406) (xy 88.571514 -254.754219) (xy 88.615588 -254.728773)
			(xy 88.663174 -254.710726) (xy 88.713038 -254.700546) (xy 88.76389 -254.698497) (xy 88.814411 -254.704631)
			(xy 88.863295 -254.718791) (xy 88.909274 -254.740608) (xy 88.951158 -254.769518) (xy 88.987862 -254.804773)
			(xy 89.018435 -254.845459) (xy 89.042086 -254.890522) (xy 89.058202 -254.938796) (xy 89.066366 -254.98903)
			(xy 89.066878 -255.014476) (xy 89.066375 -255.039465) (xy 89.373438 -255.039465) (xy 89.373438 -254.989487)
			(xy 89.381257 -254.940124) (xy 89.396701 -254.892592) (xy 89.419391 -254.84806) (xy 89.448767 -254.807627)
			(xy 89.484107 -254.772287) (xy 89.52454 -254.742911) (xy 89.569072 -254.720221) (xy 89.616604 -254.704777)
			(xy 89.665967 -254.696958) (xy 89.715945 -254.696958) (xy 89.765308 -254.704777) (xy 89.81284 -254.720221)
			(xy 89.857372 -254.742911) (xy 89.897805 -254.772287) (xy 89.933145 -254.807627) (xy 89.962521 -254.84806)
			(xy 89.985211 -254.892592) (xy 90.000655 -254.940124) (xy 90.008474 -254.989487) (xy 90.008964 -255.014476)
			(xy 90.314775 -255.014476) (xy 90.31887 -254.963748) (xy 90.331049 -254.914334) (xy 90.350997 -254.867514)
			(xy 90.378198 -254.8245) (xy 90.411946 -254.786406) (xy 90.451368 -254.754219) (xy 90.495442 -254.728773)
			(xy 90.543028 -254.710726) (xy 90.592892 -254.700546) (xy 90.643744 -254.698497) (xy 90.694265 -254.704631)
			(xy 90.743149 -254.718791) (xy 90.789128 -254.740608) (xy 90.831012 -254.769518) (xy 90.867716 -254.804773)
			(xy 90.898289 -254.845459) (xy 90.92194 -254.890522) (xy 90.938056 -254.938796) (xy 90.94622 -254.98903)
			(xy 90.946732 -255.014476) (xy 90.946229 -255.039465) (xy 91.253546 -255.039465) (xy 91.253546 -254.989487)
			(xy 91.261365 -254.940124) (xy 91.276809 -254.892592) (xy 91.299499 -254.84806) (xy 91.328875 -254.807627)
			(xy 91.364215 -254.772287) (xy 91.404648 -254.742911) (xy 91.44918 -254.720221) (xy 91.496712 -254.704777)
			(xy 91.546075 -254.696958) (xy 91.596053 -254.696958) (xy 91.645416 -254.704777) (xy 91.692948 -254.720221)
			(xy 91.73748 -254.742911) (xy 91.777913 -254.772287) (xy 91.813253 -254.807627) (xy 91.842629 -254.84806)
			(xy 91.865319 -254.892592) (xy 91.880763 -254.940124) (xy 91.888582 -254.989487) (xy 91.889072 -255.014476)
			(xy 92.194883 -255.014476) (xy 92.198978 -254.963748) (xy 92.211157 -254.914334) (xy 92.231105 -254.867514)
			(xy 92.258306 -254.8245) (xy 92.292054 -254.786406) (xy 92.331476 -254.754219) (xy 92.37555 -254.728773)
			(xy 92.423136 -254.710726) (xy 92.473 -254.700546) (xy 92.523852 -254.698497) (xy 92.574373 -254.704631)
			(xy 92.623257 -254.718791) (xy 92.669236 -254.740608) (xy 92.71112 -254.769518) (xy 92.747824 -254.804773)
			(xy 92.778397 -254.845459) (xy 92.802048 -254.890522) (xy 92.818164 -254.938796) (xy 92.826328 -254.98903)
			(xy 92.82684 -255.014476) (xy 92.826337 -255.039465) (xy 93.1334 -255.039465) (xy 93.1334 -254.989487)
			(xy 93.141219 -254.940124) (xy 93.156663 -254.892592) (xy 93.179353 -254.84806) (xy 93.208729 -254.807627)
			(xy 93.244069 -254.772287) (xy 93.284502 -254.742911) (xy 93.329034 -254.720221) (xy 93.376566 -254.704777)
			(xy 93.425929 -254.696958) (xy 93.475907 -254.696958) (xy 93.52527 -254.704777) (xy 93.572802 -254.720221)
			(xy 93.617334 -254.742911) (xy 93.657767 -254.772287) (xy 93.693107 -254.807627) (xy 93.722483 -254.84806)
			(xy 93.745173 -254.892592) (xy 93.760617 -254.940124) (xy 93.768436 -254.989487) (xy 93.768926 -255.014476)
			(xy 94.074737 -255.014476) (xy 94.078832 -254.963748) (xy 94.091011 -254.914334) (xy 94.110959 -254.867514)
			(xy 94.13816 -254.8245) (xy 94.171908 -254.786406) (xy 94.21133 -254.754219) (xy 94.255404 -254.728773)
			(xy 94.30299 -254.710726) (xy 94.352854 -254.700546) (xy 94.403706 -254.698497) (xy 94.454227 -254.704631)
			(xy 94.503111 -254.718791) (xy 94.54909 -254.740608) (xy 94.590974 -254.769518) (xy 94.627678 -254.804773)
			(xy 94.658251 -254.845459) (xy 94.681902 -254.890522) (xy 94.698018 -254.938796) (xy 94.706182 -254.98903)
			(xy 94.706694 -255.014476) (xy 95.014791 -255.014476) (xy 95.018886 -254.963748) (xy 95.031065 -254.914334)
			(xy 95.051013 -254.867514) (xy 95.078214 -254.8245) (xy 95.111962 -254.786406) (xy 95.151384 -254.754219)
			(xy 95.195458 -254.728773) (xy 95.243044 -254.710726) (xy 95.292908 -254.700546) (xy 95.34376 -254.698497)
			(xy 95.394281 -254.704631) (xy 95.443165 -254.718791) (xy 95.489144 -254.740608) (xy 95.531028 -254.769518)
			(xy 95.567732 -254.804773) (xy 95.598305 -254.845459) (xy 95.621956 -254.890522) (xy 95.638072 -254.938796)
			(xy 95.646236 -254.98903) (xy 95.646748 -255.014476) (xy 95.646236 -255.039922) (xy 95.638072 -255.090156)
			(xy 95.621956 -255.13843) (xy 95.598305 -255.183493) (xy 95.567732 -255.224179) (xy 95.531028 -255.259434)
			(xy 95.489144 -255.288344) (xy 95.443165 -255.310161) (xy 95.394281 -255.324321) (xy 95.34376 -255.330455)
			(xy 95.292908 -255.328406) (xy 95.243044 -255.318226) (xy 95.195458 -255.300179) (xy 95.151384 -255.274733)
			(xy 95.111962 -255.242546) (xy 95.078214 -255.204452) (xy 95.051013 -255.161438) (xy 95.031065 -255.114618)
			(xy 95.018886 -255.065204) (xy 95.014791 -255.014476) (xy 94.706694 -255.014476) (xy 94.706182 -255.039922)
			(xy 94.698018 -255.090156) (xy 94.681902 -255.13843) (xy 94.658251 -255.183493) (xy 94.627678 -255.224179)
			(xy 94.590974 -255.259434) (xy 94.54909 -255.288344) (xy 94.503111 -255.310161) (xy 94.454227 -255.324321)
			(xy 94.403706 -255.330455) (xy 94.352854 -255.328406) (xy 94.30299 -255.318226) (xy 94.255404 -255.300179)
			(xy 94.21133 -255.274733) (xy 94.171908 -255.242546) (xy 94.13816 -255.204452) (xy 94.110959 -255.161438)
			(xy 94.091011 -255.114618) (xy 94.078832 -255.065204) (xy 94.074737 -255.014476) (xy 93.768926 -255.014476)
			(xy 93.768436 -255.039465) (xy 93.760617 -255.088828) (xy 93.745173 -255.13636) (xy 93.722483 -255.180892)
			(xy 93.693107 -255.221325) (xy 93.657767 -255.256665) (xy 93.617334 -255.286041) (xy 93.572802 -255.308731)
			(xy 93.52527 -255.324175) (xy 93.475907 -255.331994) (xy 93.425929 -255.331994) (xy 93.376566 -255.324175)
			(xy 93.329034 -255.308731) (xy 93.284502 -255.286041) (xy 93.244069 -255.256665) (xy 93.208729 -255.221325)
			(xy 93.179353 -255.180892) (xy 93.156663 -255.13636) (xy 93.141219 -255.088828) (xy 93.1334 -255.039465)
			(xy 92.826337 -255.039465) (xy 92.826328 -255.039922) (xy 92.818164 -255.090156) (xy 92.802048 -255.13843)
			(xy 92.778397 -255.183493) (xy 92.747824 -255.224179) (xy 92.71112 -255.259434) (xy 92.669236 -255.288344)
			(xy 92.623257 -255.310161) (xy 92.574373 -255.324321) (xy 92.523852 -255.330455) (xy 92.473 -255.328406)
			(xy 92.423136 -255.318226) (xy 92.37555 -255.300179) (xy 92.331476 -255.274733) (xy 92.292054 -255.242546)
			(xy 92.258306 -255.204452) (xy 92.231105 -255.161438) (xy 92.211157 -255.114618) (xy 92.198978 -255.065204)
			(xy 92.194883 -255.014476) (xy 91.889072 -255.014476) (xy 91.888582 -255.039465) (xy 91.880763 -255.088828)
			(xy 91.865319 -255.13636) (xy 91.842629 -255.180892) (xy 91.813253 -255.221325) (xy 91.777913 -255.256665)
			(xy 91.73748 -255.286041) (xy 91.692948 -255.308731) (xy 91.645416 -255.324175) (xy 91.596053 -255.331994)
			(xy 91.546075 -255.331994) (xy 91.496712 -255.324175) (xy 91.44918 -255.308731) (xy 91.404648 -255.286041)
			(xy 91.364215 -255.256665) (xy 91.328875 -255.221325) (xy 91.299499 -255.180892) (xy 91.276809 -255.13636)
			(xy 91.261365 -255.088828) (xy 91.253546 -255.039465) (xy 90.946229 -255.039465) (xy 90.94622 -255.039922)
			(xy 90.938056 -255.090156) (xy 90.92194 -255.13843) (xy 90.898289 -255.183493) (xy 90.867716 -255.224179)
			(xy 90.831012 -255.259434) (xy 90.789128 -255.288344) (xy 90.743149 -255.310161) (xy 90.694265 -255.324321)
			(xy 90.643744 -255.330455) (xy 90.592892 -255.328406) (xy 90.543028 -255.318226) (xy 90.495442 -255.300179)
			(xy 90.451368 -255.274733) (xy 90.411946 -255.242546) (xy 90.378198 -255.204452) (xy 90.350997 -255.161438)
			(xy 90.331049 -255.114618) (xy 90.31887 -255.065204) (xy 90.314775 -255.014476) (xy 90.008964 -255.014476)
			(xy 90.008474 -255.039465) (xy 90.000655 -255.088828) (xy 89.985211 -255.13636) (xy 89.962521 -255.180892)
			(xy 89.933145 -255.221325) (xy 89.897805 -255.256665) (xy 89.857372 -255.286041) (xy 89.81284 -255.308731)
			(xy 89.765308 -255.324175) (xy 89.715945 -255.331994) (xy 89.665967 -255.331994) (xy 89.616604 -255.324175)
			(xy 89.569072 -255.308731) (xy 89.52454 -255.286041) (xy 89.484107 -255.256665) (xy 89.448767 -255.221325)
			(xy 89.419391 -255.180892) (xy 89.396701 -255.13636) (xy 89.381257 -255.088828) (xy 89.373438 -255.039465)
			(xy 89.066375 -255.039465) (xy 89.066366 -255.039922) (xy 89.058202 -255.090156) (xy 89.042086 -255.13843)
			(xy 89.018435 -255.183493) (xy 88.987862 -255.224179) (xy 88.951158 -255.259434) (xy 88.909274 -255.288344)
			(xy 88.863295 -255.310161) (xy 88.814411 -255.324321) (xy 88.76389 -255.330455) (xy 88.713038 -255.328406)
			(xy 88.663174 -255.318226) (xy 88.615588 -255.300179) (xy 88.571514 -255.274733) (xy 88.532092 -255.242546)
			(xy 88.498344 -255.204452) (xy 88.471143 -255.161438) (xy 88.451195 -255.114618) (xy 88.439016 -255.065204)
			(xy 88.434921 -255.014476) (xy 88.126824 -255.014476) (xy 88.126312 -255.039922) (xy 88.118148 -255.090156)
			(xy 88.102032 -255.13843) (xy 88.078381 -255.183493) (xy 88.047808 -255.224179) (xy 88.011104 -255.259434)
			(xy 87.96922 -255.288344) (xy 87.923241 -255.310161) (xy 87.874357 -255.324321) (xy 87.823836 -255.330455)
			(xy 87.772984 -255.328406) (xy 87.72312 -255.318226) (xy 87.675534 -255.300179) (xy 87.63146 -255.274733)
			(xy 87.592038 -255.242546) (xy 87.55829 -255.204452) (xy 87.531089 -255.161438) (xy 87.511141 -255.114618)
			(xy 87.498962 -255.065204) (xy 87.494867 -255.014476) (xy 87.189056 -255.014476) (xy 87.188566 -255.039465)
			(xy 87.180747 -255.088828) (xy 87.165303 -255.13636) (xy 87.142613 -255.180892) (xy 87.113237 -255.221325)
			(xy 87.077897 -255.256665) (xy 87.037464 -255.286041) (xy 86.992932 -255.308731) (xy 86.9454 -255.324175)
			(xy 86.896037 -255.331994) (xy 86.846059 -255.331994) (xy 86.796696 -255.324175) (xy 86.749164 -255.308731)
			(xy 86.704632 -255.286041) (xy 86.664199 -255.256665) (xy 86.628859 -255.221325) (xy 86.599483 -255.180892)
			(xy 86.576793 -255.13636) (xy 86.561349 -255.088828) (xy 86.55353 -255.039465) (xy 86.246213 -255.039465)
			(xy 86.246204 -255.039922) (xy 86.23804 -255.090156) (xy 86.221924 -255.13843) (xy 86.198273 -255.183493)
			(xy 86.1677 -255.224179) (xy 86.130996 -255.259434) (xy 86.089112 -255.288344) (xy 86.043133 -255.310161)
			(xy 85.994249 -255.324321) (xy 85.943728 -255.330455) (xy 85.892876 -255.328406) (xy 85.843012 -255.318226)
			(xy 85.795426 -255.300179) (xy 85.751352 -255.274733) (xy 85.71193 -255.242546) (xy 85.678182 -255.204452)
			(xy 85.650981 -255.161438) (xy 85.631033 -255.114618) (xy 85.618854 -255.065204) (xy 85.614759 -255.014476)
			(xy 85.308948 -255.014476) (xy 85.308458 -255.039465) (xy 85.300639 -255.088828) (xy 85.285195 -255.13636)
			(xy 85.262505 -255.180892) (xy 85.233129 -255.221325) (xy 85.197789 -255.256665) (xy 85.157356 -255.286041)
			(xy 85.112824 -255.308731) (xy 85.065292 -255.324175) (xy 85.015929 -255.331994) (xy 84.965951 -255.331994)
			(xy 84.916588 -255.324175) (xy 84.869056 -255.308731) (xy 84.824524 -255.286041) (xy 84.784091 -255.256665)
			(xy 84.748751 -255.221325) (xy 84.719375 -255.180892) (xy 84.696685 -255.13636) (xy 84.681241 -255.088828)
			(xy 84.673422 -255.039465) (xy 84.366359 -255.039465) (xy 84.36635 -255.039922) (xy 84.358186 -255.090156)
			(xy 84.34207 -255.13843) (xy 84.318419 -255.183493) (xy 84.287846 -255.224179) (xy 84.251142 -255.259434)
			(xy 84.209258 -255.288344) (xy 84.163279 -255.310161) (xy 84.114395 -255.324321) (xy 84.063874 -255.330455)
			(xy 84.013022 -255.328406) (xy 83.963158 -255.318226) (xy 83.915572 -255.300179) (xy 83.871498 -255.274733)
			(xy 83.832076 -255.242546) (xy 83.798328 -255.204452) (xy 83.771127 -255.161438) (xy 83.751179 -255.114618)
			(xy 83.739 -255.065204) (xy 83.734905 -255.014476) (xy 83.429094 -255.014476) (xy 83.428604 -255.039465)
			(xy 83.420785 -255.088828) (xy 83.405341 -255.13636) (xy 83.382651 -255.180892) (xy 83.353275 -255.221325)
			(xy 83.317935 -255.256665) (xy 83.277502 -255.286041) (xy 83.23297 -255.308731) (xy 83.185438 -255.324175)
			(xy 83.136075 -255.331994) (xy 83.086097 -255.331994) (xy 83.036734 -255.324175) (xy 82.989202 -255.308731)
			(xy 82.94467 -255.286041) (xy 82.904237 -255.256665) (xy 82.868897 -255.221325) (xy 82.839521 -255.180892)
			(xy 82.816831 -255.13636) (xy 82.801387 -255.088828) (xy 82.793568 -255.039465) (xy 82.486251 -255.039465)
			(xy 82.486242 -255.039922) (xy 82.478078 -255.090156) (xy 82.461962 -255.13843) (xy 82.438311 -255.183493)
			(xy 82.407738 -255.224179) (xy 82.371034 -255.259434) (xy 82.32915 -255.288344) (xy 82.283171 -255.310161)
			(xy 82.234287 -255.324321) (xy 82.183766 -255.330455) (xy 82.132914 -255.328406) (xy 82.08305 -255.318226)
			(xy 82.035464 -255.300179) (xy 81.99139 -255.274733) (xy 81.951968 -255.242546) (xy 81.91822 -255.204452)
			(xy 81.891019 -255.161438) (xy 81.871071 -255.114618) (xy 81.858892 -255.065204) (xy 81.854797 -255.014476)
			(xy 81.5467 -255.014476) (xy 81.546188 -255.039922) (xy 81.538024 -255.090156) (xy 81.521908 -255.13843)
			(xy 81.498257 -255.183493) (xy 81.467684 -255.224179) (xy 81.43098 -255.259434) (xy 81.389096 -255.288344)
			(xy 81.343117 -255.310161) (xy 81.294233 -255.324321) (xy 81.243712 -255.330455) (xy 81.19286 -255.328406)
			(xy 81.142996 -255.318226) (xy 81.09541 -255.300179) (xy 81.051336 -255.274733) (xy 81.011914 -255.242546)
			(xy 80.978166 -255.204452) (xy 80.950965 -255.161438) (xy 80.931017 -255.114618) (xy 80.918838 -255.065204)
			(xy 80.914743 -255.014476) (xy 80.609186 -255.014476) (xy 80.608696 -255.039465) (xy 80.600877 -255.088828)
			(xy 80.585433 -255.13636) (xy 80.562743 -255.180892) (xy 80.533367 -255.221325) (xy 80.498027 -255.256665)
			(xy 80.457594 -255.286041) (xy 80.413062 -255.308731) (xy 80.36553 -255.324175) (xy 80.316167 -255.331994)
			(xy 80.266189 -255.331994) (xy 80.216826 -255.324175) (xy 80.169294 -255.308731) (xy 80.124762 -255.286041)
			(xy 80.084329 -255.256665) (xy 80.048989 -255.221325) (xy 80.019613 -255.180892) (xy 79.996923 -255.13636)
			(xy 79.981479 -255.088828) (xy 79.97366 -255.039465) (xy 79.53248 -255.039465) (xy 79.53248 -255.448562)
			(xy 79.532976 -255.463339) (xy 79.54143 -255.491657) (xy 79.557641 -255.516367) (xy 79.580251 -255.535399)
			(xy 79.607364 -255.547158) (xy 79.636709 -255.550658) (xy 79.665828 -255.545606) (xy 79.679292 -255.539494)
			(xy 79.701428 -255.529001) (xy 79.74812 -255.514182) (xy 79.79653 -255.506687) (xy 79.821024 -255.50622)
			(xy 79.846033 -255.506712) (xy 79.895436 -255.51454) (xy 79.943005 -255.53) (xy 79.987571 -255.55271)
			(xy 80.028036 -255.582112) (xy 80.063403 -255.617482) (xy 80.092802 -255.657949) (xy 80.115509 -255.702517)
			(xy 80.130965 -255.750088) (xy 80.138789 -255.799491) (xy 80.138789 -255.824482) (xy 80.444843 -255.824482)
			(xy 80.448938 -255.773754) (xy 80.461117 -255.72434) (xy 80.481065 -255.67752) (xy 80.508266 -255.634506)
			(xy 80.542014 -255.596412) (xy 80.581436 -255.564225) (xy 80.62551 -255.538779) (xy 80.673096 -255.520732)
			(xy 80.72296 -255.510552) (xy 80.773812 -255.508503) (xy 80.824333 -255.514637) (xy 80.873217 -255.528797)
			(xy 80.919196 -255.550614) (xy 80.96108 -255.579524) (xy 80.997784 -255.614779) (xy 81.028357 -255.655465)
			(xy 81.052008 -255.700528) (xy 81.068124 -255.748802) (xy 81.076288 -255.799036) (xy 81.0768 -255.824482)
			(xy 81.076297 -255.849471) (xy 81.383614 -255.849471) (xy 81.383614 -255.799493) (xy 81.391433 -255.75013)
			(xy 81.406877 -255.702598) (xy 81.429567 -255.658066) (xy 81.458943 -255.617633) (xy 81.494283 -255.582293)
			(xy 81.534716 -255.552917) (xy 81.579248 -255.530227) (xy 81.62678 -255.514783) (xy 81.676143 -255.506964)
			(xy 81.726121 -255.506964) (xy 81.775484 -255.514783) (xy 81.823016 -255.530227) (xy 81.867548 -255.552917)
			(xy 81.907981 -255.582293) (xy 81.943321 -255.617633) (xy 81.972697 -255.658066) (xy 81.995387 -255.702598)
			(xy 82.010831 -255.75013) (xy 82.01865 -255.799493) (xy 82.01914 -255.824482) (xy 82.324697 -255.824482)
			(xy 82.328792 -255.773754) (xy 82.340971 -255.72434) (xy 82.360919 -255.67752) (xy 82.38812 -255.634506)
			(xy 82.421868 -255.596412) (xy 82.46129 -255.564225) (xy 82.505364 -255.538779) (xy 82.55295 -255.520732)
			(xy 82.602814 -255.510552) (xy 82.653666 -255.508503) (xy 82.704187 -255.514637) (xy 82.753071 -255.528797)
			(xy 82.79905 -255.550614) (xy 82.840934 -255.579524) (xy 82.877638 -255.614779) (xy 82.908211 -255.655465)
			(xy 82.931862 -255.700528) (xy 82.947978 -255.748802) (xy 82.956142 -255.799036) (xy 82.956654 -255.824482)
			(xy 82.956151 -255.849471) (xy 83.263468 -255.849471) (xy 83.263468 -255.799493) (xy 83.271287 -255.75013)
			(xy 83.286731 -255.702598) (xy 83.309421 -255.658066) (xy 83.338797 -255.617633) (xy 83.374137 -255.582293)
			(xy 83.41457 -255.552917) (xy 83.459102 -255.530227) (xy 83.506634 -255.514783) (xy 83.555997 -255.506964)
			(xy 83.605975 -255.506964) (xy 83.655338 -255.514783) (xy 83.70287 -255.530227) (xy 83.747402 -255.552917)
			(xy 83.787835 -255.582293) (xy 83.823175 -255.617633) (xy 83.852551 -255.658066) (xy 83.875241 -255.702598)
			(xy 83.890685 -255.75013) (xy 83.898504 -255.799493) (xy 83.898994 -255.824482) (xy 84.204805 -255.824482)
			(xy 84.2089 -255.773754) (xy 84.221079 -255.72434) (xy 84.241027 -255.67752) (xy 84.268228 -255.634506)
			(xy 84.301976 -255.596412) (xy 84.341398 -255.564225) (xy 84.385472 -255.538779) (xy 84.433058 -255.520732)
			(xy 84.482922 -255.510552) (xy 84.533774 -255.508503) (xy 84.584295 -255.514637) (xy 84.633179 -255.528797)
			(xy 84.679158 -255.550614) (xy 84.721042 -255.579524) (xy 84.757746 -255.614779) (xy 84.788319 -255.655465)
			(xy 84.81197 -255.700528) (xy 84.828086 -255.748802) (xy 84.83625 -255.799036) (xy 84.836762 -255.824482)
			(xy 85.144859 -255.824482) (xy 85.148954 -255.773754) (xy 85.161133 -255.72434) (xy 85.181081 -255.67752)
			(xy 85.208282 -255.634506) (xy 85.24203 -255.596412) (xy 85.281452 -255.564225) (xy 85.325526 -255.538779)
			(xy 85.373112 -255.520732) (xy 85.422976 -255.510552) (xy 85.473828 -255.508503) (xy 85.524349 -255.514637)
			(xy 85.573233 -255.528797) (xy 85.619212 -255.550614) (xy 85.661096 -255.579524) (xy 85.6978 -255.614779)
			(xy 85.728373 -255.655465) (xy 85.752024 -255.700528) (xy 85.76814 -255.748802) (xy 85.776304 -255.799036)
			(xy 85.776816 -255.824482) (xy 85.776313 -255.849471) (xy 86.08363 -255.849471) (xy 86.08363 -255.799493)
			(xy 86.091449 -255.75013) (xy 86.106893 -255.702598) (xy 86.129583 -255.658066) (xy 86.158959 -255.617633)
			(xy 86.194299 -255.582293) (xy 86.234732 -255.552917) (xy 86.279264 -255.530227) (xy 86.326796 -255.514783)
			(xy 86.376159 -255.506964) (xy 86.426137 -255.506964) (xy 86.4755 -255.514783) (xy 86.523032 -255.530227)
			(xy 86.567564 -255.552917) (xy 86.607997 -255.582293) (xy 86.643337 -255.617633) (xy 86.672713 -255.658066)
			(xy 86.695403 -255.702598) (xy 86.710847 -255.75013) (xy 86.718666 -255.799493) (xy 86.719156 -255.824482)
			(xy 87.024713 -255.824482) (xy 87.028808 -255.773754) (xy 87.040987 -255.72434) (xy 87.060935 -255.67752)
			(xy 87.088136 -255.634506) (xy 87.121884 -255.596412) (xy 87.161306 -255.564225) (xy 87.20538 -255.538779)
			(xy 87.252966 -255.520732) (xy 87.30283 -255.510552) (xy 87.353682 -255.508503) (xy 87.404203 -255.514637)
			(xy 87.453087 -255.528797) (xy 87.499066 -255.550614) (xy 87.54095 -255.579524) (xy 87.577654 -255.614779)
			(xy 87.608227 -255.655465) (xy 87.631878 -255.700528) (xy 87.647994 -255.748802) (xy 87.656158 -255.799036)
			(xy 87.65667 -255.824482) (xy 87.656167 -255.849471) (xy 87.963484 -255.849471) (xy 87.963484 -255.799493)
			(xy 87.971303 -255.75013) (xy 87.986747 -255.702598) (xy 88.009437 -255.658066) (xy 88.038813 -255.617633)
			(xy 88.074153 -255.582293) (xy 88.114586 -255.552917) (xy 88.159118 -255.530227) (xy 88.20665 -255.514783)
			(xy 88.256013 -255.506964) (xy 88.305991 -255.506964) (xy 88.355354 -255.514783) (xy 88.402886 -255.530227)
			(xy 88.447418 -255.552917) (xy 88.487851 -255.582293) (xy 88.523191 -255.617633) (xy 88.552567 -255.658066)
			(xy 88.575257 -255.702598) (xy 88.590701 -255.75013) (xy 88.59852 -255.799493) (xy 88.59901 -255.824482)
			(xy 88.904821 -255.824482) (xy 88.908916 -255.773754) (xy 88.921095 -255.72434) (xy 88.941043 -255.67752)
			(xy 88.968244 -255.634506) (xy 89.001992 -255.596412) (xy 89.041414 -255.564225) (xy 89.085488 -255.538779)
			(xy 89.133074 -255.520732) (xy 89.182938 -255.510552) (xy 89.23379 -255.508503) (xy 89.284311 -255.514637)
			(xy 89.333195 -255.528797) (xy 89.379174 -255.550614) (xy 89.421058 -255.579524) (xy 89.457762 -255.614779)
			(xy 89.488335 -255.655465) (xy 89.511986 -255.700528) (xy 89.528102 -255.748802) (xy 89.536266 -255.799036)
			(xy 89.536778 -255.824482) (xy 89.536275 -255.849471) (xy 89.843592 -255.849471) (xy 89.843592 -255.799493)
			(xy 89.851411 -255.75013) (xy 89.866855 -255.702598) (xy 89.889545 -255.658066) (xy 89.918921 -255.617633)
			(xy 89.954261 -255.582293) (xy 89.994694 -255.552917) (xy 90.039226 -255.530227) (xy 90.086758 -255.514783)
			(xy 90.136121 -255.506964) (xy 90.186099 -255.506964) (xy 90.235462 -255.514783) (xy 90.282994 -255.530227)
			(xy 90.327526 -255.552917) (xy 90.367959 -255.582293) (xy 90.403299 -255.617633) (xy 90.432675 -255.658066)
			(xy 90.455365 -255.702598) (xy 90.470809 -255.75013) (xy 90.478628 -255.799493) (xy 90.479118 -255.824482)
			(xy 90.784675 -255.824482) (xy 90.78877 -255.773754) (xy 90.800949 -255.72434) (xy 90.820897 -255.67752)
			(xy 90.848098 -255.634506) (xy 90.881846 -255.596412) (xy 90.921268 -255.564225) (xy 90.965342 -255.538779)
			(xy 91.012928 -255.520732) (xy 91.062792 -255.510552) (xy 91.113644 -255.508503) (xy 91.164165 -255.514637)
			(xy 91.213049 -255.528797) (xy 91.259028 -255.550614) (xy 91.300912 -255.579524) (xy 91.337616 -255.614779)
			(xy 91.368189 -255.655465) (xy 91.39184 -255.700528) (xy 91.407956 -255.748802) (xy 91.41612 -255.799036)
			(xy 91.416632 -255.824482) (xy 91.724729 -255.824482) (xy 91.728824 -255.773754) (xy 91.741003 -255.72434)
			(xy 91.760951 -255.67752) (xy 91.788152 -255.634506) (xy 91.8219 -255.596412) (xy 91.861322 -255.564225)
			(xy 91.905396 -255.538779) (xy 91.952982 -255.520732) (xy 92.002846 -255.510552) (xy 92.053698 -255.508503)
			(xy 92.104219 -255.514637) (xy 92.153103 -255.528797) (xy 92.199082 -255.550614) (xy 92.240966 -255.579524)
			(xy 92.27767 -255.614779) (xy 92.308243 -255.655465) (xy 92.331894 -255.700528) (xy 92.34801 -255.748802)
			(xy 92.356174 -255.799036) (xy 92.356686 -255.824482) (xy 92.356183 -255.849471) (xy 92.6635 -255.849471)
			(xy 92.6635 -255.799493) (xy 92.671319 -255.75013) (xy 92.686763 -255.702598) (xy 92.709453 -255.658066)
			(xy 92.738829 -255.617633) (xy 92.774169 -255.582293) (xy 92.814602 -255.552917) (xy 92.859134 -255.530227)
			(xy 92.906666 -255.514783) (xy 92.956029 -255.506964) (xy 93.006007 -255.506964) (xy 93.05537 -255.514783)
			(xy 93.102902 -255.530227) (xy 93.147434 -255.552917) (xy 93.187867 -255.582293) (xy 93.223207 -255.617633)
			(xy 93.252583 -255.658066) (xy 93.275273 -255.702598) (xy 93.290717 -255.75013) (xy 93.298536 -255.799493)
			(xy 93.299026 -255.824482) (xy 93.604837 -255.824482) (xy 93.608932 -255.773754) (xy 93.621111 -255.72434)
			(xy 93.641059 -255.67752) (xy 93.66826 -255.634506) (xy 93.702008 -255.596412) (xy 93.74143 -255.564225)
			(xy 93.785504 -255.538779) (xy 93.83309 -255.520732) (xy 93.882954 -255.510552) (xy 93.933806 -255.508503)
			(xy 93.984327 -255.514637) (xy 94.033211 -255.528797) (xy 94.07919 -255.550614) (xy 94.121074 -255.579524)
			(xy 94.157778 -255.614779) (xy 94.188351 -255.655465) (xy 94.212002 -255.700528) (xy 94.228118 -255.748802)
			(xy 94.236282 -255.799036) (xy 94.236794 -255.824482) (xy 94.236291 -255.849471) (xy 94.543608 -255.849471)
			(xy 94.543608 -255.799493) (xy 94.551427 -255.75013) (xy 94.566871 -255.702598) (xy 94.589561 -255.658066)
			(xy 94.618937 -255.617633) (xy 94.654277 -255.582293) (xy 94.69471 -255.552917) (xy 94.739242 -255.530227)
			(xy 94.786774 -255.514783) (xy 94.836137 -255.506964) (xy 94.886115 -255.506964) (xy 94.935478 -255.514783)
			(xy 94.98301 -255.530227) (xy 95.027542 -255.552917) (xy 95.067975 -255.582293) (xy 95.103315 -255.617633)
			(xy 95.132691 -255.658066) (xy 95.155381 -255.702598) (xy 95.170825 -255.75013) (xy 95.178644 -255.799493)
			(xy 95.179134 -255.824482) (xy 95.178644 -255.849471) (xy 95.170825 -255.898834) (xy 95.155381 -255.946366)
			(xy 95.132691 -255.990898) (xy 95.103315 -256.031331) (xy 95.067975 -256.066671) (xy 95.027542 -256.096047)
			(xy 94.98301 -256.118737) (xy 94.935478 -256.134181) (xy 94.886115 -256.142) (xy 94.836137 -256.142)
			(xy 94.786774 -256.134181) (xy 94.739242 -256.118737) (xy 94.69471 -256.096047) (xy 94.654277 -256.066671)
			(xy 94.618937 -256.031331) (xy 94.589561 -255.990898) (xy 94.566871 -255.946366) (xy 94.551427 -255.898834)
			(xy 94.543608 -255.849471) (xy 94.236291 -255.849471) (xy 94.236282 -255.849928) (xy 94.228118 -255.900162)
			(xy 94.212002 -255.948436) (xy 94.188351 -255.993499) (xy 94.157778 -256.034185) (xy 94.121074 -256.06944)
			(xy 94.07919 -256.09835) (xy 94.033211 -256.120167) (xy 93.984327 -256.134327) (xy 93.933806 -256.140461)
			(xy 93.882954 -256.138412) (xy 93.83309 -256.128232) (xy 93.785504 -256.110185) (xy 93.74143 -256.084739)
			(xy 93.702008 -256.052552) (xy 93.66826 -256.014458) (xy 93.641059 -255.971444) (xy 93.621111 -255.924624)
			(xy 93.608932 -255.87521) (xy 93.604837 -255.824482) (xy 93.299026 -255.824482) (xy 93.298536 -255.849471)
			(xy 93.290717 -255.898834) (xy 93.275273 -255.946366) (xy 93.252583 -255.990898) (xy 93.223207 -256.031331)
			(xy 93.187867 -256.066671) (xy 93.147434 -256.096047) (xy 93.102902 -256.118737) (xy 93.05537 -256.134181)
			(xy 93.006007 -256.142) (xy 92.956029 -256.142) (xy 92.906666 -256.134181) (xy 92.859134 -256.118737)
			(xy 92.814602 -256.096047) (xy 92.774169 -256.066671) (xy 92.738829 -256.031331) (xy 92.709453 -255.990898)
			(xy 92.686763 -255.946366) (xy 92.671319 -255.898834) (xy 92.6635 -255.849471) (xy 92.356183 -255.849471)
			(xy 92.356174 -255.849928) (xy 92.34801 -255.900162) (xy 92.331894 -255.948436) (xy 92.308243 -255.993499)
			(xy 92.27767 -256.034185) (xy 92.240966 -256.06944) (xy 92.199082 -256.09835) (xy 92.153103 -256.120167)
			(xy 92.104219 -256.134327) (xy 92.053698 -256.140461) (xy 92.002846 -256.138412) (xy 91.952982 -256.128232)
			(xy 91.905396 -256.110185) (xy 91.861322 -256.084739) (xy 91.8219 -256.052552) (xy 91.788152 -256.014458)
			(xy 91.760951 -255.971444) (xy 91.741003 -255.924624) (xy 91.728824 -255.87521) (xy 91.724729 -255.824482)
			(xy 91.416632 -255.824482) (xy 91.41612 -255.849928) (xy 91.407956 -255.900162) (xy 91.39184 -255.948436)
			(xy 91.368189 -255.993499) (xy 91.337616 -256.034185) (xy 91.300912 -256.06944) (xy 91.259028 -256.09835)
			(xy 91.213049 -256.120167) (xy 91.164165 -256.134327) (xy 91.113644 -256.140461) (xy 91.062792 -256.138412)
			(xy 91.012928 -256.128232) (xy 90.965342 -256.110185) (xy 90.921268 -256.084739) (xy 90.881846 -256.052552)
			(xy 90.848098 -256.014458) (xy 90.820897 -255.971444) (xy 90.800949 -255.924624) (xy 90.78877 -255.87521)
			(xy 90.784675 -255.824482) (xy 90.479118 -255.824482) (xy 90.478628 -255.849471) (xy 90.470809 -255.898834)
			(xy 90.455365 -255.946366) (xy 90.432675 -255.990898) (xy 90.403299 -256.031331) (xy 90.367959 -256.066671)
			(xy 90.327526 -256.096047) (xy 90.282994 -256.118737) (xy 90.235462 -256.134181) (xy 90.186099 -256.142)
			(xy 90.136121 -256.142) (xy 90.086758 -256.134181) (xy 90.039226 -256.118737) (xy 89.994694 -256.096047)
			(xy 89.954261 -256.066671) (xy 89.918921 -256.031331) (xy 89.889545 -255.990898) (xy 89.866855 -255.946366)
			(xy 89.851411 -255.898834) (xy 89.843592 -255.849471) (xy 89.536275 -255.849471) (xy 89.536266 -255.849928)
			(xy 89.528102 -255.900162) (xy 89.511986 -255.948436) (xy 89.488335 -255.993499) (xy 89.457762 -256.034185)
			(xy 89.421058 -256.06944) (xy 89.379174 -256.09835) (xy 89.333195 -256.120167) (xy 89.284311 -256.134327)
			(xy 89.23379 -256.140461) (xy 89.182938 -256.138412) (xy 89.133074 -256.128232) (xy 89.085488 -256.110185)
			(xy 89.041414 -256.084739) (xy 89.001992 -256.052552) (xy 88.968244 -256.014458) (xy 88.941043 -255.971444)
			(xy 88.921095 -255.924624) (xy 88.908916 -255.87521) (xy 88.904821 -255.824482) (xy 88.59901 -255.824482)
			(xy 88.59852 -255.849471) (xy 88.590701 -255.898834) (xy 88.575257 -255.946366) (xy 88.552567 -255.990898)
			(xy 88.523191 -256.031331) (xy 88.487851 -256.066671) (xy 88.447418 -256.096047) (xy 88.402886 -256.118737)
			(xy 88.355354 -256.134181) (xy 88.305991 -256.142) (xy 88.256013 -256.142) (xy 88.20665 -256.134181)
			(xy 88.159118 -256.118737) (xy 88.114586 -256.096047) (xy 88.074153 -256.066671) (xy 88.038813 -256.031331)
			(xy 88.009437 -255.990898) (xy 87.986747 -255.946366) (xy 87.971303 -255.898834) (xy 87.963484 -255.849471)
			(xy 87.656167 -255.849471) (xy 87.656158 -255.849928) (xy 87.647994 -255.900162) (xy 87.631878 -255.948436)
			(xy 87.608227 -255.993499) (xy 87.577654 -256.034185) (xy 87.54095 -256.06944) (xy 87.499066 -256.09835)
			(xy 87.453087 -256.120167) (xy 87.404203 -256.134327) (xy 87.353682 -256.140461) (xy 87.30283 -256.138412)
			(xy 87.252966 -256.128232) (xy 87.20538 -256.110185) (xy 87.161306 -256.084739) (xy 87.121884 -256.052552)
			(xy 87.088136 -256.014458) (xy 87.060935 -255.971444) (xy 87.040987 -255.924624) (xy 87.028808 -255.87521)
			(xy 87.024713 -255.824482) (xy 86.719156 -255.824482) (xy 86.718666 -255.849471) (xy 86.710847 -255.898834)
			(xy 86.695403 -255.946366) (xy 86.672713 -255.990898) (xy 86.643337 -256.031331) (xy 86.607997 -256.066671)
			(xy 86.567564 -256.096047) (xy 86.523032 -256.118737) (xy 86.4755 -256.134181) (xy 86.426137 -256.142)
			(xy 86.376159 -256.142) (xy 86.326796 -256.134181) (xy 86.279264 -256.118737) (xy 86.234732 -256.096047)
			(xy 86.194299 -256.066671) (xy 86.158959 -256.031331) (xy 86.129583 -255.990898) (xy 86.106893 -255.946366)
			(xy 86.091449 -255.898834) (xy 86.08363 -255.849471) (xy 85.776313 -255.849471) (xy 85.776304 -255.849928)
			(xy 85.76814 -255.900162) (xy 85.752024 -255.948436) (xy 85.728373 -255.993499) (xy 85.6978 -256.034185)
			(xy 85.661096 -256.06944) (xy 85.619212 -256.09835) (xy 85.573233 -256.120167) (xy 85.524349 -256.134327)
			(xy 85.473828 -256.140461) (xy 85.422976 -256.138412) (xy 85.373112 -256.128232) (xy 85.325526 -256.110185)
			(xy 85.281452 -256.084739) (xy 85.24203 -256.052552) (xy 85.208282 -256.014458) (xy 85.181081 -255.971444)
			(xy 85.161133 -255.924624) (xy 85.148954 -255.87521) (xy 85.144859 -255.824482) (xy 84.836762 -255.824482)
			(xy 84.83625 -255.849928) (xy 84.828086 -255.900162) (xy 84.81197 -255.948436) (xy 84.788319 -255.993499)
			(xy 84.757746 -256.034185) (xy 84.721042 -256.06944) (xy 84.679158 -256.09835) (xy 84.633179 -256.120167)
			(xy 84.584295 -256.134327) (xy 84.533774 -256.140461) (xy 84.482922 -256.138412) (xy 84.433058 -256.128232)
			(xy 84.385472 -256.110185) (xy 84.341398 -256.084739) (xy 84.301976 -256.052552) (xy 84.268228 -256.014458)
			(xy 84.241027 -255.971444) (xy 84.221079 -255.924624) (xy 84.2089 -255.87521) (xy 84.204805 -255.824482)
			(xy 83.898994 -255.824482) (xy 83.898504 -255.849471) (xy 83.890685 -255.898834) (xy 83.875241 -255.946366)
			(xy 83.852551 -255.990898) (xy 83.823175 -256.031331) (xy 83.787835 -256.066671) (xy 83.747402 -256.096047)
			(xy 83.70287 -256.118737) (xy 83.655338 -256.134181) (xy 83.605975 -256.142) (xy 83.555997 -256.142)
			(xy 83.506634 -256.134181) (xy 83.459102 -256.118737) (xy 83.41457 -256.096047) (xy 83.374137 -256.066671)
			(xy 83.338797 -256.031331) (xy 83.309421 -255.990898) (xy 83.286731 -255.946366) (xy 83.271287 -255.898834)
			(xy 83.263468 -255.849471) (xy 82.956151 -255.849471) (xy 82.956142 -255.849928) (xy 82.947978 -255.900162)
			(xy 82.931862 -255.948436) (xy 82.908211 -255.993499) (xy 82.877638 -256.034185) (xy 82.840934 -256.06944)
			(xy 82.79905 -256.09835) (xy 82.753071 -256.120167) (xy 82.704187 -256.134327) (xy 82.653666 -256.140461)
			(xy 82.602814 -256.138412) (xy 82.55295 -256.128232) (xy 82.505364 -256.110185) (xy 82.46129 -256.084739)
			(xy 82.421868 -256.052552) (xy 82.38812 -256.014458) (xy 82.360919 -255.971444) (xy 82.340971 -255.924624)
			(xy 82.328792 -255.87521) (xy 82.324697 -255.824482) (xy 82.01914 -255.824482) (xy 82.01865 -255.849471)
			(xy 82.010831 -255.898834) (xy 81.995387 -255.946366) (xy 81.972697 -255.990898) (xy 81.943321 -256.031331)
			(xy 81.907981 -256.066671) (xy 81.867548 -256.096047) (xy 81.823016 -256.118737) (xy 81.775484 -256.134181)
			(xy 81.726121 -256.142) (xy 81.676143 -256.142) (xy 81.62678 -256.134181) (xy 81.579248 -256.118737)
			(xy 81.534716 -256.096047) (xy 81.494283 -256.066671) (xy 81.458943 -256.031331) (xy 81.429567 -255.990898)
			(xy 81.406877 -255.946366) (xy 81.391433 -255.898834) (xy 81.383614 -255.849471) (xy 81.076297 -255.849471)
			(xy 81.076288 -255.849928) (xy 81.068124 -255.900162) (xy 81.052008 -255.948436) (xy 81.028357 -255.993499)
			(xy 80.997784 -256.034185) (xy 80.96108 -256.06944) (xy 80.919196 -256.09835) (xy 80.873217 -256.120167)
			(xy 80.824333 -256.134327) (xy 80.773812 -256.140461) (xy 80.72296 -256.138412) (xy 80.673096 -256.128232)
			(xy 80.62551 -256.110185) (xy 80.581436 -256.084739) (xy 80.542014 -256.052552) (xy 80.508266 -256.014458)
			(xy 80.481065 -255.971444) (xy 80.461117 -255.924624) (xy 80.448938 -255.87521) (xy 80.444843 -255.824482)
			(xy 80.138789 -255.824482) (xy 80.138789 -255.849509) (xy 80.130965 -255.898912) (xy 80.115509 -255.946483)
			(xy 80.092802 -255.991051) (xy 80.063403 -256.031518) (xy 80.028036 -256.066888) (xy 79.987571 -256.09629)
			(xy 79.943005 -256.119) (xy 79.895436 -256.13446) (xy 79.846033 -256.142288) (xy 79.821024 -256.142744)
			(xy 79.796529 -256.142296) (xy 79.748117 -256.134797) (xy 79.701425 -256.119973) (xy 79.679292 -256.10947)
			(xy 79.665838 -256.103348) (xy 79.636723 -256.098329) (xy 79.607389 -256.101848) (xy 79.580286 -256.11361)
			(xy 79.557681 -256.132633) (xy 79.541461 -256.157328) (xy 79.532983 -256.18563) (xy 79.53248 -256.200402)
			(xy 79.53248 -256.659477) (xy 79.97366 -256.659477) (xy 79.97366 -256.609499) (xy 79.981479 -256.560136)
			(xy 79.996923 -256.512604) (xy 80.019613 -256.468072) (xy 80.048989 -256.427639) (xy 80.084329 -256.392299)
			(xy 80.124762 -256.362923) (xy 80.169294 -256.340233) (xy 80.216826 -256.324789) (xy 80.266189 -256.31697)
			(xy 80.316167 -256.31697) (xy 80.36553 -256.324789) (xy 80.413062 -256.340233) (xy 80.457594 -256.362923)
			(xy 80.498027 -256.392299) (xy 80.533367 -256.427639) (xy 80.562743 -256.468072) (xy 80.585433 -256.512604)
			(xy 80.600877 -256.560136) (xy 80.608696 -256.609499) (xy 80.609186 -256.634488) (xy 80.914743 -256.634488)
			(xy 80.918838 -256.58376) (xy 80.931017 -256.534346) (xy 80.950965 -256.487526) (xy 80.978166 -256.444512)
			(xy 81.011914 -256.406418) (xy 81.051336 -256.374231) (xy 81.09541 -256.348785) (xy 81.142996 -256.330738)
			(xy 81.19286 -256.320558) (xy 81.243712 -256.318509) (xy 81.294233 -256.324643) (xy 81.343117 -256.338803)
			(xy 81.389096 -256.36062) (xy 81.43098 -256.38953) (xy 81.467684 -256.424785) (xy 81.498257 -256.465471)
			(xy 81.521908 -256.510534) (xy 81.538024 -256.558808) (xy 81.546188 -256.609042) (xy 81.5467 -256.634488)
			(xy 81.546197 -256.659477) (xy 81.853514 -256.659477) (xy 81.853514 -256.609499) (xy 81.861333 -256.560136)
			(xy 81.876777 -256.512604) (xy 81.899467 -256.468072) (xy 81.928843 -256.427639) (xy 81.964183 -256.392299)
			(xy 82.004616 -256.362923) (xy 82.049148 -256.340233) (xy 82.09668 -256.324789) (xy 82.146043 -256.31697)
			(xy 82.196021 -256.31697) (xy 82.245384 -256.324789) (xy 82.292916 -256.340233) (xy 82.337448 -256.362923)
			(xy 82.377881 -256.392299) (xy 82.413221 -256.427639) (xy 82.442597 -256.468072) (xy 82.465287 -256.512604)
			(xy 82.480731 -256.560136) (xy 82.48855 -256.609499) (xy 82.48904 -256.634488) (xy 82.48855 -256.659477)
			(xy 82.793568 -256.659477) (xy 82.793568 -256.609499) (xy 82.801387 -256.560136) (xy 82.816831 -256.512604)
			(xy 82.839521 -256.468072) (xy 82.868897 -256.427639) (xy 82.904237 -256.392299) (xy 82.94467 -256.362923)
			(xy 82.989202 -256.340233) (xy 83.036734 -256.324789) (xy 83.086097 -256.31697) (xy 83.136075 -256.31697)
			(xy 83.185438 -256.324789) (xy 83.23297 -256.340233) (xy 83.277502 -256.362923) (xy 83.317935 -256.392299)
			(xy 83.353275 -256.427639) (xy 83.382651 -256.468072) (xy 83.405341 -256.512604) (xy 83.420785 -256.560136)
			(xy 83.428604 -256.609499) (xy 83.429094 -256.634488) (xy 83.734905 -256.634488) (xy 83.739 -256.58376)
			(xy 83.751179 -256.534346) (xy 83.771127 -256.487526) (xy 83.798328 -256.444512) (xy 83.832076 -256.406418)
			(xy 83.871498 -256.374231) (xy 83.915572 -256.348785) (xy 83.963158 -256.330738) (xy 84.013022 -256.320558)
			(xy 84.063874 -256.318509) (xy 84.114395 -256.324643) (xy 84.163279 -256.338803) (xy 84.209258 -256.36062)
			(xy 84.251142 -256.38953) (xy 84.287846 -256.424785) (xy 84.318419 -256.465471) (xy 84.34207 -256.510534)
			(xy 84.358186 -256.558808) (xy 84.36635 -256.609042) (xy 84.366862 -256.634488) (xy 84.366359 -256.659477)
			(xy 84.673422 -256.659477) (xy 84.673422 -256.609499) (xy 84.681241 -256.560136) (xy 84.696685 -256.512604)
			(xy 84.719375 -256.468072) (xy 84.748751 -256.427639) (xy 84.784091 -256.392299) (xy 84.824524 -256.362923)
			(xy 84.869056 -256.340233) (xy 84.916588 -256.324789) (xy 84.965951 -256.31697) (xy 85.015929 -256.31697)
			(xy 85.065292 -256.324789) (xy 85.112824 -256.340233) (xy 85.157356 -256.362923) (xy 85.197789 -256.392299)
			(xy 85.233129 -256.427639) (xy 85.262505 -256.468072) (xy 85.285195 -256.512604) (xy 85.300639 -256.560136)
			(xy 85.308458 -256.609499) (xy 85.308948 -256.634488) (xy 85.308458 -256.659477) (xy 85.613476 -256.659477)
			(xy 85.613476 -256.609499) (xy 85.621295 -256.560136) (xy 85.636739 -256.512604) (xy 85.659429 -256.468072)
			(xy 85.688805 -256.427639) (xy 85.724145 -256.392299) (xy 85.764578 -256.362923) (xy 85.80911 -256.340233)
			(xy 85.856642 -256.324789) (xy 85.906005 -256.31697) (xy 85.955983 -256.31697) (xy 86.005346 -256.324789)
			(xy 86.052878 -256.340233) (xy 86.09741 -256.362923) (xy 86.137843 -256.392299) (xy 86.173183 -256.427639)
			(xy 86.202559 -256.468072) (xy 86.225249 -256.512604) (xy 86.240693 -256.560136) (xy 86.248512 -256.609499)
			(xy 86.249002 -256.634488) (xy 86.248512 -256.659477) (xy 86.55353 -256.659477) (xy 86.55353 -256.609499)
			(xy 86.561349 -256.560136) (xy 86.576793 -256.512604) (xy 86.599483 -256.468072) (xy 86.628859 -256.427639)
			(xy 86.664199 -256.392299) (xy 86.704632 -256.362923) (xy 86.749164 -256.340233) (xy 86.796696 -256.324789)
			(xy 86.846059 -256.31697) (xy 86.896037 -256.31697) (xy 86.9454 -256.324789) (xy 86.992932 -256.340233)
			(xy 87.037464 -256.362923) (xy 87.077897 -256.392299) (xy 87.113237 -256.427639) (xy 87.142613 -256.468072)
			(xy 87.165303 -256.512604) (xy 87.180747 -256.560136) (xy 87.188566 -256.609499) (xy 87.189056 -256.634488)
			(xy 87.494867 -256.634488) (xy 87.498962 -256.58376) (xy 87.511141 -256.534346) (xy 87.531089 -256.487526)
			(xy 87.55829 -256.444512) (xy 87.592038 -256.406418) (xy 87.63146 -256.374231) (xy 87.675534 -256.348785)
			(xy 87.72312 -256.330738) (xy 87.772984 -256.320558) (xy 87.823836 -256.318509) (xy 87.874357 -256.324643)
			(xy 87.923241 -256.338803) (xy 87.96922 -256.36062) (xy 88.011104 -256.38953) (xy 88.047808 -256.424785)
			(xy 88.078381 -256.465471) (xy 88.102032 -256.510534) (xy 88.118148 -256.558808) (xy 88.126312 -256.609042)
			(xy 88.126824 -256.634488) (xy 88.126321 -256.659477) (xy 88.433638 -256.659477) (xy 88.433638 -256.609499)
			(xy 88.441457 -256.560136) (xy 88.456901 -256.512604) (xy 88.479591 -256.468072) (xy 88.508967 -256.427639)
			(xy 88.544307 -256.392299) (xy 88.58474 -256.362923) (xy 88.629272 -256.340233) (xy 88.676804 -256.324789)
			(xy 88.726167 -256.31697) (xy 88.776145 -256.31697) (xy 88.825508 -256.324789) (xy 88.87304 -256.340233)
			(xy 88.917572 -256.362923) (xy 88.958005 -256.392299) (xy 88.993345 -256.427639) (xy 89.022721 -256.468072)
			(xy 89.045411 -256.512604) (xy 89.060855 -256.560136) (xy 89.068674 -256.609499) (xy 89.069164 -256.634488)
			(xy 89.068674 -256.659477) (xy 89.373438 -256.659477) (xy 89.373438 -256.609499) (xy 89.381257 -256.560136)
			(xy 89.396701 -256.512604) (xy 89.419391 -256.468072) (xy 89.448767 -256.427639) (xy 89.484107 -256.392299)
			(xy 89.52454 -256.362923) (xy 89.569072 -256.340233) (xy 89.616604 -256.324789) (xy 89.665967 -256.31697)
			(xy 89.715945 -256.31697) (xy 89.765308 -256.324789) (xy 89.81284 -256.340233) (xy 89.857372 -256.362923)
			(xy 89.897805 -256.392299) (xy 89.933145 -256.427639) (xy 89.962521 -256.468072) (xy 89.985211 -256.512604)
			(xy 90.000655 -256.560136) (xy 90.008474 -256.609499) (xy 90.008964 -256.634488) (xy 90.314775 -256.634488)
			(xy 90.31887 -256.58376) (xy 90.331049 -256.534346) (xy 90.350997 -256.487526) (xy 90.378198 -256.444512)
			(xy 90.411946 -256.406418) (xy 90.451368 -256.374231) (xy 90.495442 -256.348785) (xy 90.543028 -256.330738)
			(xy 90.592892 -256.320558) (xy 90.643744 -256.318509) (xy 90.694265 -256.324643) (xy 90.743149 -256.338803)
			(xy 90.789128 -256.36062) (xy 90.831012 -256.38953) (xy 90.867716 -256.424785) (xy 90.898289 -256.465471)
			(xy 90.92194 -256.510534) (xy 90.938056 -256.558808) (xy 90.94622 -256.609042) (xy 90.946732 -256.634488)
			(xy 90.946229 -256.659477) (xy 91.253546 -256.659477) (xy 91.253546 -256.609499) (xy 91.261365 -256.560136)
			(xy 91.276809 -256.512604) (xy 91.299499 -256.468072) (xy 91.328875 -256.427639) (xy 91.364215 -256.392299)
			(xy 91.404648 -256.362923) (xy 91.44918 -256.340233) (xy 91.496712 -256.324789) (xy 91.546075 -256.31697)
			(xy 91.596053 -256.31697) (xy 91.645416 -256.324789) (xy 91.692948 -256.340233) (xy 91.73748 -256.362923)
			(xy 91.777913 -256.392299) (xy 91.813253 -256.427639) (xy 91.842629 -256.468072) (xy 91.865319 -256.512604)
			(xy 91.880763 -256.560136) (xy 91.888582 -256.609499) (xy 91.889072 -256.634488) (xy 91.888582 -256.659477)
			(xy 92.1936 -256.659477) (xy 92.1936 -256.609499) (xy 92.201419 -256.560136) (xy 92.216863 -256.512604)
			(xy 92.239553 -256.468072) (xy 92.268929 -256.427639) (xy 92.304269 -256.392299) (xy 92.344702 -256.362923)
			(xy 92.389234 -256.340233) (xy 92.436766 -256.324789) (xy 92.486129 -256.31697) (xy 92.536107 -256.31697)
			(xy 92.58547 -256.324789) (xy 92.633002 -256.340233) (xy 92.677534 -256.362923) (xy 92.717967 -256.392299)
			(xy 92.753307 -256.427639) (xy 92.782683 -256.468072) (xy 92.805373 -256.512604) (xy 92.820817 -256.560136)
			(xy 92.828636 -256.609499) (xy 92.829126 -256.634488) (xy 92.828636 -256.659477) (xy 93.1334 -256.659477)
			(xy 93.1334 -256.609499) (xy 93.141219 -256.560136) (xy 93.156663 -256.512604) (xy 93.179353 -256.468072)
			(xy 93.208729 -256.427639) (xy 93.244069 -256.392299) (xy 93.284502 -256.362923) (xy 93.329034 -256.340233)
			(xy 93.376566 -256.324789) (xy 93.425929 -256.31697) (xy 93.475907 -256.31697) (xy 93.52527 -256.324789)
			(xy 93.572802 -256.340233) (xy 93.617334 -256.362923) (xy 93.657767 -256.392299) (xy 93.693107 -256.427639)
			(xy 93.722483 -256.468072) (xy 93.745173 -256.512604) (xy 93.760617 -256.560136) (xy 93.768436 -256.609499)
			(xy 93.768926 -256.634488) (xy 94.074737 -256.634488) (xy 94.078832 -256.58376) (xy 94.091011 -256.534346)
			(xy 94.110959 -256.487526) (xy 94.13816 -256.444512) (xy 94.171908 -256.406418) (xy 94.21133 -256.374231)
			(xy 94.255404 -256.348785) (xy 94.30299 -256.330738) (xy 94.352854 -256.320558) (xy 94.403706 -256.318509)
			(xy 94.454227 -256.324643) (xy 94.503111 -256.338803) (xy 94.54909 -256.36062) (xy 94.590974 -256.38953)
			(xy 94.627678 -256.424785) (xy 94.658251 -256.465471) (xy 94.681902 -256.510534) (xy 94.698018 -256.558808)
			(xy 94.706182 -256.609042) (xy 94.706694 -256.634488) (xy 94.706191 -256.659477) (xy 95.013508 -256.659477)
			(xy 95.013508 -256.609499) (xy 95.021327 -256.560136) (xy 95.036771 -256.512604) (xy 95.059461 -256.468072)
			(xy 95.088837 -256.427639) (xy 95.124177 -256.392299) (xy 95.16461 -256.362923) (xy 95.209142 -256.340233)
			(xy 95.256674 -256.324789) (xy 95.306037 -256.31697) (xy 95.356015 -256.31697) (xy 95.405378 -256.324789)
			(xy 95.45291 -256.340233) (xy 95.497442 -256.362923) (xy 95.537875 -256.392299) (xy 95.573215 -256.427639)
			(xy 95.602591 -256.468072) (xy 95.625281 -256.512604) (xy 95.640725 -256.560136) (xy 95.648544 -256.609499)
			(xy 95.649034 -256.634488) (xy 95.648544 -256.659477) (xy 95.640725 -256.70884) (xy 95.625281 -256.756372)
			(xy 95.602591 -256.800904) (xy 95.573215 -256.841337) (xy 95.537875 -256.876677) (xy 95.497442 -256.906053)
			(xy 95.45291 -256.928743) (xy 95.405378 -256.944187) (xy 95.356015 -256.952006) (xy 95.306037 -256.952006)
			(xy 95.256674 -256.944187) (xy 95.209142 -256.928743) (xy 95.16461 -256.906053) (xy 95.124177 -256.876677)
			(xy 95.088837 -256.841337) (xy 95.059461 -256.800904) (xy 95.036771 -256.756372) (xy 95.021327 -256.70884)
			(xy 95.013508 -256.659477) (xy 94.706191 -256.659477) (xy 94.706182 -256.659934) (xy 94.698018 -256.710168)
			(xy 94.681902 -256.758442) (xy 94.658251 -256.803505) (xy 94.627678 -256.844191) (xy 94.590974 -256.879446)
			(xy 94.54909 -256.908356) (xy 94.503111 -256.930173) (xy 94.454227 -256.944333) (xy 94.403706 -256.950467)
			(xy 94.352854 -256.948418) (xy 94.30299 -256.938238) (xy 94.255404 -256.920191) (xy 94.21133 -256.894745)
			(xy 94.171908 -256.862558) (xy 94.13816 -256.824464) (xy 94.110959 -256.78145) (xy 94.091011 -256.73463)
			(xy 94.078832 -256.685216) (xy 94.074737 -256.634488) (xy 93.768926 -256.634488) (xy 93.768436 -256.659477)
			(xy 93.760617 -256.70884) (xy 93.745173 -256.756372) (xy 93.722483 -256.800904) (xy 93.693107 -256.841337)
			(xy 93.657767 -256.876677) (xy 93.617334 -256.906053) (xy 93.572802 -256.928743) (xy 93.52527 -256.944187)
			(xy 93.475907 -256.952006) (xy 93.425929 -256.952006) (xy 93.376566 -256.944187) (xy 93.329034 -256.928743)
			(xy 93.284502 -256.906053) (xy 93.244069 -256.876677) (xy 93.208729 -256.841337) (xy 93.179353 -256.800904)
			(xy 93.156663 -256.756372) (xy 93.141219 -256.70884) (xy 93.1334 -256.659477) (xy 92.828636 -256.659477)
			(xy 92.820817 -256.70884) (xy 92.805373 -256.756372) (xy 92.782683 -256.800904) (xy 92.753307 -256.841337)
			(xy 92.717967 -256.876677) (xy 92.677534 -256.906053) (xy 92.633002 -256.928743) (xy 92.58547 -256.944187)
			(xy 92.536107 -256.952006) (xy 92.486129 -256.952006) (xy 92.436766 -256.944187) (xy 92.389234 -256.928743)
			(xy 92.344702 -256.906053) (xy 92.304269 -256.876677) (xy 92.268929 -256.841337) (xy 92.239553 -256.800904)
			(xy 92.216863 -256.756372) (xy 92.201419 -256.70884) (xy 92.1936 -256.659477) (xy 91.888582 -256.659477)
			(xy 91.880763 -256.70884) (xy 91.865319 -256.756372) (xy 91.842629 -256.800904) (xy 91.813253 -256.841337)
			(xy 91.777913 -256.876677) (xy 91.73748 -256.906053) (xy 91.692948 -256.928743) (xy 91.645416 -256.944187)
			(xy 91.596053 -256.952006) (xy 91.546075 -256.952006) (xy 91.496712 -256.944187) (xy 91.44918 -256.928743)
			(xy 91.404648 -256.906053) (xy 91.364215 -256.876677) (xy 91.328875 -256.841337) (xy 91.299499 -256.800904)
			(xy 91.276809 -256.756372) (xy 91.261365 -256.70884) (xy 91.253546 -256.659477) (xy 90.946229 -256.659477)
			(xy 90.94622 -256.659934) (xy 90.938056 -256.710168) (xy 90.92194 -256.758442) (xy 90.898289 -256.803505)
			(xy 90.867716 -256.844191) (xy 90.831012 -256.879446) (xy 90.789128 -256.908356) (xy 90.743149 -256.930173)
			(xy 90.694265 -256.944333) (xy 90.643744 -256.950467) (xy 90.592892 -256.948418) (xy 90.543028 -256.938238)
			(xy 90.495442 -256.920191) (xy 90.451368 -256.894745) (xy 90.411946 -256.862558) (xy 90.378198 -256.824464)
			(xy 90.350997 -256.78145) (xy 90.331049 -256.73463) (xy 90.31887 -256.685216) (xy 90.314775 -256.634488)
			(xy 90.008964 -256.634488) (xy 90.008474 -256.659477) (xy 90.000655 -256.70884) (xy 89.985211 -256.756372)
			(xy 89.962521 -256.800904) (xy 89.933145 -256.841337) (xy 89.897805 -256.876677) (xy 89.857372 -256.906053)
			(xy 89.81284 -256.928743) (xy 89.765308 -256.944187) (xy 89.715945 -256.952006) (xy 89.665967 -256.952006)
			(xy 89.616604 -256.944187) (xy 89.569072 -256.928743) (xy 89.52454 -256.906053) (xy 89.484107 -256.876677)
			(xy 89.448767 -256.841337) (xy 89.419391 -256.800904) (xy 89.396701 -256.756372) (xy 89.381257 -256.70884)
			(xy 89.373438 -256.659477) (xy 89.068674 -256.659477) (xy 89.060855 -256.70884) (xy 89.045411 -256.756372)
			(xy 89.022721 -256.800904) (xy 88.993345 -256.841337) (xy 88.958005 -256.876677) (xy 88.917572 -256.906053)
			(xy 88.87304 -256.928743) (xy 88.825508 -256.944187) (xy 88.776145 -256.952006) (xy 88.726167 -256.952006)
			(xy 88.676804 -256.944187) (xy 88.629272 -256.928743) (xy 88.58474 -256.906053) (xy 88.544307 -256.876677)
			(xy 88.508967 -256.841337) (xy 88.479591 -256.800904) (xy 88.456901 -256.756372) (xy 88.441457 -256.70884)
			(xy 88.433638 -256.659477) (xy 88.126321 -256.659477) (xy 88.126312 -256.659934) (xy 88.118148 -256.710168)
			(xy 88.102032 -256.758442) (xy 88.078381 -256.803505) (xy 88.047808 -256.844191) (xy 88.011104 -256.879446)
			(xy 87.96922 -256.908356) (xy 87.923241 -256.930173) (xy 87.874357 -256.944333) (xy 87.823836 -256.950467)
			(xy 87.772984 -256.948418) (xy 87.72312 -256.938238) (xy 87.675534 -256.920191) (xy 87.63146 -256.894745)
			(xy 87.592038 -256.862558) (xy 87.55829 -256.824464) (xy 87.531089 -256.78145) (xy 87.511141 -256.73463)
			(xy 87.498962 -256.685216) (xy 87.494867 -256.634488) (xy 87.189056 -256.634488) (xy 87.188566 -256.659477)
			(xy 87.180747 -256.70884) (xy 87.165303 -256.756372) (xy 87.142613 -256.800904) (xy 87.113237 -256.841337)
			(xy 87.077897 -256.876677) (xy 87.037464 -256.906053) (xy 86.992932 -256.928743) (xy 86.9454 -256.944187)
			(xy 86.896037 -256.952006) (xy 86.846059 -256.952006) (xy 86.796696 -256.944187) (xy 86.749164 -256.928743)
			(xy 86.704632 -256.906053) (xy 86.664199 -256.876677) (xy 86.628859 -256.841337) (xy 86.599483 -256.800904)
			(xy 86.576793 -256.756372) (xy 86.561349 -256.70884) (xy 86.55353 -256.659477) (xy 86.248512 -256.659477)
			(xy 86.240693 -256.70884) (xy 86.225249 -256.756372) (xy 86.202559 -256.800904) (xy 86.173183 -256.841337)
			(xy 86.137843 -256.876677) (xy 86.09741 -256.906053) (xy 86.052878 -256.928743) (xy 86.005346 -256.944187)
			(xy 85.955983 -256.952006) (xy 85.906005 -256.952006) (xy 85.856642 -256.944187) (xy 85.80911 -256.928743)
			(xy 85.764578 -256.906053) (xy 85.724145 -256.876677) (xy 85.688805 -256.841337) (xy 85.659429 -256.800904)
			(xy 85.636739 -256.756372) (xy 85.621295 -256.70884) (xy 85.613476 -256.659477) (xy 85.308458 -256.659477)
			(xy 85.300639 -256.70884) (xy 85.285195 -256.756372) (xy 85.262505 -256.800904) (xy 85.233129 -256.841337)
			(xy 85.197789 -256.876677) (xy 85.157356 -256.906053) (xy 85.112824 -256.928743) (xy 85.065292 -256.944187)
			(xy 85.015929 -256.952006) (xy 84.965951 -256.952006) (xy 84.916588 -256.944187) (xy 84.869056 -256.928743)
			(xy 84.824524 -256.906053) (xy 84.784091 -256.876677) (xy 84.748751 -256.841337) (xy 84.719375 -256.800904)
			(xy 84.696685 -256.756372) (xy 84.681241 -256.70884) (xy 84.673422 -256.659477) (xy 84.366359 -256.659477)
			(xy 84.36635 -256.659934) (xy 84.358186 -256.710168) (xy 84.34207 -256.758442) (xy 84.318419 -256.803505)
			(xy 84.287846 -256.844191) (xy 84.251142 -256.879446) (xy 84.209258 -256.908356) (xy 84.163279 -256.930173)
			(xy 84.114395 -256.944333) (xy 84.063874 -256.950467) (xy 84.013022 -256.948418) (xy 83.963158 -256.938238)
			(xy 83.915572 -256.920191) (xy 83.871498 -256.894745) (xy 83.832076 -256.862558) (xy 83.798328 -256.824464)
			(xy 83.771127 -256.78145) (xy 83.751179 -256.73463) (xy 83.739 -256.685216) (xy 83.734905 -256.634488)
			(xy 83.429094 -256.634488) (xy 83.428604 -256.659477) (xy 83.420785 -256.70884) (xy 83.405341 -256.756372)
			(xy 83.382651 -256.800904) (xy 83.353275 -256.841337) (xy 83.317935 -256.876677) (xy 83.277502 -256.906053)
			(xy 83.23297 -256.928743) (xy 83.185438 -256.944187) (xy 83.136075 -256.952006) (xy 83.086097 -256.952006)
			(xy 83.036734 -256.944187) (xy 82.989202 -256.928743) (xy 82.94467 -256.906053) (xy 82.904237 -256.876677)
			(xy 82.868897 -256.841337) (xy 82.839521 -256.800904) (xy 82.816831 -256.756372) (xy 82.801387 -256.70884)
			(xy 82.793568 -256.659477) (xy 82.48855 -256.659477) (xy 82.480731 -256.70884) (xy 82.465287 -256.756372)
			(xy 82.442597 -256.800904) (xy 82.413221 -256.841337) (xy 82.377881 -256.876677) (xy 82.337448 -256.906053)
			(xy 82.292916 -256.928743) (xy 82.245384 -256.944187) (xy 82.196021 -256.952006) (xy 82.146043 -256.952006)
			(xy 82.09668 -256.944187) (xy 82.049148 -256.928743) (xy 82.004616 -256.906053) (xy 81.964183 -256.876677)
			(xy 81.928843 -256.841337) (xy 81.899467 -256.800904) (xy 81.876777 -256.756372) (xy 81.861333 -256.70884)
			(xy 81.853514 -256.659477) (xy 81.546197 -256.659477) (xy 81.546188 -256.659934) (xy 81.538024 -256.710168)
			(xy 81.521908 -256.758442) (xy 81.498257 -256.803505) (xy 81.467684 -256.844191) (xy 81.43098 -256.879446)
			(xy 81.389096 -256.908356) (xy 81.343117 -256.930173) (xy 81.294233 -256.944333) (xy 81.243712 -256.950467)
			(xy 81.19286 -256.948418) (xy 81.142996 -256.938238) (xy 81.09541 -256.920191) (xy 81.051336 -256.894745)
			(xy 81.011914 -256.862558) (xy 80.978166 -256.824464) (xy 80.950965 -256.78145) (xy 80.931017 -256.73463)
			(xy 80.918838 -256.685216) (xy 80.914743 -256.634488) (xy 80.609186 -256.634488) (xy 80.608696 -256.659477)
			(xy 80.600877 -256.70884) (xy 80.585433 -256.756372) (xy 80.562743 -256.800904) (xy 80.533367 -256.841337)
			(xy 80.498027 -256.876677) (xy 80.457594 -256.906053) (xy 80.413062 -256.928743) (xy 80.36553 -256.944187)
			(xy 80.316167 -256.952006) (xy 80.266189 -256.952006) (xy 80.216826 -256.944187) (xy 80.169294 -256.928743)
			(xy 80.124762 -256.906053) (xy 80.084329 -256.876677) (xy 80.048989 -256.841337) (xy 80.019613 -256.800904)
			(xy 79.996923 -256.756372) (xy 79.981479 -256.70884) (xy 79.97366 -256.659477) (xy 79.53248 -256.659477)
			(xy 79.53248 -258.184396) (xy 98.589084 -258.184396) (xy 98.589084 -257.676396) (xy 98.589585 -257.66639)
			(xy 98.597242 -257.647901) (xy 98.611391 -257.633749) (xy 98.629878 -257.626087) (xy 98.639884 -257.625596)
			(xy 98.85426 -257.625596) (xy 98.85426 -257.616452) (xy 98.854748 -257.606446) (xy 98.862416 -257.587961)
			(xy 98.876568 -257.573811) (xy 98.895054 -257.566146) (xy 98.90506 -257.565652) (xy 99.109022 -257.565652)
			(xy 99.129091 -257.566144) (xy 99.168519 -257.573657) (xy 99.205845 -257.588413) (xy 99.239752 -257.609892)
			(xy 99.269042 -257.637334) (xy 99.281234 -257.653282) (xy 99.288854 -257.661664) (xy 99.309391 -257.680247)
			(xy 99.345034 -257.722639) (xy 99.373687 -257.770035) (xy 99.394662 -257.821293) (xy 99.407452 -257.87518)
			(xy 99.41175 -257.930397) (xy 99.407453 -257.985614) (xy 99.394663 -258.039501) (xy 99.373689 -258.090761)
			(xy 99.345037 -258.138157) (xy 99.309395 -258.180549) (xy 99.288854 -258.199128) (xy 99.281234 -258.20751)
			(xy 99.269023 -258.223439) (xy 99.239721 -258.250862) (xy 99.205818 -258.272335) (xy 99.168503 -258.287106)
			(xy 99.129087 -258.294653) (xy 99.109022 -258.29514) (xy 98.85426 -258.29514) (xy 98.85426 -258.285996)
			(xy 98.853883 -258.275969) (xy 98.846204 -258.257445) (xy 98.832018 -258.243271) (xy 98.813487 -258.235609)
			(xy 98.80346 -258.235196) (xy 98.639884 -258.235196) (xy 98.629875 -258.234725) (xy 98.611382 -258.22706)
			(xy 98.597229 -258.212901) (xy 98.589571 -258.194405) (xy 98.589084 -258.184396) (xy 79.53248 -258.184396)
			(xy 79.53248 -259.084064) (xy 98.589084 -259.084064) (xy 98.589084 -258.576572) (xy 98.589565 -258.566565)
			(xy 98.59723 -258.548075) (xy 98.611385 -258.533924) (xy 98.629876 -258.526262) (xy 98.639884 -258.525772)
			(xy 98.85426 -258.525772) (xy 98.85426 -258.516628) (xy 98.85481 -258.506627) (xy 98.862453 -258.488143)
			(xy 98.876586 -258.473991) (xy 98.89506 -258.466323) (xy 98.90506 -258.465828) (xy 99.109022 -258.465828)
			(xy 99.129078 -258.46629) (xy 99.168486 -258.47377) (xy 99.205802 -258.488481) (xy 99.239713 -258.509904)
			(xy 99.269025 -258.537286) (xy 99.281234 -258.553204) (xy 99.288854 -258.561586) (xy 99.309413 -258.580146)
			(xy 99.345055 -258.622541) (xy 99.373708 -258.66994) (xy 99.394682 -258.721202) (xy 99.407471 -258.775092)
			(xy 99.411767 -258.830312) (xy 99.407467 -258.885531) (xy 99.394675 -258.93942) (xy 99.373698 -258.990681)
			(xy 99.345042 -259.038078) (xy 99.309397 -259.080471) (xy 99.288854 -259.09905) (xy 99.281234 -259.107432)
			(xy 99.269012 -259.123339) (xy 99.2397 -259.150716) (xy 99.205791 -259.17214) (xy 99.16848 -259.186857)
			(xy 99.129077 -259.194349) (xy 99.109022 -259.194808) (xy 98.85426 -259.194808) (xy 98.85426 -259.185664)
			(xy 98.853909 -259.175635) (xy 98.84622 -259.15711) (xy 98.832026 -259.142937) (xy 98.813489 -259.135276)
			(xy 98.80346 -259.134864) (xy 98.639884 -259.134864) (xy 98.629857 -259.134493) (xy 98.611333 -259.126811)
			(xy 98.59716 -259.112623) (xy 98.589497 -259.094091) (xy 98.589084 -259.084064) (xy 79.53248 -259.084064)
			(xy 79.53248 -259.98424) (xy 98.589084 -259.98424) (xy 98.589084 -259.47624) (xy 98.589552 -259.466223)
			(xy 98.597206 -259.44771) (xy 98.611363 -259.433537) (xy 98.629868 -259.425863) (xy 98.639884 -259.42544)
			(xy 98.85426 -259.42544) (xy 98.85426 -259.416296) (xy 98.854784 -259.406293) (xy 98.862437 -259.387809)
			(xy 98.876579 -259.373658) (xy 98.895057 -259.365991) (xy 98.90506 -259.365496) (xy 99.109022 -259.365496)
			(xy 99.129092 -259.36597) (xy 99.168522 -259.373485) (xy 99.205849 -259.388244) (xy 99.239756 -259.409728)
			(xy 99.269044 -259.437176) (xy 99.281234 -259.453126) (xy 99.288854 -259.461508) (xy 99.309435 -259.480045)
			(xy 99.345077 -259.522443) (xy 99.37373 -259.569846) (xy 99.394702 -259.621111) (xy 99.407489 -259.675004)
			(xy 99.411784 -259.730226) (xy 99.407481 -259.785448) (xy 99.394686 -259.839339) (xy 99.373706 -259.890601)
			(xy 99.345047 -259.938) (xy 99.309398 -259.980393) (xy 99.288854 -259.998972) (xy 99.281234 -260.007354)
			(xy 99.269034 -260.023292) (xy 99.239729 -260.050712) (xy 99.205822 -260.072183) (xy 99.168505 -260.086951)
			(xy 99.129088 -260.094498) (xy 99.109022 -260.094984) (xy 98.85426 -260.094984) (xy 98.85426 -260.08584)
			(xy 98.853847 -260.075816) (xy 98.846182 -260.057293) (xy 98.832007 -260.043118) (xy 98.813484 -260.035453)
			(xy 98.80346 -260.03504) (xy 98.639884 -260.03504) (xy 98.62988 -260.034526) (xy 98.611396 -260.026869)
			(xy 98.597245 -260.012724) (xy 98.589578 -259.994244) (xy 98.589084 -259.98424) (xy 79.53248 -259.98424)
			(xy 79.53248 -260.70687) (xy 79.532953 -260.720513) (xy 79.540245 -260.746811) (xy 79.554235 -260.770241)
			(xy 79.573927 -260.789133) (xy 79.597917 -260.802141) (xy 79.624494 -260.808336) (xy 79.638144 -260.808216)
			(xy 79.651098 -260.807962) (xy 79.676107 -260.808427) (xy 79.72551 -260.816251) (xy 79.773081 -260.831708)
			(xy 79.817648 -260.854416) (xy 79.858114 -260.883816) (xy 79.893483 -260.919184) (xy 79.922883 -260.95965)
			(xy 79.945591 -261.004217) (xy 79.961048 -261.051788) (xy 79.968873 -261.101191) (xy 79.968873 -261.151209)
			(xy 79.968872 -261.151213) (xy 81.213434 -261.151213) (xy 81.213434 -261.101235) (xy 81.221253 -261.051872)
			(xy 81.236697 -261.00434) (xy 81.259387 -260.959808) (xy 81.288763 -260.919375) (xy 81.324103 -260.884035)
			(xy 81.364536 -260.854659) (xy 81.409068 -260.831969) (xy 81.4566 -260.816525) (xy 81.505963 -260.808706)
			(xy 81.555941 -260.808706) (xy 81.605304 -260.816525) (xy 81.652836 -260.831969) (xy 81.697368 -260.854659)
			(xy 81.737801 -260.884035) (xy 81.773141 -260.919375) (xy 81.802517 -260.959808) (xy 81.825207 -261.00434)
			(xy 81.840651 -261.051872) (xy 81.84847 -261.101235) (xy 81.84896 -261.126224) (xy 81.84847 -261.151213)
			(xy 82.153488 -261.151213) (xy 82.153488 -261.101235) (xy 82.161307 -261.051872) (xy 82.176751 -261.00434)
			(xy 82.199441 -260.959808) (xy 82.228817 -260.919375) (xy 82.264157 -260.884035) (xy 82.30459 -260.854659)
			(xy 82.349122 -260.831969) (xy 82.396654 -260.816525) (xy 82.446017 -260.808706) (xy 82.495995 -260.808706)
			(xy 82.545358 -260.816525) (xy 82.59289 -260.831969) (xy 82.637422 -260.854659) (xy 82.677855 -260.884035)
			(xy 82.713195 -260.919375) (xy 82.742571 -260.959808) (xy 82.765261 -261.00434) (xy 82.780705 -261.051872)
			(xy 82.788524 -261.101235) (xy 82.789014 -261.126224) (xy 82.788524 -261.151213) (xy 83.093542 -261.151213)
			(xy 83.093542 -261.101235) (xy 83.101361 -261.051872) (xy 83.116805 -261.00434) (xy 83.139495 -260.959808)
			(xy 83.168871 -260.919375) (xy 83.204211 -260.884035) (xy 83.244644 -260.854659) (xy 83.289176 -260.831969)
			(xy 83.336708 -260.816525) (xy 83.386071 -260.808706) (xy 83.436049 -260.808706) (xy 83.485412 -260.816525)
			(xy 83.532944 -260.831969) (xy 83.577476 -260.854659) (xy 83.617909 -260.884035) (xy 83.653249 -260.919375)
			(xy 83.682625 -260.959808) (xy 83.705315 -261.00434) (xy 83.720759 -261.051872) (xy 83.728578 -261.101235)
			(xy 83.729068 -261.126224) (xy 83.728578 -261.151213) (xy 84.033596 -261.151213) (xy 84.033596 -261.101235)
			(xy 84.041415 -261.051872) (xy 84.056859 -261.00434) (xy 84.079549 -260.959808) (xy 84.108925 -260.919375)
			(xy 84.144265 -260.884035) (xy 84.184698 -260.854659) (xy 84.22923 -260.831969) (xy 84.276762 -260.816525)
			(xy 84.326125 -260.808706) (xy 84.376103 -260.808706) (xy 84.425466 -260.816525) (xy 84.472998 -260.831969)
			(xy 84.51753 -260.854659) (xy 84.557963 -260.884035) (xy 84.593303 -260.919375) (xy 84.622679 -260.959808)
			(xy 84.645369 -261.00434) (xy 84.660813 -261.051872) (xy 84.668632 -261.101235) (xy 84.669122 -261.126224)
			(xy 84.668632 -261.151213) (xy 84.973396 -261.151213) (xy 84.973396 -261.101235) (xy 84.981215 -261.051872)
			(xy 84.996659 -261.00434) (xy 85.019349 -260.959808) (xy 85.048725 -260.919375) (xy 85.084065 -260.884035)
			(xy 85.124498 -260.854659) (xy 85.16903 -260.831969) (xy 85.216562 -260.816525) (xy 85.265925 -260.808706)
			(xy 85.315903 -260.808706) (xy 85.365266 -260.816525) (xy 85.412798 -260.831969) (xy 85.45733 -260.854659)
			(xy 85.497763 -260.884035) (xy 85.533103 -260.919375) (xy 85.562479 -260.959808) (xy 85.585169 -261.00434)
			(xy 85.600613 -261.051872) (xy 85.608432 -261.101235) (xy 85.608922 -261.126224) (xy 85.608432 -261.151213)
			(xy 85.91345 -261.151213) (xy 85.91345 -261.101235) (xy 85.921269 -261.051872) (xy 85.936713 -261.00434)
			(xy 85.959403 -260.959808) (xy 85.988779 -260.919375) (xy 86.024119 -260.884035) (xy 86.064552 -260.854659)
			(xy 86.109084 -260.831969) (xy 86.156616 -260.816525) (xy 86.205979 -260.808706) (xy 86.255957 -260.808706)
			(xy 86.30532 -260.816525) (xy 86.352852 -260.831969) (xy 86.397384 -260.854659) (xy 86.437817 -260.884035)
			(xy 86.473157 -260.919375) (xy 86.502533 -260.959808) (xy 86.525223 -261.00434) (xy 86.540667 -261.051872)
			(xy 86.548486 -261.101235) (xy 86.548976 -261.126224) (xy 86.548486 -261.151213) (xy 87.793558 -261.151213)
			(xy 87.793558 -261.101235) (xy 87.801377 -261.051872) (xy 87.816821 -261.00434) (xy 87.839511 -260.959808)
			(xy 87.868887 -260.919375) (xy 87.904227 -260.884035) (xy 87.94466 -260.854659) (xy 87.989192 -260.831969)
			(xy 88.036724 -260.816525) (xy 88.086087 -260.808706) (xy 88.136065 -260.808706) (xy 88.185428 -260.816525)
			(xy 88.23296 -260.831969) (xy 88.277492 -260.854659) (xy 88.317925 -260.884035) (xy 88.353265 -260.919375)
			(xy 88.382641 -260.959808) (xy 88.405331 -261.00434) (xy 88.420775 -261.051872) (xy 88.428594 -261.101235)
			(xy 88.429084 -261.126224) (xy 88.428594 -261.151213) (xy 88.733612 -261.151213) (xy 88.733612 -261.101235)
			(xy 88.741431 -261.051872) (xy 88.756875 -261.00434) (xy 88.779565 -260.959808) (xy 88.808941 -260.919375)
			(xy 88.844281 -260.884035) (xy 88.884714 -260.854659) (xy 88.929246 -260.831969) (xy 88.976778 -260.816525)
			(xy 89.026141 -260.808706) (xy 89.076119 -260.808706) (xy 89.125482 -260.816525) (xy 89.173014 -260.831969)
			(xy 89.217546 -260.854659) (xy 89.257979 -260.884035) (xy 89.293319 -260.919375) (xy 89.322695 -260.959808)
			(xy 89.345385 -261.00434) (xy 89.360829 -261.051872) (xy 89.368648 -261.101235) (xy 89.369138 -261.126224)
			(xy 89.368648 -261.151213) (xy 89.673412 -261.151213) (xy 89.673412 -261.101235) (xy 89.681231 -261.051872)
			(xy 89.696675 -261.00434) (xy 89.719365 -260.959808) (xy 89.748741 -260.919375) (xy 89.784081 -260.884035)
			(xy 89.824514 -260.854659) (xy 89.869046 -260.831969) (xy 89.916578 -260.816525) (xy 89.965941 -260.808706)
			(xy 90.015919 -260.808706) (xy 90.065282 -260.816525) (xy 90.112814 -260.831969) (xy 90.157346 -260.854659)
			(xy 90.197779 -260.884035) (xy 90.233119 -260.919375) (xy 90.262495 -260.959808) (xy 90.285185 -261.00434)
			(xy 90.300629 -261.051872) (xy 90.308448 -261.101235) (xy 90.308938 -261.126224) (xy 90.308448 -261.151213)
			(xy 90.613466 -261.151213) (xy 90.613466 -261.101235) (xy 90.621285 -261.051872) (xy 90.636729 -261.00434)
			(xy 90.659419 -260.959808) (xy 90.688795 -260.919375) (xy 90.724135 -260.884035) (xy 90.764568 -260.854659)
			(xy 90.8091 -260.831969) (xy 90.856632 -260.816525) (xy 90.905995 -260.808706) (xy 90.955973 -260.808706)
			(xy 91.005336 -260.816525) (xy 91.052868 -260.831969) (xy 91.0974 -260.854659) (xy 91.137833 -260.884035)
			(xy 91.173173 -260.919375) (xy 91.202549 -260.959808) (xy 91.225239 -261.00434) (xy 91.240683 -261.051872)
			(xy 91.248502 -261.101235) (xy 91.248992 -261.126224) (xy 91.248502 -261.151213) (xy 91.55352 -261.151213)
			(xy 91.55352 -261.101235) (xy 91.561339 -261.051872) (xy 91.576783 -261.00434) (xy 91.599473 -260.959808)
			(xy 91.628849 -260.919375) (xy 91.664189 -260.884035) (xy 91.704622 -260.854659) (xy 91.749154 -260.831969)
			(xy 91.796686 -260.816525) (xy 91.846049 -260.808706) (xy 91.896027 -260.808706) (xy 91.94539 -260.816525)
			(xy 91.992922 -260.831969) (xy 92.037454 -260.854659) (xy 92.077887 -260.884035) (xy 92.113227 -260.919375)
			(xy 92.142603 -260.959808) (xy 92.165293 -261.00434) (xy 92.180737 -261.051872) (xy 92.188556 -261.101235)
			(xy 92.189046 -261.126224) (xy 92.188556 -261.151213) (xy 92.493574 -261.151213) (xy 92.493574 -261.101235)
			(xy 92.501393 -261.051872) (xy 92.516837 -261.00434) (xy 92.539527 -260.959808) (xy 92.568903 -260.919375)
			(xy 92.604243 -260.884035) (xy 92.644676 -260.854659) (xy 92.689208 -260.831969) (xy 92.73674 -260.816525)
			(xy 92.786103 -260.808706) (xy 92.836081 -260.808706) (xy 92.885444 -260.816525) (xy 92.932976 -260.831969)
			(xy 92.977508 -260.854659) (xy 93.017941 -260.884035) (xy 93.053281 -260.919375) (xy 93.082657 -260.959808)
			(xy 93.105347 -261.00434) (xy 93.120791 -261.051872) (xy 93.12861 -261.101235) (xy 93.1291 -261.126224)
			(xy 93.12861 -261.151213) (xy 94.373428 -261.151213) (xy 94.373428 -261.101235) (xy 94.381247 -261.051872)
			(xy 94.396691 -261.00434) (xy 94.419381 -260.959808) (xy 94.448757 -260.919375) (xy 94.484097 -260.884035)
			(xy 94.52453 -260.854659) (xy 94.569062 -260.831969) (xy 94.616594 -260.816525) (xy 94.665957 -260.808706)
			(xy 94.715935 -260.808706) (xy 94.765298 -260.816525) (xy 94.81283 -260.831969) (xy 94.857362 -260.854659)
			(xy 94.897795 -260.884035) (xy 94.933135 -260.919375) (xy 94.962511 -260.959808) (xy 94.985201 -261.00434)
			(xy 95.000645 -261.051872) (xy 95.008464 -261.101235) (xy 95.008954 -261.126224) (xy 95.008464 -261.151213)
			(xy 95.313482 -261.151213) (xy 95.313482 -261.101235) (xy 95.321301 -261.051872) (xy 95.336745 -261.00434)
			(xy 95.359435 -260.959808) (xy 95.388811 -260.919375) (xy 95.424151 -260.884035) (xy 95.464584 -260.854659)
			(xy 95.509116 -260.831969) (xy 95.556648 -260.816525) (xy 95.606011 -260.808706) (xy 95.655989 -260.808706)
			(xy 95.705352 -260.816525) (xy 95.752884 -260.831969) (xy 95.797416 -260.854659) (xy 95.837849 -260.884035)
			(xy 95.873189 -260.919375) (xy 95.902565 -260.959808) (xy 95.925255 -261.00434) (xy 95.940699 -261.051872)
			(xy 95.948518 -261.101235) (xy 95.949008 -261.126224) (xy 95.948518 -261.151213) (xy 96.253536 -261.151213)
			(xy 96.253536 -261.101235) (xy 96.261355 -261.051872) (xy 96.276799 -261.00434) (xy 96.299489 -260.959808)
			(xy 96.328865 -260.919375) (xy 96.364205 -260.884035) (xy 96.404638 -260.854659) (xy 96.44917 -260.831969)
			(xy 96.496702 -260.816525) (xy 96.546065 -260.808706) (xy 96.596043 -260.808706) (xy 96.645406 -260.816525)
			(xy 96.692938 -260.831969) (xy 96.73747 -260.854659) (xy 96.777903 -260.884035) (xy 96.813243 -260.919375)
			(xy 96.842619 -260.959808) (xy 96.865309 -261.00434) (xy 96.880753 -261.051872) (xy 96.888572 -261.101235)
			(xy 96.889062 -261.126224) (xy 96.888572 -261.151213) (xy 98.133644 -261.151213) (xy 98.133644 -261.101235)
			(xy 98.141463 -261.051872) (xy 98.156907 -261.00434) (xy 98.179597 -260.959808) (xy 98.208973 -260.919375)
			(xy 98.244313 -260.884035) (xy 98.284746 -260.854659) (xy 98.329278 -260.831969) (xy 98.37681 -260.816525)
			(xy 98.426173 -260.808706) (xy 98.476151 -260.808706) (xy 98.525514 -260.816525) (xy 98.573046 -260.831969)
			(xy 98.617578 -260.854659) (xy 98.658011 -260.884035) (xy 98.693351 -260.919375) (xy 98.722727 -260.959808)
			(xy 98.745417 -261.00434) (xy 98.760861 -261.051872) (xy 98.76868 -261.101235) (xy 98.76917 -261.126224)
			(xy 98.76868 -261.151213) (xy 98.760861 -261.200576) (xy 98.745417 -261.248108) (xy 98.722727 -261.29264)
			(xy 98.693351 -261.333073) (xy 98.658011 -261.368413) (xy 98.617578 -261.397789) (xy 98.573046 -261.420479)
			(xy 98.525514 -261.435923) (xy 98.476151 -261.443742) (xy 98.426173 -261.443742) (xy 98.37681 -261.435923)
			(xy 98.329278 -261.420479) (xy 98.284746 -261.397789) (xy 98.244313 -261.368413) (xy 98.208973 -261.333073)
			(xy 98.179597 -261.29264) (xy 98.156907 -261.248108) (xy 98.141463 -261.200576) (xy 98.133644 -261.151213)
			(xy 96.888572 -261.151213) (xy 96.880753 -261.200576) (xy 96.865309 -261.248108) (xy 96.842619 -261.29264)
			(xy 96.813243 -261.333073) (xy 96.777903 -261.368413) (xy 96.73747 -261.397789) (xy 96.692938 -261.420479)
			(xy 96.645406 -261.435923) (xy 96.596043 -261.443742) (xy 96.546065 -261.443742) (xy 96.496702 -261.435923)
			(xy 96.44917 -261.420479) (xy 96.404638 -261.397789) (xy 96.364205 -261.368413) (xy 96.328865 -261.333073)
			(xy 96.299489 -261.29264) (xy 96.276799 -261.248108) (xy 96.261355 -261.200576) (xy 96.253536 -261.151213)
			(xy 95.948518 -261.151213) (xy 95.940699 -261.200576) (xy 95.925255 -261.248108) (xy 95.902565 -261.29264)
			(xy 95.873189 -261.333073) (xy 95.837849 -261.368413) (xy 95.797416 -261.397789) (xy 95.752884 -261.420479)
			(xy 95.705352 -261.435923) (xy 95.655989 -261.443742) (xy 95.606011 -261.443742) (xy 95.556648 -261.435923)
			(xy 95.509116 -261.420479) (xy 95.464584 -261.397789) (xy 95.424151 -261.368413) (xy 95.388811 -261.333073)
			(xy 95.359435 -261.29264) (xy 95.336745 -261.248108) (xy 95.321301 -261.200576) (xy 95.313482 -261.151213)
			(xy 95.008464 -261.151213) (xy 95.000645 -261.200576) (xy 94.985201 -261.248108) (xy 94.962511 -261.29264)
			(xy 94.933135 -261.333073) (xy 94.897795 -261.368413) (xy 94.857362 -261.397789) (xy 94.81283 -261.420479)
			(xy 94.765298 -261.435923) (xy 94.715935 -261.443742) (xy 94.665957 -261.443742) (xy 94.616594 -261.435923)
			(xy 94.569062 -261.420479) (xy 94.52453 -261.397789) (xy 94.484097 -261.368413) (xy 94.448757 -261.333073)
			(xy 94.419381 -261.29264) (xy 94.396691 -261.248108) (xy 94.381247 -261.200576) (xy 94.373428 -261.151213)
			(xy 93.12861 -261.151213) (xy 93.120791 -261.200576) (xy 93.105347 -261.248108) (xy 93.082657 -261.29264)
			(xy 93.053281 -261.333073) (xy 93.017941 -261.368413) (xy 92.977508 -261.397789) (xy 92.932976 -261.420479)
			(xy 92.885444 -261.435923) (xy 92.836081 -261.443742) (xy 92.786103 -261.443742) (xy 92.73674 -261.435923)
			(xy 92.689208 -261.420479) (xy 92.644676 -261.397789) (xy 92.604243 -261.368413) (xy 92.568903 -261.333073)
			(xy 92.539527 -261.29264) (xy 92.516837 -261.248108) (xy 92.501393 -261.200576) (xy 92.493574 -261.151213)
			(xy 92.188556 -261.151213) (xy 92.180737 -261.200576) (xy 92.165293 -261.248108) (xy 92.142603 -261.29264)
			(xy 92.113227 -261.333073) (xy 92.077887 -261.368413) (xy 92.037454 -261.397789) (xy 91.992922 -261.420479)
			(xy 91.94539 -261.435923) (xy 91.896027 -261.443742) (xy 91.846049 -261.443742) (xy 91.796686 -261.435923)
			(xy 91.749154 -261.420479) (xy 91.704622 -261.397789) (xy 91.664189 -261.368413) (xy 91.628849 -261.333073)
			(xy 91.599473 -261.29264) (xy 91.576783 -261.248108) (xy 91.561339 -261.200576) (xy 91.55352 -261.151213)
			(xy 91.248502 -261.151213) (xy 91.240683 -261.200576) (xy 91.225239 -261.248108) (xy 91.202549 -261.29264)
			(xy 91.173173 -261.333073) (xy 91.137833 -261.368413) (xy 91.0974 -261.397789) (xy 91.052868 -261.420479)
			(xy 91.005336 -261.435923) (xy 90.955973 -261.443742) (xy 90.905995 -261.443742) (xy 90.856632 -261.435923)
			(xy 90.8091 -261.420479) (xy 90.764568 -261.397789) (xy 90.724135 -261.368413) (xy 90.688795 -261.333073)
			(xy 90.659419 -261.29264) (xy 90.636729 -261.248108) (xy 90.621285 -261.200576) (xy 90.613466 -261.151213)
			(xy 90.308448 -261.151213) (xy 90.300629 -261.200576) (xy 90.285185 -261.248108) (xy 90.262495 -261.29264)
			(xy 90.233119 -261.333073) (xy 90.197779 -261.368413) (xy 90.157346 -261.397789) (xy 90.112814 -261.420479)
			(xy 90.065282 -261.435923) (xy 90.015919 -261.443742) (xy 89.965941 -261.443742) (xy 89.916578 -261.435923)
			(xy 89.869046 -261.420479) (xy 89.824514 -261.397789) (xy 89.784081 -261.368413) (xy 89.748741 -261.333073)
			(xy 89.719365 -261.29264) (xy 89.696675 -261.248108) (xy 89.681231 -261.200576) (xy 89.673412 -261.151213)
			(xy 89.368648 -261.151213) (xy 89.360829 -261.200576) (xy 89.345385 -261.248108) (xy 89.322695 -261.29264)
			(xy 89.293319 -261.333073) (xy 89.257979 -261.368413) (xy 89.217546 -261.397789) (xy 89.173014 -261.420479)
			(xy 89.125482 -261.435923) (xy 89.076119 -261.443742) (xy 89.026141 -261.443742) (xy 88.976778 -261.435923)
			(xy 88.929246 -261.420479) (xy 88.884714 -261.397789) (xy 88.844281 -261.368413) (xy 88.808941 -261.333073)
			(xy 88.779565 -261.29264) (xy 88.756875 -261.248108) (xy 88.741431 -261.200576) (xy 88.733612 -261.151213)
			(xy 88.428594 -261.151213) (xy 88.420775 -261.200576) (xy 88.405331 -261.248108) (xy 88.382641 -261.29264)
			(xy 88.353265 -261.333073) (xy 88.317925 -261.368413) (xy 88.277492 -261.397789) (xy 88.23296 -261.420479)
			(xy 88.185428 -261.435923) (xy 88.136065 -261.443742) (xy 88.086087 -261.443742) (xy 88.036724 -261.435923)
			(xy 87.989192 -261.420479) (xy 87.94466 -261.397789) (xy 87.904227 -261.368413) (xy 87.868887 -261.333073)
			(xy 87.839511 -261.29264) (xy 87.816821 -261.248108) (xy 87.801377 -261.200576) (xy 87.793558 -261.151213)
			(xy 86.548486 -261.151213) (xy 86.540667 -261.200576) (xy 86.525223 -261.248108) (xy 86.502533 -261.29264)
			(xy 86.473157 -261.333073) (xy 86.437817 -261.368413) (xy 86.397384 -261.397789) (xy 86.352852 -261.420479)
			(xy 86.30532 -261.435923) (xy 86.255957 -261.443742) (xy 86.205979 -261.443742) (xy 86.156616 -261.435923)
			(xy 86.109084 -261.420479) (xy 86.064552 -261.397789) (xy 86.024119 -261.368413) (xy 85.988779 -261.333073)
			(xy 85.959403 -261.29264) (xy 85.936713 -261.248108) (xy 85.921269 -261.200576) (xy 85.91345 -261.151213)
			(xy 85.608432 -261.151213) (xy 85.600613 -261.200576) (xy 85.585169 -261.248108) (xy 85.562479 -261.29264)
			(xy 85.533103 -261.333073) (xy 85.497763 -261.368413) (xy 85.45733 -261.397789) (xy 85.412798 -261.420479)
			(xy 85.365266 -261.435923) (xy 85.315903 -261.443742) (xy 85.265925 -261.443742) (xy 85.216562 -261.435923)
			(xy 85.16903 -261.420479) (xy 85.124498 -261.397789) (xy 85.084065 -261.368413) (xy 85.048725 -261.333073)
			(xy 85.019349 -261.29264) (xy 84.996659 -261.248108) (xy 84.981215 -261.200576) (xy 84.973396 -261.151213)
			(xy 84.668632 -261.151213) (xy 84.660813 -261.200576) (xy 84.645369 -261.248108) (xy 84.622679 -261.29264)
			(xy 84.593303 -261.333073) (xy 84.557963 -261.368413) (xy 84.51753 -261.397789) (xy 84.472998 -261.420479)
			(xy 84.425466 -261.435923) (xy 84.376103 -261.443742) (xy 84.326125 -261.443742) (xy 84.276762 -261.435923)
			(xy 84.22923 -261.420479) (xy 84.184698 -261.397789) (xy 84.144265 -261.368413) (xy 84.108925 -261.333073)
			(xy 84.079549 -261.29264) (xy 84.056859 -261.248108) (xy 84.041415 -261.200576) (xy 84.033596 -261.151213)
			(xy 83.728578 -261.151213) (xy 83.720759 -261.200576) (xy 83.705315 -261.248108) (xy 83.682625 -261.29264)
			(xy 83.653249 -261.333073) (xy 83.617909 -261.368413) (xy 83.577476 -261.397789) (xy 83.532944 -261.420479)
			(xy 83.485412 -261.435923) (xy 83.436049 -261.443742) (xy 83.386071 -261.443742) (xy 83.336708 -261.435923)
			(xy 83.289176 -261.420479) (xy 83.244644 -261.397789) (xy 83.204211 -261.368413) (xy 83.168871 -261.333073)
			(xy 83.139495 -261.29264) (xy 83.116805 -261.248108) (xy 83.101361 -261.200576) (xy 83.093542 -261.151213)
			(xy 82.788524 -261.151213) (xy 82.780705 -261.200576) (xy 82.765261 -261.248108) (xy 82.742571 -261.29264)
			(xy 82.713195 -261.333073) (xy 82.677855 -261.368413) (xy 82.637422 -261.397789) (xy 82.59289 -261.420479)
			(xy 82.545358 -261.435923) (xy 82.495995 -261.443742) (xy 82.446017 -261.443742) (xy 82.396654 -261.435923)
			(xy 82.349122 -261.420479) (xy 82.30459 -261.397789) (xy 82.264157 -261.368413) (xy 82.228817 -261.333073)
			(xy 82.199441 -261.29264) (xy 82.176751 -261.248108) (xy 82.161307 -261.200576) (xy 82.153488 -261.151213)
			(xy 81.84847 -261.151213) (xy 81.840651 -261.200576) (xy 81.825207 -261.248108) (xy 81.802517 -261.29264)
			(xy 81.773141 -261.333073) (xy 81.737801 -261.368413) (xy 81.697368 -261.397789) (xy 81.652836 -261.420479)
			(xy 81.605304 -261.435923) (xy 81.555941 -261.443742) (xy 81.505963 -261.443742) (xy 81.4566 -261.435923)
			(xy 81.409068 -261.420479) (xy 81.364536 -261.397789) (xy 81.324103 -261.368413) (xy 81.288763 -261.333073)
			(xy 81.259387 -261.29264) (xy 81.236697 -261.248108) (xy 81.221253 -261.200576) (xy 81.213434 -261.151213)
			(xy 79.968872 -261.151213) (xy 79.961048 -261.200612) (xy 79.945591 -261.248183) (xy 79.922883 -261.29275)
			(xy 79.893483 -261.333216) (xy 79.858114 -261.368584) (xy 79.817648 -261.397984) (xy 79.773081 -261.420692)
			(xy 79.72551 -261.436149) (xy 79.676107 -261.443973) (xy 79.651098 -261.444486) (xy 79.638144 -261.444232)
			(xy 79.624486 -261.444114) (xy 79.597887 -261.450275) (xy 79.573874 -261.463268) (xy 79.554167 -261.482164)
			(xy 79.540176 -261.50561) (xy 79.532904 -261.531927) (xy 79.53248 -261.545578) (xy 79.53248 -261.961219)
			(xy 79.80348 -261.961219) (xy 79.80348 -261.911241) (xy 79.811299 -261.861878) (xy 79.826743 -261.814346)
			(xy 79.849433 -261.769814) (xy 79.878809 -261.729381) (xy 79.914149 -261.694041) (xy 79.954582 -261.664665)
			(xy 79.999114 -261.641975) (xy 80.046646 -261.626531) (xy 80.096009 -261.618712) (xy 80.145987 -261.618712)
			(xy 80.19535 -261.626531) (xy 80.242882 -261.641975) (xy 80.287414 -261.664665) (xy 80.327847 -261.694041)
			(xy 80.363187 -261.729381) (xy 80.392563 -261.769814) (xy 80.415253 -261.814346) (xy 80.430697 -261.861878)
			(xy 80.438516 -261.911241) (xy 80.439006 -261.93623) (xy 80.438516 -261.961219) (xy 80.743534 -261.961219)
			(xy 80.743534 -261.911241) (xy 80.751353 -261.861878) (xy 80.766797 -261.814346) (xy 80.789487 -261.769814)
			(xy 80.818863 -261.729381) (xy 80.854203 -261.694041) (xy 80.894636 -261.664665) (xy 80.939168 -261.641975)
			(xy 80.9867 -261.626531) (xy 81.036063 -261.618712) (xy 81.086041 -261.618712) (xy 81.135404 -261.626531)
			(xy 81.182936 -261.641975) (xy 81.227468 -261.664665) (xy 81.267901 -261.694041) (xy 81.303241 -261.729381)
			(xy 81.332617 -261.769814) (xy 81.355307 -261.814346) (xy 81.370751 -261.861878) (xy 81.37857 -261.911241)
			(xy 81.37906 -261.93623) (xy 81.37857 -261.961219) (xy 81.683588 -261.961219) (xy 81.683588 -261.911241)
			(xy 81.691407 -261.861878) (xy 81.706851 -261.814346) (xy 81.729541 -261.769814) (xy 81.758917 -261.729381)
			(xy 81.794257 -261.694041) (xy 81.83469 -261.664665) (xy 81.879222 -261.641975) (xy 81.926754 -261.626531)
			(xy 81.976117 -261.618712) (xy 82.026095 -261.618712) (xy 82.075458 -261.626531) (xy 82.12299 -261.641975)
			(xy 82.167522 -261.664665) (xy 82.207955 -261.694041) (xy 82.243295 -261.729381) (xy 82.272671 -261.769814)
			(xy 82.295361 -261.814346) (xy 82.310805 -261.861878) (xy 82.318624 -261.911241) (xy 82.319114 -261.93623)
			(xy 82.624671 -261.93623) (xy 82.628766 -261.885502) (xy 82.640945 -261.836088) (xy 82.660893 -261.789268)
			(xy 82.688094 -261.746254) (xy 82.721842 -261.70816) (xy 82.761264 -261.675973) (xy 82.805338 -261.650527)
			(xy 82.852924 -261.63248) (xy 82.902788 -261.6223) (xy 82.95364 -261.620251) (xy 83.004161 -261.626385)
			(xy 83.053045 -261.640545) (xy 83.099024 -261.662362) (xy 83.140908 -261.691272) (xy 83.177612 -261.726527)
			(xy 83.208185 -261.767213) (xy 83.231836 -261.812276) (xy 83.247952 -261.86055) (xy 83.256116 -261.910784)
			(xy 83.256628 -261.93623) (xy 83.256125 -261.961219) (xy 83.563442 -261.961219) (xy 83.563442 -261.911241)
			(xy 83.571261 -261.861878) (xy 83.586705 -261.814346) (xy 83.609395 -261.769814) (xy 83.638771 -261.729381)
			(xy 83.674111 -261.694041) (xy 83.714544 -261.664665) (xy 83.759076 -261.641975) (xy 83.806608 -261.626531)
			(xy 83.855971 -261.618712) (xy 83.905949 -261.618712) (xy 83.955312 -261.626531) (xy 84.002844 -261.641975)
			(xy 84.047376 -261.664665) (xy 84.087809 -261.694041) (xy 84.123149 -261.729381) (xy 84.152525 -261.769814)
			(xy 84.175215 -261.814346) (xy 84.190659 -261.861878) (xy 84.198478 -261.911241) (xy 84.198968 -261.93623)
			(xy 84.198478 -261.961219) (xy 84.503496 -261.961219) (xy 84.503496 -261.911241) (xy 84.511315 -261.861878)
			(xy 84.526759 -261.814346) (xy 84.549449 -261.769814) (xy 84.578825 -261.729381) (xy 84.614165 -261.694041)
			(xy 84.654598 -261.664665) (xy 84.69913 -261.641975) (xy 84.746662 -261.626531) (xy 84.796025 -261.618712)
			(xy 84.846003 -261.618712) (xy 84.895366 -261.626531) (xy 84.942898 -261.641975) (xy 84.98743 -261.664665)
			(xy 85.027863 -261.694041) (xy 85.063203 -261.729381) (xy 85.092579 -261.769814) (xy 85.115269 -261.814346)
			(xy 85.130713 -261.861878) (xy 85.138532 -261.911241) (xy 85.139022 -261.93623) (xy 85.444833 -261.93623)
			(xy 85.448928 -261.885502) (xy 85.461107 -261.836088) (xy 85.481055 -261.789268) (xy 85.508256 -261.746254)
			(xy 85.542004 -261.70816) (xy 85.581426 -261.675973) (xy 85.6255 -261.650527) (xy 85.673086 -261.63248)
			(xy 85.72295 -261.6223) (xy 85.773802 -261.620251) (xy 85.824323 -261.626385) (xy 85.873207 -261.640545)
			(xy 85.919186 -261.662362) (xy 85.96107 -261.691272) (xy 85.997774 -261.726527) (xy 86.028347 -261.767213)
			(xy 86.051998 -261.812276) (xy 86.068114 -261.86055) (xy 86.076278 -261.910784) (xy 86.07679 -261.93623)
			(xy 86.076287 -261.961219) (xy 86.383604 -261.961219) (xy 86.383604 -261.911241) (xy 86.391423 -261.861878)
			(xy 86.406867 -261.814346) (xy 86.429557 -261.769814) (xy 86.458933 -261.729381) (xy 86.494273 -261.694041)
			(xy 86.534706 -261.664665) (xy 86.579238 -261.641975) (xy 86.62677 -261.626531) (xy 86.676133 -261.618712)
			(xy 86.726111 -261.618712) (xy 86.775474 -261.626531) (xy 86.823006 -261.641975) (xy 86.867538 -261.664665)
			(xy 86.907971 -261.694041) (xy 86.943311 -261.729381) (xy 86.972687 -261.769814) (xy 86.995377 -261.814346)
			(xy 87.010821 -261.861878) (xy 87.01864 -261.911241) (xy 87.01913 -261.93623) (xy 87.01864 -261.961219)
			(xy 87.323404 -261.961219) (xy 87.323404 -261.911241) (xy 87.331223 -261.861878) (xy 87.346667 -261.814346)
			(xy 87.369357 -261.769814) (xy 87.398733 -261.729381) (xy 87.434073 -261.694041) (xy 87.474506 -261.664665)
			(xy 87.519038 -261.641975) (xy 87.56657 -261.626531) (xy 87.615933 -261.618712) (xy 87.665911 -261.618712)
			(xy 87.715274 -261.626531) (xy 87.762806 -261.641975) (xy 87.807338 -261.664665) (xy 87.847771 -261.694041)
			(xy 87.883111 -261.729381) (xy 87.912487 -261.769814) (xy 87.935177 -261.814346) (xy 87.950621 -261.861878)
			(xy 87.95844 -261.911241) (xy 87.95893 -261.93623) (xy 87.95844 -261.961219) (xy 88.263458 -261.961219)
			(xy 88.263458 -261.911241) (xy 88.271277 -261.861878) (xy 88.286721 -261.814346) (xy 88.309411 -261.769814)
			(xy 88.338787 -261.729381) (xy 88.374127 -261.694041) (xy 88.41456 -261.664665) (xy 88.459092 -261.641975)
			(xy 88.506624 -261.626531) (xy 88.555987 -261.618712) (xy 88.605965 -261.618712) (xy 88.655328 -261.626531)
			(xy 88.70286 -261.641975) (xy 88.747392 -261.664665) (xy 88.787825 -261.694041) (xy 88.823165 -261.729381)
			(xy 88.852541 -261.769814) (xy 88.875231 -261.814346) (xy 88.890675 -261.861878) (xy 88.898494 -261.911241)
			(xy 88.898984 -261.93623) (xy 89.204795 -261.93623) (xy 89.20889 -261.885502) (xy 89.221069 -261.836088)
			(xy 89.241017 -261.789268) (xy 89.268218 -261.746254) (xy 89.301966 -261.70816) (xy 89.341388 -261.675973)
			(xy 89.385462 -261.650527) (xy 89.433048 -261.63248) (xy 89.482912 -261.6223) (xy 89.533764 -261.620251)
			(xy 89.584285 -261.626385) (xy 89.633169 -261.640545) (xy 89.679148 -261.662362) (xy 89.721032 -261.691272)
			(xy 89.757736 -261.726527) (xy 89.788309 -261.767213) (xy 89.81196 -261.812276) (xy 89.828076 -261.86055)
			(xy 89.83624 -261.910784) (xy 89.836752 -261.93623) (xy 89.836249 -261.961219) (xy 90.143566 -261.961219)
			(xy 90.143566 -261.911241) (xy 90.151385 -261.861878) (xy 90.166829 -261.814346) (xy 90.189519 -261.769814)
			(xy 90.218895 -261.729381) (xy 90.254235 -261.694041) (xy 90.294668 -261.664665) (xy 90.3392 -261.641975)
			(xy 90.386732 -261.626531) (xy 90.436095 -261.618712) (xy 90.486073 -261.618712) (xy 90.535436 -261.626531)
			(xy 90.582968 -261.641975) (xy 90.6275 -261.664665) (xy 90.667933 -261.694041) (xy 90.703273 -261.729381)
			(xy 90.732649 -261.769814) (xy 90.755339 -261.814346) (xy 90.770783 -261.861878) (xy 90.778602 -261.911241)
			(xy 90.779092 -261.93623) (xy 90.778602 -261.961219) (xy 91.08362 -261.961219) (xy 91.08362 -261.911241)
			(xy 91.091439 -261.861878) (xy 91.106883 -261.814346) (xy 91.129573 -261.769814) (xy 91.158949 -261.729381)
			(xy 91.194289 -261.694041) (xy 91.234722 -261.664665) (xy 91.279254 -261.641975) (xy 91.326786 -261.626531)
			(xy 91.376149 -261.618712) (xy 91.426127 -261.618712) (xy 91.47549 -261.626531) (xy 91.523022 -261.641975)
			(xy 91.567554 -261.664665) (xy 91.607987 -261.694041) (xy 91.643327 -261.729381) (xy 91.672703 -261.769814)
			(xy 91.695393 -261.814346) (xy 91.710837 -261.861878) (xy 91.718656 -261.911241) (xy 91.719146 -261.93623)
			(xy 92.024703 -261.93623) (xy 92.028798 -261.885502) (xy 92.040977 -261.836088) (xy 92.060925 -261.789268)
			(xy 92.088126 -261.746254) (xy 92.121874 -261.70816) (xy 92.161296 -261.675973) (xy 92.20537 -261.650527)
			(xy 92.252956 -261.63248) (xy 92.30282 -261.6223) (xy 92.353672 -261.620251) (xy 92.404193 -261.626385)
			(xy 92.453077 -261.640545) (xy 92.499056 -261.662362) (xy 92.54094 -261.691272) (xy 92.577644 -261.726527)
			(xy 92.608217 -261.767213) (xy 92.631868 -261.812276) (xy 92.647984 -261.86055) (xy 92.656148 -261.910784)
			(xy 92.65666 -261.93623) (xy 92.656157 -261.961219) (xy 92.963474 -261.961219) (xy 92.963474 -261.911241)
			(xy 92.971293 -261.861878) (xy 92.986737 -261.814346) (xy 93.009427 -261.769814) (xy 93.038803 -261.729381)
			(xy 93.074143 -261.694041) (xy 93.114576 -261.664665) (xy 93.159108 -261.641975) (xy 93.20664 -261.626531)
			(xy 93.256003 -261.618712) (xy 93.305981 -261.618712) (xy 93.355344 -261.626531) (xy 93.402876 -261.641975)
			(xy 93.447408 -261.664665) (xy 93.487841 -261.694041) (xy 93.523181 -261.729381) (xy 93.552557 -261.769814)
			(xy 93.575247 -261.814346) (xy 93.590691 -261.861878) (xy 93.59851 -261.911241) (xy 93.599 -261.93623)
			(xy 93.59851 -261.961219) (xy 93.903528 -261.961219) (xy 93.903528 -261.911241) (xy 93.911347 -261.861878)
			(xy 93.926791 -261.814346) (xy 93.949481 -261.769814) (xy 93.978857 -261.729381) (xy 94.014197 -261.694041)
			(xy 94.05463 -261.664665) (xy 94.099162 -261.641975) (xy 94.146694 -261.626531) (xy 94.196057 -261.618712)
			(xy 94.246035 -261.618712) (xy 94.295398 -261.626531) (xy 94.34293 -261.641975) (xy 94.387462 -261.664665)
			(xy 94.427895 -261.694041) (xy 94.463235 -261.729381) (xy 94.492611 -261.769814) (xy 94.515301 -261.814346)
			(xy 94.530745 -261.861878) (xy 94.538564 -261.911241) (xy 94.539054 -261.93623) (xy 94.538564 -261.961219)
			(xy 94.843582 -261.961219) (xy 94.843582 -261.911241) (xy 94.851401 -261.861878) (xy 94.866845 -261.814346)
			(xy 94.889535 -261.769814) (xy 94.918911 -261.729381) (xy 94.954251 -261.694041) (xy 94.994684 -261.664665)
			(xy 95.039216 -261.641975) (xy 95.086748 -261.626531) (xy 95.136111 -261.618712) (xy 95.186089 -261.618712)
			(xy 95.235452 -261.626531) (xy 95.282984 -261.641975) (xy 95.327516 -261.664665) (xy 95.367949 -261.694041)
			(xy 95.403289 -261.729381) (xy 95.432665 -261.769814) (xy 95.455355 -261.814346) (xy 95.470799 -261.861878)
			(xy 95.478618 -261.911241) (xy 95.479108 -261.93623) (xy 95.784919 -261.93623) (xy 95.789014 -261.885502)
			(xy 95.801193 -261.836088) (xy 95.821141 -261.789268) (xy 95.848342 -261.746254) (xy 95.88209 -261.70816)
			(xy 95.921512 -261.675973) (xy 95.965586 -261.650527) (xy 96.013172 -261.63248) (xy 96.063036 -261.6223)
			(xy 96.113888 -261.620251) (xy 96.164409 -261.626385) (xy 96.213293 -261.640545) (xy 96.259272 -261.662362)
			(xy 96.301156 -261.691272) (xy 96.33786 -261.726527) (xy 96.368433 -261.767213) (xy 96.392084 -261.812276)
			(xy 96.4082 -261.86055) (xy 96.416364 -261.910784) (xy 96.416876 -261.93623) (xy 97.663 -261.93623)
			(xy 97.663 -261.935976) (xy 97.663546 -261.908875) (xy 97.67271 -261.855454) (xy 97.690802 -261.804361)
			(xy 97.717298 -261.757078) (xy 97.75143 -261.714973) (xy 97.771458 -261.696708) (xy 97.774304 -261.694121)
			(xy 97.779278 -261.688255) (xy 97.781364 -261.685024) (xy 97.793154 -261.666566) (xy 97.823024 -261.634541)
			(xy 97.858793 -261.609275) (xy 97.89896 -261.591828) (xy 97.941839 -261.582931) (xy 97.963736 -261.582408)
			(xy 98.218752 -261.582408) (xy 98.218752 -261.591552) (xy 98.219326 -261.601551) (xy 98.226961 -261.620032)
			(xy 98.241087 -261.634185) (xy 98.259554 -261.641855) (xy 98.269552 -261.642352) (xy 98.43262 -261.642352)
			(xy 98.442623 -261.64287) (xy 98.461106 -261.650528) (xy 98.475257 -261.66467) (xy 98.482924 -261.683149)
			(xy 98.48342 -261.693152) (xy 98.48342 -262.097266) (xy 99.528376 -262.097266) (xy 99.528376 -262.096758)
			(xy 99.528376 -261.797546) (xy 99.528376 -261.797038) (xy 99.528677 -261.775986) (xy 99.536682 -261.734655)
			(xy 99.552624 -261.695692) (xy 99.575888 -261.660605) (xy 99.605573 -261.630753) (xy 99.640528 -261.607291)
			(xy 99.679401 -261.591129) (xy 99.720686 -261.582892) (xy 99.741736 -261.582408) (xy 99.996752 -261.582408)
			(xy 99.996752 -261.591552) (xy 99.997326 -261.601551) (xy 100.004961 -261.620032) (xy 100.019087 -261.634185)
			(xy 100.037554 -261.641855) (xy 100.047552 -261.642352) (xy 100.21062 -261.642352) (xy 100.220623 -261.64287)
			(xy 100.239106 -261.650528) (xy 100.253257 -261.66467) (xy 100.260924 -261.683149) (xy 100.26142 -261.693152)
			(xy 100.26142 -262.201152) (xy 100.260942 -262.211168) (xy 100.253291 -262.22968) (xy 100.239137 -262.243853)
			(xy 100.220635 -262.251528) (xy 100.21062 -262.251952) (xy 99.996752 -262.251952) (xy 99.996752 -262.261096)
			(xy 99.996376 -262.271123) (xy 99.988698 -262.289649) (xy 99.974512 -262.303823) (xy 99.955979 -262.311485)
			(xy 99.945952 -262.311896) (xy 99.741736 -262.311896) (xy 99.720693 -262.311343) (xy 99.679421 -262.303109)
			(xy 99.64056 -262.286952) (xy 99.605615 -262.263499) (xy 99.57594 -262.233656) (xy 99.552683 -262.19858)
			(xy 99.536744 -262.159629) (xy 99.528742 -262.118311) (xy 99.528376 -262.097266) (xy 98.48342 -262.097266)
			(xy 98.48342 -262.201152) (xy 98.482942 -262.211168) (xy 98.475291 -262.22968) (xy 98.461137 -262.243853)
			(xy 98.442635 -262.251528) (xy 98.43262 -262.251952) (xy 98.218752 -262.251952) (xy 98.218752 -262.261096)
			(xy 98.218376 -262.271123) (xy 98.210698 -262.289649) (xy 98.196512 -262.303823) (xy 98.177979 -262.311485)
			(xy 98.167952 -262.311896) (xy 97.963736 -262.311896) (xy 97.942407 -262.311378) (xy 97.900599 -262.302894)
			(xy 97.861309 -262.286277) (xy 97.826102 -262.262189) (xy 97.796379 -262.231589) (xy 97.773324 -262.195697)
			(xy 97.765108 -262.176006) (xy 97.763086 -262.171291) (xy 97.757455 -262.162718) (xy 97.753932 -262.158988)
			(xy 97.737001 -262.141018) (xy 97.708318 -262.100834) (xy 97.686178 -262.056706) (xy 97.67111 -262.009691)
			(xy 97.663474 -261.960915) (xy 97.663 -261.93623) (xy 96.416876 -261.93623) (xy 96.416364 -261.961676)
			(xy 96.4082 -262.01191) (xy 96.392084 -262.060184) (xy 96.368433 -262.105247) (xy 96.33786 -262.145933)
			(xy 96.301156 -262.181188) (xy 96.259272 -262.210098) (xy 96.213293 -262.231915) (xy 96.164409 -262.246075)
			(xy 96.113888 -262.252209) (xy 96.063036 -262.25016) (xy 96.013172 -262.23998) (xy 95.965586 -262.221933)
			(xy 95.921512 -262.196487) (xy 95.88209 -262.1643) (xy 95.848342 -262.126206) (xy 95.821141 -262.083192)
			(xy 95.801193 -262.036372) (xy 95.789014 -261.986958) (xy 95.784919 -261.93623) (xy 95.479108 -261.93623)
			(xy 95.478618 -261.961219) (xy 95.470799 -262.010582) (xy 95.455355 -262.058114) (xy 95.432665 -262.102646)
			(xy 95.403289 -262.143079) (xy 95.367949 -262.178419) (xy 95.327516 -262.207795) (xy 95.282984 -262.230485)
			(xy 95.235452 -262.245929) (xy 95.186089 -262.253748) (xy 95.136111 -262.253748) (xy 95.086748 -262.245929)
			(xy 95.039216 -262.230485) (xy 94.994684 -262.207795) (xy 94.954251 -262.178419) (xy 94.918911 -262.143079)
			(xy 94.889535 -262.102646) (xy 94.866845 -262.058114) (xy 94.851401 -262.010582) (xy 94.843582 -261.961219)
			(xy 94.538564 -261.961219) (xy 94.530745 -262.010582) (xy 94.515301 -262.058114) (xy 94.492611 -262.102646)
			(xy 94.463235 -262.143079) (xy 94.427895 -262.178419) (xy 94.387462 -262.207795) (xy 94.34293 -262.230485)
			(xy 94.295398 -262.245929) (xy 94.246035 -262.253748) (xy 94.196057 -262.253748) (xy 94.146694 -262.245929)
			(xy 94.099162 -262.230485) (xy 94.05463 -262.207795) (xy 94.014197 -262.178419) (xy 93.978857 -262.143079)
			(xy 93.949481 -262.102646) (xy 93.926791 -262.058114) (xy 93.911347 -262.010582) (xy 93.903528 -261.961219)
			(xy 93.59851 -261.961219) (xy 93.590691 -262.010582) (xy 93.575247 -262.058114) (xy 93.552557 -262.102646)
			(xy 93.523181 -262.143079) (xy 93.487841 -262.178419) (xy 93.447408 -262.207795) (xy 93.402876 -262.230485)
			(xy 93.355344 -262.245929) (xy 93.305981 -262.253748) (xy 93.256003 -262.253748) (xy 93.20664 -262.245929)
			(xy 93.159108 -262.230485) (xy 93.114576 -262.207795) (xy 93.074143 -262.178419) (xy 93.038803 -262.143079)
			(xy 93.009427 -262.102646) (xy 92.986737 -262.058114) (xy 92.971293 -262.010582) (xy 92.963474 -261.961219)
			(xy 92.656157 -261.961219) (xy 92.656148 -261.961676) (xy 92.647984 -262.01191) (xy 92.631868 -262.060184)
			(xy 92.608217 -262.105247) (xy 92.577644 -262.145933) (xy 92.54094 -262.181188) (xy 92.499056 -262.210098)
			(xy 92.453077 -262.231915) (xy 92.404193 -262.246075) (xy 92.353672 -262.252209) (xy 92.30282 -262.25016)
			(xy 92.252956 -262.23998) (xy 92.20537 -262.221933) (xy 92.161296 -262.196487) (xy 92.121874 -262.1643)
			(xy 92.088126 -262.126206) (xy 92.060925 -262.083192) (xy 92.040977 -262.036372) (xy 92.028798 -261.986958)
			(xy 92.024703 -261.93623) (xy 91.719146 -261.93623) (xy 91.718656 -261.961219) (xy 91.710837 -262.010582)
			(xy 91.695393 -262.058114) (xy 91.672703 -262.102646) (xy 91.643327 -262.143079) (xy 91.607987 -262.178419)
			(xy 91.567554 -262.207795) (xy 91.523022 -262.230485) (xy 91.47549 -262.245929) (xy 91.426127 -262.253748)
			(xy 91.376149 -262.253748) (xy 91.326786 -262.245929) (xy 91.279254 -262.230485) (xy 91.234722 -262.207795)
			(xy 91.194289 -262.178419) (xy 91.158949 -262.143079) (xy 91.129573 -262.102646) (xy 91.106883 -262.058114)
			(xy 91.091439 -262.010582) (xy 91.08362 -261.961219) (xy 90.778602 -261.961219) (xy 90.770783 -262.010582)
			(xy 90.755339 -262.058114) (xy 90.732649 -262.102646) (xy 90.703273 -262.143079) (xy 90.667933 -262.178419)
			(xy 90.6275 -262.207795) (xy 90.582968 -262.230485) (xy 90.535436 -262.245929) (xy 90.486073 -262.253748)
			(xy 90.436095 -262.253748) (xy 90.386732 -262.245929) (xy 90.3392 -262.230485) (xy 90.294668 -262.207795)
			(xy 90.254235 -262.178419) (xy 90.218895 -262.143079) (xy 90.189519 -262.102646) (xy 90.166829 -262.058114)
			(xy 90.151385 -262.010582) (xy 90.143566 -261.961219) (xy 89.836249 -261.961219) (xy 89.83624 -261.961676)
			(xy 89.828076 -262.01191) (xy 89.81196 -262.060184) (xy 89.788309 -262.105247) (xy 89.757736 -262.145933)
			(xy 89.721032 -262.181188) (xy 89.679148 -262.210098) (xy 89.633169 -262.231915) (xy 89.584285 -262.246075)
			(xy 89.533764 -262.252209) (xy 89.482912 -262.25016) (xy 89.433048 -262.23998) (xy 89.385462 -262.221933)
			(xy 89.341388 -262.196487) (xy 89.301966 -262.1643) (xy 89.268218 -262.126206) (xy 89.241017 -262.083192)
			(xy 89.221069 -262.036372) (xy 89.20889 -261.986958) (xy 89.204795 -261.93623) (xy 88.898984 -261.93623)
			(xy 88.898494 -261.961219) (xy 88.890675 -262.010582) (xy 88.875231 -262.058114) (xy 88.852541 -262.102646)
			(xy 88.823165 -262.143079) (xy 88.787825 -262.178419) (xy 88.747392 -262.207795) (xy 88.70286 -262.230485)
			(xy 88.655328 -262.245929) (xy 88.605965 -262.253748) (xy 88.555987 -262.253748) (xy 88.506624 -262.245929)
			(xy 88.459092 -262.230485) (xy 88.41456 -262.207795) (xy 88.374127 -262.178419) (xy 88.338787 -262.143079)
			(xy 88.309411 -262.102646) (xy 88.286721 -262.058114) (xy 88.271277 -262.010582) (xy 88.263458 -261.961219)
			(xy 87.95844 -261.961219) (xy 87.950621 -262.010582) (xy 87.935177 -262.058114) (xy 87.912487 -262.102646)
			(xy 87.883111 -262.143079) (xy 87.847771 -262.178419) (xy 87.807338 -262.207795) (xy 87.762806 -262.230485)
			(xy 87.715274 -262.245929) (xy 87.665911 -262.253748) (xy 87.615933 -262.253748) (xy 87.56657 -262.245929)
			(xy 87.519038 -262.230485) (xy 87.474506 -262.207795) (xy 87.434073 -262.178419) (xy 87.398733 -262.143079)
			(xy 87.369357 -262.102646) (xy 87.346667 -262.058114) (xy 87.331223 -262.010582) (xy 87.323404 -261.961219)
			(xy 87.01864 -261.961219) (xy 87.010821 -262.010582) (xy 86.995377 -262.058114) (xy 86.972687 -262.102646)
			(xy 86.943311 -262.143079) (xy 86.907971 -262.178419) (xy 86.867538 -262.207795) (xy 86.823006 -262.230485)
			(xy 86.775474 -262.245929) (xy 86.726111 -262.253748) (xy 86.676133 -262.253748) (xy 86.62677 -262.245929)
			(xy 86.579238 -262.230485) (xy 86.534706 -262.207795) (xy 86.494273 -262.178419) (xy 86.458933 -262.143079)
			(xy 86.429557 -262.102646) (xy 86.406867 -262.058114) (xy 86.391423 -262.010582) (xy 86.383604 -261.961219)
			(xy 86.076287 -261.961219) (xy 86.076278 -261.961676) (xy 86.068114 -262.01191) (xy 86.051998 -262.060184)
			(xy 86.028347 -262.105247) (xy 85.997774 -262.145933) (xy 85.96107 -262.181188) (xy 85.919186 -262.210098)
			(xy 85.873207 -262.231915) (xy 85.824323 -262.246075) (xy 85.773802 -262.252209) (xy 85.72295 -262.25016)
			(xy 85.673086 -262.23998) (xy 85.6255 -262.221933) (xy 85.581426 -262.196487) (xy 85.542004 -262.1643)
			(xy 85.508256 -262.126206) (xy 85.481055 -262.083192) (xy 85.461107 -262.036372) (xy 85.448928 -261.986958)
			(xy 85.444833 -261.93623) (xy 85.139022 -261.93623) (xy 85.138532 -261.961219) (xy 85.130713 -262.010582)
			(xy 85.115269 -262.058114) (xy 85.092579 -262.102646) (xy 85.063203 -262.143079) (xy 85.027863 -262.178419)
			(xy 84.98743 -262.207795) (xy 84.942898 -262.230485) (xy 84.895366 -262.245929) (xy 84.846003 -262.253748)
			(xy 84.796025 -262.253748) (xy 84.746662 -262.245929) (xy 84.69913 -262.230485) (xy 84.654598 -262.207795)
			(xy 84.614165 -262.178419) (xy 84.578825 -262.143079) (xy 84.549449 -262.102646) (xy 84.526759 -262.058114)
			(xy 84.511315 -262.010582) (xy 84.503496 -261.961219) (xy 84.198478 -261.961219) (xy 84.190659 -262.010582)
			(xy 84.175215 -262.058114) (xy 84.152525 -262.102646) (xy 84.123149 -262.143079) (xy 84.087809 -262.178419)
			(xy 84.047376 -262.207795) (xy 84.002844 -262.230485) (xy 83.955312 -262.245929) (xy 83.905949 -262.253748)
			(xy 83.855971 -262.253748) (xy 83.806608 -262.245929) (xy 83.759076 -262.230485) (xy 83.714544 -262.207795)
			(xy 83.674111 -262.178419) (xy 83.638771 -262.143079) (xy 83.609395 -262.102646) (xy 83.586705 -262.058114)
			(xy 83.571261 -262.010582) (xy 83.563442 -261.961219) (xy 83.256125 -261.961219) (xy 83.256116 -261.961676)
			(xy 83.247952 -262.01191) (xy 83.231836 -262.060184) (xy 83.208185 -262.105247) (xy 83.177612 -262.145933)
			(xy 83.140908 -262.181188) (xy 83.099024 -262.210098) (xy 83.053045 -262.231915) (xy 83.004161 -262.246075)
			(xy 82.95364 -262.252209) (xy 82.902788 -262.25016) (xy 82.852924 -262.23998) (xy 82.805338 -262.221933)
			(xy 82.761264 -262.196487) (xy 82.721842 -262.1643) (xy 82.688094 -262.126206) (xy 82.660893 -262.083192)
			(xy 82.640945 -262.036372) (xy 82.628766 -261.986958) (xy 82.624671 -261.93623) (xy 82.319114 -261.93623)
			(xy 82.318624 -261.961219) (xy 82.310805 -262.010582) (xy 82.295361 -262.058114) (xy 82.272671 -262.102646)
			(xy 82.243295 -262.143079) (xy 82.207955 -262.178419) (xy 82.167522 -262.207795) (xy 82.12299 -262.230485)
			(xy 82.075458 -262.245929) (xy 82.026095 -262.253748) (xy 81.976117 -262.253748) (xy 81.926754 -262.245929)
			(xy 81.879222 -262.230485) (xy 81.83469 -262.207795) (xy 81.794257 -262.178419) (xy 81.758917 -262.143079)
			(xy 81.729541 -262.102646) (xy 81.706851 -262.058114) (xy 81.691407 -262.010582) (xy 81.683588 -261.961219)
			(xy 81.37857 -261.961219) (xy 81.370751 -262.010582) (xy 81.355307 -262.058114) (xy 81.332617 -262.102646)
			(xy 81.303241 -262.143079) (xy 81.267901 -262.178419) (xy 81.227468 -262.207795) (xy 81.182936 -262.230485)
			(xy 81.135404 -262.245929) (xy 81.086041 -262.253748) (xy 81.036063 -262.253748) (xy 80.9867 -262.245929)
			(xy 80.939168 -262.230485) (xy 80.894636 -262.207795) (xy 80.854203 -262.178419) (xy 80.818863 -262.143079)
			(xy 80.789487 -262.102646) (xy 80.766797 -262.058114) (xy 80.751353 -262.010582) (xy 80.743534 -261.961219)
			(xy 80.438516 -261.961219) (xy 80.430697 -262.010582) (xy 80.415253 -262.058114) (xy 80.392563 -262.102646)
			(xy 80.363187 -262.143079) (xy 80.327847 -262.178419) (xy 80.287414 -262.207795) (xy 80.242882 -262.230485)
			(xy 80.19535 -262.245929) (xy 80.145987 -262.253748) (xy 80.096009 -262.253748) (xy 80.046646 -262.245929)
			(xy 79.999114 -262.230485) (xy 79.954582 -262.207795) (xy 79.914149 -262.178419) (xy 79.878809 -262.143079)
			(xy 79.849433 -262.102646) (xy 79.826743 -262.058114) (xy 79.811299 -262.010582) (xy 79.80348 -261.961219)
			(xy 79.53248 -261.961219) (xy 79.53248 -262.771225) (xy 80.273634 -262.771225) (xy 80.273634 -262.721247)
			(xy 80.281453 -262.671884) (xy 80.296897 -262.624352) (xy 80.319587 -262.57982) (xy 80.348963 -262.539387)
			(xy 80.384303 -262.504047) (xy 80.424736 -262.474671) (xy 80.469268 -262.451981) (xy 80.5168 -262.436537)
			(xy 80.566163 -262.428718) (xy 80.616141 -262.428718) (xy 80.665504 -262.436537) (xy 80.713036 -262.451981)
			(xy 80.757568 -262.474671) (xy 80.798001 -262.504047) (xy 80.833341 -262.539387) (xy 80.862717 -262.57982)
			(xy 80.885407 -262.624352) (xy 80.900851 -262.671884) (xy 80.90867 -262.721247) (xy 80.90916 -262.746236)
			(xy 81.214717 -262.746236) (xy 81.218812 -262.695508) (xy 81.230991 -262.646094) (xy 81.250939 -262.599274)
			(xy 81.27814 -262.55626) (xy 81.311888 -262.518166) (xy 81.35131 -262.485979) (xy 81.395384 -262.460533)
			(xy 81.44297 -262.442486) (xy 81.492834 -262.432306) (xy 81.543686 -262.430257) (xy 81.594207 -262.436391)
			(xy 81.643091 -262.450551) (xy 81.68907 -262.472368) (xy 81.730954 -262.501278) (xy 81.767658 -262.536533)
			(xy 81.798231 -262.577219) (xy 81.821882 -262.622282) (xy 81.837998 -262.670556) (xy 81.846162 -262.72079)
			(xy 81.846674 -262.746236) (xy 82.154771 -262.746236) (xy 82.158866 -262.695508) (xy 82.171045 -262.646094)
			(xy 82.190993 -262.599274) (xy 82.218194 -262.55626) (xy 82.251942 -262.518166) (xy 82.291364 -262.485979)
			(xy 82.335438 -262.460533) (xy 82.383024 -262.442486) (xy 82.432888 -262.432306) (xy 82.48374 -262.430257)
			(xy 82.534261 -262.436391) (xy 82.583145 -262.450551) (xy 82.629124 -262.472368) (xy 82.671008 -262.501278)
			(xy 82.707712 -262.536533) (xy 82.738285 -262.577219) (xy 82.761936 -262.622282) (xy 82.778052 -262.670556)
			(xy 82.786216 -262.72079) (xy 82.786728 -262.746236) (xy 82.786225 -262.771225) (xy 83.093542 -262.771225)
			(xy 83.093542 -262.721247) (xy 83.101361 -262.671884) (xy 83.116805 -262.624352) (xy 83.139495 -262.57982)
			(xy 83.168871 -262.539387) (xy 83.204211 -262.504047) (xy 83.244644 -262.474671) (xy 83.289176 -262.451981)
			(xy 83.336708 -262.436537) (xy 83.386071 -262.428718) (xy 83.436049 -262.428718) (xy 83.485412 -262.436537)
			(xy 83.532944 -262.451981) (xy 83.577476 -262.474671) (xy 83.617909 -262.504047) (xy 83.653249 -262.539387)
			(xy 83.682625 -262.57982) (xy 83.705315 -262.624352) (xy 83.720759 -262.671884) (xy 83.728578 -262.721247)
			(xy 83.729068 -262.746236) (xy 84.034879 -262.746236) (xy 84.038974 -262.695508) (xy 84.051153 -262.646094)
			(xy 84.071101 -262.599274) (xy 84.098302 -262.55626) (xy 84.13205 -262.518166) (xy 84.171472 -262.485979)
			(xy 84.215546 -262.460533) (xy 84.263132 -262.442486) (xy 84.312996 -262.432306) (xy 84.363848 -262.430257)
			(xy 84.414369 -262.436391) (xy 84.463253 -262.450551) (xy 84.509232 -262.472368) (xy 84.551116 -262.501278)
			(xy 84.58782 -262.536533) (xy 84.618393 -262.577219) (xy 84.642044 -262.622282) (xy 84.65816 -262.670556)
			(xy 84.666324 -262.72079) (xy 84.666836 -262.746236) (xy 84.666333 -262.771225) (xy 84.973396 -262.771225)
			(xy 84.973396 -262.721247) (xy 84.981215 -262.671884) (xy 84.996659 -262.624352) (xy 85.019349 -262.57982)
			(xy 85.048725 -262.539387) (xy 85.084065 -262.504047) (xy 85.124498 -262.474671) (xy 85.16903 -262.451981)
			(xy 85.216562 -262.436537) (xy 85.265925 -262.428718) (xy 85.315903 -262.428718) (xy 85.365266 -262.436537)
			(xy 85.412798 -262.451981) (xy 85.45733 -262.474671) (xy 85.497763 -262.504047) (xy 85.533103 -262.539387)
			(xy 85.562479 -262.57982) (xy 85.585169 -262.624352) (xy 85.600613 -262.671884) (xy 85.608432 -262.721247)
			(xy 85.608922 -262.746236) (xy 85.914733 -262.746236) (xy 85.918828 -262.695508) (xy 85.931007 -262.646094)
			(xy 85.950955 -262.599274) (xy 85.978156 -262.55626) (xy 86.011904 -262.518166) (xy 86.051326 -262.485979)
			(xy 86.0954 -262.460533) (xy 86.142986 -262.442486) (xy 86.19285 -262.432306) (xy 86.243702 -262.430257)
			(xy 86.294223 -262.436391) (xy 86.343107 -262.450551) (xy 86.389086 -262.472368) (xy 86.43097 -262.501278)
			(xy 86.467674 -262.536533) (xy 86.498247 -262.577219) (xy 86.521898 -262.622282) (xy 86.538014 -262.670556)
			(xy 86.546178 -262.72079) (xy 86.54669 -262.746236) (xy 86.546187 -262.771225) (xy 86.853504 -262.771225)
			(xy 86.853504 -262.721247) (xy 86.861323 -262.671884) (xy 86.876767 -262.624352) (xy 86.899457 -262.57982)
			(xy 86.928833 -262.539387) (xy 86.964173 -262.504047) (xy 87.004606 -262.474671) (xy 87.049138 -262.451981)
			(xy 87.09667 -262.436537) (xy 87.146033 -262.428718) (xy 87.196011 -262.428718) (xy 87.245374 -262.436537)
			(xy 87.292906 -262.451981) (xy 87.337438 -262.474671) (xy 87.377871 -262.504047) (xy 87.413211 -262.539387)
			(xy 87.442587 -262.57982) (xy 87.465277 -262.624352) (xy 87.480721 -262.671884) (xy 87.48854 -262.721247)
			(xy 87.48903 -262.746236) (xy 87.794841 -262.746236) (xy 87.798936 -262.695508) (xy 87.811115 -262.646094)
			(xy 87.831063 -262.599274) (xy 87.858264 -262.55626) (xy 87.892012 -262.518166) (xy 87.931434 -262.485979)
			(xy 87.975508 -262.460533) (xy 88.023094 -262.442486) (xy 88.072958 -262.432306) (xy 88.12381 -262.430257)
			(xy 88.174331 -262.436391) (xy 88.223215 -262.450551) (xy 88.269194 -262.472368) (xy 88.311078 -262.501278)
			(xy 88.347782 -262.536533) (xy 88.378355 -262.577219) (xy 88.402006 -262.622282) (xy 88.418122 -262.670556)
			(xy 88.426286 -262.72079) (xy 88.426798 -262.746236) (xy 88.734895 -262.746236) (xy 88.73899 -262.695508)
			(xy 88.751169 -262.646094) (xy 88.771117 -262.599274) (xy 88.798318 -262.55626) (xy 88.832066 -262.518166)
			(xy 88.871488 -262.485979) (xy 88.915562 -262.460533) (xy 88.963148 -262.442486) (xy 89.013012 -262.432306)
			(xy 89.063864 -262.430257) (xy 89.114385 -262.436391) (xy 89.163269 -262.450551) (xy 89.209248 -262.472368)
			(xy 89.251132 -262.501278) (xy 89.287836 -262.536533) (xy 89.318409 -262.577219) (xy 89.34206 -262.622282)
			(xy 89.358176 -262.670556) (xy 89.36634 -262.72079) (xy 89.366852 -262.746236) (xy 89.366349 -262.771225)
			(xy 89.673412 -262.771225) (xy 89.673412 -262.721247) (xy 89.681231 -262.671884) (xy 89.696675 -262.624352)
			(xy 89.719365 -262.57982) (xy 89.748741 -262.539387) (xy 89.784081 -262.504047) (xy 89.824514 -262.474671)
			(xy 89.869046 -262.451981) (xy 89.916578 -262.436537) (xy 89.965941 -262.428718) (xy 90.015919 -262.428718)
			(xy 90.065282 -262.436537) (xy 90.112814 -262.451981) (xy 90.157346 -262.474671) (xy 90.197779 -262.504047)
			(xy 90.233119 -262.539387) (xy 90.262495 -262.57982) (xy 90.285185 -262.624352) (xy 90.300629 -262.671884)
			(xy 90.308448 -262.721247) (xy 90.308938 -262.746236) (xy 90.614749 -262.746236) (xy 90.618844 -262.695508)
			(xy 90.631023 -262.646094) (xy 90.650971 -262.599274) (xy 90.678172 -262.55626) (xy 90.71192 -262.518166)
			(xy 90.751342 -262.485979) (xy 90.795416 -262.460533) (xy 90.843002 -262.442486) (xy 90.892866 -262.432306)
			(xy 90.943718 -262.430257) (xy 90.994239 -262.436391) (xy 91.043123 -262.450551) (xy 91.089102 -262.472368)
			(xy 91.130986 -262.501278) (xy 91.16769 -262.536533) (xy 91.198263 -262.577219) (xy 91.221914 -262.622282)
			(xy 91.23803 -262.670556) (xy 91.246194 -262.72079) (xy 91.246706 -262.746236) (xy 91.246203 -262.771225)
			(xy 91.55352 -262.771225) (xy 91.55352 -262.721247) (xy 91.561339 -262.671884) (xy 91.576783 -262.624352)
			(xy 91.599473 -262.57982) (xy 91.628849 -262.539387) (xy 91.664189 -262.504047) (xy 91.704622 -262.474671)
			(xy 91.749154 -262.451981) (xy 91.796686 -262.436537) (xy 91.846049 -262.428718) (xy 91.896027 -262.428718)
			(xy 91.94539 -262.436537) (xy 91.992922 -262.451981) (xy 92.037454 -262.474671) (xy 92.077887 -262.504047)
			(xy 92.113227 -262.539387) (xy 92.142603 -262.57982) (xy 92.165293 -262.624352) (xy 92.180737 -262.671884)
			(xy 92.188556 -262.721247) (xy 92.189046 -262.746236) (xy 92.494857 -262.746236) (xy 92.498952 -262.695508)
			(xy 92.511131 -262.646094) (xy 92.531079 -262.599274) (xy 92.55828 -262.55626) (xy 92.592028 -262.518166)
			(xy 92.63145 -262.485979) (xy 92.675524 -262.460533) (xy 92.72311 -262.442486) (xy 92.772974 -262.432306)
			(xy 92.823826 -262.430257) (xy 92.874347 -262.436391) (xy 92.923231 -262.450551) (xy 92.96921 -262.472368)
			(xy 93.011094 -262.501278) (xy 93.047798 -262.536533) (xy 93.078371 -262.577219) (xy 93.102022 -262.622282)
			(xy 93.118138 -262.670556) (xy 93.126302 -262.72079) (xy 93.126814 -262.746236) (xy 93.126311 -262.771225)
			(xy 93.433628 -262.771225) (xy 93.433628 -262.721247) (xy 93.441447 -262.671884) (xy 93.456891 -262.624352)
			(xy 93.479581 -262.57982) (xy 93.508957 -262.539387) (xy 93.544297 -262.504047) (xy 93.58473 -262.474671)
			(xy 93.629262 -262.451981) (xy 93.676794 -262.436537) (xy 93.726157 -262.428718) (xy 93.776135 -262.428718)
			(xy 93.825498 -262.436537) (xy 93.87303 -262.451981) (xy 93.917562 -262.474671) (xy 93.957995 -262.504047)
			(xy 93.993335 -262.539387) (xy 94.022711 -262.57982) (xy 94.045401 -262.624352) (xy 94.060845 -262.671884)
			(xy 94.068664 -262.721247) (xy 94.069154 -262.746236) (xy 94.374711 -262.746236) (xy 94.378806 -262.695508)
			(xy 94.390985 -262.646094) (xy 94.410933 -262.599274) (xy 94.438134 -262.55626) (xy 94.471882 -262.518166)
			(xy 94.511304 -262.485979) (xy 94.555378 -262.460533) (xy 94.602964 -262.442486) (xy 94.652828 -262.432306)
			(xy 94.70368 -262.430257) (xy 94.754201 -262.436391) (xy 94.803085 -262.450551) (xy 94.849064 -262.472368)
			(xy 94.890948 -262.501278) (xy 94.927652 -262.536533) (xy 94.958225 -262.577219) (xy 94.981876 -262.622282)
			(xy 94.997992 -262.670556) (xy 95.006156 -262.72079) (xy 95.006668 -262.746236) (xy 95.314765 -262.746236)
			(xy 95.31886 -262.695508) (xy 95.331039 -262.646094) (xy 95.350987 -262.599274) (xy 95.378188 -262.55626)
			(xy 95.411936 -262.518166) (xy 95.451358 -262.485979) (xy 95.495432 -262.460533) (xy 95.543018 -262.442486)
			(xy 95.592882 -262.432306) (xy 95.643734 -262.430257) (xy 95.694255 -262.436391) (xy 95.743139 -262.450551)
			(xy 95.789118 -262.472368) (xy 95.831002 -262.501278) (xy 95.867706 -262.536533) (xy 95.898279 -262.577219)
			(xy 95.92193 -262.622282) (xy 95.938046 -262.670556) (xy 95.94621 -262.72079) (xy 95.946722 -262.746236)
			(xy 95.946219 -262.771225) (xy 96.253536 -262.771225) (xy 96.253536 -262.721247) (xy 96.261355 -262.671884)
			(xy 96.276799 -262.624352) (xy 96.299489 -262.57982) (xy 96.328865 -262.539387) (xy 96.364205 -262.504047)
			(xy 96.404638 -262.474671) (xy 96.44917 -262.451981) (xy 96.496702 -262.436537) (xy 96.546065 -262.428718)
			(xy 96.596043 -262.428718) (xy 96.645406 -262.436537) (xy 96.692938 -262.451981) (xy 96.73747 -262.474671)
			(xy 96.777903 -262.504047) (xy 96.813243 -262.539387) (xy 96.842619 -262.57982) (xy 96.865309 -262.624352)
			(xy 96.880753 -262.671884) (xy 96.888572 -262.721247) (xy 96.889062 -262.746236) (xy 96.888572 -262.771225)
			(xy 98.133644 -262.771225) (xy 98.133644 -262.721247) (xy 98.141463 -262.671884) (xy 98.156907 -262.624352)
			(xy 98.179597 -262.57982) (xy 98.208973 -262.539387) (xy 98.244313 -262.504047) (xy 98.284746 -262.474671)
			(xy 98.329278 -262.451981) (xy 98.37681 -262.436537) (xy 98.426173 -262.428718) (xy 98.476151 -262.428718)
			(xy 98.525514 -262.436537) (xy 98.573046 -262.451981) (xy 98.617578 -262.474671) (xy 98.658011 -262.504047)
			(xy 98.693351 -262.539387) (xy 98.722727 -262.57982) (xy 98.745417 -262.624352) (xy 98.760861 -262.671884)
			(xy 98.76868 -262.721247) (xy 98.76917 -262.746236) (xy 98.76868 -262.771225) (xy 100.013498 -262.771225)
			(xy 100.013498 -262.721247) (xy 100.021317 -262.671884) (xy 100.036761 -262.624352) (xy 100.059451 -262.57982)
			(xy 100.088827 -262.539387) (xy 100.124167 -262.504047) (xy 100.1646 -262.474671) (xy 100.209132 -262.451981)
			(xy 100.256664 -262.436537) (xy 100.306027 -262.428718) (xy 100.356005 -262.428718) (xy 100.405368 -262.436537)
			(xy 100.4529 -262.451981) (xy 100.497432 -262.474671) (xy 100.537865 -262.504047) (xy 100.573205 -262.539387)
			(xy 100.602581 -262.57982) (xy 100.625271 -262.624352) (xy 100.640715 -262.671884) (xy 100.648534 -262.721247)
			(xy 100.649024 -262.746236) (xy 100.648534 -262.771225) (xy 100.640715 -262.820588) (xy 100.625271 -262.86812)
			(xy 100.602581 -262.912652) (xy 100.573205 -262.953085) (xy 100.537865 -262.988425) (xy 100.497432 -263.017801)
			(xy 100.4529 -263.040491) (xy 100.405368 -263.055935) (xy 100.356005 -263.063754) (xy 100.306027 -263.063754)
			(xy 100.256664 -263.055935) (xy 100.209132 -263.040491) (xy 100.1646 -263.017801) (xy 100.124167 -262.988425)
			(xy 100.088827 -262.953085) (xy 100.059451 -262.912652) (xy 100.036761 -262.86812) (xy 100.021317 -262.820588)
			(xy 100.013498 -262.771225) (xy 98.76868 -262.771225) (xy 98.760861 -262.820588) (xy 98.745417 -262.86812)
			(xy 98.722727 -262.912652) (xy 98.693351 -262.953085) (xy 98.658011 -262.988425) (xy 98.617578 -263.017801)
			(xy 98.573046 -263.040491) (xy 98.525514 -263.055935) (xy 98.476151 -263.063754) (xy 98.426173 -263.063754)
			(xy 98.37681 -263.055935) (xy 98.329278 -263.040491) (xy 98.284746 -263.017801) (xy 98.244313 -262.988425)
			(xy 98.208973 -262.953085) (xy 98.179597 -262.912652) (xy 98.156907 -262.86812) (xy 98.141463 -262.820588)
			(xy 98.133644 -262.771225) (xy 96.888572 -262.771225) (xy 96.880753 -262.820588) (xy 96.865309 -262.86812)
			(xy 96.842619 -262.912652) (xy 96.813243 -262.953085) (xy 96.777903 -262.988425) (xy 96.73747 -263.017801)
			(xy 96.692938 -263.040491) (xy 96.645406 -263.055935) (xy 96.596043 -263.063754) (xy 96.546065 -263.063754)
			(xy 96.496702 -263.055935) (xy 96.44917 -263.040491) (xy 96.404638 -263.017801) (xy 96.364205 -262.988425)
			(xy 96.328865 -262.953085) (xy 96.299489 -262.912652) (xy 96.276799 -262.86812) (xy 96.261355 -262.820588)
			(xy 96.253536 -262.771225) (xy 95.946219 -262.771225) (xy 95.94621 -262.771682) (xy 95.938046 -262.821916)
			(xy 95.92193 -262.87019) (xy 95.898279 -262.915253) (xy 95.867706 -262.955939) (xy 95.831002 -262.991194)
			(xy 95.789118 -263.020104) (xy 95.743139 -263.041921) (xy 95.694255 -263.056081) (xy 95.643734 -263.062215)
			(xy 95.592882 -263.060166) (xy 95.543018 -263.049986) (xy 95.495432 -263.031939) (xy 95.451358 -263.006493)
			(xy 95.411936 -262.974306) (xy 95.378188 -262.936212) (xy 95.350987 -262.893198) (xy 95.331039 -262.846378)
			(xy 95.31886 -262.796964) (xy 95.314765 -262.746236) (xy 95.006668 -262.746236) (xy 95.006156 -262.771682)
			(xy 94.997992 -262.821916) (xy 94.981876 -262.87019) (xy 94.958225 -262.915253) (xy 94.927652 -262.955939)
			(xy 94.890948 -262.991194) (xy 94.849064 -263.020104) (xy 94.803085 -263.041921) (xy 94.754201 -263.056081)
			(xy 94.70368 -263.062215) (xy 94.652828 -263.060166) (xy 94.602964 -263.049986) (xy 94.555378 -263.031939)
			(xy 94.511304 -263.006493) (xy 94.471882 -262.974306) (xy 94.438134 -262.936212) (xy 94.410933 -262.893198)
			(xy 94.390985 -262.846378) (xy 94.378806 -262.796964) (xy 94.374711 -262.746236) (xy 94.069154 -262.746236)
			(xy 94.068664 -262.771225) (xy 94.060845 -262.820588) (xy 94.045401 -262.86812) (xy 94.022711 -262.912652)
			(xy 93.993335 -262.953085) (xy 93.957995 -262.988425) (xy 93.917562 -263.017801) (xy 93.87303 -263.040491)
			(xy 93.825498 -263.055935) (xy 93.776135 -263.063754) (xy 93.726157 -263.063754) (xy 93.676794 -263.055935)
			(xy 93.629262 -263.040491) (xy 93.58473 -263.017801) (xy 93.544297 -262.988425) (xy 93.508957 -262.953085)
			(xy 93.479581 -262.912652) (xy 93.456891 -262.86812) (xy 93.441447 -262.820588) (xy 93.433628 -262.771225)
			(xy 93.126311 -262.771225) (xy 93.126302 -262.771682) (xy 93.118138 -262.821916) (xy 93.102022 -262.87019)
			(xy 93.078371 -262.915253) (xy 93.047798 -262.955939) (xy 93.011094 -262.991194) (xy 92.96921 -263.020104)
			(xy 92.923231 -263.041921) (xy 92.874347 -263.056081) (xy 92.823826 -263.062215) (xy 92.772974 -263.060166)
			(xy 92.72311 -263.049986) (xy 92.675524 -263.031939) (xy 92.63145 -263.006493) (xy 92.592028 -262.974306)
			(xy 92.55828 -262.936212) (xy 92.531079 -262.893198) (xy 92.511131 -262.846378) (xy 92.498952 -262.796964)
			(xy 92.494857 -262.746236) (xy 92.189046 -262.746236) (xy 92.188556 -262.771225) (xy 92.180737 -262.820588)
			(xy 92.165293 -262.86812) (xy 92.142603 -262.912652) (xy 92.113227 -262.953085) (xy 92.077887 -262.988425)
			(xy 92.037454 -263.017801) (xy 91.992922 -263.040491) (xy 91.94539 -263.055935) (xy 91.896027 -263.063754)
			(xy 91.846049 -263.063754) (xy 91.796686 -263.055935) (xy 91.749154 -263.040491) (xy 91.704622 -263.017801)
			(xy 91.664189 -262.988425) (xy 91.628849 -262.953085) (xy 91.599473 -262.912652) (xy 91.576783 -262.86812)
			(xy 91.561339 -262.820588) (xy 91.55352 -262.771225) (xy 91.246203 -262.771225) (xy 91.246194 -262.771682)
			(xy 91.23803 -262.821916) (xy 91.221914 -262.87019) (xy 91.198263 -262.915253) (xy 91.16769 -262.955939)
			(xy 91.130986 -262.991194) (xy 91.089102 -263.020104) (xy 91.043123 -263.041921) (xy 90.994239 -263.056081)
			(xy 90.943718 -263.062215) (xy 90.892866 -263.060166) (xy 90.843002 -263.049986) (xy 90.795416 -263.031939)
			(xy 90.751342 -263.006493) (xy 90.71192 -262.974306) (xy 90.678172 -262.936212) (xy 90.650971 -262.893198)
			(xy 90.631023 -262.846378) (xy 90.618844 -262.796964) (xy 90.614749 -262.746236) (xy 90.308938 -262.746236)
			(xy 90.308448 -262.771225) (xy 90.300629 -262.820588) (xy 90.285185 -262.86812) (xy 90.262495 -262.912652)
			(xy 90.233119 -262.953085) (xy 90.197779 -262.988425) (xy 90.157346 -263.017801) (xy 90.112814 -263.040491)
			(xy 90.065282 -263.055935) (xy 90.015919 -263.063754) (xy 89.965941 -263.063754) (xy 89.916578 -263.055935)
			(xy 89.869046 -263.040491) (xy 89.824514 -263.017801) (xy 89.784081 -262.988425) (xy 89.748741 -262.953085)
			(xy 89.719365 -262.912652) (xy 89.696675 -262.86812) (xy 89.681231 -262.820588) (xy 89.673412 -262.771225)
			(xy 89.366349 -262.771225) (xy 89.36634 -262.771682) (xy 89.358176 -262.821916) (xy 89.34206 -262.87019)
			(xy 89.318409 -262.915253) (xy 89.287836 -262.955939) (xy 89.251132 -262.991194) (xy 89.209248 -263.020104)
			(xy 89.163269 -263.041921) (xy 89.114385 -263.056081) (xy 89.063864 -263.062215) (xy 89.013012 -263.060166)
			(xy 88.963148 -263.049986) (xy 88.915562 -263.031939) (xy 88.871488 -263.006493) (xy 88.832066 -262.974306)
			(xy 88.798318 -262.936212) (xy 88.771117 -262.893198) (xy 88.751169 -262.846378) (xy 88.73899 -262.796964)
			(xy 88.734895 -262.746236) (xy 88.426798 -262.746236) (xy 88.426286 -262.771682) (xy 88.418122 -262.821916)
			(xy 88.402006 -262.87019) (xy 88.378355 -262.915253) (xy 88.347782 -262.955939) (xy 88.311078 -262.991194)
			(xy 88.269194 -263.020104) (xy 88.223215 -263.041921) (xy 88.174331 -263.056081) (xy 88.12381 -263.062215)
			(xy 88.072958 -263.060166) (xy 88.023094 -263.049986) (xy 87.975508 -263.031939) (xy 87.931434 -263.006493)
			(xy 87.892012 -262.974306) (xy 87.858264 -262.936212) (xy 87.831063 -262.893198) (xy 87.811115 -262.846378)
			(xy 87.798936 -262.796964) (xy 87.794841 -262.746236) (xy 87.48903 -262.746236) (xy 87.48854 -262.771225)
			(xy 87.480721 -262.820588) (xy 87.465277 -262.86812) (xy 87.442587 -262.912652) (xy 87.413211 -262.953085)
			(xy 87.377871 -262.988425) (xy 87.337438 -263.017801) (xy 87.292906 -263.040491) (xy 87.245374 -263.055935)
			(xy 87.196011 -263.063754) (xy 87.146033 -263.063754) (xy 87.09667 -263.055935) (xy 87.049138 -263.040491)
			(xy 87.004606 -263.017801) (xy 86.964173 -262.988425) (xy 86.928833 -262.953085) (xy 86.899457 -262.912652)
			(xy 86.876767 -262.86812) (xy 86.861323 -262.820588) (xy 86.853504 -262.771225) (xy 86.546187 -262.771225)
			(xy 86.546178 -262.771682) (xy 86.538014 -262.821916) (xy 86.521898 -262.87019) (xy 86.498247 -262.915253)
			(xy 86.467674 -262.955939) (xy 86.43097 -262.991194) (xy 86.389086 -263.020104) (xy 86.343107 -263.041921)
			(xy 86.294223 -263.056081) (xy 86.243702 -263.062215) (xy 86.19285 -263.060166) (xy 86.142986 -263.049986)
			(xy 86.0954 -263.031939) (xy 86.051326 -263.006493) (xy 86.011904 -262.974306) (xy 85.978156 -262.936212)
			(xy 85.950955 -262.893198) (xy 85.931007 -262.846378) (xy 85.918828 -262.796964) (xy 85.914733 -262.746236)
			(xy 85.608922 -262.746236) (xy 85.608432 -262.771225) (xy 85.600613 -262.820588) (xy 85.585169 -262.86812)
			(xy 85.562479 -262.912652) (xy 85.533103 -262.953085) (xy 85.497763 -262.988425) (xy 85.45733 -263.017801)
			(xy 85.412798 -263.040491) (xy 85.365266 -263.055935) (xy 85.315903 -263.063754) (xy 85.265925 -263.063754)
			(xy 85.216562 -263.055935) (xy 85.16903 -263.040491) (xy 85.124498 -263.017801) (xy 85.084065 -262.988425)
			(xy 85.048725 -262.953085) (xy 85.019349 -262.912652) (xy 84.996659 -262.86812) (xy 84.981215 -262.820588)
			(xy 84.973396 -262.771225) (xy 84.666333 -262.771225) (xy 84.666324 -262.771682) (xy 84.65816 -262.821916)
			(xy 84.642044 -262.87019) (xy 84.618393 -262.915253) (xy 84.58782 -262.955939) (xy 84.551116 -262.991194)
			(xy 84.509232 -263.020104) (xy 84.463253 -263.041921) (xy 84.414369 -263.056081) (xy 84.363848 -263.062215)
			(xy 84.312996 -263.060166) (xy 84.263132 -263.049986) (xy 84.215546 -263.031939) (xy 84.171472 -263.006493)
			(xy 84.13205 -262.974306) (xy 84.098302 -262.936212) (xy 84.071101 -262.893198) (xy 84.051153 -262.846378)
			(xy 84.038974 -262.796964) (xy 84.034879 -262.746236) (xy 83.729068 -262.746236) (xy 83.728578 -262.771225)
			(xy 83.720759 -262.820588) (xy 83.705315 -262.86812) (xy 83.682625 -262.912652) (xy 83.653249 -262.953085)
			(xy 83.617909 -262.988425) (xy 83.577476 -263.017801) (xy 83.532944 -263.040491) (xy 83.485412 -263.055935)
			(xy 83.436049 -263.063754) (xy 83.386071 -263.063754) (xy 83.336708 -263.055935) (xy 83.289176 -263.040491)
			(xy 83.244644 -263.017801) (xy 83.204211 -262.988425) (xy 83.168871 -262.953085) (xy 83.139495 -262.912652)
			(xy 83.116805 -262.86812) (xy 83.101361 -262.820588) (xy 83.093542 -262.771225) (xy 82.786225 -262.771225)
			(xy 82.786216 -262.771682) (xy 82.778052 -262.821916) (xy 82.761936 -262.87019) (xy 82.738285 -262.915253)
			(xy 82.707712 -262.955939) (xy 82.671008 -262.991194) (xy 82.629124 -263.020104) (xy 82.583145 -263.041921)
			(xy 82.534261 -263.056081) (xy 82.48374 -263.062215) (xy 82.432888 -263.060166) (xy 82.383024 -263.049986)
			(xy 82.335438 -263.031939) (xy 82.291364 -263.006493) (xy 82.251942 -262.974306) (xy 82.218194 -262.936212)
			(xy 82.190993 -262.893198) (xy 82.171045 -262.846378) (xy 82.158866 -262.796964) (xy 82.154771 -262.746236)
			(xy 81.846674 -262.746236) (xy 81.846162 -262.771682) (xy 81.837998 -262.821916) (xy 81.821882 -262.87019)
			(xy 81.798231 -262.915253) (xy 81.767658 -262.955939) (xy 81.730954 -262.991194) (xy 81.68907 -263.020104)
			(xy 81.643091 -263.041921) (xy 81.594207 -263.056081) (xy 81.543686 -263.062215) (xy 81.492834 -263.060166)
			(xy 81.44297 -263.049986) (xy 81.395384 -263.031939) (xy 81.35131 -263.006493) (xy 81.311888 -262.974306)
			(xy 81.27814 -262.936212) (xy 81.250939 -262.893198) (xy 81.230991 -262.846378) (xy 81.218812 -262.796964)
			(xy 81.214717 -262.746236) (xy 80.90916 -262.746236) (xy 80.90867 -262.771225) (xy 80.900851 -262.820588)
			(xy 80.885407 -262.86812) (xy 80.862717 -262.912652) (xy 80.833341 -262.953085) (xy 80.798001 -262.988425)
			(xy 80.757568 -263.017801) (xy 80.713036 -263.040491) (xy 80.665504 -263.055935) (xy 80.616141 -263.063754)
			(xy 80.566163 -263.063754) (xy 80.5168 -263.055935) (xy 80.469268 -263.040491) (xy 80.424736 -263.017801)
			(xy 80.384303 -262.988425) (xy 80.348963 -262.953085) (xy 80.319587 -262.912652) (xy 80.296897 -262.86812)
			(xy 80.281453 -262.820588) (xy 80.273634 -262.771225) (xy 79.53248 -262.771225) (xy 79.53248 -263.556242)
			(xy 80.744817 -263.556242) (xy 80.748912 -263.505514) (xy 80.761091 -263.4561) (xy 80.781039 -263.40928)
			(xy 80.80824 -263.366266) (xy 80.841988 -263.328172) (xy 80.88141 -263.295985) (xy 80.925484 -263.270539)
			(xy 80.97307 -263.252492) (xy 81.022934 -263.242312) (xy 81.073786 -263.240263) (xy 81.124307 -263.246397)
			(xy 81.173191 -263.260557) (xy 81.21917 -263.282374) (xy 81.261054 -263.311284) (xy 81.297758 -263.346539)
			(xy 81.328331 -263.387225) (xy 81.351982 -263.432288) (xy 81.368098 -263.480562) (xy 81.376262 -263.530796)
			(xy 81.376774 -263.556242) (xy 81.376271 -263.581231) (xy 81.683588 -263.581231) (xy 81.683588 -263.531253)
			(xy 81.691407 -263.48189) (xy 81.706851 -263.434358) (xy 81.729541 -263.389826) (xy 81.758917 -263.349393)
			(xy 81.794257 -263.314053) (xy 81.83469 -263.284677) (xy 81.879222 -263.261987) (xy 81.926754 -263.246543)
			(xy 81.976117 -263.238724) (xy 82.026095 -263.238724) (xy 82.075458 -263.246543) (xy 82.12299 -263.261987)
			(xy 82.167522 -263.284677) (xy 82.207955 -263.314053) (xy 82.243295 -263.349393) (xy 82.272671 -263.389826)
			(xy 82.295361 -263.434358) (xy 82.310805 -263.48189) (xy 82.318624 -263.531253) (xy 82.319114 -263.556242)
			(xy 82.624671 -263.556242) (xy 82.628766 -263.505514) (xy 82.640945 -263.4561) (xy 82.660893 -263.40928)
			(xy 82.688094 -263.366266) (xy 82.721842 -263.328172) (xy 82.761264 -263.295985) (xy 82.805338 -263.270539)
			(xy 82.852924 -263.252492) (xy 82.902788 -263.242312) (xy 82.95364 -263.240263) (xy 83.004161 -263.246397)
			(xy 83.053045 -263.260557) (xy 83.099024 -263.282374) (xy 83.140908 -263.311284) (xy 83.177612 -263.346539)
			(xy 83.208185 -263.387225) (xy 83.231836 -263.432288) (xy 83.247952 -263.480562) (xy 83.256116 -263.530796)
			(xy 83.256628 -263.556242) (xy 83.256125 -263.581231) (xy 83.563442 -263.581231) (xy 83.563442 -263.531253)
			(xy 83.571261 -263.48189) (xy 83.586705 -263.434358) (xy 83.609395 -263.389826) (xy 83.638771 -263.349393)
			(xy 83.674111 -263.314053) (xy 83.714544 -263.284677) (xy 83.759076 -263.261987) (xy 83.806608 -263.246543)
			(xy 83.855971 -263.238724) (xy 83.905949 -263.238724) (xy 83.955312 -263.246543) (xy 84.002844 -263.261987)
			(xy 84.047376 -263.284677) (xy 84.087809 -263.314053) (xy 84.123149 -263.349393) (xy 84.152525 -263.389826)
			(xy 84.175215 -263.434358) (xy 84.190659 -263.48189) (xy 84.198478 -263.531253) (xy 84.198968 -263.556242)
			(xy 84.504779 -263.556242) (xy 84.508874 -263.505514) (xy 84.521053 -263.4561) (xy 84.541001 -263.40928)
			(xy 84.568202 -263.366266) (xy 84.60195 -263.328172) (xy 84.641372 -263.295985) (xy 84.685446 -263.270539)
			(xy 84.733032 -263.252492) (xy 84.782896 -263.242312) (xy 84.833748 -263.240263) (xy 84.884269 -263.246397)
			(xy 84.933153 -263.260557) (xy 84.979132 -263.282374) (xy 85.021016 -263.311284) (xy 85.05772 -263.346539)
			(xy 85.088293 -263.387225) (xy 85.111944 -263.432288) (xy 85.12806 -263.480562) (xy 85.136224 -263.530796)
			(xy 85.136736 -263.556242) (xy 85.444833 -263.556242) (xy 85.448928 -263.505514) (xy 85.461107 -263.4561)
			(xy 85.481055 -263.40928) (xy 85.508256 -263.366266) (xy 85.542004 -263.328172) (xy 85.581426 -263.295985)
			(xy 85.6255 -263.270539) (xy 85.673086 -263.252492) (xy 85.72295 -263.242312) (xy 85.773802 -263.240263)
			(xy 85.824323 -263.246397) (xy 85.873207 -263.260557) (xy 85.919186 -263.282374) (xy 85.96107 -263.311284)
			(xy 85.997774 -263.346539) (xy 86.028347 -263.387225) (xy 86.051998 -263.432288) (xy 86.068114 -263.480562)
			(xy 86.076278 -263.530796) (xy 86.07679 -263.556242) (xy 87.324687 -263.556242) (xy 87.328782 -263.505514)
			(xy 87.340961 -263.4561) (xy 87.360909 -263.40928) (xy 87.38811 -263.366266) (xy 87.421858 -263.328172)
			(xy 87.46128 -263.295985) (xy 87.505354 -263.270539) (xy 87.55294 -263.252492) (xy 87.602804 -263.242312)
			(xy 87.653656 -263.240263) (xy 87.704177 -263.246397) (xy 87.753061 -263.260557) (xy 87.79904 -263.282374)
			(xy 87.840924 -263.311284) (xy 87.877628 -263.346539) (xy 87.908201 -263.387225) (xy 87.931852 -263.432288)
			(xy 87.947968 -263.480562) (xy 87.956132 -263.530796) (xy 87.956644 -263.556242) (xy 87.956141 -263.581231)
			(xy 88.263458 -263.581231) (xy 88.263458 -263.531253) (xy 88.271277 -263.48189) (xy 88.286721 -263.434358)
			(xy 88.309411 -263.389826) (xy 88.338787 -263.349393) (xy 88.374127 -263.314053) (xy 88.41456 -263.284677)
			(xy 88.459092 -263.261987) (xy 88.506624 -263.246543) (xy 88.555987 -263.238724) (xy 88.605965 -263.238724)
			(xy 88.655328 -263.246543) (xy 88.70286 -263.261987) (xy 88.747392 -263.284677) (xy 88.787825 -263.314053)
			(xy 88.823165 -263.349393) (xy 88.852541 -263.389826) (xy 88.875231 -263.434358) (xy 88.890675 -263.48189)
			(xy 88.898494 -263.531253) (xy 88.898984 -263.556242) (xy 89.204795 -263.556242) (xy 89.20889 -263.505514)
			(xy 89.221069 -263.4561) (xy 89.241017 -263.40928) (xy 89.268218 -263.366266) (xy 89.301966 -263.328172)
			(xy 89.341388 -263.295985) (xy 89.385462 -263.270539) (xy 89.433048 -263.252492) (xy 89.482912 -263.242312)
			(xy 89.533764 -263.240263) (xy 89.584285 -263.246397) (xy 89.633169 -263.260557) (xy 89.679148 -263.282374)
			(xy 89.721032 -263.311284) (xy 89.757736 -263.346539) (xy 89.788309 -263.387225) (xy 89.81196 -263.432288)
			(xy 89.828076 -263.480562) (xy 89.83624 -263.530796) (xy 89.836752 -263.556242) (xy 89.836249 -263.581231)
			(xy 90.143566 -263.581231) (xy 90.143566 -263.531253) (xy 90.151385 -263.48189) (xy 90.166829 -263.434358)
			(xy 90.189519 -263.389826) (xy 90.218895 -263.349393) (xy 90.254235 -263.314053) (xy 90.294668 -263.284677)
			(xy 90.3392 -263.261987) (xy 90.386732 -263.246543) (xy 90.436095 -263.238724) (xy 90.486073 -263.238724)
			(xy 90.535436 -263.246543) (xy 90.582968 -263.261987) (xy 90.6275 -263.284677) (xy 90.667933 -263.314053)
			(xy 90.703273 -263.349393) (xy 90.732649 -263.389826) (xy 90.755339 -263.434358) (xy 90.770783 -263.48189)
			(xy 90.778602 -263.531253) (xy 90.779092 -263.556242) (xy 91.084903 -263.556242) (xy 91.088998 -263.505514)
			(xy 91.101177 -263.4561) (xy 91.121125 -263.40928) (xy 91.148326 -263.366266) (xy 91.182074 -263.328172)
			(xy 91.221496 -263.295985) (xy 91.26557 -263.270539) (xy 91.313156 -263.252492) (xy 91.36302 -263.242312)
			(xy 91.413872 -263.240263) (xy 91.464393 -263.246397) (xy 91.513277 -263.260557) (xy 91.559256 -263.282374)
			(xy 91.60114 -263.311284) (xy 91.637844 -263.346539) (xy 91.668417 -263.387225) (xy 91.692068 -263.432288)
			(xy 91.708184 -263.480562) (xy 91.716348 -263.530796) (xy 91.71686 -263.556242) (xy 92.024703 -263.556242)
			(xy 92.028798 -263.505514) (xy 92.040977 -263.4561) (xy 92.060925 -263.40928) (xy 92.088126 -263.366266)
			(xy 92.121874 -263.328172) (xy 92.161296 -263.295985) (xy 92.20537 -263.270539) (xy 92.252956 -263.252492)
			(xy 92.30282 -263.242312) (xy 92.353672 -263.240263) (xy 92.404193 -263.246397) (xy 92.453077 -263.260557)
			(xy 92.499056 -263.282374) (xy 92.54094 -263.311284) (xy 92.577644 -263.346539) (xy 92.608217 -263.387225)
			(xy 92.631868 -263.432288) (xy 92.647984 -263.480562) (xy 92.656148 -263.530796) (xy 92.65666 -263.556242)
			(xy 93.904811 -263.556242) (xy 93.908906 -263.505514) (xy 93.921085 -263.4561) (xy 93.941033 -263.40928)
			(xy 93.968234 -263.366266) (xy 94.001982 -263.328172) (xy 94.041404 -263.295985) (xy 94.085478 -263.270539)
			(xy 94.133064 -263.252492) (xy 94.182928 -263.242312) (xy 94.23378 -263.240263) (xy 94.284301 -263.246397)
			(xy 94.333185 -263.260557) (xy 94.379164 -263.282374) (xy 94.421048 -263.311284) (xy 94.457752 -263.346539)
			(xy 94.488325 -263.387225) (xy 94.511976 -263.432288) (xy 94.528092 -263.480562) (xy 94.536256 -263.530796)
			(xy 94.536768 -263.556242) (xy 94.536265 -263.581231) (xy 94.843582 -263.581231) (xy 94.843582 -263.531253)
			(xy 94.851401 -263.48189) (xy 94.866845 -263.434358) (xy 94.889535 -263.389826) (xy 94.918911 -263.349393)
			(xy 94.954251 -263.314053) (xy 94.994684 -263.284677) (xy 95.039216 -263.261987) (xy 95.086748 -263.246543)
			(xy 95.136111 -263.238724) (xy 95.186089 -263.238724) (xy 95.235452 -263.246543) (xy 95.282984 -263.261987)
			(xy 95.327516 -263.284677) (xy 95.367949 -263.314053) (xy 95.403289 -263.349393) (xy 95.432665 -263.389826)
			(xy 95.455355 -263.434358) (xy 95.470799 -263.48189) (xy 95.478618 -263.531253) (xy 95.479108 -263.556242)
			(xy 95.784919 -263.556242) (xy 95.789014 -263.505514) (xy 95.801193 -263.4561) (xy 95.821141 -263.40928)
			(xy 95.848342 -263.366266) (xy 95.88209 -263.328172) (xy 95.921512 -263.295985) (xy 95.965586 -263.270539)
			(xy 96.013172 -263.252492) (xy 96.063036 -263.242312) (xy 96.113888 -263.240263) (xy 96.164409 -263.246397)
			(xy 96.213293 -263.260557) (xy 96.259272 -263.282374) (xy 96.301156 -263.311284) (xy 96.33786 -263.346539)
			(xy 96.368433 -263.387225) (xy 96.392084 -263.432288) (xy 96.4082 -263.480562) (xy 96.416364 -263.530796)
			(xy 96.416876 -263.556242) (xy 97.663 -263.556242) (xy 97.663381 -263.532919) (xy 97.67018 -263.486771)
			(xy 97.68364 -263.442108) (xy 97.703471 -263.399888) (xy 97.72925 -263.361012) (xy 97.744534 -263.34339)
			(xy 97.748631 -263.33857) (xy 97.754541 -263.327391) (xy 97.756218 -263.321292) (xy 97.761356 -263.30155)
			(xy 97.778187 -263.264393) (xy 97.801754 -263.231099) (xy 97.831203 -263.202873) (xy 97.865466 -263.180738)
			(xy 97.903302 -263.165495) (xy 97.943341 -263.157698) (xy 97.963736 -263.157208) (xy 98.218752 -263.157208)
			(xy 98.218752 -263.166352) (xy 98.219326 -263.176351) (xy 98.226961 -263.194832) (xy 98.241087 -263.208985)
			(xy 98.259554 -263.216655) (xy 98.269552 -263.217152) (xy 98.43262 -263.217152) (xy 98.442623 -263.21767)
			(xy 98.461106 -263.225328) (xy 98.475257 -263.23947) (xy 98.482924 -263.257949) (xy 98.48342 -263.267952)
			(xy 98.48342 -263.672066) (xy 99.528376 -263.672066) (xy 99.528376 -263.671558) (xy 99.528376 -263.371838)
			(xy 99.528677 -263.350786) (xy 99.536682 -263.309455) (xy 99.552624 -263.270492) (xy 99.575888 -263.235405)
			(xy 99.605573 -263.205553) (xy 99.640528 -263.182091) (xy 99.679401 -263.165929) (xy 99.720686 -263.157692)
			(xy 99.741736 -263.157208) (xy 99.996752 -263.157208) (xy 99.996752 -263.166352) (xy 99.997326 -263.176351)
			(xy 100.004961 -263.194832) (xy 100.019087 -263.208985) (xy 100.037554 -263.216655) (xy 100.047552 -263.217152)
			(xy 100.21062 -263.217152) (xy 100.220623 -263.21767) (xy 100.239106 -263.225328) (xy 100.253257 -263.23947)
			(xy 100.260924 -263.257949) (xy 100.26142 -263.267952) (xy 100.26142 -263.775952) (xy 100.260942 -263.785968)
			(xy 100.253291 -263.80448) (xy 100.239137 -263.818653) (xy 100.220635 -263.826328) (xy 100.21062 -263.826752)
			(xy 100.042472 -263.826752) (xy 100.035884 -263.826914) (xy 100.023143 -263.83026) (xy 100.017326 -263.833356)
			(xy 99.996752 -263.844024) (xy 99.996752 -263.856978) (xy 99.967034 -263.886696) (xy 99.741736 -263.886696)
			(xy 99.720693 -263.886143) (xy 99.679421 -263.877909) (xy 99.64056 -263.861752) (xy 99.605615 -263.838299)
			(xy 99.57594 -263.808456) (xy 99.552683 -263.77338) (xy 99.536744 -263.734429) (xy 99.528742 -263.693111)
			(xy 99.528376 -263.672066) (xy 98.48342 -263.672066) (xy 98.48342 -263.775952) (xy 98.482942 -263.785968)
			(xy 98.475291 -263.80448) (xy 98.461137 -263.818653) (xy 98.442635 -263.826328) (xy 98.43262 -263.826752)
			(xy 98.218752 -263.826752) (xy 98.218752 -263.835896) (xy 98.218376 -263.845923) (xy 98.210698 -263.864449)
			(xy 98.196512 -263.878623) (xy 98.177979 -263.886285) (xy 98.167952 -263.886696) (xy 97.963736 -263.886696)
			(xy 97.944421 -263.886256) (xy 97.906425 -263.879284) (xy 97.870307 -263.865582) (xy 97.837248 -263.845596)
			(xy 97.822512 -263.833102) (xy 97.8154 -263.827768) (xy 97.792518 -263.813177) (xy 97.751668 -263.777454)
			(xy 97.717469 -263.73532) (xy 97.690911 -263.687996) (xy 97.672763 -263.636854) (xy 97.663553 -263.583375)
			(xy 97.663 -263.556242) (xy 96.416876 -263.556242) (xy 96.416364 -263.581688) (xy 96.4082 -263.631922)
			(xy 96.392084 -263.680196) (xy 96.368433 -263.725259) (xy 96.33786 -263.765945) (xy 96.301156 -263.8012)
			(xy 96.259272 -263.83011) (xy 96.213293 -263.851927) (xy 96.164409 -263.866087) (xy 96.113888 -263.872221)
			(xy 96.063036 -263.870172) (xy 96.013172 -263.859992) (xy 95.965586 -263.841945) (xy 95.921512 -263.816499)
			(xy 95.88209 -263.784312) (xy 95.848342 -263.746218) (xy 95.821141 -263.703204) (xy 95.801193 -263.656384)
			(xy 95.789014 -263.60697) (xy 95.784919 -263.556242) (xy 95.479108 -263.556242) (xy 95.478618 -263.581231)
			(xy 95.470799 -263.630594) (xy 95.455355 -263.678126) (xy 95.432665 -263.722658) (xy 95.403289 -263.763091)
			(xy 95.367949 -263.798431) (xy 95.327516 -263.827807) (xy 95.282984 -263.850497) (xy 95.235452 -263.865941)
			(xy 95.186089 -263.87376) (xy 95.136111 -263.87376) (xy 95.086748 -263.865941) (xy 95.039216 -263.850497)
			(xy 94.994684 -263.827807) (xy 94.954251 -263.798431) (xy 94.918911 -263.763091) (xy 94.889535 -263.722658)
			(xy 94.866845 -263.678126) (xy 94.851401 -263.630594) (xy 94.843582 -263.581231) (xy 94.536265 -263.581231)
			(xy 94.536256 -263.581688) (xy 94.528092 -263.631922) (xy 94.511976 -263.680196) (xy 94.488325 -263.725259)
			(xy 94.457752 -263.765945) (xy 94.421048 -263.8012) (xy 94.379164 -263.83011) (xy 94.333185 -263.851927)
			(xy 94.284301 -263.866087) (xy 94.23378 -263.872221) (xy 94.182928 -263.870172) (xy 94.133064 -263.859992)
			(xy 94.085478 -263.841945) (xy 94.041404 -263.816499) (xy 94.001982 -263.784312) (xy 93.968234 -263.746218)
			(xy 93.941033 -263.703204) (xy 93.921085 -263.656384) (xy 93.908906 -263.60697) (xy 93.904811 -263.556242)
			(xy 92.65666 -263.556242) (xy 92.656148 -263.581688) (xy 92.647984 -263.631922) (xy 92.631868 -263.680196)
			(xy 92.608217 -263.725259) (xy 92.577644 -263.765945) (xy 92.54094 -263.8012) (xy 92.499056 -263.83011)
			(xy 92.453077 -263.851927) (xy 92.404193 -263.866087) (xy 92.353672 -263.872221) (xy 92.30282 -263.870172)
			(xy 92.252956 -263.859992) (xy 92.20537 -263.841945) (xy 92.161296 -263.816499) (xy 92.121874 -263.784312)
			(xy 92.088126 -263.746218) (xy 92.060925 -263.703204) (xy 92.040977 -263.656384) (xy 92.028798 -263.60697)
			(xy 92.024703 -263.556242) (xy 91.71686 -263.556242) (xy 91.716348 -263.581688) (xy 91.708184 -263.631922)
			(xy 91.692068 -263.680196) (xy 91.668417 -263.725259) (xy 91.637844 -263.765945) (xy 91.60114 -263.8012)
			(xy 91.559256 -263.83011) (xy 91.513277 -263.851927) (xy 91.464393 -263.866087) (xy 91.413872 -263.872221)
			(xy 91.36302 -263.870172) (xy 91.313156 -263.859992) (xy 91.26557 -263.841945) (xy 91.221496 -263.816499)
			(xy 91.182074 -263.784312) (xy 91.148326 -263.746218) (xy 91.121125 -263.703204) (xy 91.101177 -263.656384)
			(xy 91.088998 -263.60697) (xy 91.084903 -263.556242) (xy 90.779092 -263.556242) (xy 90.778602 -263.581231)
			(xy 90.770783 -263.630594) (xy 90.755339 -263.678126) (xy 90.732649 -263.722658) (xy 90.703273 -263.763091)
			(xy 90.667933 -263.798431) (xy 90.6275 -263.827807) (xy 90.582968 -263.850497) (xy 90.535436 -263.865941)
			(xy 90.486073 -263.87376) (xy 90.436095 -263.87376) (xy 90.386732 -263.865941) (xy 90.3392 -263.850497)
			(xy 90.294668 -263.827807) (xy 90.254235 -263.798431) (xy 90.218895 -263.763091) (xy 90.189519 -263.722658)
			(xy 90.166829 -263.678126) (xy 90.151385 -263.630594) (xy 90.143566 -263.581231) (xy 89.836249 -263.581231)
			(xy 89.83624 -263.581688) (xy 89.828076 -263.631922) (xy 89.81196 -263.680196) (xy 89.788309 -263.725259)
			(xy 89.757736 -263.765945) (xy 89.721032 -263.8012) (xy 89.679148 -263.83011) (xy 89.633169 -263.851927)
			(xy 89.584285 -263.866087) (xy 89.533764 -263.872221) (xy 89.482912 -263.870172) (xy 89.433048 -263.859992)
			(xy 89.385462 -263.841945) (xy 89.341388 -263.816499) (xy 89.301966 -263.784312) (xy 89.268218 -263.746218)
			(xy 89.241017 -263.703204) (xy 89.221069 -263.656384) (xy 89.20889 -263.60697) (xy 89.204795 -263.556242)
			(xy 88.898984 -263.556242) (xy 88.898494 -263.581231) (xy 88.890675 -263.630594) (xy 88.875231 -263.678126)
			(xy 88.852541 -263.722658) (xy 88.823165 -263.763091) (xy 88.787825 -263.798431) (xy 88.747392 -263.827807)
			(xy 88.70286 -263.850497) (xy 88.655328 -263.865941) (xy 88.605965 -263.87376) (xy 88.555987 -263.87376)
			(xy 88.506624 -263.865941) (xy 88.459092 -263.850497) (xy 88.41456 -263.827807) (xy 88.374127 -263.798431)
			(xy 88.338787 -263.763091) (xy 88.309411 -263.722658) (xy 88.286721 -263.678126) (xy 88.271277 -263.630594)
			(xy 88.263458 -263.581231) (xy 87.956141 -263.581231) (xy 87.956132 -263.581688) (xy 87.947968 -263.631922)
			(xy 87.931852 -263.680196) (xy 87.908201 -263.725259) (xy 87.877628 -263.765945) (xy 87.840924 -263.8012)
			(xy 87.79904 -263.83011) (xy 87.753061 -263.851927) (xy 87.704177 -263.866087) (xy 87.653656 -263.872221)
			(xy 87.602804 -263.870172) (xy 87.55294 -263.859992) (xy 87.505354 -263.841945) (xy 87.46128 -263.816499)
			(xy 87.421858 -263.784312) (xy 87.38811 -263.746218) (xy 87.360909 -263.703204) (xy 87.340961 -263.656384)
			(xy 87.328782 -263.60697) (xy 87.324687 -263.556242) (xy 86.07679 -263.556242) (xy 86.076278 -263.581688)
			(xy 86.068114 -263.631922) (xy 86.051998 -263.680196) (xy 86.028347 -263.725259) (xy 85.997774 -263.765945)
			(xy 85.96107 -263.8012) (xy 85.919186 -263.83011) (xy 85.873207 -263.851927) (xy 85.824323 -263.866087)
			(xy 85.773802 -263.872221) (xy 85.72295 -263.870172) (xy 85.673086 -263.859992) (xy 85.6255 -263.841945)
			(xy 85.581426 -263.816499) (xy 85.542004 -263.784312) (xy 85.508256 -263.746218) (xy 85.481055 -263.703204)
			(xy 85.461107 -263.656384) (xy 85.448928 -263.60697) (xy 85.444833 -263.556242) (xy 85.136736 -263.556242)
			(xy 85.136224 -263.581688) (xy 85.12806 -263.631922) (xy 85.111944 -263.680196) (xy 85.088293 -263.725259)
			(xy 85.05772 -263.765945) (xy 85.021016 -263.8012) (xy 84.979132 -263.83011) (xy 84.933153 -263.851927)
			(xy 84.884269 -263.866087) (xy 84.833748 -263.872221) (xy 84.782896 -263.870172) (xy 84.733032 -263.859992)
			(xy 84.685446 -263.841945) (xy 84.641372 -263.816499) (xy 84.60195 -263.784312) (xy 84.568202 -263.746218)
			(xy 84.541001 -263.703204) (xy 84.521053 -263.656384) (xy 84.508874 -263.60697) (xy 84.504779 -263.556242)
			(xy 84.198968 -263.556242) (xy 84.198478 -263.581231) (xy 84.190659 -263.630594) (xy 84.175215 -263.678126)
			(xy 84.152525 -263.722658) (xy 84.123149 -263.763091) (xy 84.087809 -263.798431) (xy 84.047376 -263.827807)
			(xy 84.002844 -263.850497) (xy 83.955312 -263.865941) (xy 83.905949 -263.87376) (xy 83.855971 -263.87376)
			(xy 83.806608 -263.865941) (xy 83.759076 -263.850497) (xy 83.714544 -263.827807) (xy 83.674111 -263.798431)
			(xy 83.638771 -263.763091) (xy 83.609395 -263.722658) (xy 83.586705 -263.678126) (xy 83.571261 -263.630594)
			(xy 83.563442 -263.581231) (xy 83.256125 -263.581231) (xy 83.256116 -263.581688) (xy 83.247952 -263.631922)
			(xy 83.231836 -263.680196) (xy 83.208185 -263.725259) (xy 83.177612 -263.765945) (xy 83.140908 -263.8012)
			(xy 83.099024 -263.83011) (xy 83.053045 -263.851927) (xy 83.004161 -263.866087) (xy 82.95364 -263.872221)
			(xy 82.902788 -263.870172) (xy 82.852924 -263.859992) (xy 82.805338 -263.841945) (xy 82.761264 -263.816499)
			(xy 82.721842 -263.784312) (xy 82.688094 -263.746218) (xy 82.660893 -263.703204) (xy 82.640945 -263.656384)
			(xy 82.628766 -263.60697) (xy 82.624671 -263.556242) (xy 82.319114 -263.556242) (xy 82.318624 -263.581231)
			(xy 82.310805 -263.630594) (xy 82.295361 -263.678126) (xy 82.272671 -263.722658) (xy 82.243295 -263.763091)
			(xy 82.207955 -263.798431) (xy 82.167522 -263.827807) (xy 82.12299 -263.850497) (xy 82.075458 -263.865941)
			(xy 82.026095 -263.87376) (xy 81.976117 -263.87376) (xy 81.926754 -263.865941) (xy 81.879222 -263.850497)
			(xy 81.83469 -263.827807) (xy 81.794257 -263.798431) (xy 81.758917 -263.763091) (xy 81.729541 -263.722658)
			(xy 81.706851 -263.678126) (xy 81.691407 -263.630594) (xy 81.683588 -263.581231) (xy 81.376271 -263.581231)
			(xy 81.376262 -263.581688) (xy 81.368098 -263.631922) (xy 81.351982 -263.680196) (xy 81.328331 -263.725259)
			(xy 81.297758 -263.765945) (xy 81.261054 -263.8012) (xy 81.21917 -263.83011) (xy 81.173191 -263.851927)
			(xy 81.124307 -263.866087) (xy 81.073786 -263.872221) (xy 81.022934 -263.870172) (xy 80.97307 -263.859992)
			(xy 80.925484 -263.841945) (xy 80.88141 -263.816499) (xy 80.841988 -263.784312) (xy 80.80824 -263.746218)
			(xy 80.781039 -263.703204) (xy 80.761091 -263.656384) (xy 80.748912 -263.60697) (xy 80.744817 -263.556242)
			(xy 79.53248 -263.556242) (xy 79.53248 -264.391237) (xy 80.273634 -264.391237) (xy 80.273634 -264.341259)
			(xy 80.281453 -264.291896) (xy 80.296897 -264.244364) (xy 80.319587 -264.199832) (xy 80.348963 -264.159399)
			(xy 80.384303 -264.124059) (xy 80.424736 -264.094683) (xy 80.469268 -264.071993) (xy 80.5168 -264.056549)
			(xy 80.566163 -264.04873) (xy 80.616141 -264.04873) (xy 80.665504 -264.056549) (xy 80.713036 -264.071993)
			(xy 80.757568 -264.094683) (xy 80.798001 -264.124059) (xy 80.833341 -264.159399) (xy 80.862717 -264.199832)
			(xy 80.885407 -264.244364) (xy 80.900851 -264.291896) (xy 80.90867 -264.341259) (xy 80.90916 -264.366248)
			(xy 81.214717 -264.366248) (xy 81.218812 -264.31552) (xy 81.230991 -264.266106) (xy 81.250939 -264.219286)
			(xy 81.27814 -264.176272) (xy 81.311888 -264.138178) (xy 81.35131 -264.105991) (xy 81.395384 -264.080545)
			(xy 81.44297 -264.062498) (xy 81.492834 -264.052318) (xy 81.543686 -264.050269) (xy 81.594207 -264.056403)
			(xy 81.643091 -264.070563) (xy 81.68907 -264.09238) (xy 81.730954 -264.12129) (xy 81.767658 -264.156545)
			(xy 81.798231 -264.197231) (xy 81.821882 -264.242294) (xy 81.837998 -264.290568) (xy 81.846162 -264.340802)
			(xy 81.846674 -264.366248) (xy 82.154771 -264.366248) (xy 82.158866 -264.31552) (xy 82.171045 -264.266106)
			(xy 82.190993 -264.219286) (xy 82.218194 -264.176272) (xy 82.251942 -264.138178) (xy 82.291364 -264.105991)
			(xy 82.335438 -264.080545) (xy 82.383024 -264.062498) (xy 82.432888 -264.052318) (xy 82.48374 -264.050269)
			(xy 82.534261 -264.056403) (xy 82.583145 -264.070563) (xy 82.629124 -264.09238) (xy 82.671008 -264.12129)
			(xy 82.707712 -264.156545) (xy 82.738285 -264.197231) (xy 82.761936 -264.242294) (xy 82.778052 -264.290568)
			(xy 82.786216 -264.340802) (xy 82.786728 -264.366248) (xy 82.786225 -264.391237) (xy 83.093542 -264.391237)
			(xy 83.093542 -264.341259) (xy 83.101361 -264.291896) (xy 83.116805 -264.244364) (xy 83.139495 -264.199832)
			(xy 83.168871 -264.159399) (xy 83.204211 -264.124059) (xy 83.244644 -264.094683) (xy 83.289176 -264.071993)
			(xy 83.336708 -264.056549) (xy 83.386071 -264.04873) (xy 83.436049 -264.04873) (xy 83.485412 -264.056549)
			(xy 83.532944 -264.071993) (xy 83.577476 -264.094683) (xy 83.617909 -264.124059) (xy 83.653249 -264.159399)
			(xy 83.682625 -264.199832) (xy 83.705315 -264.244364) (xy 83.720759 -264.291896) (xy 83.728578 -264.341259)
			(xy 83.729068 -264.366248) (xy 84.034879 -264.366248) (xy 84.038974 -264.31552) (xy 84.051153 -264.266106)
			(xy 84.071101 -264.219286) (xy 84.098302 -264.176272) (xy 84.13205 -264.138178) (xy 84.171472 -264.105991)
			(xy 84.215546 -264.080545) (xy 84.263132 -264.062498) (xy 84.312996 -264.052318) (xy 84.363848 -264.050269)
			(xy 84.414369 -264.056403) (xy 84.463253 -264.070563) (xy 84.509232 -264.09238) (xy 84.551116 -264.12129)
			(xy 84.58782 -264.156545) (xy 84.618393 -264.197231) (xy 84.642044 -264.242294) (xy 84.65816 -264.290568)
			(xy 84.666324 -264.340802) (xy 84.666836 -264.366248) (xy 84.666333 -264.391237) (xy 84.973396 -264.391237)
			(xy 84.973396 -264.341259) (xy 84.981215 -264.291896) (xy 84.996659 -264.244364) (xy 85.019349 -264.199832)
			(xy 85.048725 -264.159399) (xy 85.084065 -264.124059) (xy 85.124498 -264.094683) (xy 85.16903 -264.071993)
			(xy 85.216562 -264.056549) (xy 85.265925 -264.04873) (xy 85.315903 -264.04873) (xy 85.365266 -264.056549)
			(xy 85.412798 -264.071993) (xy 85.45733 -264.094683) (xy 85.497763 -264.124059) (xy 85.533103 -264.159399)
			(xy 85.562479 -264.199832) (xy 85.585169 -264.244364) (xy 85.600613 -264.291896) (xy 85.608432 -264.341259)
			(xy 85.608922 -264.366248) (xy 85.914733 -264.366248) (xy 85.918828 -264.31552) (xy 85.931007 -264.266106)
			(xy 85.950955 -264.219286) (xy 85.978156 -264.176272) (xy 86.011904 -264.138178) (xy 86.051326 -264.105991)
			(xy 86.0954 -264.080545) (xy 86.142986 -264.062498) (xy 86.19285 -264.052318) (xy 86.243702 -264.050269)
			(xy 86.294223 -264.056403) (xy 86.343107 -264.070563) (xy 86.389086 -264.09238) (xy 86.43097 -264.12129)
			(xy 86.467674 -264.156545) (xy 86.498247 -264.197231) (xy 86.521898 -264.242294) (xy 86.538014 -264.290568)
			(xy 86.546178 -264.340802) (xy 86.54669 -264.366248) (xy 86.546187 -264.391237) (xy 86.853504 -264.391237)
			(xy 86.853504 -264.341259) (xy 86.861323 -264.291896) (xy 86.876767 -264.244364) (xy 86.899457 -264.199832)
			(xy 86.928833 -264.159399) (xy 86.964173 -264.124059) (xy 87.004606 -264.094683) (xy 87.049138 -264.071993)
			(xy 87.09667 -264.056549) (xy 87.146033 -264.04873) (xy 87.196011 -264.04873) (xy 87.245374 -264.056549)
			(xy 87.292906 -264.071993) (xy 87.337438 -264.094683) (xy 87.377871 -264.124059) (xy 87.413211 -264.159399)
			(xy 87.442587 -264.199832) (xy 87.465277 -264.244364) (xy 87.480721 -264.291896) (xy 87.48854 -264.341259)
			(xy 87.48903 -264.366248) (xy 87.794841 -264.366248) (xy 87.798936 -264.31552) (xy 87.811115 -264.266106)
			(xy 87.831063 -264.219286) (xy 87.858264 -264.176272) (xy 87.892012 -264.138178) (xy 87.931434 -264.105991)
			(xy 87.975508 -264.080545) (xy 88.023094 -264.062498) (xy 88.072958 -264.052318) (xy 88.12381 -264.050269)
			(xy 88.174331 -264.056403) (xy 88.223215 -264.070563) (xy 88.269194 -264.09238) (xy 88.311078 -264.12129)
			(xy 88.347782 -264.156545) (xy 88.378355 -264.197231) (xy 88.402006 -264.242294) (xy 88.418122 -264.290568)
			(xy 88.426286 -264.340802) (xy 88.426798 -264.366248) (xy 88.734895 -264.366248) (xy 88.73899 -264.31552)
			(xy 88.751169 -264.266106) (xy 88.771117 -264.219286) (xy 88.798318 -264.176272) (xy 88.832066 -264.138178)
			(xy 88.871488 -264.105991) (xy 88.915562 -264.080545) (xy 88.963148 -264.062498) (xy 89.013012 -264.052318)
			(xy 89.063864 -264.050269) (xy 89.114385 -264.056403) (xy 89.163269 -264.070563) (xy 89.209248 -264.09238)
			(xy 89.251132 -264.12129) (xy 89.287836 -264.156545) (xy 89.318409 -264.197231) (xy 89.34206 -264.242294)
			(xy 89.358176 -264.290568) (xy 89.36634 -264.340802) (xy 89.366852 -264.366248) (xy 89.366349 -264.391237)
			(xy 89.673412 -264.391237) (xy 89.673412 -264.341259) (xy 89.681231 -264.291896) (xy 89.696675 -264.244364)
			(xy 89.719365 -264.199832) (xy 89.748741 -264.159399) (xy 89.784081 -264.124059) (xy 89.824514 -264.094683)
			(xy 89.869046 -264.071993) (xy 89.916578 -264.056549) (xy 89.965941 -264.04873) (xy 90.015919 -264.04873)
			(xy 90.065282 -264.056549) (xy 90.112814 -264.071993) (xy 90.157346 -264.094683) (xy 90.197779 -264.124059)
			(xy 90.233119 -264.159399) (xy 90.262495 -264.199832) (xy 90.285185 -264.244364) (xy 90.300629 -264.291896)
			(xy 90.308448 -264.341259) (xy 90.308938 -264.366248) (xy 90.614749 -264.366248) (xy 90.618844 -264.31552)
			(xy 90.631023 -264.266106) (xy 90.650971 -264.219286) (xy 90.678172 -264.176272) (xy 90.71192 -264.138178)
			(xy 90.751342 -264.105991) (xy 90.795416 -264.080545) (xy 90.843002 -264.062498) (xy 90.892866 -264.052318)
			(xy 90.943718 -264.050269) (xy 90.994239 -264.056403) (xy 91.043123 -264.070563) (xy 91.089102 -264.09238)
			(xy 91.130986 -264.12129) (xy 91.16769 -264.156545) (xy 91.198263 -264.197231) (xy 91.221914 -264.242294)
			(xy 91.23803 -264.290568) (xy 91.246194 -264.340802) (xy 91.246706 -264.366248) (xy 91.246203 -264.391237)
			(xy 91.55352 -264.391237) (xy 91.55352 -264.341259) (xy 91.561339 -264.291896) (xy 91.576783 -264.244364)
			(xy 91.599473 -264.199832) (xy 91.628849 -264.159399) (xy 91.664189 -264.124059) (xy 91.704622 -264.094683)
			(xy 91.749154 -264.071993) (xy 91.796686 -264.056549) (xy 91.846049 -264.04873) (xy 91.896027 -264.04873)
			(xy 91.94539 -264.056549) (xy 91.992922 -264.071993) (xy 92.037454 -264.094683) (xy 92.077887 -264.124059)
			(xy 92.113227 -264.159399) (xy 92.142603 -264.199832) (xy 92.165293 -264.244364) (xy 92.180737 -264.291896)
			(xy 92.188556 -264.341259) (xy 92.189046 -264.366248) (xy 92.494857 -264.366248) (xy 92.498952 -264.31552)
			(xy 92.511131 -264.266106) (xy 92.531079 -264.219286) (xy 92.55828 -264.176272) (xy 92.592028 -264.138178)
			(xy 92.63145 -264.105991) (xy 92.675524 -264.080545) (xy 92.72311 -264.062498) (xy 92.772974 -264.052318)
			(xy 92.823826 -264.050269) (xy 92.874347 -264.056403) (xy 92.923231 -264.070563) (xy 92.96921 -264.09238)
			(xy 93.011094 -264.12129) (xy 93.047798 -264.156545) (xy 93.078371 -264.197231) (xy 93.102022 -264.242294)
			(xy 93.118138 -264.290568) (xy 93.126302 -264.340802) (xy 93.126814 -264.366248) (xy 93.126311 -264.391237)
			(xy 93.433628 -264.391237) (xy 93.433628 -264.341259) (xy 93.441447 -264.291896) (xy 93.456891 -264.244364)
			(xy 93.479581 -264.199832) (xy 93.508957 -264.159399) (xy 93.544297 -264.124059) (xy 93.58473 -264.094683)
			(xy 93.629262 -264.071993) (xy 93.676794 -264.056549) (xy 93.726157 -264.04873) (xy 93.776135 -264.04873)
			(xy 93.825498 -264.056549) (xy 93.87303 -264.071993) (xy 93.917562 -264.094683) (xy 93.957995 -264.124059)
			(xy 93.993335 -264.159399) (xy 94.022711 -264.199832) (xy 94.045401 -264.244364) (xy 94.060845 -264.291896)
			(xy 94.068664 -264.341259) (xy 94.069154 -264.366248) (xy 94.374711 -264.366248) (xy 94.378806 -264.31552)
			(xy 94.390985 -264.266106) (xy 94.410933 -264.219286) (xy 94.438134 -264.176272) (xy 94.471882 -264.138178)
			(xy 94.511304 -264.105991) (xy 94.555378 -264.080545) (xy 94.602964 -264.062498) (xy 94.652828 -264.052318)
			(xy 94.70368 -264.050269) (xy 94.754201 -264.056403) (xy 94.803085 -264.070563) (xy 94.849064 -264.09238)
			(xy 94.890948 -264.12129) (xy 94.927652 -264.156545) (xy 94.958225 -264.197231) (xy 94.981876 -264.242294)
			(xy 94.997992 -264.290568) (xy 95.006156 -264.340802) (xy 95.006668 -264.366248) (xy 95.314765 -264.366248)
			(xy 95.31886 -264.31552) (xy 95.331039 -264.266106) (xy 95.350987 -264.219286) (xy 95.378188 -264.176272)
			(xy 95.411936 -264.138178) (xy 95.451358 -264.105991) (xy 95.495432 -264.080545) (xy 95.543018 -264.062498)
			(xy 95.592882 -264.052318) (xy 95.643734 -264.050269) (xy 95.694255 -264.056403) (xy 95.743139 -264.070563)
			(xy 95.789118 -264.09238) (xy 95.831002 -264.12129) (xy 95.867706 -264.156545) (xy 95.898279 -264.197231)
			(xy 95.92193 -264.242294) (xy 95.938046 -264.290568) (xy 95.94621 -264.340802) (xy 95.946722 -264.366248)
			(xy 95.946219 -264.391237) (xy 96.253536 -264.391237) (xy 96.253536 -264.341259) (xy 96.261355 -264.291896)
			(xy 96.276799 -264.244364) (xy 96.299489 -264.199832) (xy 96.328865 -264.159399) (xy 96.364205 -264.124059)
			(xy 96.404638 -264.094683) (xy 96.44917 -264.071993) (xy 96.496702 -264.056549) (xy 96.546065 -264.04873)
			(xy 96.596043 -264.04873) (xy 96.645406 -264.056549) (xy 96.692938 -264.071993) (xy 96.73747 -264.094683)
			(xy 96.777903 -264.124059) (xy 96.813243 -264.159399) (xy 96.842619 -264.199832) (xy 96.865309 -264.244364)
			(xy 96.880753 -264.291896) (xy 96.888572 -264.341259) (xy 96.889062 -264.366248) (xy 96.888572 -264.391237)
			(xy 96.880753 -264.4406) (xy 96.865309 -264.488132) (xy 96.842619 -264.532664) (xy 96.813243 -264.573097)
			(xy 96.777903 -264.608437) (xy 96.73747 -264.637813) (xy 96.692938 -264.660503) (xy 96.645406 -264.675947)
			(xy 96.596043 -264.683766) (xy 96.546065 -264.683766) (xy 96.496702 -264.675947) (xy 96.44917 -264.660503)
			(xy 96.404638 -264.637813) (xy 96.364205 -264.608437) (xy 96.328865 -264.573097) (xy 96.299489 -264.532664)
			(xy 96.276799 -264.488132) (xy 96.261355 -264.4406) (xy 96.253536 -264.391237) (xy 95.946219 -264.391237)
			(xy 95.94621 -264.391694) (xy 95.938046 -264.441928) (xy 95.92193 -264.490202) (xy 95.898279 -264.535265)
			(xy 95.867706 -264.575951) (xy 95.831002 -264.611206) (xy 95.789118 -264.640116) (xy 95.743139 -264.661933)
			(xy 95.694255 -264.676093) (xy 95.643734 -264.682227) (xy 95.592882 -264.680178) (xy 95.543018 -264.669998)
			(xy 95.495432 -264.651951) (xy 95.451358 -264.626505) (xy 95.411936 -264.594318) (xy 95.378188 -264.556224)
			(xy 95.350987 -264.51321) (xy 95.331039 -264.46639) (xy 95.31886 -264.416976) (xy 95.314765 -264.366248)
			(xy 95.006668 -264.366248) (xy 95.006156 -264.391694) (xy 94.997992 -264.441928) (xy 94.981876 -264.490202)
			(xy 94.958225 -264.535265) (xy 94.927652 -264.575951) (xy 94.890948 -264.611206) (xy 94.849064 -264.640116)
			(xy 94.803085 -264.661933) (xy 94.754201 -264.676093) (xy 94.70368 -264.682227) (xy 94.652828 -264.680178)
			(xy 94.602964 -264.669998) (xy 94.555378 -264.651951) (xy 94.511304 -264.626505) (xy 94.471882 -264.594318)
			(xy 94.438134 -264.556224) (xy 94.410933 -264.51321) (xy 94.390985 -264.46639) (xy 94.378806 -264.416976)
			(xy 94.374711 -264.366248) (xy 94.069154 -264.366248) (xy 94.068664 -264.391237) (xy 94.060845 -264.4406)
			(xy 94.045401 -264.488132) (xy 94.022711 -264.532664) (xy 93.993335 -264.573097) (xy 93.957995 -264.608437)
			(xy 93.917562 -264.637813) (xy 93.87303 -264.660503) (xy 93.825498 -264.675947) (xy 93.776135 -264.683766)
			(xy 93.726157 -264.683766) (xy 93.676794 -264.675947) (xy 93.629262 -264.660503) (xy 93.58473 -264.637813)
			(xy 93.544297 -264.608437) (xy 93.508957 -264.573097) (xy 93.479581 -264.532664) (xy 93.456891 -264.488132)
			(xy 93.441447 -264.4406) (xy 93.433628 -264.391237) (xy 93.126311 -264.391237) (xy 93.126302 -264.391694)
			(xy 93.118138 -264.441928) (xy 93.102022 -264.490202) (xy 93.078371 -264.535265) (xy 93.047798 -264.575951)
			(xy 93.011094 -264.611206) (xy 92.96921 -264.640116) (xy 92.923231 -264.661933) (xy 92.874347 -264.676093)
			(xy 92.823826 -264.682227) (xy 92.772974 -264.680178) (xy 92.72311 -264.669998) (xy 92.675524 -264.651951)
			(xy 92.63145 -264.626505) (xy 92.592028 -264.594318) (xy 92.55828 -264.556224) (xy 92.531079 -264.51321)
			(xy 92.511131 -264.46639) (xy 92.498952 -264.416976) (xy 92.494857 -264.366248) (xy 92.189046 -264.366248)
			(xy 92.188556 -264.391237) (xy 92.180737 -264.4406) (xy 92.165293 -264.488132) (xy 92.142603 -264.532664)
			(xy 92.113227 -264.573097) (xy 92.077887 -264.608437) (xy 92.037454 -264.637813) (xy 91.992922 -264.660503)
			(xy 91.94539 -264.675947) (xy 91.896027 -264.683766) (xy 91.846049 -264.683766) (xy 91.796686 -264.675947)
			(xy 91.749154 -264.660503) (xy 91.704622 -264.637813) (xy 91.664189 -264.608437) (xy 91.628849 -264.573097)
			(xy 91.599473 -264.532664) (xy 91.576783 -264.488132) (xy 91.561339 -264.4406) (xy 91.55352 -264.391237)
			(xy 91.246203 -264.391237) (xy 91.246194 -264.391694) (xy 91.23803 -264.441928) (xy 91.221914 -264.490202)
			(xy 91.198263 -264.535265) (xy 91.16769 -264.575951) (xy 91.130986 -264.611206) (xy 91.089102 -264.640116)
			(xy 91.043123 -264.661933) (xy 90.994239 -264.676093) (xy 90.943718 -264.682227) (xy 90.892866 -264.680178)
			(xy 90.843002 -264.669998) (xy 90.795416 -264.651951) (xy 90.751342 -264.626505) (xy 90.71192 -264.594318)
			(xy 90.678172 -264.556224) (xy 90.650971 -264.51321) (xy 90.631023 -264.46639) (xy 90.618844 -264.416976)
			(xy 90.614749 -264.366248) (xy 90.308938 -264.366248) (xy 90.308448 -264.391237) (xy 90.300629 -264.4406)
			(xy 90.285185 -264.488132) (xy 90.262495 -264.532664) (xy 90.233119 -264.573097) (xy 90.197779 -264.608437)
			(xy 90.157346 -264.637813) (xy 90.112814 -264.660503) (xy 90.065282 -264.675947) (xy 90.015919 -264.683766)
			(xy 89.965941 -264.683766) (xy 89.916578 -264.675947) (xy 89.869046 -264.660503) (xy 89.824514 -264.637813)
			(xy 89.784081 -264.608437) (xy 89.748741 -264.573097) (xy 89.719365 -264.532664) (xy 89.696675 -264.488132)
			(xy 89.681231 -264.4406) (xy 89.673412 -264.391237) (xy 89.366349 -264.391237) (xy 89.36634 -264.391694)
			(xy 89.358176 -264.441928) (xy 89.34206 -264.490202) (xy 89.318409 -264.535265) (xy 89.287836 -264.575951)
			(xy 89.251132 -264.611206) (xy 89.209248 -264.640116) (xy 89.163269 -264.661933) (xy 89.114385 -264.676093)
			(xy 89.063864 -264.682227) (xy 89.013012 -264.680178) (xy 88.963148 -264.669998) (xy 88.915562 -264.651951)
			(xy 88.871488 -264.626505) (xy 88.832066 -264.594318) (xy 88.798318 -264.556224) (xy 88.771117 -264.51321)
			(xy 88.751169 -264.46639) (xy 88.73899 -264.416976) (xy 88.734895 -264.366248) (xy 88.426798 -264.366248)
			(xy 88.426286 -264.391694) (xy 88.418122 -264.441928) (xy 88.402006 -264.490202) (xy 88.378355 -264.535265)
			(xy 88.347782 -264.575951) (xy 88.311078 -264.611206) (xy 88.269194 -264.640116) (xy 88.223215 -264.661933)
			(xy 88.174331 -264.676093) (xy 88.12381 -264.682227) (xy 88.072958 -264.680178) (xy 88.023094 -264.669998)
			(xy 87.975508 -264.651951) (xy 87.931434 -264.626505) (xy 87.892012 -264.594318) (xy 87.858264 -264.556224)
			(xy 87.831063 -264.51321) (xy 87.811115 -264.46639) (xy 87.798936 -264.416976) (xy 87.794841 -264.366248)
			(xy 87.48903 -264.366248) (xy 87.48854 -264.391237) (xy 87.480721 -264.4406) (xy 87.465277 -264.488132)
			(xy 87.442587 -264.532664) (xy 87.413211 -264.573097) (xy 87.377871 -264.608437) (xy 87.337438 -264.637813)
			(xy 87.292906 -264.660503) (xy 87.245374 -264.675947) (xy 87.196011 -264.683766) (xy 87.146033 -264.683766)
			(xy 87.09667 -264.675947) (xy 87.049138 -264.660503) (xy 87.004606 -264.637813) (xy 86.964173 -264.608437)
			(xy 86.928833 -264.573097) (xy 86.899457 -264.532664) (xy 86.876767 -264.488132) (xy 86.861323 -264.4406)
			(xy 86.853504 -264.391237) (xy 86.546187 -264.391237) (xy 86.546178 -264.391694) (xy 86.538014 -264.441928)
			(xy 86.521898 -264.490202) (xy 86.498247 -264.535265) (xy 86.467674 -264.575951) (xy 86.43097 -264.611206)
			(xy 86.389086 -264.640116) (xy 86.343107 -264.661933) (xy 86.294223 -264.676093) (xy 86.243702 -264.682227)
			(xy 86.19285 -264.680178) (xy 86.142986 -264.669998) (xy 86.0954 -264.651951) (xy 86.051326 -264.626505)
			(xy 86.011904 -264.594318) (xy 85.978156 -264.556224) (xy 85.950955 -264.51321) (xy 85.931007 -264.46639)
			(xy 85.918828 -264.416976) (xy 85.914733 -264.366248) (xy 85.608922 -264.366248) (xy 85.608432 -264.391237)
			(xy 85.600613 -264.4406) (xy 85.585169 -264.488132) (xy 85.562479 -264.532664) (xy 85.533103 -264.573097)
			(xy 85.497763 -264.608437) (xy 85.45733 -264.637813) (xy 85.412798 -264.660503) (xy 85.365266 -264.675947)
			(xy 85.315903 -264.683766) (xy 85.265925 -264.683766) (xy 85.216562 -264.675947) (xy 85.16903 -264.660503)
			(xy 85.124498 -264.637813) (xy 85.084065 -264.608437) (xy 85.048725 -264.573097) (xy 85.019349 -264.532664)
			(xy 84.996659 -264.488132) (xy 84.981215 -264.4406) (xy 84.973396 -264.391237) (xy 84.666333 -264.391237)
			(xy 84.666324 -264.391694) (xy 84.65816 -264.441928) (xy 84.642044 -264.490202) (xy 84.618393 -264.535265)
			(xy 84.58782 -264.575951) (xy 84.551116 -264.611206) (xy 84.509232 -264.640116) (xy 84.463253 -264.661933)
			(xy 84.414369 -264.676093) (xy 84.363848 -264.682227) (xy 84.312996 -264.680178) (xy 84.263132 -264.669998)
			(xy 84.215546 -264.651951) (xy 84.171472 -264.626505) (xy 84.13205 -264.594318) (xy 84.098302 -264.556224)
			(xy 84.071101 -264.51321) (xy 84.051153 -264.46639) (xy 84.038974 -264.416976) (xy 84.034879 -264.366248)
			(xy 83.729068 -264.366248) (xy 83.728578 -264.391237) (xy 83.720759 -264.4406) (xy 83.705315 -264.488132)
			(xy 83.682625 -264.532664) (xy 83.653249 -264.573097) (xy 83.617909 -264.608437) (xy 83.577476 -264.637813)
			(xy 83.532944 -264.660503) (xy 83.485412 -264.675947) (xy 83.436049 -264.683766) (xy 83.386071 -264.683766)
			(xy 83.336708 -264.675947) (xy 83.289176 -264.660503) (xy 83.244644 -264.637813) (xy 83.204211 -264.608437)
			(xy 83.168871 -264.573097) (xy 83.139495 -264.532664) (xy 83.116805 -264.488132) (xy 83.101361 -264.4406)
			(xy 83.093542 -264.391237) (xy 82.786225 -264.391237) (xy 82.786216 -264.391694) (xy 82.778052 -264.441928)
			(xy 82.761936 -264.490202) (xy 82.738285 -264.535265) (xy 82.707712 -264.575951) (xy 82.671008 -264.611206)
			(xy 82.629124 -264.640116) (xy 82.583145 -264.661933) (xy 82.534261 -264.676093) (xy 82.48374 -264.682227)
			(xy 82.432888 -264.680178) (xy 82.383024 -264.669998) (xy 82.335438 -264.651951) (xy 82.291364 -264.626505)
			(xy 82.251942 -264.594318) (xy 82.218194 -264.556224) (xy 82.190993 -264.51321) (xy 82.171045 -264.46639)
			(xy 82.158866 -264.416976) (xy 82.154771 -264.366248) (xy 81.846674 -264.366248) (xy 81.846162 -264.391694)
			(xy 81.837998 -264.441928) (xy 81.821882 -264.490202) (xy 81.798231 -264.535265) (xy 81.767658 -264.575951)
			(xy 81.730954 -264.611206) (xy 81.68907 -264.640116) (xy 81.643091 -264.661933) (xy 81.594207 -264.676093)
			(xy 81.543686 -264.682227) (xy 81.492834 -264.680178) (xy 81.44297 -264.669998) (xy 81.395384 -264.651951)
			(xy 81.35131 -264.626505) (xy 81.311888 -264.594318) (xy 81.27814 -264.556224) (xy 81.250939 -264.51321)
			(xy 81.230991 -264.46639) (xy 81.218812 -264.416976) (xy 81.214717 -264.366248) (xy 80.90916 -264.366248)
			(xy 80.90867 -264.391237) (xy 80.900851 -264.4406) (xy 80.885407 -264.488132) (xy 80.862717 -264.532664)
			(xy 80.833341 -264.573097) (xy 80.798001 -264.608437) (xy 80.757568 -264.637813) (xy 80.713036 -264.660503)
			(xy 80.665504 -264.675947) (xy 80.616141 -264.683766) (xy 80.566163 -264.683766) (xy 80.5168 -264.675947)
			(xy 80.469268 -264.660503) (xy 80.424736 -264.637813) (xy 80.384303 -264.608437) (xy 80.348963 -264.573097)
			(xy 80.319587 -264.532664) (xy 80.296897 -264.488132) (xy 80.281453 -264.4406) (xy 80.273634 -264.391237)
			(xy 79.53248 -264.391237) (xy 79.53248 -265.201243) (xy 79.80348 -265.201243) (xy 79.80348 -265.151265)
			(xy 79.811299 -265.101902) (xy 79.826743 -265.05437) (xy 79.849433 -265.009838) (xy 79.878809 -264.969405)
			(xy 79.914149 -264.934065) (xy 79.954582 -264.904689) (xy 79.999114 -264.881999) (xy 80.046646 -264.866555)
			(xy 80.096009 -264.858736) (xy 80.145987 -264.858736) (xy 80.19535 -264.866555) (xy 80.242882 -264.881999)
			(xy 80.287414 -264.904689) (xy 80.327847 -264.934065) (xy 80.363187 -264.969405) (xy 80.392563 -265.009838)
			(xy 80.415253 -265.05437) (xy 80.430697 -265.101902) (xy 80.438516 -265.151265) (xy 80.439006 -265.176254)
			(xy 80.744817 -265.176254) (xy 80.748912 -265.125526) (xy 80.761091 -265.076112) (xy 80.781039 -265.029292)
			(xy 80.80824 -264.986278) (xy 80.841988 -264.948184) (xy 80.88141 -264.915997) (xy 80.925484 -264.890551)
			(xy 80.97307 -264.872504) (xy 81.022934 -264.862324) (xy 81.073786 -264.860275) (xy 81.124307 -264.866409)
			(xy 81.173191 -264.880569) (xy 81.21917 -264.902386) (xy 81.261054 -264.931296) (xy 81.297758 -264.966551)
			(xy 81.328331 -265.007237) (xy 81.351982 -265.0523) (xy 81.368098 -265.100574) (xy 81.376262 -265.150808)
			(xy 81.376774 -265.176254) (xy 81.376271 -265.201243) (xy 81.683588 -265.201243) (xy 81.683588 -265.151265)
			(xy 81.691407 -265.101902) (xy 81.706851 -265.05437) (xy 81.729541 -265.009838) (xy 81.758917 -264.969405)
			(xy 81.794257 -264.934065) (xy 81.83469 -264.904689) (xy 81.879222 -264.881999) (xy 81.926754 -264.866555)
			(xy 81.976117 -264.858736) (xy 82.026095 -264.858736) (xy 82.075458 -264.866555) (xy 82.12299 -264.881999)
			(xy 82.167522 -264.904689) (xy 82.207955 -264.934065) (xy 82.243295 -264.969405) (xy 82.272671 -265.009838)
			(xy 82.295361 -265.05437) (xy 82.310805 -265.101902) (xy 82.318624 -265.151265) (xy 82.319114 -265.176254)
			(xy 82.318624 -265.201243) (xy 82.623642 -265.201243) (xy 82.623642 -265.151265) (xy 82.631461 -265.101902)
			(xy 82.646905 -265.05437) (xy 82.669595 -265.009838) (xy 82.698971 -264.969405) (xy 82.734311 -264.934065)
			(xy 82.774744 -264.904689) (xy 82.819276 -264.881999) (xy 82.866808 -264.866555) (xy 82.916171 -264.858736)
			(xy 82.966149 -264.858736) (xy 83.015512 -264.866555) (xy 83.063044 -264.881999) (xy 83.107576 -264.904689)
			(xy 83.148009 -264.934065) (xy 83.183349 -264.969405) (xy 83.212725 -265.009838) (xy 83.235415 -265.05437)
			(xy 83.250859 -265.101902) (xy 83.258678 -265.151265) (xy 83.259168 -265.176254) (xy 83.258678 -265.201243)
			(xy 83.563442 -265.201243) (xy 83.563442 -265.151265) (xy 83.571261 -265.101902) (xy 83.586705 -265.05437)
			(xy 83.609395 -265.009838) (xy 83.638771 -264.969405) (xy 83.674111 -264.934065) (xy 83.714544 -264.904689)
			(xy 83.759076 -264.881999) (xy 83.806608 -264.866555) (xy 83.855971 -264.858736) (xy 83.905949 -264.858736)
			(xy 83.955312 -264.866555) (xy 84.002844 -264.881999) (xy 84.047376 -264.904689) (xy 84.087809 -264.934065)
			(xy 84.123149 -264.969405) (xy 84.152525 -265.009838) (xy 84.175215 -265.05437) (xy 84.190659 -265.101902)
			(xy 84.198478 -265.151265) (xy 84.198968 -265.176254) (xy 84.504779 -265.176254) (xy 84.508874 -265.125526)
			(xy 84.521053 -265.076112) (xy 84.541001 -265.029292) (xy 84.568202 -264.986278) (xy 84.60195 -264.948184)
			(xy 84.641372 -264.915997) (xy 84.685446 -264.890551) (xy 84.733032 -264.872504) (xy 84.782896 -264.862324)
			(xy 84.833748 -264.860275) (xy 84.884269 -264.866409) (xy 84.933153 -264.880569) (xy 84.979132 -264.902386)
			(xy 85.021016 -264.931296) (xy 85.05772 -264.966551) (xy 85.088293 -265.007237) (xy 85.111944 -265.0523)
			(xy 85.12806 -265.100574) (xy 85.136224 -265.150808) (xy 85.136736 -265.176254) (xy 85.136233 -265.201243)
			(xy 85.44355 -265.201243) (xy 85.44355 -265.151265) (xy 85.451369 -265.101902) (xy 85.466813 -265.05437)
			(xy 85.489503 -265.009838) (xy 85.518879 -264.969405) (xy 85.554219 -264.934065) (xy 85.594652 -264.904689)
			(xy 85.639184 -264.881999) (xy 85.686716 -264.866555) (xy 85.736079 -264.858736) (xy 85.786057 -264.858736)
			(xy 85.83542 -264.866555) (xy 85.882952 -264.881999) (xy 85.927484 -264.904689) (xy 85.967917 -264.934065)
			(xy 86.003257 -264.969405) (xy 86.032633 -265.009838) (xy 86.055323 -265.05437) (xy 86.070767 -265.101902)
			(xy 86.078586 -265.151265) (xy 86.079076 -265.176254) (xy 86.078586 -265.201243) (xy 86.383604 -265.201243)
			(xy 86.383604 -265.151265) (xy 86.391423 -265.101902) (xy 86.406867 -265.05437) (xy 86.429557 -265.009838)
			(xy 86.458933 -264.969405) (xy 86.494273 -264.934065) (xy 86.534706 -264.904689) (xy 86.579238 -264.881999)
			(xy 86.62677 -264.866555) (xy 86.676133 -264.858736) (xy 86.726111 -264.858736) (xy 86.775474 -264.866555)
			(xy 86.823006 -264.881999) (xy 86.867538 -264.904689) (xy 86.907971 -264.934065) (xy 86.943311 -264.969405)
			(xy 86.972687 -265.009838) (xy 86.995377 -265.05437) (xy 87.010821 -265.101902) (xy 87.01864 -265.151265)
			(xy 87.01913 -265.176254) (xy 87.324687 -265.176254) (xy 87.328782 -265.125526) (xy 87.340961 -265.076112)
			(xy 87.360909 -265.029292) (xy 87.38811 -264.986278) (xy 87.421858 -264.948184) (xy 87.46128 -264.915997)
			(xy 87.505354 -264.890551) (xy 87.55294 -264.872504) (xy 87.602804 -264.862324) (xy 87.653656 -264.860275)
			(xy 87.704177 -264.866409) (xy 87.753061 -264.880569) (xy 87.79904 -264.902386) (xy 87.840924 -264.931296)
			(xy 87.877628 -264.966551) (xy 87.908201 -265.007237) (xy 87.931852 -265.0523) (xy 87.947968 -265.100574)
			(xy 87.956132 -265.150808) (xy 87.956644 -265.176254) (xy 87.956141 -265.201243) (xy 88.263458 -265.201243)
			(xy 88.263458 -265.151265) (xy 88.271277 -265.101902) (xy 88.286721 -265.05437) (xy 88.309411 -265.009838)
			(xy 88.338787 -264.969405) (xy 88.374127 -264.934065) (xy 88.41456 -264.904689) (xy 88.459092 -264.881999)
			(xy 88.506624 -264.866555) (xy 88.555987 -264.858736) (xy 88.605965 -264.858736) (xy 88.655328 -264.866555)
			(xy 88.70286 -264.881999) (xy 88.747392 -264.904689) (xy 88.787825 -264.934065) (xy 88.823165 -264.969405)
			(xy 88.852541 -265.009838) (xy 88.875231 -265.05437) (xy 88.890675 -265.101902) (xy 88.898494 -265.151265)
			(xy 88.898984 -265.176254) (xy 88.898494 -265.201243) (xy 89.203512 -265.201243) (xy 89.203512 -265.151265)
			(xy 89.211331 -265.101902) (xy 89.226775 -265.05437) (xy 89.249465 -265.009838) (xy 89.278841 -264.969405)
			(xy 89.314181 -264.934065) (xy 89.354614 -264.904689) (xy 89.399146 -264.881999) (xy 89.446678 -264.866555)
			(xy 89.496041 -264.858736) (xy 89.546019 -264.858736) (xy 89.595382 -264.866555) (xy 89.642914 -264.881999)
			(xy 89.687446 -264.904689) (xy 89.727879 -264.934065) (xy 89.763219 -264.969405) (xy 89.792595 -265.009838)
			(xy 89.815285 -265.05437) (xy 89.830729 -265.101902) (xy 89.838548 -265.151265) (xy 89.839038 -265.176254)
			(xy 89.838548 -265.201243) (xy 90.143566 -265.201243) (xy 90.143566 -265.151265) (xy 90.151385 -265.101902)
			(xy 90.166829 -265.05437) (xy 90.189519 -265.009838) (xy 90.218895 -264.969405) (xy 90.254235 -264.934065)
			(xy 90.294668 -264.904689) (xy 90.3392 -264.881999) (xy 90.386732 -264.866555) (xy 90.436095 -264.858736)
			(xy 90.486073 -264.858736) (xy 90.535436 -264.866555) (xy 90.582968 -264.881999) (xy 90.6275 -264.904689)
			(xy 90.667933 -264.934065) (xy 90.703273 -264.969405) (xy 90.732649 -265.009838) (xy 90.755339 -265.05437)
			(xy 90.770783 -265.101902) (xy 90.778602 -265.151265) (xy 90.779092 -265.176254) (xy 91.084903 -265.176254)
			(xy 91.088998 -265.125526) (xy 91.101177 -265.076112) (xy 91.121125 -265.029292) (xy 91.148326 -264.986278)
			(xy 91.182074 -264.948184) (xy 91.221496 -264.915997) (xy 91.26557 -264.890551) (xy 91.313156 -264.872504)
			(xy 91.36302 -264.862324) (xy 91.413872 -264.860275) (xy 91.464393 -264.866409) (xy 91.513277 -264.880569)
			(xy 91.559256 -264.902386) (xy 91.60114 -264.931296) (xy 91.637844 -264.966551) (xy 91.668417 -265.007237)
			(xy 91.692068 -265.0523) (xy 91.708184 -265.100574) (xy 91.716348 -265.150808) (xy 91.71686 -265.176254)
			(xy 91.716357 -265.201243) (xy 92.02342 -265.201243) (xy 92.02342 -265.151265) (xy 92.031239 -265.101902)
			(xy 92.046683 -265.05437) (xy 92.069373 -265.009838) (xy 92.098749 -264.969405) (xy 92.134089 -264.934065)
			(xy 92.174522 -264.904689) (xy 92.219054 -264.881999) (xy 92.266586 -264.866555) (xy 92.315949 -264.858736)
			(xy 92.365927 -264.858736) (xy 92.41529 -264.866555) (xy 92.462822 -264.881999) (xy 92.507354 -264.904689)
			(xy 92.547787 -264.934065) (xy 92.583127 -264.969405) (xy 92.612503 -265.009838) (xy 92.635193 -265.05437)
			(xy 92.650637 -265.101902) (xy 92.658456 -265.151265) (xy 92.658946 -265.176254) (xy 92.658456 -265.201243)
			(xy 92.963474 -265.201243) (xy 92.963474 -265.151265) (xy 92.971293 -265.101902) (xy 92.986737 -265.05437)
			(xy 93.009427 -265.009838) (xy 93.038803 -264.969405) (xy 93.074143 -264.934065) (xy 93.114576 -264.904689)
			(xy 93.159108 -264.881999) (xy 93.20664 -264.866555) (xy 93.256003 -264.858736) (xy 93.305981 -264.858736)
			(xy 93.355344 -264.866555) (xy 93.402876 -264.881999) (xy 93.447408 -264.904689) (xy 93.487841 -264.934065)
			(xy 93.523181 -264.969405) (xy 93.552557 -265.009838) (xy 93.575247 -265.05437) (xy 93.590691 -265.101902)
			(xy 93.59851 -265.151265) (xy 93.599 -265.176254) (xy 93.904811 -265.176254) (xy 93.908906 -265.125526)
			(xy 93.921085 -265.076112) (xy 93.941033 -265.029292) (xy 93.968234 -264.986278) (xy 94.001982 -264.948184)
			(xy 94.041404 -264.915997) (xy 94.085478 -264.890551) (xy 94.133064 -264.872504) (xy 94.182928 -264.862324)
			(xy 94.23378 -264.860275) (xy 94.284301 -264.866409) (xy 94.333185 -264.880569) (xy 94.379164 -264.902386)
			(xy 94.421048 -264.931296) (xy 94.457752 -264.966551) (xy 94.488325 -265.007237) (xy 94.511976 -265.0523)
			(xy 94.528092 -265.100574) (xy 94.536256 -265.150808) (xy 94.536768 -265.176254) (xy 94.536265 -265.201243)
			(xy 94.843582 -265.201243) (xy 94.843582 -265.151265) (xy 94.851401 -265.101902) (xy 94.866845 -265.05437)
			(xy 94.889535 -265.009838) (xy 94.918911 -264.969405) (xy 94.954251 -264.934065) (xy 94.994684 -264.904689)
			(xy 95.039216 -264.881999) (xy 95.086748 -264.866555) (xy 95.136111 -264.858736) (xy 95.186089 -264.858736)
			(xy 95.235452 -264.866555) (xy 95.282984 -264.881999) (xy 95.327516 -264.904689) (xy 95.367949 -264.934065)
			(xy 95.403289 -264.969405) (xy 95.432665 -265.009838) (xy 95.455355 -265.05437) (xy 95.470799 -265.101902)
			(xy 95.478618 -265.151265) (xy 95.479108 -265.176254) (xy 95.478618 -265.201243) (xy 95.783636 -265.201243)
			(xy 95.783636 -265.151265) (xy 95.791455 -265.101902) (xy 95.806899 -265.05437) (xy 95.829589 -265.009838)
			(xy 95.858965 -264.969405) (xy 95.894305 -264.934065) (xy 95.934738 -264.904689) (xy 95.97927 -264.881999)
			(xy 96.026802 -264.866555) (xy 96.076165 -264.858736) (xy 96.126143 -264.858736) (xy 96.175506 -264.866555)
			(xy 96.223038 -264.881999) (xy 96.26757 -264.904689) (xy 96.308003 -264.934065) (xy 96.343343 -264.969405)
			(xy 96.372719 -265.009838) (xy 96.395409 -265.05437) (xy 96.410853 -265.101902) (xy 96.418672 -265.151265)
			(xy 96.419162 -265.176254) (xy 97.663 -265.176254) (xy 97.6636 -265.14827) (xy 97.673378 -265.093163)
			(xy 97.692641 -265.040615) (xy 97.720796 -264.992244) (xy 97.738438 -264.970514) (xy 97.743876 -264.963432)
			(xy 97.749983 -264.946668) (xy 97.750376 -264.937748) (xy 97.750376 -264.895838) (xy 97.750677 -264.874786)
			(xy 97.758682 -264.833455) (xy 97.774624 -264.794492) (xy 97.797888 -264.759405) (xy 97.827573 -264.729553)
			(xy 97.862528 -264.706091) (xy 97.901401 -264.689929) (xy 97.942686 -264.681692) (xy 97.963736 -264.681208)
			(xy 98.089974 -264.681208) (xy 98.098931 -264.680865) (xy 98.115759 -264.674729) (xy 98.129438 -264.663166)
			(xy 98.13417 -264.655554) (xy 98.177604 -264.5791) (xy 98.181749 -264.571168) (xy 98.184768 -264.553538)
			(xy 98.18157 -264.535939) (xy 98.17735 -264.528046) (xy 98.163509 -264.503345) (xy 98.143794 -264.450275)
			(xy 98.133774 -264.394555) (xy 98.133154 -264.366248) (xy 98.133644 -264.341259) (xy 98.141463 -264.291896)
			(xy 98.156907 -264.244364) (xy 98.179597 -264.199832) (xy 98.208973 -264.159399) (xy 98.244313 -264.124059)
			(xy 98.284746 -264.094683) (xy 98.329278 -264.071993) (xy 98.37681 -264.056549) (xy 98.426173 -264.04873)
			(xy 98.476151 -264.04873) (xy 98.525514 -264.056549) (xy 98.573046 -264.071993) (xy 98.617578 -264.094683)
			(xy 98.658011 -264.124059) (xy 98.693351 -264.159399) (xy 98.722727 -264.199832) (xy 98.745417 -264.244364)
			(xy 98.760861 -264.291896) (xy 98.76868 -264.341259) (xy 98.76917 -264.366248) (xy 98.768648 -264.392974)
			(xy 98.759719 -264.445674) (xy 98.742105 -264.49614) (xy 98.716302 -264.542951) (xy 98.683035 -264.584788)
			(xy 98.643241 -264.620475) (xy 98.598041 -264.649005) (xy 98.548706 -264.669577) (xy 98.52279 -264.676128)
			(xy 98.511802 -264.679336) (xy 98.493962 -264.693628) (xy 98.484059 -264.714229) (xy 98.48342 -264.725658)
			(xy 98.48342 -265.196066) (xy 99.528376 -265.196066) (xy 99.528376 -265.195558) (xy 99.528376 -264.895838)
			(xy 99.528677 -264.874786) (xy 99.536682 -264.833455) (xy 99.552624 -264.794492) (xy 99.575888 -264.759405)
			(xy 99.605573 -264.729553) (xy 99.640528 -264.706091) (xy 99.679401 -264.689929) (xy 99.720686 -264.681692)
			(xy 99.741736 -264.681208) (xy 99.996752 -264.681208) (xy 99.996752 -264.690352) (xy 99.997326 -264.700351)
			(xy 100.004961 -264.718832) (xy 100.019087 -264.732985) (xy 100.037554 -264.740655) (xy 100.047552 -264.741152)
			(xy 100.155248 -264.741152) (xy 100.165265 -264.74075) (xy 100.183767 -264.733066) (xy 100.19792 -264.718886)
			(xy 100.205569 -264.70037) (xy 100.206048 -264.690352) (xy 100.206048 -264.676382) (xy 100.191824 -264.652506)
			(xy 100.179378 -264.645902) (xy 100.158122 -264.633888) (xy 100.119277 -264.604309) (xy 100.085406 -264.569142)
			(xy 100.057305 -264.529215) (xy 100.035633 -264.485463) (xy 100.020899 -264.438914) (xy 100.013448 -264.390661)
			(xy 100.013008 -264.366248) (xy 100.013498 -264.341259) (xy 100.021317 -264.291896) (xy 100.036761 -264.244364)
			(xy 100.059451 -264.199832) (xy 100.088827 -264.159399) (xy 100.124167 -264.124059) (xy 100.1646 -264.094683)
			(xy 100.209132 -264.071993) (xy 100.256664 -264.056549) (xy 100.306027 -264.04873) (xy 100.356005 -264.04873)
			(xy 100.405368 -264.056549) (xy 100.4529 -264.071993) (xy 100.497432 -264.094683) (xy 100.537865 -264.124059)
			(xy 100.573205 -264.159399) (xy 100.602581 -264.199832) (xy 100.625271 -264.244364) (xy 100.640715 -264.291896)
			(xy 100.648534 -264.341259) (xy 100.649024 -264.366248) (xy 100.648452 -264.392653) (xy 100.639706 -264.444733)
			(xy 100.622479 -264.494654) (xy 100.597243 -264.541044) (xy 100.564693 -264.582629) (xy 100.525722 -264.618268)
			(xy 100.4814 -264.646981) (xy 100.432944 -264.667979) (xy 100.381686 -264.680687) (xy 100.3554 -264.68324)
			(xy 100.345748 -264.684002) (xy 100.32873 -264.69213) (xy 100.274882 -264.750042) (xy 100.268743 -264.757329)
			(xy 100.261821 -264.775067) (xy 100.26142 -264.784586) (xy 100.26142 -265.299952) (xy 100.260942 -265.309968)
			(xy 100.253291 -265.32848) (xy 100.239137 -265.342653) (xy 100.220635 -265.350328) (xy 100.21062 -265.350752)
			(xy 100.153216 -265.350752) (xy 100.141566 -265.351384) (xy 100.120666 -265.361698) (xy 100.113084 -265.370564)
			(xy 100.097891 -265.389451) (xy 100.06278 -265.422866) (xy 100.023012 -265.450575) (xy 99.979503 -265.471937)
			(xy 99.933261 -265.48646) (xy 99.885351 -265.493807) (xy 99.861116 -265.494262) (xy 99.835656 -265.493744)
			(xy 99.785386 -265.485625) (xy 99.73705 -265.469607) (xy 99.69188 -265.4461) (xy 99.651028 -265.415701)
			(xy 99.615535 -265.379188) (xy 99.600512 -265.358626) (xy 99.594162 -265.35126) (xy 99.578901 -265.335855)
			(xy 99.554292 -265.300164) (xy 99.53737 -265.260249) (xy 99.52883 -265.217745) (xy 99.528376 -265.196066)
			(xy 98.48342 -265.196066) (xy 98.48342 -265.299952) (xy 98.482942 -265.309968) (xy 98.475291 -265.32848)
			(xy 98.461137 -265.342653) (xy 98.442635 -265.350328) (xy 98.43262 -265.350752) (xy 98.272854 -265.350752)
			(xy 98.261287 -265.351335) (xy 98.240515 -265.361519) (xy 98.232976 -265.37031) (xy 98.229674 -265.374374)
			(xy 98.22942 -265.374628) (xy 98.224562 -265.381516) (xy 98.219109 -265.39745) (xy 98.218752 -265.40587)
			(xy 98.218752 -265.410696) (xy 98.205798 -265.410696) (xy 98.189542 -265.416538) (xy 98.182684 -265.422126)
			(xy 98.161192 -265.439012) (xy 98.113638 -265.465944) (xy 98.06218 -265.484352) (xy 98.008334 -265.493695)
			(xy 97.981008 -265.494262) (xy 97.956015 -265.493836) (xy 97.906643 -265.486017) (xy 97.859104 -265.47057)
			(xy 97.814566 -265.447875) (xy 97.774127 -265.418492) (xy 97.738783 -265.383144) (xy 97.709405 -265.342702)
			(xy 97.686716 -265.298161) (xy 97.671274 -265.25062) (xy 97.663461 -265.201247) (xy 97.663 -265.176254)
			(xy 96.419162 -265.176254) (xy 96.418672 -265.201243) (xy 96.410853 -265.250606) (xy 96.395409 -265.298138)
			(xy 96.372719 -265.34267) (xy 96.343343 -265.383103) (xy 96.308003 -265.418443) (xy 96.26757 -265.447819)
			(xy 96.223038 -265.470509) (xy 96.175506 -265.485953) (xy 96.126143 -265.493772) (xy 96.076165 -265.493772)
			(xy 96.026802 -265.485953) (xy 95.97927 -265.470509) (xy 95.934738 -265.447819) (xy 95.894305 -265.418443)
			(xy 95.858965 -265.383103) (xy 95.829589 -265.34267) (xy 95.806899 -265.298138) (xy 95.791455 -265.250606)
			(xy 95.783636 -265.201243) (xy 95.478618 -265.201243) (xy 95.470799 -265.250606) (xy 95.455355 -265.298138)
			(xy 95.432665 -265.34267) (xy 95.403289 -265.383103) (xy 95.367949 -265.418443) (xy 95.327516 -265.447819)
			(xy 95.282984 -265.470509) (xy 95.235452 -265.485953) (xy 95.186089 -265.493772) (xy 95.136111 -265.493772)
			(xy 95.086748 -265.485953) (xy 95.039216 -265.470509) (xy 94.994684 -265.447819) (xy 94.954251 -265.418443)
			(xy 94.918911 -265.383103) (xy 94.889535 -265.34267) (xy 94.866845 -265.298138) (xy 94.851401 -265.250606)
			(xy 94.843582 -265.201243) (xy 94.536265 -265.201243) (xy 94.536256 -265.2017) (xy 94.528092 -265.251934)
			(xy 94.511976 -265.300208) (xy 94.488325 -265.345271) (xy 94.457752 -265.385957) (xy 94.421048 -265.421212)
			(xy 94.379164 -265.450122) (xy 94.333185 -265.471939) (xy 94.284301 -265.486099) (xy 94.23378 -265.492233)
			(xy 94.182928 -265.490184) (xy 94.133064 -265.480004) (xy 94.085478 -265.461957) (xy 94.041404 -265.436511)
			(xy 94.001982 -265.404324) (xy 93.968234 -265.36623) (xy 93.941033 -265.323216) (xy 93.921085 -265.276396)
			(xy 93.908906 -265.226982) (xy 93.904811 -265.176254) (xy 93.599 -265.176254) (xy 93.59851 -265.201243)
			(xy 93.590691 -265.250606) (xy 93.575247 -265.298138) (xy 93.552557 -265.34267) (xy 93.523181 -265.383103)
			(xy 93.487841 -265.418443) (xy 93.447408 -265.447819) (xy 93.402876 -265.470509) (xy 93.355344 -265.485953)
			(xy 93.305981 -265.493772) (xy 93.256003 -265.493772) (xy 93.20664 -265.485953) (xy 93.159108 -265.470509)
			(xy 93.114576 -265.447819) (xy 93.074143 -265.418443) (xy 93.038803 -265.383103) (xy 93.009427 -265.34267)
			(xy 92.986737 -265.298138) (xy 92.971293 -265.250606) (xy 92.963474 -265.201243) (xy 92.658456 -265.201243)
			(xy 92.650637 -265.250606) (xy 92.635193 -265.298138) (xy 92.612503 -265.34267) (xy 92.583127 -265.383103)
			(xy 92.547787 -265.418443) (xy 92.507354 -265.447819) (xy 92.462822 -265.470509) (xy 92.41529 -265.485953)
			(xy 92.365927 -265.493772) (xy 92.315949 -265.493772) (xy 92.266586 -265.485953) (xy 92.219054 -265.470509)
			(xy 92.174522 -265.447819) (xy 92.134089 -265.418443) (xy 92.098749 -265.383103) (xy 92.069373 -265.34267)
			(xy 92.046683 -265.298138) (xy 92.031239 -265.250606) (xy 92.02342 -265.201243) (xy 91.716357 -265.201243)
			(xy 91.716348 -265.2017) (xy 91.708184 -265.251934) (xy 91.692068 -265.300208) (xy 91.668417 -265.345271)
			(xy 91.637844 -265.385957) (xy 91.60114 -265.421212) (xy 91.559256 -265.450122) (xy 91.513277 -265.471939)
			(xy 91.464393 -265.486099) (xy 91.413872 -265.492233) (xy 91.36302 -265.490184) (xy 91.313156 -265.480004)
			(xy 91.26557 -265.461957) (xy 91.221496 -265.436511) (xy 91.182074 -265.404324) (xy 91.148326 -265.36623)
			(xy 91.121125 -265.323216) (xy 91.101177 -265.276396) (xy 91.088998 -265.226982) (xy 91.084903 -265.176254)
			(xy 90.779092 -265.176254) (xy 90.778602 -265.201243) (xy 90.770783 -265.250606) (xy 90.755339 -265.298138)
			(xy 90.732649 -265.34267) (xy 90.703273 -265.383103) (xy 90.667933 -265.418443) (xy 90.6275 -265.447819)
			(xy 90.582968 -265.470509) (xy 90.535436 -265.485953) (xy 90.486073 -265.493772) (xy 90.436095 -265.493772)
			(xy 90.386732 -265.485953) (xy 90.3392 -265.470509) (xy 90.294668 -265.447819) (xy 90.254235 -265.418443)
			(xy 90.218895 -265.383103) (xy 90.189519 -265.34267) (xy 90.166829 -265.298138) (xy 90.151385 -265.250606)
			(xy 90.143566 -265.201243) (xy 89.838548 -265.201243) (xy 89.830729 -265.250606) (xy 89.815285 -265.298138)
			(xy 89.792595 -265.34267) (xy 89.763219 -265.383103) (xy 89.727879 -265.418443) (xy 89.687446 -265.447819)
			(xy 89.642914 -265.470509) (xy 89.595382 -265.485953) (xy 89.546019 -265.493772) (xy 89.496041 -265.493772)
			(xy 89.446678 -265.485953) (xy 89.399146 -265.470509) (xy 89.354614 -265.447819) (xy 89.314181 -265.418443)
			(xy 89.278841 -265.383103) (xy 89.249465 -265.34267) (xy 89.226775 -265.298138) (xy 89.211331 -265.250606)
			(xy 89.203512 -265.201243) (xy 88.898494 -265.201243) (xy 88.890675 -265.250606) (xy 88.875231 -265.298138)
			(xy 88.852541 -265.34267) (xy 88.823165 -265.383103) (xy 88.787825 -265.418443) (xy 88.747392 -265.447819)
			(xy 88.70286 -265.470509) (xy 88.655328 -265.485953) (xy 88.605965 -265.493772) (xy 88.555987 -265.493772)
			(xy 88.506624 -265.485953) (xy 88.459092 -265.470509) (xy 88.41456 -265.447819) (xy 88.374127 -265.418443)
			(xy 88.338787 -265.383103) (xy 88.309411 -265.34267) (xy 88.286721 -265.298138) (xy 88.271277 -265.250606)
			(xy 88.263458 -265.201243) (xy 87.956141 -265.201243) (xy 87.956132 -265.2017) (xy 87.947968 -265.251934)
			(xy 87.931852 -265.300208) (xy 87.908201 -265.345271) (xy 87.877628 -265.385957) (xy 87.840924 -265.421212)
			(xy 87.79904 -265.450122) (xy 87.753061 -265.471939) (xy 87.704177 -265.486099) (xy 87.653656 -265.492233)
			(xy 87.602804 -265.490184) (xy 87.55294 -265.480004) (xy 87.505354 -265.461957) (xy 87.46128 -265.436511)
			(xy 87.421858 -265.404324) (xy 87.38811 -265.36623) (xy 87.360909 -265.323216) (xy 87.340961 -265.276396)
			(xy 87.328782 -265.226982) (xy 87.324687 -265.176254) (xy 87.01913 -265.176254) (xy 87.01864 -265.201243)
			(xy 87.010821 -265.250606) (xy 86.995377 -265.298138) (xy 86.972687 -265.34267) (xy 86.943311 -265.383103)
			(xy 86.907971 -265.418443) (xy 86.867538 -265.447819) (xy 86.823006 -265.470509) (xy 86.775474 -265.485953)
			(xy 86.726111 -265.493772) (xy 86.676133 -265.493772) (xy 86.62677 -265.485953) (xy 86.579238 -265.470509)
			(xy 86.534706 -265.447819) (xy 86.494273 -265.418443) (xy 86.458933 -265.383103) (xy 86.429557 -265.34267)
			(xy 86.406867 -265.298138) (xy 86.391423 -265.250606) (xy 86.383604 -265.201243) (xy 86.078586 -265.201243)
			(xy 86.070767 -265.250606) (xy 86.055323 -265.298138) (xy 86.032633 -265.34267) (xy 86.003257 -265.383103)
			(xy 85.967917 -265.418443) (xy 85.927484 -265.447819) (xy 85.882952 -265.470509) (xy 85.83542 -265.485953)
			(xy 85.786057 -265.493772) (xy 85.736079 -265.493772) (xy 85.686716 -265.485953) (xy 85.639184 -265.470509)
			(xy 85.594652 -265.447819) (xy 85.554219 -265.418443) (xy 85.518879 -265.383103) (xy 85.489503 -265.34267)
			(xy 85.466813 -265.298138) (xy 85.451369 -265.250606) (xy 85.44355 -265.201243) (xy 85.136233 -265.201243)
			(xy 85.136224 -265.2017) (xy 85.12806 -265.251934) (xy 85.111944 -265.300208) (xy 85.088293 -265.345271)
			(xy 85.05772 -265.385957) (xy 85.021016 -265.421212) (xy 84.979132 -265.450122) (xy 84.933153 -265.471939)
			(xy 84.884269 -265.486099) (xy 84.833748 -265.492233) (xy 84.782896 -265.490184) (xy 84.733032 -265.480004)
			(xy 84.685446 -265.461957) (xy 84.641372 -265.436511) (xy 84.60195 -265.404324) (xy 84.568202 -265.36623)
			(xy 84.541001 -265.323216) (xy 84.521053 -265.276396) (xy 84.508874 -265.226982) (xy 84.504779 -265.176254)
			(xy 84.198968 -265.176254) (xy 84.198478 -265.201243) (xy 84.190659 -265.250606) (xy 84.175215 -265.298138)
			(xy 84.152525 -265.34267) (xy 84.123149 -265.383103) (xy 84.087809 -265.418443) (xy 84.047376 -265.447819)
			(xy 84.002844 -265.470509) (xy 83.955312 -265.485953) (xy 83.905949 -265.493772) (xy 83.855971 -265.493772)
			(xy 83.806608 -265.485953) (xy 83.759076 -265.470509) (xy 83.714544 -265.447819) (xy 83.674111 -265.418443)
			(xy 83.638771 -265.383103) (xy 83.609395 -265.34267) (xy 83.586705 -265.298138) (xy 83.571261 -265.250606)
			(xy 83.563442 -265.201243) (xy 83.258678 -265.201243) (xy 83.250859 -265.250606) (xy 83.235415 -265.298138)
			(xy 83.212725 -265.34267) (xy 83.183349 -265.383103) (xy 83.148009 -265.418443) (xy 83.107576 -265.447819)
			(xy 83.063044 -265.470509) (xy 83.015512 -265.485953) (xy 82.966149 -265.493772) (xy 82.916171 -265.493772)
			(xy 82.866808 -265.485953) (xy 82.819276 -265.470509) (xy 82.774744 -265.447819) (xy 82.734311 -265.418443)
			(xy 82.698971 -265.383103) (xy 82.669595 -265.34267) (xy 82.646905 -265.298138) (xy 82.631461 -265.250606)
			(xy 82.623642 -265.201243) (xy 82.318624 -265.201243) (xy 82.310805 -265.250606) (xy 82.295361 -265.298138)
			(xy 82.272671 -265.34267) (xy 82.243295 -265.383103) (xy 82.207955 -265.418443) (xy 82.167522 -265.447819)
			(xy 82.12299 -265.470509) (xy 82.075458 -265.485953) (xy 82.026095 -265.493772) (xy 81.976117 -265.493772)
			(xy 81.926754 -265.485953) (xy 81.879222 -265.470509) (xy 81.83469 -265.447819) (xy 81.794257 -265.418443)
			(xy 81.758917 -265.383103) (xy 81.729541 -265.34267) (xy 81.706851 -265.298138) (xy 81.691407 -265.250606)
			(xy 81.683588 -265.201243) (xy 81.376271 -265.201243) (xy 81.376262 -265.2017) (xy 81.368098 -265.251934)
			(xy 81.351982 -265.300208) (xy 81.328331 -265.345271) (xy 81.297758 -265.385957) (xy 81.261054 -265.421212)
			(xy 81.21917 -265.450122) (xy 81.173191 -265.471939) (xy 81.124307 -265.486099) (xy 81.073786 -265.492233)
			(xy 81.022934 -265.490184) (xy 80.97307 -265.480004) (xy 80.925484 -265.461957) (xy 80.88141 -265.436511)
			(xy 80.841988 -265.404324) (xy 80.80824 -265.36623) (xy 80.781039 -265.323216) (xy 80.761091 -265.276396)
			(xy 80.748912 -265.226982) (xy 80.744817 -265.176254) (xy 80.439006 -265.176254) (xy 80.438516 -265.201243)
			(xy 80.430697 -265.250606) (xy 80.415253 -265.298138) (xy 80.392563 -265.34267) (xy 80.363187 -265.383103)
			(xy 80.327847 -265.418443) (xy 80.287414 -265.447819) (xy 80.242882 -265.470509) (xy 80.19535 -265.485953)
			(xy 80.145987 -265.493772) (xy 80.096009 -265.493772) (xy 80.046646 -265.485953) (xy 79.999114 -265.470509)
			(xy 79.954582 -265.447819) (xy 79.914149 -265.418443) (xy 79.878809 -265.383103) (xy 79.849433 -265.34267)
			(xy 79.826743 -265.298138) (xy 79.811299 -265.250606) (xy 79.80348 -265.201243) (xy 79.53248 -265.201243)
			(xy 79.53248 -266.011249) (xy 81.213434 -266.011249) (xy 81.213434 -265.961271) (xy 81.221253 -265.911908)
			(xy 81.236697 -265.864376) (xy 81.259387 -265.819844) (xy 81.288763 -265.779411) (xy 81.324103 -265.744071)
			(xy 81.364536 -265.714695) (xy 81.409068 -265.692005) (xy 81.4566 -265.676561) (xy 81.505963 -265.668742)
			(xy 81.555941 -265.668742) (xy 81.605304 -265.676561) (xy 81.652836 -265.692005) (xy 81.697368 -265.714695)
			(xy 81.737801 -265.744071) (xy 81.773141 -265.779411) (xy 81.802517 -265.819844) (xy 81.825207 -265.864376)
			(xy 81.840651 -265.911908) (xy 81.84847 -265.961271) (xy 81.84896 -265.98626) (xy 82.154771 -265.98626)
			(xy 82.158866 -265.935532) (xy 82.171045 -265.886118) (xy 82.190993 -265.839298) (xy 82.218194 -265.796284)
			(xy 82.251942 -265.75819) (xy 82.291364 -265.726003) (xy 82.335438 -265.700557) (xy 82.383024 -265.68251)
			(xy 82.432888 -265.67233) (xy 82.48374 -265.670281) (xy 82.534261 -265.676415) (xy 82.583145 -265.690575)
			(xy 82.629124 -265.712392) (xy 82.671008 -265.741302) (xy 82.707712 -265.776557) (xy 82.738285 -265.817243)
			(xy 82.761936 -265.862306) (xy 82.778052 -265.91058) (xy 82.786216 -265.960814) (xy 82.786728 -265.98626)
			(xy 82.786225 -266.011249) (xy 83.093542 -266.011249) (xy 83.093542 -265.961271) (xy 83.101361 -265.911908)
			(xy 83.116805 -265.864376) (xy 83.139495 -265.819844) (xy 83.168871 -265.779411) (xy 83.204211 -265.744071)
			(xy 83.244644 -265.714695) (xy 83.289176 -265.692005) (xy 83.336708 -265.676561) (xy 83.386071 -265.668742)
			(xy 83.436049 -265.668742) (xy 83.485412 -265.676561) (xy 83.532944 -265.692005) (xy 83.577476 -265.714695)
			(xy 83.617909 -265.744071) (xy 83.653249 -265.779411) (xy 83.682625 -265.819844) (xy 83.705315 -265.864376)
			(xy 83.720759 -265.911908) (xy 83.728578 -265.961271) (xy 83.729068 -265.98626) (xy 83.728578 -266.011249)
			(xy 84.033596 -266.011249) (xy 84.033596 -265.961271) (xy 84.041415 -265.911908) (xy 84.056859 -265.864376)
			(xy 84.079549 -265.819844) (xy 84.108925 -265.779411) (xy 84.144265 -265.744071) (xy 84.184698 -265.714695)
			(xy 84.22923 -265.692005) (xy 84.276762 -265.676561) (xy 84.326125 -265.668742) (xy 84.376103 -265.668742)
			(xy 84.425466 -265.676561) (xy 84.472998 -265.692005) (xy 84.51753 -265.714695) (xy 84.557963 -265.744071)
			(xy 84.593303 -265.779411) (xy 84.622679 -265.819844) (xy 84.645369 -265.864376) (xy 84.660813 -265.911908)
			(xy 84.668632 -265.961271) (xy 84.669122 -265.98626) (xy 84.668632 -266.011249) (xy 84.973396 -266.011249)
			(xy 84.973396 -265.961271) (xy 84.981215 -265.911908) (xy 84.996659 -265.864376) (xy 85.019349 -265.819844)
			(xy 85.048725 -265.779411) (xy 85.084065 -265.744071) (xy 85.124498 -265.714695) (xy 85.16903 -265.692005)
			(xy 85.216562 -265.676561) (xy 85.265925 -265.668742) (xy 85.315903 -265.668742) (xy 85.365266 -265.676561)
			(xy 85.412798 -265.692005) (xy 85.45733 -265.714695) (xy 85.497763 -265.744071) (xy 85.533103 -265.779411)
			(xy 85.562479 -265.819844) (xy 85.585169 -265.864376) (xy 85.600613 -265.911908) (xy 85.608432 -265.961271)
			(xy 85.608922 -265.98626) (xy 85.914733 -265.98626) (xy 85.918828 -265.935532) (xy 85.931007 -265.886118)
			(xy 85.950955 -265.839298) (xy 85.978156 -265.796284) (xy 86.011904 -265.75819) (xy 86.051326 -265.726003)
			(xy 86.0954 -265.700557) (xy 86.142986 -265.68251) (xy 86.19285 -265.67233) (xy 86.243702 -265.670281)
			(xy 86.294223 -265.676415) (xy 86.343107 -265.690575) (xy 86.389086 -265.712392) (xy 86.43097 -265.741302)
			(xy 86.467674 -265.776557) (xy 86.498247 -265.817243) (xy 86.521898 -265.862306) (xy 86.538014 -265.91058)
			(xy 86.546178 -265.960814) (xy 86.54669 -265.98626) (xy 86.546187 -266.011249) (xy 87.793558 -266.011249)
			(xy 87.793558 -265.961271) (xy 87.801377 -265.911908) (xy 87.816821 -265.864376) (xy 87.839511 -265.819844)
			(xy 87.868887 -265.779411) (xy 87.904227 -265.744071) (xy 87.94466 -265.714695) (xy 87.989192 -265.692005)
			(xy 88.036724 -265.676561) (xy 88.086087 -265.668742) (xy 88.136065 -265.668742) (xy 88.185428 -265.676561)
			(xy 88.23296 -265.692005) (xy 88.277492 -265.714695) (xy 88.317925 -265.744071) (xy 88.353265 -265.779411)
			(xy 88.382641 -265.819844) (xy 88.405331 -265.864376) (xy 88.420775 -265.911908) (xy 88.428594 -265.961271)
			(xy 88.429084 -265.98626) (xy 88.734895 -265.98626) (xy 88.73899 -265.935532) (xy 88.751169 -265.886118)
			(xy 88.771117 -265.839298) (xy 88.798318 -265.796284) (xy 88.832066 -265.75819) (xy 88.871488 -265.726003)
			(xy 88.915562 -265.700557) (xy 88.963148 -265.68251) (xy 89.013012 -265.67233) (xy 89.063864 -265.670281)
			(xy 89.114385 -265.676415) (xy 89.163269 -265.690575) (xy 89.209248 -265.712392) (xy 89.251132 -265.741302)
			(xy 89.287836 -265.776557) (xy 89.318409 -265.817243) (xy 89.34206 -265.862306) (xy 89.358176 -265.91058)
			(xy 89.36634 -265.960814) (xy 89.366852 -265.98626) (xy 89.366349 -266.011249) (xy 89.673412 -266.011249)
			(xy 89.673412 -265.961271) (xy 89.681231 -265.911908) (xy 89.696675 -265.864376) (xy 89.719365 -265.819844)
			(xy 89.748741 -265.779411) (xy 89.784081 -265.744071) (xy 89.824514 -265.714695) (xy 89.869046 -265.692005)
			(xy 89.916578 -265.676561) (xy 89.965941 -265.668742) (xy 90.015919 -265.668742) (xy 90.065282 -265.676561)
			(xy 90.112814 -265.692005) (xy 90.157346 -265.714695) (xy 90.197779 -265.744071) (xy 90.233119 -265.779411)
			(xy 90.262495 -265.819844) (xy 90.285185 -265.864376) (xy 90.300629 -265.911908) (xy 90.308448 -265.961271)
			(xy 90.308938 -265.98626) (xy 90.308448 -266.011249) (xy 90.613466 -266.011249) (xy 90.613466 -265.961271)
			(xy 90.621285 -265.911908) (xy 90.636729 -265.864376) (xy 90.659419 -265.819844) (xy 90.688795 -265.779411)
			(xy 90.724135 -265.744071) (xy 90.764568 -265.714695) (xy 90.8091 -265.692005) (xy 90.856632 -265.676561)
			(xy 90.905995 -265.668742) (xy 90.955973 -265.668742) (xy 91.005336 -265.676561) (xy 91.052868 -265.692005)
			(xy 91.0974 -265.714695) (xy 91.137833 -265.744071) (xy 91.173173 -265.779411) (xy 91.202549 -265.819844)
			(xy 91.225239 -265.864376) (xy 91.240683 -265.911908) (xy 91.248502 -265.961271) (xy 91.248992 -265.98626)
			(xy 91.248502 -266.011249) (xy 91.55352 -266.011249) (xy 91.55352 -265.961271) (xy 91.561339 -265.911908)
			(xy 91.576783 -265.864376) (xy 91.599473 -265.819844) (xy 91.628849 -265.779411) (xy 91.664189 -265.744071)
			(xy 91.704622 -265.714695) (xy 91.749154 -265.692005) (xy 91.796686 -265.676561) (xy 91.846049 -265.668742)
			(xy 91.896027 -265.668742) (xy 91.94539 -265.676561) (xy 91.992922 -265.692005) (xy 92.037454 -265.714695)
			(xy 92.077887 -265.744071) (xy 92.113227 -265.779411) (xy 92.142603 -265.819844) (xy 92.165293 -265.864376)
			(xy 92.180737 -265.911908) (xy 92.188556 -265.961271) (xy 92.189046 -265.98626) (xy 92.494857 -265.98626)
			(xy 92.498952 -265.935532) (xy 92.511131 -265.886118) (xy 92.531079 -265.839298) (xy 92.55828 -265.796284)
			(xy 92.592028 -265.75819) (xy 92.63145 -265.726003) (xy 92.675524 -265.700557) (xy 92.72311 -265.68251)
			(xy 92.772974 -265.67233) (xy 92.823826 -265.670281) (xy 92.874347 -265.676415) (xy 92.923231 -265.690575)
			(xy 92.96921 -265.712392) (xy 93.011094 -265.741302) (xy 93.047798 -265.776557) (xy 93.078371 -265.817243)
			(xy 93.102022 -265.862306) (xy 93.118138 -265.91058) (xy 93.126302 -265.960814) (xy 93.126814 -265.98626)
			(xy 93.126311 -266.011249) (xy 94.373428 -266.011249) (xy 94.373428 -265.961271) (xy 94.381247 -265.911908)
			(xy 94.396691 -265.864376) (xy 94.419381 -265.819844) (xy 94.448757 -265.779411) (xy 94.484097 -265.744071)
			(xy 94.52453 -265.714695) (xy 94.569062 -265.692005) (xy 94.616594 -265.676561) (xy 94.665957 -265.668742)
			(xy 94.715935 -265.668742) (xy 94.765298 -265.676561) (xy 94.81283 -265.692005) (xy 94.857362 -265.714695)
			(xy 94.897795 -265.744071) (xy 94.933135 -265.779411) (xy 94.962511 -265.819844) (xy 94.985201 -265.864376)
			(xy 95.000645 -265.911908) (xy 95.008464 -265.961271) (xy 95.008954 -265.98626) (xy 95.314765 -265.98626)
			(xy 95.31886 -265.935532) (xy 95.331039 -265.886118) (xy 95.350987 -265.839298) (xy 95.378188 -265.796284)
			(xy 95.411936 -265.75819) (xy 95.451358 -265.726003) (xy 95.495432 -265.700557) (xy 95.543018 -265.68251)
			(xy 95.592882 -265.67233) (xy 95.643734 -265.670281) (xy 95.694255 -265.676415) (xy 95.743139 -265.690575)
			(xy 95.789118 -265.712392) (xy 95.831002 -265.741302) (xy 95.867706 -265.776557) (xy 95.898279 -265.817243)
			(xy 95.92193 -265.862306) (xy 95.938046 -265.91058) (xy 95.94621 -265.960814) (xy 95.946722 -265.98626)
			(xy 95.946219 -266.011249) (xy 96.253536 -266.011249) (xy 96.253536 -265.961271) (xy 96.261355 -265.911908)
			(xy 96.276799 -265.864376) (xy 96.299489 -265.819844) (xy 96.328865 -265.779411) (xy 96.364205 -265.744071)
			(xy 96.404638 -265.714695) (xy 96.44917 -265.692005) (xy 96.496702 -265.676561) (xy 96.546065 -265.668742)
			(xy 96.596043 -265.668742) (xy 96.645406 -265.676561) (xy 96.692938 -265.692005) (xy 96.73747 -265.714695)
			(xy 96.777903 -265.744071) (xy 96.813243 -265.779411) (xy 96.842619 -265.819844) (xy 96.865309 -265.864376)
			(xy 96.880753 -265.911908) (xy 96.888572 -265.961271) (xy 96.889062 -265.98626) (xy 96.888572 -266.011249)
			(xy 96.880753 -266.060612) (xy 96.865309 -266.108144) (xy 96.842619 -266.152676) (xy 96.813243 -266.193109)
			(xy 96.777903 -266.228449) (xy 96.73747 -266.257825) (xy 96.692938 -266.280515) (xy 96.645406 -266.295959)
			(xy 96.596043 -266.303778) (xy 96.546065 -266.303778) (xy 96.496702 -266.295959) (xy 96.44917 -266.280515)
			(xy 96.404638 -266.257825) (xy 96.364205 -266.228449) (xy 96.328865 -266.193109) (xy 96.299489 -266.152676)
			(xy 96.276799 -266.108144) (xy 96.261355 -266.060612) (xy 96.253536 -266.011249) (xy 95.946219 -266.011249)
			(xy 95.94621 -266.011706) (xy 95.938046 -266.06194) (xy 95.92193 -266.110214) (xy 95.898279 -266.155277)
			(xy 95.867706 -266.195963) (xy 95.831002 -266.231218) (xy 95.789118 -266.260128) (xy 95.743139 -266.281945)
			(xy 95.694255 -266.296105) (xy 95.643734 -266.302239) (xy 95.592882 -266.30019) (xy 95.543018 -266.29001)
			(xy 95.495432 -266.271963) (xy 95.451358 -266.246517) (xy 95.411936 -266.21433) (xy 95.378188 -266.176236)
			(xy 95.350987 -266.133222) (xy 95.331039 -266.086402) (xy 95.31886 -266.036988) (xy 95.314765 -265.98626)
			(xy 95.008954 -265.98626) (xy 95.008464 -266.011249) (xy 95.000645 -266.060612) (xy 94.985201 -266.108144)
			(xy 94.962511 -266.152676) (xy 94.933135 -266.193109) (xy 94.897795 -266.228449) (xy 94.857362 -266.257825)
			(xy 94.81283 -266.280515) (xy 94.765298 -266.295959) (xy 94.715935 -266.303778) (xy 94.665957 -266.303778)
			(xy 94.616594 -266.295959) (xy 94.569062 -266.280515) (xy 94.52453 -266.257825) (xy 94.484097 -266.228449)
			(xy 94.448757 -266.193109) (xy 94.419381 -266.152676) (xy 94.396691 -266.108144) (xy 94.381247 -266.060612)
			(xy 94.373428 -266.011249) (xy 93.126311 -266.011249) (xy 93.126302 -266.011706) (xy 93.118138 -266.06194)
			(xy 93.102022 -266.110214) (xy 93.078371 -266.155277) (xy 93.047798 -266.195963) (xy 93.011094 -266.231218)
			(xy 92.96921 -266.260128) (xy 92.923231 -266.281945) (xy 92.874347 -266.296105) (xy 92.823826 -266.302239)
			(xy 92.772974 -266.30019) (xy 92.72311 -266.29001) (xy 92.675524 -266.271963) (xy 92.63145 -266.246517)
			(xy 92.592028 -266.21433) (xy 92.55828 -266.176236) (xy 92.531079 -266.133222) (xy 92.511131 -266.086402)
			(xy 92.498952 -266.036988) (xy 92.494857 -265.98626) (xy 92.189046 -265.98626) (xy 92.188556 -266.011249)
			(xy 92.180737 -266.060612) (xy 92.165293 -266.108144) (xy 92.142603 -266.152676) (xy 92.113227 -266.193109)
			(xy 92.077887 -266.228449) (xy 92.037454 -266.257825) (xy 91.992922 -266.280515) (xy 91.94539 -266.295959)
			(xy 91.896027 -266.303778) (xy 91.846049 -266.303778) (xy 91.796686 -266.295959) (xy 91.749154 -266.280515)
			(xy 91.704622 -266.257825) (xy 91.664189 -266.228449) (xy 91.628849 -266.193109) (xy 91.599473 -266.152676)
			(xy 91.576783 -266.108144) (xy 91.561339 -266.060612) (xy 91.55352 -266.011249) (xy 91.248502 -266.011249)
			(xy 91.240683 -266.060612) (xy 91.225239 -266.108144) (xy 91.202549 -266.152676) (xy 91.173173 -266.193109)
			(xy 91.137833 -266.228449) (xy 91.0974 -266.257825) (xy 91.052868 -266.280515) (xy 91.005336 -266.295959)
			(xy 90.955973 -266.303778) (xy 90.905995 -266.303778) (xy 90.856632 -266.295959) (xy 90.8091 -266.280515)
			(xy 90.764568 -266.257825) (xy 90.724135 -266.228449) (xy 90.688795 -266.193109) (xy 90.659419 -266.152676)
			(xy 90.636729 -266.108144) (xy 90.621285 -266.060612) (xy 90.613466 -266.011249) (xy 90.308448 -266.011249)
			(xy 90.300629 -266.060612) (xy 90.285185 -266.108144) (xy 90.262495 -266.152676) (xy 90.233119 -266.193109)
			(xy 90.197779 -266.228449) (xy 90.157346 -266.257825) (xy 90.112814 -266.280515) (xy 90.065282 -266.295959)
			(xy 90.015919 -266.303778) (xy 89.965941 -266.303778) (xy 89.916578 -266.295959) (xy 89.869046 -266.280515)
			(xy 89.824514 -266.257825) (xy 89.784081 -266.228449) (xy 89.748741 -266.193109) (xy 89.719365 -266.152676)
			(xy 89.696675 -266.108144) (xy 89.681231 -266.060612) (xy 89.673412 -266.011249) (xy 89.366349 -266.011249)
			(xy 89.36634 -266.011706) (xy 89.358176 -266.06194) (xy 89.34206 -266.110214) (xy 89.318409 -266.155277)
			(xy 89.287836 -266.195963) (xy 89.251132 -266.231218) (xy 89.209248 -266.260128) (xy 89.163269 -266.281945)
			(xy 89.114385 -266.296105) (xy 89.063864 -266.302239) (xy 89.013012 -266.30019) (xy 88.963148 -266.29001)
			(xy 88.915562 -266.271963) (xy 88.871488 -266.246517) (xy 88.832066 -266.21433) (xy 88.798318 -266.176236)
			(xy 88.771117 -266.133222) (xy 88.751169 -266.086402) (xy 88.73899 -266.036988) (xy 88.734895 -265.98626)
			(xy 88.429084 -265.98626) (xy 88.428594 -266.011249) (xy 88.420775 -266.060612) (xy 88.405331 -266.108144)
			(xy 88.382641 -266.152676) (xy 88.353265 -266.193109) (xy 88.317925 -266.228449) (xy 88.277492 -266.257825)
			(xy 88.23296 -266.280515) (xy 88.185428 -266.295959) (xy 88.136065 -266.303778) (xy 88.086087 -266.303778)
			(xy 88.036724 -266.295959) (xy 87.989192 -266.280515) (xy 87.94466 -266.257825) (xy 87.904227 -266.228449)
			(xy 87.868887 -266.193109) (xy 87.839511 -266.152676) (xy 87.816821 -266.108144) (xy 87.801377 -266.060612)
			(xy 87.793558 -266.011249) (xy 86.546187 -266.011249) (xy 86.546178 -266.011706) (xy 86.538014 -266.06194)
			(xy 86.521898 -266.110214) (xy 86.498247 -266.155277) (xy 86.467674 -266.195963) (xy 86.43097 -266.231218)
			(xy 86.389086 -266.260128) (xy 86.343107 -266.281945) (xy 86.294223 -266.296105) (xy 86.243702 -266.302239)
			(xy 86.19285 -266.30019) (xy 86.142986 -266.29001) (xy 86.0954 -266.271963) (xy 86.051326 -266.246517)
			(xy 86.011904 -266.21433) (xy 85.978156 -266.176236) (xy 85.950955 -266.133222) (xy 85.931007 -266.086402)
			(xy 85.918828 -266.036988) (xy 85.914733 -265.98626) (xy 85.608922 -265.98626) (xy 85.608432 -266.011249)
			(xy 85.600613 -266.060612) (xy 85.585169 -266.108144) (xy 85.562479 -266.152676) (xy 85.533103 -266.193109)
			(xy 85.497763 -266.228449) (xy 85.45733 -266.257825) (xy 85.412798 -266.280515) (xy 85.365266 -266.295959)
			(xy 85.315903 -266.303778) (xy 85.265925 -266.303778) (xy 85.216562 -266.295959) (xy 85.16903 -266.280515)
			(xy 85.124498 -266.257825) (xy 85.084065 -266.228449) (xy 85.048725 -266.193109) (xy 85.019349 -266.152676)
			(xy 84.996659 -266.108144) (xy 84.981215 -266.060612) (xy 84.973396 -266.011249) (xy 84.668632 -266.011249)
			(xy 84.660813 -266.060612) (xy 84.645369 -266.108144) (xy 84.622679 -266.152676) (xy 84.593303 -266.193109)
			(xy 84.557963 -266.228449) (xy 84.51753 -266.257825) (xy 84.472998 -266.280515) (xy 84.425466 -266.295959)
			(xy 84.376103 -266.303778) (xy 84.326125 -266.303778) (xy 84.276762 -266.295959) (xy 84.22923 -266.280515)
			(xy 84.184698 -266.257825) (xy 84.144265 -266.228449) (xy 84.108925 -266.193109) (xy 84.079549 -266.152676)
			(xy 84.056859 -266.108144) (xy 84.041415 -266.060612) (xy 84.033596 -266.011249) (xy 83.728578 -266.011249)
			(xy 83.720759 -266.060612) (xy 83.705315 -266.108144) (xy 83.682625 -266.152676) (xy 83.653249 -266.193109)
			(xy 83.617909 -266.228449) (xy 83.577476 -266.257825) (xy 83.532944 -266.280515) (xy 83.485412 -266.295959)
			(xy 83.436049 -266.303778) (xy 83.386071 -266.303778) (xy 83.336708 -266.295959) (xy 83.289176 -266.280515)
			(xy 83.244644 -266.257825) (xy 83.204211 -266.228449) (xy 83.168871 -266.193109) (xy 83.139495 -266.152676)
			(xy 83.116805 -266.108144) (xy 83.101361 -266.060612) (xy 83.093542 -266.011249) (xy 82.786225 -266.011249)
			(xy 82.786216 -266.011706) (xy 82.778052 -266.06194) (xy 82.761936 -266.110214) (xy 82.738285 -266.155277)
			(xy 82.707712 -266.195963) (xy 82.671008 -266.231218) (xy 82.629124 -266.260128) (xy 82.583145 -266.281945)
			(xy 82.534261 -266.296105) (xy 82.48374 -266.302239) (xy 82.432888 -266.30019) (xy 82.383024 -266.29001)
			(xy 82.335438 -266.271963) (xy 82.291364 -266.246517) (xy 82.251942 -266.21433) (xy 82.218194 -266.176236)
			(xy 82.190993 -266.133222) (xy 82.171045 -266.086402) (xy 82.158866 -266.036988) (xy 82.154771 -265.98626)
			(xy 81.84896 -265.98626) (xy 81.84847 -266.011249) (xy 81.840651 -266.060612) (xy 81.825207 -266.108144)
			(xy 81.802517 -266.152676) (xy 81.773141 -266.193109) (xy 81.737801 -266.228449) (xy 81.697368 -266.257825)
			(xy 81.652836 -266.280515) (xy 81.605304 -266.295959) (xy 81.555941 -266.303778) (xy 81.505963 -266.303778)
			(xy 81.4566 -266.295959) (xy 81.409068 -266.280515) (xy 81.364536 -266.257825) (xy 81.324103 -266.228449)
			(xy 81.288763 -266.193109) (xy 81.259387 -266.152676) (xy 81.236697 -266.108144) (xy 81.221253 -266.060612)
			(xy 81.213434 -266.011249) (xy 79.53248 -266.011249) (xy 79.53248 -266.821255) (xy 79.80348 -266.821255)
			(xy 79.80348 -266.771277) (xy 79.811299 -266.721914) (xy 79.826743 -266.674382) (xy 79.849433 -266.62985)
			(xy 79.878809 -266.589417) (xy 79.914149 -266.554077) (xy 79.954582 -266.524701) (xy 79.999114 -266.502011)
			(xy 80.046646 -266.486567) (xy 80.096009 -266.478748) (xy 80.145987 -266.478748) (xy 80.19535 -266.486567)
			(xy 80.242882 -266.502011) (xy 80.287414 -266.524701) (xy 80.327847 -266.554077) (xy 80.363187 -266.589417)
			(xy 80.392563 -266.62985) (xy 80.415253 -266.674382) (xy 80.430697 -266.721914) (xy 80.438516 -266.771277)
			(xy 80.439006 -266.796266) (xy 80.744817 -266.796266) (xy 80.748912 -266.745538) (xy 80.761091 -266.696124)
			(xy 80.781039 -266.649304) (xy 80.80824 -266.60629) (xy 80.841988 -266.568196) (xy 80.88141 -266.536009)
			(xy 80.925484 -266.510563) (xy 80.97307 -266.492516) (xy 81.022934 -266.482336) (xy 81.073786 -266.480287)
			(xy 81.124307 -266.486421) (xy 81.173191 -266.500581) (xy 81.21917 -266.522398) (xy 81.261054 -266.551308)
			(xy 81.297758 -266.586563) (xy 81.328331 -266.627249) (xy 81.351982 -266.672312) (xy 81.368098 -266.720586)
			(xy 81.376262 -266.77082) (xy 81.376774 -266.796266) (xy 81.376271 -266.821255) (xy 81.683588 -266.821255)
			(xy 81.683588 -266.771277) (xy 81.691407 -266.721914) (xy 81.706851 -266.674382) (xy 81.729541 -266.62985)
			(xy 81.758917 -266.589417) (xy 81.794257 -266.554077) (xy 81.83469 -266.524701) (xy 81.879222 -266.502011)
			(xy 81.926754 -266.486567) (xy 81.976117 -266.478748) (xy 82.026095 -266.478748) (xy 82.075458 -266.486567)
			(xy 82.12299 -266.502011) (xy 82.167522 -266.524701) (xy 82.207955 -266.554077) (xy 82.243295 -266.589417)
			(xy 82.272671 -266.62985) (xy 82.295361 -266.674382) (xy 82.310805 -266.721914) (xy 82.318624 -266.771277)
			(xy 82.319114 -266.796266) (xy 82.624671 -266.796266) (xy 82.628766 -266.745538) (xy 82.640945 -266.696124)
			(xy 82.660893 -266.649304) (xy 82.688094 -266.60629) (xy 82.721842 -266.568196) (xy 82.761264 -266.536009)
			(xy 82.805338 -266.510563) (xy 82.852924 -266.492516) (xy 82.902788 -266.482336) (xy 82.95364 -266.480287)
			(xy 83.004161 -266.486421) (xy 83.053045 -266.500581) (xy 83.099024 -266.522398) (xy 83.140908 -266.551308)
			(xy 83.177612 -266.586563) (xy 83.208185 -266.627249) (xy 83.231836 -266.672312) (xy 83.247952 -266.720586)
			(xy 83.256116 -266.77082) (xy 83.256628 -266.796266) (xy 83.256125 -266.821255) (xy 83.563442 -266.821255)
			(xy 83.563442 -266.771277) (xy 83.571261 -266.721914) (xy 83.586705 -266.674382) (xy 83.609395 -266.62985)
			(xy 83.638771 -266.589417) (xy 83.674111 -266.554077) (xy 83.714544 -266.524701) (xy 83.759076 -266.502011)
			(xy 83.806608 -266.486567) (xy 83.855971 -266.478748) (xy 83.905949 -266.478748) (xy 83.955312 -266.486567)
			(xy 84.002844 -266.502011) (xy 84.047376 -266.524701) (xy 84.087809 -266.554077) (xy 84.123149 -266.589417)
			(xy 84.152525 -266.62985) (xy 84.175215 -266.674382) (xy 84.190659 -266.721914) (xy 84.198478 -266.771277)
			(xy 84.198968 -266.796266) (xy 84.504779 -266.796266) (xy 84.508874 -266.745538) (xy 84.521053 -266.696124)
			(xy 84.541001 -266.649304) (xy 84.568202 -266.60629) (xy 84.60195 -266.568196) (xy 84.641372 -266.536009)
			(xy 84.685446 -266.510563) (xy 84.733032 -266.492516) (xy 84.782896 -266.482336) (xy 84.833748 -266.480287)
			(xy 84.884269 -266.486421) (xy 84.933153 -266.500581) (xy 84.979132 -266.522398) (xy 85.021016 -266.551308)
			(xy 85.05772 -266.586563) (xy 85.088293 -266.627249) (xy 85.111944 -266.672312) (xy 85.12806 -266.720586)
			(xy 85.136224 -266.77082) (xy 85.136736 -266.796266) (xy 85.444833 -266.796266) (xy 85.448928 -266.745538)
			(xy 85.461107 -266.696124) (xy 85.481055 -266.649304) (xy 85.508256 -266.60629) (xy 85.542004 -266.568196)
			(xy 85.581426 -266.536009) (xy 85.6255 -266.510563) (xy 85.673086 -266.492516) (xy 85.72295 -266.482336)
			(xy 85.773802 -266.480287) (xy 85.824323 -266.486421) (xy 85.873207 -266.500581) (xy 85.919186 -266.522398)
			(xy 85.96107 -266.551308) (xy 85.997774 -266.586563) (xy 86.028347 -266.627249) (xy 86.051998 -266.672312)
			(xy 86.068114 -266.720586) (xy 86.076278 -266.77082) (xy 86.07679 -266.796266) (xy 86.076287 -266.821255)
			(xy 86.383604 -266.821255) (xy 86.383604 -266.771277) (xy 86.391423 -266.721914) (xy 86.406867 -266.674382)
			(xy 86.429557 -266.62985) (xy 86.458933 -266.589417) (xy 86.494273 -266.554077) (xy 86.534706 -266.524701)
			(xy 86.579238 -266.502011) (xy 86.62677 -266.486567) (xy 86.676133 -266.478748) (xy 86.726111 -266.478748)
			(xy 86.775474 -266.486567) (xy 86.823006 -266.502011) (xy 86.867538 -266.524701) (xy 86.907971 -266.554077)
			(xy 86.943311 -266.589417) (xy 86.972687 -266.62985) (xy 86.995377 -266.674382) (xy 87.010821 -266.721914)
			(xy 87.01864 -266.771277) (xy 87.01913 -266.796266) (xy 87.324687 -266.796266) (xy 87.328782 -266.745538)
			(xy 87.340961 -266.696124) (xy 87.360909 -266.649304) (xy 87.38811 -266.60629) (xy 87.421858 -266.568196)
			(xy 87.46128 -266.536009) (xy 87.505354 -266.510563) (xy 87.55294 -266.492516) (xy 87.602804 -266.482336)
			(xy 87.653656 -266.480287) (xy 87.704177 -266.486421) (xy 87.753061 -266.500581) (xy 87.79904 -266.522398)
			(xy 87.840924 -266.551308) (xy 87.877628 -266.586563) (xy 87.908201 -266.627249) (xy 87.931852 -266.672312)
			(xy 87.947968 -266.720586) (xy 87.956132 -266.77082) (xy 87.956644 -266.796266) (xy 87.956141 -266.821255)
			(xy 88.263458 -266.821255) (xy 88.263458 -266.771277) (xy 88.271277 -266.721914) (xy 88.286721 -266.674382)
			(xy 88.309411 -266.62985) (xy 88.338787 -266.589417) (xy 88.374127 -266.554077) (xy 88.41456 -266.524701)
			(xy 88.459092 -266.502011) (xy 88.506624 -266.486567) (xy 88.555987 -266.478748) (xy 88.605965 -266.478748)
			(xy 88.655328 -266.486567) (xy 88.70286 -266.502011) (xy 88.747392 -266.524701) (xy 88.787825 -266.554077)
			(xy 88.823165 -266.589417) (xy 88.852541 -266.62985) (xy 88.875231 -266.674382) (xy 88.890675 -266.721914)
			(xy 88.898494 -266.771277) (xy 88.898984 -266.796266) (xy 89.204795 -266.796266) (xy 89.20889 -266.745538)
			(xy 89.221069 -266.696124) (xy 89.241017 -266.649304) (xy 89.268218 -266.60629) (xy 89.301966 -266.568196)
			(xy 89.341388 -266.536009) (xy 89.385462 -266.510563) (xy 89.433048 -266.492516) (xy 89.482912 -266.482336)
			(xy 89.533764 -266.480287) (xy 89.584285 -266.486421) (xy 89.633169 -266.500581) (xy 89.679148 -266.522398)
			(xy 89.721032 -266.551308) (xy 89.757736 -266.586563) (xy 89.788309 -266.627249) (xy 89.81196 -266.672312)
			(xy 89.828076 -266.720586) (xy 89.83624 -266.77082) (xy 89.836752 -266.796266) (xy 89.836249 -266.821255)
			(xy 90.143566 -266.821255) (xy 90.143566 -266.771277) (xy 90.151385 -266.721914) (xy 90.166829 -266.674382)
			(xy 90.189519 -266.62985) (xy 90.218895 -266.589417) (xy 90.254235 -266.554077) (xy 90.294668 -266.524701)
			(xy 90.3392 -266.502011) (xy 90.386732 -266.486567) (xy 90.436095 -266.478748) (xy 90.486073 -266.478748)
			(xy 90.535436 -266.486567) (xy 90.582968 -266.502011) (xy 90.6275 -266.524701) (xy 90.667933 -266.554077)
			(xy 90.703273 -266.589417) (xy 90.732649 -266.62985) (xy 90.755339 -266.674382) (xy 90.770783 -266.721914)
			(xy 90.778602 -266.771277) (xy 90.779092 -266.796266) (xy 91.084903 -266.796266) (xy 91.088998 -266.745538)
			(xy 91.101177 -266.696124) (xy 91.121125 -266.649304) (xy 91.148326 -266.60629) (xy 91.182074 -266.568196)
			(xy 91.221496 -266.536009) (xy 91.26557 -266.510563) (xy 91.313156 -266.492516) (xy 91.36302 -266.482336)
			(xy 91.413872 -266.480287) (xy 91.464393 -266.486421) (xy 91.513277 -266.500581) (xy 91.559256 -266.522398)
			(xy 91.60114 -266.551308) (xy 91.637844 -266.586563) (xy 91.668417 -266.627249) (xy 91.692068 -266.672312)
			(xy 91.708184 -266.720586) (xy 91.716348 -266.77082) (xy 91.71686 -266.796266) (xy 92.024703 -266.796266)
			(xy 92.028798 -266.745538) (xy 92.040977 -266.696124) (xy 92.060925 -266.649304) (xy 92.088126 -266.60629)
			(xy 92.121874 -266.568196) (xy 92.161296 -266.536009) (xy 92.20537 -266.510563) (xy 92.252956 -266.492516)
			(xy 92.30282 -266.482336) (xy 92.353672 -266.480287) (xy 92.404193 -266.486421) (xy 92.453077 -266.500581)
			(xy 92.499056 -266.522398) (xy 92.54094 -266.551308) (xy 92.577644 -266.586563) (xy 92.608217 -266.627249)
			(xy 92.631868 -266.672312) (xy 92.647984 -266.720586) (xy 92.656148 -266.77082) (xy 92.65666 -266.796266)
			(xy 92.656157 -266.821255) (xy 92.963474 -266.821255) (xy 92.963474 -266.771277) (xy 92.971293 -266.721914)
			(xy 92.986737 -266.674382) (xy 93.009427 -266.62985) (xy 93.038803 -266.589417) (xy 93.074143 -266.554077)
			(xy 93.114576 -266.524701) (xy 93.159108 -266.502011) (xy 93.20664 -266.486567) (xy 93.256003 -266.478748)
			(xy 93.305981 -266.478748) (xy 93.355344 -266.486567) (xy 93.402876 -266.502011) (xy 93.447408 -266.524701)
			(xy 93.487841 -266.554077) (xy 93.523181 -266.589417) (xy 93.552557 -266.62985) (xy 93.575247 -266.674382)
			(xy 93.590691 -266.721914) (xy 93.59851 -266.771277) (xy 93.599 -266.796266) (xy 93.904811 -266.796266)
			(xy 93.908906 -266.745538) (xy 93.921085 -266.696124) (xy 93.941033 -266.649304) (xy 93.968234 -266.60629)
			(xy 94.001982 -266.568196) (xy 94.041404 -266.536009) (xy 94.085478 -266.510563) (xy 94.133064 -266.492516)
			(xy 94.182928 -266.482336) (xy 94.23378 -266.480287) (xy 94.284301 -266.486421) (xy 94.333185 -266.500581)
			(xy 94.379164 -266.522398) (xy 94.421048 -266.551308) (xy 94.457752 -266.586563) (xy 94.488325 -266.627249)
			(xy 94.511976 -266.672312) (xy 94.528092 -266.720586) (xy 94.536256 -266.77082) (xy 94.536768 -266.796266)
			(xy 94.536265 -266.821255) (xy 94.843582 -266.821255) (xy 94.843582 -266.771277) (xy 94.851401 -266.721914)
			(xy 94.866845 -266.674382) (xy 94.889535 -266.62985) (xy 94.918911 -266.589417) (xy 94.954251 -266.554077)
			(xy 94.994684 -266.524701) (xy 95.039216 -266.502011) (xy 95.086748 -266.486567) (xy 95.136111 -266.478748)
			(xy 95.186089 -266.478748) (xy 95.235452 -266.486567) (xy 95.282984 -266.502011) (xy 95.327516 -266.524701)
			(xy 95.367949 -266.554077) (xy 95.403289 -266.589417) (xy 95.432665 -266.62985) (xy 95.455355 -266.674382)
			(xy 95.470799 -266.721914) (xy 95.478618 -266.771277) (xy 95.479108 -266.796266) (xy 95.784919 -266.796266)
			(xy 95.789014 -266.745538) (xy 95.801193 -266.696124) (xy 95.821141 -266.649304) (xy 95.848342 -266.60629)
			(xy 95.88209 -266.568196) (xy 95.921512 -266.536009) (xy 95.965586 -266.510563) (xy 96.013172 -266.492516)
			(xy 96.063036 -266.482336) (xy 96.113888 -266.480287) (xy 96.164409 -266.486421) (xy 96.213293 -266.500581)
			(xy 96.259272 -266.522398) (xy 96.301156 -266.551308) (xy 96.33786 -266.586563) (xy 96.368433 -266.627249)
			(xy 96.392084 -266.672312) (xy 96.4082 -266.720586) (xy 96.416364 -266.77082) (xy 96.416876 -266.796266)
			(xy 96.416364 -266.821712) (xy 96.4082 -266.871946) (xy 96.392084 -266.92022) (xy 96.368433 -266.965283)
			(xy 96.33786 -267.005969) (xy 96.301156 -267.041224) (xy 96.259272 -267.070134) (xy 96.213293 -267.091951)
			(xy 96.164409 -267.106111) (xy 96.113888 -267.112245) (xy 96.063036 -267.110196) (xy 96.013172 -267.100016)
			(xy 95.965586 -267.081969) (xy 95.921512 -267.056523) (xy 95.88209 -267.024336) (xy 95.848342 -266.986242)
			(xy 95.821141 -266.943228) (xy 95.801193 -266.896408) (xy 95.789014 -266.846994) (xy 95.784919 -266.796266)
			(xy 95.479108 -266.796266) (xy 95.478618 -266.821255) (xy 95.470799 -266.870618) (xy 95.455355 -266.91815)
			(xy 95.432665 -266.962682) (xy 95.403289 -267.003115) (xy 95.367949 -267.038455) (xy 95.327516 -267.067831)
			(xy 95.282984 -267.090521) (xy 95.235452 -267.105965) (xy 95.186089 -267.113784) (xy 95.136111 -267.113784)
			(xy 95.086748 -267.105965) (xy 95.039216 -267.090521) (xy 94.994684 -267.067831) (xy 94.954251 -267.038455)
			(xy 94.918911 -267.003115) (xy 94.889535 -266.962682) (xy 94.866845 -266.91815) (xy 94.851401 -266.870618)
			(xy 94.843582 -266.821255) (xy 94.536265 -266.821255) (xy 94.536256 -266.821712) (xy 94.528092 -266.871946)
			(xy 94.511976 -266.92022) (xy 94.488325 -266.965283) (xy 94.457752 -267.005969) (xy 94.421048 -267.041224)
			(xy 94.379164 -267.070134) (xy 94.333185 -267.091951) (xy 94.284301 -267.106111) (xy 94.23378 -267.112245)
			(xy 94.182928 -267.110196) (xy 94.133064 -267.100016) (xy 94.085478 -267.081969) (xy 94.041404 -267.056523)
			(xy 94.001982 -267.024336) (xy 93.968234 -266.986242) (xy 93.941033 -266.943228) (xy 93.921085 -266.896408)
			(xy 93.908906 -266.846994) (xy 93.904811 -266.796266) (xy 93.599 -266.796266) (xy 93.59851 -266.821255)
			(xy 93.590691 -266.870618) (xy 93.575247 -266.91815) (xy 93.552557 -266.962682) (xy 93.523181 -267.003115)
			(xy 93.487841 -267.038455) (xy 93.447408 -267.067831) (xy 93.402876 -267.090521) (xy 93.355344 -267.105965)
			(xy 93.305981 -267.113784) (xy 93.256003 -267.113784) (xy 93.20664 -267.105965) (xy 93.159108 -267.090521)
			(xy 93.114576 -267.067831) (xy 93.074143 -267.038455) (xy 93.038803 -267.003115) (xy 93.009427 -266.962682)
			(xy 92.986737 -266.91815) (xy 92.971293 -266.870618) (xy 92.963474 -266.821255) (xy 92.656157 -266.821255)
			(xy 92.656148 -266.821712) (xy 92.647984 -266.871946) (xy 92.631868 -266.92022) (xy 92.608217 -266.965283)
			(xy 92.577644 -267.005969) (xy 92.54094 -267.041224) (xy 92.499056 -267.070134) (xy 92.453077 -267.091951)
			(xy 92.404193 -267.106111) (xy 92.353672 -267.112245) (xy 92.30282 -267.110196) (xy 92.252956 -267.100016)
			(xy 92.20537 -267.081969) (xy 92.161296 -267.056523) (xy 92.121874 -267.024336) (xy 92.088126 -266.986242)
			(xy 92.060925 -266.943228) (xy 92.040977 -266.896408) (xy 92.028798 -266.846994) (xy 92.024703 -266.796266)
			(xy 91.71686 -266.796266) (xy 91.716348 -266.821712) (xy 91.708184 -266.871946) (xy 91.692068 -266.92022)
			(xy 91.668417 -266.965283) (xy 91.637844 -267.005969) (xy 91.60114 -267.041224) (xy 91.559256 -267.070134)
			(xy 91.513277 -267.091951) (xy 91.464393 -267.106111) (xy 91.413872 -267.112245) (xy 91.36302 -267.110196)
			(xy 91.313156 -267.100016) (xy 91.26557 -267.081969) (xy 91.221496 -267.056523) (xy 91.182074 -267.024336)
			(xy 91.148326 -266.986242) (xy 91.121125 -266.943228) (xy 91.101177 -266.896408) (xy 91.088998 -266.846994)
			(xy 91.084903 -266.796266) (xy 90.779092 -266.796266) (xy 90.778602 -266.821255) (xy 90.770783 -266.870618)
			(xy 90.755339 -266.91815) (xy 90.732649 -266.962682) (xy 90.703273 -267.003115) (xy 90.667933 -267.038455)
			(xy 90.6275 -267.067831) (xy 90.582968 -267.090521) (xy 90.535436 -267.105965) (xy 90.486073 -267.113784)
			(xy 90.436095 -267.113784) (xy 90.386732 -267.105965) (xy 90.3392 -267.090521) (xy 90.294668 -267.067831)
			(xy 90.254235 -267.038455) (xy 90.218895 -267.003115) (xy 90.189519 -266.962682) (xy 90.166829 -266.91815)
			(xy 90.151385 -266.870618) (xy 90.143566 -266.821255) (xy 89.836249 -266.821255) (xy 89.83624 -266.821712)
			(xy 89.828076 -266.871946) (xy 89.81196 -266.92022) (xy 89.788309 -266.965283) (xy 89.757736 -267.005969)
			(xy 89.721032 -267.041224) (xy 89.679148 -267.070134) (xy 89.633169 -267.091951) (xy 89.584285 -267.106111)
			(xy 89.533764 -267.112245) (xy 89.482912 -267.110196) (xy 89.433048 -267.100016) (xy 89.385462 -267.081969)
			(xy 89.341388 -267.056523) (xy 89.301966 -267.024336) (xy 89.268218 -266.986242) (xy 89.241017 -266.943228)
			(xy 89.221069 -266.896408) (xy 89.20889 -266.846994) (xy 89.204795 -266.796266) (xy 88.898984 -266.796266)
			(xy 88.898494 -266.821255) (xy 88.890675 -266.870618) (xy 88.875231 -266.91815) (xy 88.852541 -266.962682)
			(xy 88.823165 -267.003115) (xy 88.787825 -267.038455) (xy 88.747392 -267.067831) (xy 88.70286 -267.090521)
			(xy 88.655328 -267.105965) (xy 88.605965 -267.113784) (xy 88.555987 -267.113784) (xy 88.506624 -267.105965)
			(xy 88.459092 -267.090521) (xy 88.41456 -267.067831) (xy 88.374127 -267.038455) (xy 88.338787 -267.003115)
			(xy 88.309411 -266.962682) (xy 88.286721 -266.91815) (xy 88.271277 -266.870618) (xy 88.263458 -266.821255)
			(xy 87.956141 -266.821255) (xy 87.956132 -266.821712) (xy 87.947968 -266.871946) (xy 87.931852 -266.92022)
			(xy 87.908201 -266.965283) (xy 87.877628 -267.005969) (xy 87.840924 -267.041224) (xy 87.79904 -267.070134)
			(xy 87.753061 -267.091951) (xy 87.704177 -267.106111) (xy 87.653656 -267.112245) (xy 87.602804 -267.110196)
			(xy 87.55294 -267.100016) (xy 87.505354 -267.081969) (xy 87.46128 -267.056523) (xy 87.421858 -267.024336)
			(xy 87.38811 -266.986242) (xy 87.360909 -266.943228) (xy 87.340961 -266.896408) (xy 87.328782 -266.846994)
			(xy 87.324687 -266.796266) (xy 87.01913 -266.796266) (xy 87.01864 -266.821255) (xy 87.010821 -266.870618)
			(xy 86.995377 -266.91815) (xy 86.972687 -266.962682) (xy 86.943311 -267.003115) (xy 86.907971 -267.038455)
			(xy 86.867538 -267.067831) (xy 86.823006 -267.090521) (xy 86.775474 -267.105965) (xy 86.726111 -267.113784)
			(xy 86.676133 -267.113784) (xy 86.62677 -267.105965) (xy 86.579238 -267.090521) (xy 86.534706 -267.067831)
			(xy 86.494273 -267.038455) (xy 86.458933 -267.003115) (xy 86.429557 -266.962682) (xy 86.406867 -266.91815)
			(xy 86.391423 -266.870618) (xy 86.383604 -266.821255) (xy 86.076287 -266.821255) (xy 86.076278 -266.821712)
			(xy 86.068114 -266.871946) (xy 86.051998 -266.92022) (xy 86.028347 -266.965283) (xy 85.997774 -267.005969)
			(xy 85.96107 -267.041224) (xy 85.919186 -267.070134) (xy 85.873207 -267.091951) (xy 85.824323 -267.106111)
			(xy 85.773802 -267.112245) (xy 85.72295 -267.110196) (xy 85.673086 -267.100016) (xy 85.6255 -267.081969)
			(xy 85.581426 -267.056523) (xy 85.542004 -267.024336) (xy 85.508256 -266.986242) (xy 85.481055 -266.943228)
			(xy 85.461107 -266.896408) (xy 85.448928 -266.846994) (xy 85.444833 -266.796266) (xy 85.136736 -266.796266)
			(xy 85.136224 -266.821712) (xy 85.12806 -266.871946) (xy 85.111944 -266.92022) (xy 85.088293 -266.965283)
			(xy 85.05772 -267.005969) (xy 85.021016 -267.041224) (xy 84.979132 -267.070134) (xy 84.933153 -267.091951)
			(xy 84.884269 -267.106111) (xy 84.833748 -267.112245) (xy 84.782896 -267.110196) (xy 84.733032 -267.100016)
			(xy 84.685446 -267.081969) (xy 84.641372 -267.056523) (xy 84.60195 -267.024336) (xy 84.568202 -266.986242)
			(xy 84.541001 -266.943228) (xy 84.521053 -266.896408) (xy 84.508874 -266.846994) (xy 84.504779 -266.796266)
			(xy 84.198968 -266.796266) (xy 84.198478 -266.821255) (xy 84.190659 -266.870618) (xy 84.175215 -266.91815)
			(xy 84.152525 -266.962682) (xy 84.123149 -267.003115) (xy 84.087809 -267.038455) (xy 84.047376 -267.067831)
			(xy 84.002844 -267.090521) (xy 83.955312 -267.105965) (xy 83.905949 -267.113784) (xy 83.855971 -267.113784)
			(xy 83.806608 -267.105965) (xy 83.759076 -267.090521) (xy 83.714544 -267.067831) (xy 83.674111 -267.038455)
			(xy 83.638771 -267.003115) (xy 83.609395 -266.962682) (xy 83.586705 -266.91815) (xy 83.571261 -266.870618)
			(xy 83.563442 -266.821255) (xy 83.256125 -266.821255) (xy 83.256116 -266.821712) (xy 83.247952 -266.871946)
			(xy 83.231836 -266.92022) (xy 83.208185 -266.965283) (xy 83.177612 -267.005969) (xy 83.140908 -267.041224)
			(xy 83.099024 -267.070134) (xy 83.053045 -267.091951) (xy 83.004161 -267.106111) (xy 82.95364 -267.112245)
			(xy 82.902788 -267.110196) (xy 82.852924 -267.100016) (xy 82.805338 -267.081969) (xy 82.761264 -267.056523)
			(xy 82.721842 -267.024336) (xy 82.688094 -266.986242) (xy 82.660893 -266.943228) (xy 82.640945 -266.896408)
			(xy 82.628766 -266.846994) (xy 82.624671 -266.796266) (xy 82.319114 -266.796266) (xy 82.318624 -266.821255)
			(xy 82.310805 -266.870618) (xy 82.295361 -266.91815) (xy 82.272671 -266.962682) (xy 82.243295 -267.003115)
			(xy 82.207955 -267.038455) (xy 82.167522 -267.067831) (xy 82.12299 -267.090521) (xy 82.075458 -267.105965)
			(xy 82.026095 -267.113784) (xy 81.976117 -267.113784) (xy 81.926754 -267.105965) (xy 81.879222 -267.090521)
			(xy 81.83469 -267.067831) (xy 81.794257 -267.038455) (xy 81.758917 -267.003115) (xy 81.729541 -266.962682)
			(xy 81.706851 -266.91815) (xy 81.691407 -266.870618) (xy 81.683588 -266.821255) (xy 81.376271 -266.821255)
			(xy 81.376262 -266.821712) (xy 81.368098 -266.871946) (xy 81.351982 -266.92022) (xy 81.328331 -266.965283)
			(xy 81.297758 -267.005969) (xy 81.261054 -267.041224) (xy 81.21917 -267.070134) (xy 81.173191 -267.091951)
			(xy 81.124307 -267.106111) (xy 81.073786 -267.112245) (xy 81.022934 -267.110196) (xy 80.97307 -267.100016)
			(xy 80.925484 -267.081969) (xy 80.88141 -267.056523) (xy 80.841988 -267.024336) (xy 80.80824 -266.986242)
			(xy 80.781039 -266.943228) (xy 80.761091 -266.896408) (xy 80.748912 -266.846994) (xy 80.744817 -266.796266)
			(xy 80.439006 -266.796266) (xy 80.438516 -266.821255) (xy 80.430697 -266.870618) (xy 80.415253 -266.91815)
			(xy 80.392563 -266.962682) (xy 80.363187 -267.003115) (xy 80.327847 -267.038455) (xy 80.287414 -267.067831)
			(xy 80.242882 -267.090521) (xy 80.19535 -267.105965) (xy 80.145987 -267.113784) (xy 80.096009 -267.113784)
			(xy 80.046646 -267.105965) (xy 79.999114 -267.090521) (xy 79.954582 -267.067831) (xy 79.914149 -267.038455)
			(xy 79.878809 -267.003115) (xy 79.849433 -266.962682) (xy 79.826743 -266.91815) (xy 79.811299 -266.870618)
			(xy 79.80348 -266.821255) (xy 79.53248 -266.821255) (xy 79.53248 -267.631261) (xy 80.273634 -267.631261)
			(xy 80.273634 -267.581283) (xy 80.281453 -267.53192) (xy 80.296897 -267.484388) (xy 80.319587 -267.439856)
			(xy 80.348963 -267.399423) (xy 80.384303 -267.364083) (xy 80.424736 -267.334707) (xy 80.469268 -267.312017)
			(xy 80.5168 -267.296573) (xy 80.566163 -267.288754) (xy 80.616141 -267.288754) (xy 80.665504 -267.296573)
			(xy 80.713036 -267.312017) (xy 80.757568 -267.334707) (xy 80.798001 -267.364083) (xy 80.833341 -267.399423)
			(xy 80.862717 -267.439856) (xy 80.885407 -267.484388) (xy 80.900851 -267.53192) (xy 80.90867 -267.581283)
			(xy 80.90916 -267.606272) (xy 81.214717 -267.606272) (xy 81.218812 -267.555544) (xy 81.230991 -267.50613)
			(xy 81.250939 -267.45931) (xy 81.27814 -267.416296) (xy 81.311888 -267.378202) (xy 81.35131 -267.346015)
			(xy 81.395384 -267.320569) (xy 81.44297 -267.302522) (xy 81.492834 -267.292342) (xy 81.543686 -267.290293)
			(xy 81.594207 -267.296427) (xy 81.643091 -267.310587) (xy 81.68907 -267.332404) (xy 81.730954 -267.361314)
			(xy 81.767658 -267.396569) (xy 81.798231 -267.437255) (xy 81.821882 -267.482318) (xy 81.837998 -267.530592)
			(xy 81.846162 -267.580826) (xy 81.846674 -267.606272) (xy 81.846171 -267.631261) (xy 82.153488 -267.631261)
			(xy 82.153488 -267.581283) (xy 82.161307 -267.53192) (xy 82.176751 -267.484388) (xy 82.199441 -267.439856)
			(xy 82.228817 -267.399423) (xy 82.264157 -267.364083) (xy 82.30459 -267.334707) (xy 82.349122 -267.312017)
			(xy 82.396654 -267.296573) (xy 82.446017 -267.288754) (xy 82.495995 -267.288754) (xy 82.545358 -267.296573)
			(xy 82.59289 -267.312017) (xy 82.637422 -267.334707) (xy 82.677855 -267.364083) (xy 82.713195 -267.399423)
			(xy 82.742571 -267.439856) (xy 82.765261 -267.484388) (xy 82.780705 -267.53192) (xy 82.788524 -267.581283)
			(xy 82.789014 -267.606272) (xy 82.788524 -267.631261) (xy 83.093542 -267.631261) (xy 83.093542 -267.581283)
			(xy 83.101361 -267.53192) (xy 83.116805 -267.484388) (xy 83.139495 -267.439856) (xy 83.168871 -267.399423)
			(xy 83.204211 -267.364083) (xy 83.244644 -267.334707) (xy 83.289176 -267.312017) (xy 83.336708 -267.296573)
			(xy 83.386071 -267.288754) (xy 83.436049 -267.288754) (xy 83.485412 -267.296573) (xy 83.532944 -267.312017)
			(xy 83.577476 -267.334707) (xy 83.617909 -267.364083) (xy 83.653249 -267.399423) (xy 83.682625 -267.439856)
			(xy 83.705315 -267.484388) (xy 83.720759 -267.53192) (xy 83.728578 -267.581283) (xy 83.729068 -267.606272)
			(xy 84.034879 -267.606272) (xy 84.038974 -267.555544) (xy 84.051153 -267.50613) (xy 84.071101 -267.45931)
			(xy 84.098302 -267.416296) (xy 84.13205 -267.378202) (xy 84.171472 -267.346015) (xy 84.215546 -267.320569)
			(xy 84.263132 -267.302522) (xy 84.312996 -267.292342) (xy 84.363848 -267.290293) (xy 84.414369 -267.296427)
			(xy 84.463253 -267.310587) (xy 84.509232 -267.332404) (xy 84.551116 -267.361314) (xy 84.58782 -267.396569)
			(xy 84.618393 -267.437255) (xy 84.642044 -267.482318) (xy 84.65816 -267.530592) (xy 84.666324 -267.580826)
			(xy 84.666836 -267.606272) (xy 84.666333 -267.631261) (xy 84.973396 -267.631261) (xy 84.973396 -267.581283)
			(xy 84.981215 -267.53192) (xy 84.996659 -267.484388) (xy 85.019349 -267.439856) (xy 85.048725 -267.399423)
			(xy 85.084065 -267.364083) (xy 85.124498 -267.334707) (xy 85.16903 -267.312017) (xy 85.216562 -267.296573)
			(xy 85.265925 -267.288754) (xy 85.315903 -267.288754) (xy 85.365266 -267.296573) (xy 85.412798 -267.312017)
			(xy 85.45733 -267.334707) (xy 85.497763 -267.364083) (xy 85.533103 -267.399423) (xy 85.562479 -267.439856)
			(xy 85.585169 -267.484388) (xy 85.600613 -267.53192) (xy 85.608432 -267.581283) (xy 85.608922 -267.606272)
			(xy 85.608432 -267.631261) (xy 85.91345 -267.631261) (xy 85.91345 -267.581283) (xy 85.921269 -267.53192)
			(xy 85.936713 -267.484388) (xy 85.959403 -267.439856) (xy 85.988779 -267.399423) (xy 86.024119 -267.364083)
			(xy 86.064552 -267.334707) (xy 86.109084 -267.312017) (xy 86.156616 -267.296573) (xy 86.205979 -267.288754)
			(xy 86.255957 -267.288754) (xy 86.30532 -267.296573) (xy 86.352852 -267.312017) (xy 86.397384 -267.334707)
			(xy 86.437817 -267.364083) (xy 86.473157 -267.399423) (xy 86.502533 -267.439856) (xy 86.525223 -267.484388)
			(xy 86.540667 -267.53192) (xy 86.548486 -267.581283) (xy 86.548976 -267.606272) (xy 86.548486 -267.631261)
			(xy 86.853504 -267.631261) (xy 86.853504 -267.581283) (xy 86.861323 -267.53192) (xy 86.876767 -267.484388)
			(xy 86.899457 -267.439856) (xy 86.928833 -267.399423) (xy 86.964173 -267.364083) (xy 87.004606 -267.334707)
			(xy 87.049138 -267.312017) (xy 87.09667 -267.296573) (xy 87.146033 -267.288754) (xy 87.196011 -267.288754)
			(xy 87.245374 -267.296573) (xy 87.292906 -267.312017) (xy 87.337438 -267.334707) (xy 87.377871 -267.364083)
			(xy 87.413211 -267.399423) (xy 87.442587 -267.439856) (xy 87.465277 -267.484388) (xy 87.480721 -267.53192)
			(xy 87.48854 -267.581283) (xy 87.48903 -267.606272) (xy 87.794841 -267.606272) (xy 87.798936 -267.555544)
			(xy 87.811115 -267.50613) (xy 87.831063 -267.45931) (xy 87.858264 -267.416296) (xy 87.892012 -267.378202)
			(xy 87.931434 -267.346015) (xy 87.975508 -267.320569) (xy 88.023094 -267.302522) (xy 88.072958 -267.292342)
			(xy 88.12381 -267.290293) (xy 88.174331 -267.296427) (xy 88.223215 -267.310587) (xy 88.269194 -267.332404)
			(xy 88.311078 -267.361314) (xy 88.347782 -267.396569) (xy 88.378355 -267.437255) (xy 88.402006 -267.482318)
			(xy 88.418122 -267.530592) (xy 88.426286 -267.580826) (xy 88.426798 -267.606272) (xy 88.426295 -267.631261)
			(xy 88.733612 -267.631261) (xy 88.733612 -267.581283) (xy 88.741431 -267.53192) (xy 88.756875 -267.484388)
			(xy 88.779565 -267.439856) (xy 88.808941 -267.399423) (xy 88.844281 -267.364083) (xy 88.884714 -267.334707)
			(xy 88.929246 -267.312017) (xy 88.976778 -267.296573) (xy 89.026141 -267.288754) (xy 89.076119 -267.288754)
			(xy 89.125482 -267.296573) (xy 89.173014 -267.312017) (xy 89.217546 -267.334707) (xy 89.257979 -267.364083)
			(xy 89.293319 -267.399423) (xy 89.322695 -267.439856) (xy 89.345385 -267.484388) (xy 89.360829 -267.53192)
			(xy 89.368648 -267.581283) (xy 89.369138 -267.606272) (xy 89.368648 -267.631261) (xy 89.673412 -267.631261)
			(xy 89.673412 -267.581283) (xy 89.681231 -267.53192) (xy 89.696675 -267.484388) (xy 89.719365 -267.439856)
			(xy 89.748741 -267.399423) (xy 89.784081 -267.364083) (xy 89.824514 -267.334707) (xy 89.869046 -267.312017)
			(xy 89.916578 -267.296573) (xy 89.965941 -267.288754) (xy 90.015919 -267.288754) (xy 90.065282 -267.296573)
			(xy 90.112814 -267.312017) (xy 90.157346 -267.334707) (xy 90.197779 -267.364083) (xy 90.233119 -267.399423)
			(xy 90.262495 -267.439856) (xy 90.285185 -267.484388) (xy 90.300629 -267.53192) (xy 90.308448 -267.581283)
			(xy 90.308938 -267.606272) (xy 90.614749 -267.606272) (xy 90.618844 -267.555544) (xy 90.631023 -267.50613)
			(xy 90.650971 -267.45931) (xy 90.678172 -267.416296) (xy 90.71192 -267.378202) (xy 90.751342 -267.346015)
			(xy 90.795416 -267.320569) (xy 90.843002 -267.302522) (xy 90.892866 -267.292342) (xy 90.943718 -267.290293)
			(xy 90.994239 -267.296427) (xy 91.043123 -267.310587) (xy 91.089102 -267.332404) (xy 91.130986 -267.361314)
			(xy 91.16769 -267.396569) (xy 91.198263 -267.437255) (xy 91.221914 -267.482318) (xy 91.23803 -267.530592)
			(xy 91.246194 -267.580826) (xy 91.246706 -267.606272) (xy 91.246203 -267.631261) (xy 91.55352 -267.631261)
			(xy 91.55352 -267.581283) (xy 91.561339 -267.53192) (xy 91.576783 -267.484388) (xy 91.599473 -267.439856)
			(xy 91.628849 -267.399423) (xy 91.664189 -267.364083) (xy 91.704622 -267.334707) (xy 91.749154 -267.312017)
			(xy 91.796686 -267.296573) (xy 91.846049 -267.288754) (xy 91.896027 -267.288754) (xy 91.94539 -267.296573)
			(xy 91.992922 -267.312017) (xy 92.037454 -267.334707) (xy 92.077887 -267.364083) (xy 92.113227 -267.399423)
			(xy 92.142603 -267.439856) (xy 92.165293 -267.484388) (xy 92.180737 -267.53192) (xy 92.188556 -267.581283)
			(xy 92.189046 -267.606272) (xy 92.188556 -267.631261) (xy 92.493574 -267.631261) (xy 92.493574 -267.581283)
			(xy 92.501393 -267.53192) (xy 92.516837 -267.484388) (xy 92.539527 -267.439856) (xy 92.568903 -267.399423)
			(xy 92.604243 -267.364083) (xy 92.644676 -267.334707) (xy 92.689208 -267.312017) (xy 92.73674 -267.296573)
			(xy 92.786103 -267.288754) (xy 92.836081 -267.288754) (xy 92.885444 -267.296573) (xy 92.932976 -267.312017)
			(xy 92.977508 -267.334707) (xy 93.017941 -267.364083) (xy 93.053281 -267.399423) (xy 93.082657 -267.439856)
			(xy 93.105347 -267.484388) (xy 93.120791 -267.53192) (xy 93.12861 -267.581283) (xy 93.1291 -267.606272)
			(xy 93.12861 -267.631261) (xy 93.433628 -267.631261) (xy 93.433628 -267.581283) (xy 93.441447 -267.53192)
			(xy 93.456891 -267.484388) (xy 93.479581 -267.439856) (xy 93.508957 -267.399423) (xy 93.544297 -267.364083)
			(xy 93.58473 -267.334707) (xy 93.629262 -267.312017) (xy 93.676794 -267.296573) (xy 93.726157 -267.288754)
			(xy 93.776135 -267.288754) (xy 93.825498 -267.296573) (xy 93.87303 -267.312017) (xy 93.917562 -267.334707)
			(xy 93.957995 -267.364083) (xy 93.993335 -267.399423) (xy 94.022711 -267.439856) (xy 94.045401 -267.484388)
			(xy 94.060845 -267.53192) (xy 94.068664 -267.581283) (xy 94.069154 -267.606272) (xy 94.374711 -267.606272)
			(xy 94.378806 -267.555544) (xy 94.390985 -267.50613) (xy 94.410933 -267.45931) (xy 94.438134 -267.416296)
			(xy 94.471882 -267.378202) (xy 94.511304 -267.346015) (xy 94.555378 -267.320569) (xy 94.602964 -267.302522)
			(xy 94.652828 -267.292342) (xy 94.70368 -267.290293) (xy 94.754201 -267.296427) (xy 94.803085 -267.310587)
			(xy 94.849064 -267.332404) (xy 94.890948 -267.361314) (xy 94.927652 -267.396569) (xy 94.958225 -267.437255)
			(xy 94.981876 -267.482318) (xy 94.997992 -267.530592) (xy 95.006156 -267.580826) (xy 95.006668 -267.606272)
			(xy 95.006165 -267.631261) (xy 95.313482 -267.631261) (xy 95.313482 -267.581283) (xy 95.321301 -267.53192)
			(xy 95.336745 -267.484388) (xy 95.359435 -267.439856) (xy 95.388811 -267.399423) (xy 95.424151 -267.364083)
			(xy 95.464584 -267.334707) (xy 95.509116 -267.312017) (xy 95.556648 -267.296573) (xy 95.606011 -267.288754)
			(xy 95.655989 -267.288754) (xy 95.705352 -267.296573) (xy 95.752884 -267.312017) (xy 95.797416 -267.334707)
			(xy 95.837849 -267.364083) (xy 95.873189 -267.399423) (xy 95.902565 -267.439856) (xy 95.925255 -267.484388)
			(xy 95.940699 -267.53192) (xy 95.948518 -267.581283) (xy 95.949008 -267.606272) (xy 95.948518 -267.631261)
			(xy 95.940699 -267.680624) (xy 95.925255 -267.728156) (xy 95.902565 -267.772688) (xy 95.873189 -267.813121)
			(xy 95.837849 -267.848461) (xy 95.797416 -267.877837) (xy 95.752884 -267.900527) (xy 95.705352 -267.915971)
			(xy 95.655989 -267.92379) (xy 95.606011 -267.92379) (xy 95.556648 -267.915971) (xy 95.509116 -267.900527)
			(xy 95.464584 -267.877837) (xy 95.424151 -267.848461) (xy 95.388811 -267.813121) (xy 95.359435 -267.772688)
			(xy 95.336745 -267.728156) (xy 95.321301 -267.680624) (xy 95.313482 -267.631261) (xy 95.006165 -267.631261)
			(xy 95.006156 -267.631718) (xy 94.997992 -267.681952) (xy 94.981876 -267.730226) (xy 94.958225 -267.775289)
			(xy 94.927652 -267.815975) (xy 94.890948 -267.85123) (xy 94.849064 -267.88014) (xy 94.803085 -267.901957)
			(xy 94.754201 -267.916117) (xy 94.70368 -267.922251) (xy 94.652828 -267.920202) (xy 94.602964 -267.910022)
			(xy 94.555378 -267.891975) (xy 94.511304 -267.866529) (xy 94.471882 -267.834342) (xy 94.438134 -267.796248)
			(xy 94.410933 -267.753234) (xy 94.390985 -267.706414) (xy 94.378806 -267.657) (xy 94.374711 -267.606272)
			(xy 94.069154 -267.606272) (xy 94.068664 -267.631261) (xy 94.060845 -267.680624) (xy 94.045401 -267.728156)
			(xy 94.022711 -267.772688) (xy 93.993335 -267.813121) (xy 93.957995 -267.848461) (xy 93.917562 -267.877837)
			(xy 93.87303 -267.900527) (xy 93.825498 -267.915971) (xy 93.776135 -267.92379) (xy 93.726157 -267.92379)
			(xy 93.676794 -267.915971) (xy 93.629262 -267.900527) (xy 93.58473 -267.877837) (xy 93.544297 -267.848461)
			(xy 93.508957 -267.813121) (xy 93.479581 -267.772688) (xy 93.456891 -267.728156) (xy 93.441447 -267.680624)
			(xy 93.433628 -267.631261) (xy 93.12861 -267.631261) (xy 93.120791 -267.680624) (xy 93.105347 -267.728156)
			(xy 93.082657 -267.772688) (xy 93.053281 -267.813121) (xy 93.017941 -267.848461) (xy 92.977508 -267.877837)
			(xy 92.932976 -267.900527) (xy 92.885444 -267.915971) (xy 92.836081 -267.92379) (xy 92.786103 -267.92379)
			(xy 92.73674 -267.915971) (xy 92.689208 -267.900527) (xy 92.644676 -267.877837) (xy 92.604243 -267.848461)
			(xy 92.568903 -267.813121) (xy 92.539527 -267.772688) (xy 92.516837 -267.728156) (xy 92.501393 -267.680624)
			(xy 92.493574 -267.631261) (xy 92.188556 -267.631261) (xy 92.180737 -267.680624) (xy 92.165293 -267.728156)
			(xy 92.142603 -267.772688) (xy 92.113227 -267.813121) (xy 92.077887 -267.848461) (xy 92.037454 -267.877837)
			(xy 91.992922 -267.900527) (xy 91.94539 -267.915971) (xy 91.896027 -267.92379) (xy 91.846049 -267.92379)
			(xy 91.796686 -267.915971) (xy 91.749154 -267.900527) (xy 91.704622 -267.877837) (xy 91.664189 -267.848461)
			(xy 91.628849 -267.813121) (xy 91.599473 -267.772688) (xy 91.576783 -267.728156) (xy 91.561339 -267.680624)
			(xy 91.55352 -267.631261) (xy 91.246203 -267.631261) (xy 91.246194 -267.631718) (xy 91.23803 -267.681952)
			(xy 91.221914 -267.730226) (xy 91.198263 -267.775289) (xy 91.16769 -267.815975) (xy 91.130986 -267.85123)
			(xy 91.089102 -267.88014) (xy 91.043123 -267.901957) (xy 90.994239 -267.916117) (xy 90.943718 -267.922251)
			(xy 90.892866 -267.920202) (xy 90.843002 -267.910022) (xy 90.795416 -267.891975) (xy 90.751342 -267.866529)
			(xy 90.71192 -267.834342) (xy 90.678172 -267.796248) (xy 90.650971 -267.753234) (xy 90.631023 -267.706414)
			(xy 90.618844 -267.657) (xy 90.614749 -267.606272) (xy 90.308938 -267.606272) (xy 90.308448 -267.631261)
			(xy 90.300629 -267.680624) (xy 90.285185 -267.728156) (xy 90.262495 -267.772688) (xy 90.233119 -267.813121)
			(xy 90.197779 -267.848461) (xy 90.157346 -267.877837) (xy 90.112814 -267.900527) (xy 90.065282 -267.915971)
			(xy 90.015919 -267.92379) (xy 89.965941 -267.92379) (xy 89.916578 -267.915971) (xy 89.869046 -267.900527)
			(xy 89.824514 -267.877837) (xy 89.784081 -267.848461) (xy 89.748741 -267.813121) (xy 89.719365 -267.772688)
			(xy 89.696675 -267.728156) (xy 89.681231 -267.680624) (xy 89.673412 -267.631261) (xy 89.368648 -267.631261)
			(xy 89.360829 -267.680624) (xy 89.345385 -267.728156) (xy 89.322695 -267.772688) (xy 89.293319 -267.813121)
			(xy 89.257979 -267.848461) (xy 89.217546 -267.877837) (xy 89.173014 -267.900527) (xy 89.125482 -267.915971)
			(xy 89.076119 -267.92379) (xy 89.026141 -267.92379) (xy 88.976778 -267.915971) (xy 88.929246 -267.900527)
			(xy 88.884714 -267.877837) (xy 88.844281 -267.848461) (xy 88.808941 -267.813121) (xy 88.779565 -267.772688)
			(xy 88.756875 -267.728156) (xy 88.741431 -267.680624) (xy 88.733612 -267.631261) (xy 88.426295 -267.631261)
			(xy 88.426286 -267.631718) (xy 88.418122 -267.681952) (xy 88.402006 -267.730226) (xy 88.378355 -267.775289)
			(xy 88.347782 -267.815975) (xy 88.311078 -267.85123) (xy 88.269194 -267.88014) (xy 88.223215 -267.901957)
			(xy 88.174331 -267.916117) (xy 88.12381 -267.922251) (xy 88.072958 -267.920202) (xy 88.023094 -267.910022)
			(xy 87.975508 -267.891975) (xy 87.931434 -267.866529) (xy 87.892012 -267.834342) (xy 87.858264 -267.796248)
			(xy 87.831063 -267.753234) (xy 87.811115 -267.706414) (xy 87.798936 -267.657) (xy 87.794841 -267.606272)
			(xy 87.48903 -267.606272) (xy 87.48854 -267.631261) (xy 87.480721 -267.680624) (xy 87.465277 -267.728156)
			(xy 87.442587 -267.772688) (xy 87.413211 -267.813121) (xy 87.377871 -267.848461) (xy 87.337438 -267.877837)
			(xy 87.292906 -267.900527) (xy 87.245374 -267.915971) (xy 87.196011 -267.92379) (xy 87.146033 -267.92379)
			(xy 87.09667 -267.915971) (xy 87.049138 -267.900527) (xy 87.004606 -267.877837) (xy 86.964173 -267.848461)
			(xy 86.928833 -267.813121) (xy 86.899457 -267.772688) (xy 86.876767 -267.728156) (xy 86.861323 -267.680624)
			(xy 86.853504 -267.631261) (xy 86.548486 -267.631261) (xy 86.540667 -267.680624) (xy 86.525223 -267.728156)
			(xy 86.502533 -267.772688) (xy 86.473157 -267.813121) (xy 86.437817 -267.848461) (xy 86.397384 -267.877837)
			(xy 86.352852 -267.900527) (xy 86.30532 -267.915971) (xy 86.255957 -267.92379) (xy 86.205979 -267.92379)
			(xy 86.156616 -267.915971) (xy 86.109084 -267.900527) (xy 86.064552 -267.877837) (xy 86.024119 -267.848461)
			(xy 85.988779 -267.813121) (xy 85.959403 -267.772688) (xy 85.936713 -267.728156) (xy 85.921269 -267.680624)
			(xy 85.91345 -267.631261) (xy 85.608432 -267.631261) (xy 85.600613 -267.680624) (xy 85.585169 -267.728156)
			(xy 85.562479 -267.772688) (xy 85.533103 -267.813121) (xy 85.497763 -267.848461) (xy 85.45733 -267.877837)
			(xy 85.412798 -267.900527) (xy 85.365266 -267.915971) (xy 85.315903 -267.92379) (xy 85.265925 -267.92379)
			(xy 85.216562 -267.915971) (xy 85.16903 -267.900527) (xy 85.124498 -267.877837) (xy 85.084065 -267.848461)
			(xy 85.048725 -267.813121) (xy 85.019349 -267.772688) (xy 84.996659 -267.728156) (xy 84.981215 -267.680624)
			(xy 84.973396 -267.631261) (xy 84.666333 -267.631261) (xy 84.666324 -267.631718) (xy 84.65816 -267.681952)
			(xy 84.642044 -267.730226) (xy 84.618393 -267.775289) (xy 84.58782 -267.815975) (xy 84.551116 -267.85123)
			(xy 84.509232 -267.88014) (xy 84.463253 -267.901957) (xy 84.414369 -267.916117) (xy 84.363848 -267.922251)
			(xy 84.312996 -267.920202) (xy 84.263132 -267.910022) (xy 84.215546 -267.891975) (xy 84.171472 -267.866529)
			(xy 84.13205 -267.834342) (xy 84.098302 -267.796248) (xy 84.071101 -267.753234) (xy 84.051153 -267.706414)
			(xy 84.038974 -267.657) (xy 84.034879 -267.606272) (xy 83.729068 -267.606272) (xy 83.728578 -267.631261)
			(xy 83.720759 -267.680624) (xy 83.705315 -267.728156) (xy 83.682625 -267.772688) (xy 83.653249 -267.813121)
			(xy 83.617909 -267.848461) (xy 83.577476 -267.877837) (xy 83.532944 -267.900527) (xy 83.485412 -267.915971)
			(xy 83.436049 -267.92379) (xy 83.386071 -267.92379) (xy 83.336708 -267.915971) (xy 83.289176 -267.900527)
			(xy 83.244644 -267.877837) (xy 83.204211 -267.848461) (xy 83.168871 -267.813121) (xy 83.139495 -267.772688)
			(xy 83.116805 -267.728156) (xy 83.101361 -267.680624) (xy 83.093542 -267.631261) (xy 82.788524 -267.631261)
			(xy 82.780705 -267.680624) (xy 82.765261 -267.728156) (xy 82.742571 -267.772688) (xy 82.713195 -267.813121)
			(xy 82.677855 -267.848461) (xy 82.637422 -267.877837) (xy 82.59289 -267.900527) (xy 82.545358 -267.915971)
			(xy 82.495995 -267.92379) (xy 82.446017 -267.92379) (xy 82.396654 -267.915971) (xy 82.349122 -267.900527)
			(xy 82.30459 -267.877837) (xy 82.264157 -267.848461) (xy 82.228817 -267.813121) (xy 82.199441 -267.772688)
			(xy 82.176751 -267.728156) (xy 82.161307 -267.680624) (xy 82.153488 -267.631261) (xy 81.846171 -267.631261)
			(xy 81.846162 -267.631718) (xy 81.837998 -267.681952) (xy 81.821882 -267.730226) (xy 81.798231 -267.775289)
			(xy 81.767658 -267.815975) (xy 81.730954 -267.85123) (xy 81.68907 -267.88014) (xy 81.643091 -267.901957)
			(xy 81.594207 -267.916117) (xy 81.543686 -267.922251) (xy 81.492834 -267.920202) (xy 81.44297 -267.910022)
			(xy 81.395384 -267.891975) (xy 81.35131 -267.866529) (xy 81.311888 -267.834342) (xy 81.27814 -267.796248)
			(xy 81.250939 -267.753234) (xy 81.230991 -267.706414) (xy 81.218812 -267.657) (xy 81.214717 -267.606272)
			(xy 80.90916 -267.606272) (xy 80.90867 -267.631261) (xy 80.900851 -267.680624) (xy 80.885407 -267.728156)
			(xy 80.862717 -267.772688) (xy 80.833341 -267.813121) (xy 80.798001 -267.848461) (xy 80.757568 -267.877837)
			(xy 80.713036 -267.900527) (xy 80.665504 -267.915971) (xy 80.616141 -267.92379) (xy 80.566163 -267.92379)
			(xy 80.5168 -267.915971) (xy 80.469268 -267.900527) (xy 80.424736 -267.877837) (xy 80.384303 -267.848461)
			(xy 80.348963 -267.813121) (xy 80.319587 -267.772688) (xy 80.296897 -267.728156) (xy 80.281453 -267.680624)
			(xy 80.273634 -267.631261) (xy 79.53248 -267.631261) (xy 79.53248 -268.441267) (xy 80.743534 -268.441267)
			(xy 80.743534 -268.391289) (xy 80.751353 -268.341926) (xy 80.766797 -268.294394) (xy 80.789487 -268.249862)
			(xy 80.818863 -268.209429) (xy 80.854203 -268.174089) (xy 80.894636 -268.144713) (xy 80.939168 -268.122023)
			(xy 80.9867 -268.106579) (xy 81.036063 -268.09876) (xy 81.086041 -268.09876) (xy 81.135404 -268.106579)
			(xy 81.182936 -268.122023) (xy 81.227468 -268.144713) (xy 81.267901 -268.174089) (xy 81.303241 -268.209429)
			(xy 81.332617 -268.249862) (xy 81.355307 -268.294394) (xy 81.370751 -268.341926) (xy 81.37857 -268.391289)
			(xy 81.37906 -268.416278) (xy 81.37857 -268.441267) (xy 81.683588 -268.441267) (xy 81.683588 -268.391289)
			(xy 81.691407 -268.341926) (xy 81.706851 -268.294394) (xy 81.729541 -268.249862) (xy 81.758917 -268.209429)
			(xy 81.794257 -268.174089) (xy 81.83469 -268.144713) (xy 81.879222 -268.122023) (xy 81.926754 -268.106579)
			(xy 81.976117 -268.09876) (xy 82.026095 -268.09876) (xy 82.075458 -268.106579) (xy 82.12299 -268.122023)
			(xy 82.167522 -268.144713) (xy 82.207955 -268.174089) (xy 82.243295 -268.209429) (xy 82.272671 -268.249862)
			(xy 82.295361 -268.294394) (xy 82.310805 -268.341926) (xy 82.318624 -268.391289) (xy 82.319114 -268.416278)
			(xy 82.318624 -268.441267) (xy 82.623388 -268.441267) (xy 82.623388 -268.391289) (xy 82.631207 -268.341926)
			(xy 82.646651 -268.294394) (xy 82.669341 -268.249862) (xy 82.698717 -268.209429) (xy 82.734057 -268.174089)
			(xy 82.77449 -268.144713) (xy 82.819022 -268.122023) (xy 82.866554 -268.106579) (xy 82.915917 -268.09876)
			(xy 82.965895 -268.09876) (xy 83.015258 -268.106579) (xy 83.06279 -268.122023) (xy 83.107322 -268.144713)
			(xy 83.147755 -268.174089) (xy 83.183095 -268.209429) (xy 83.212471 -268.249862) (xy 83.235161 -268.294394)
			(xy 83.250605 -268.341926) (xy 83.258424 -268.391289) (xy 83.258914 -268.416278) (xy 83.258424 -268.441267)
			(xy 83.563442 -268.441267) (xy 83.563442 -268.391289) (xy 83.571261 -268.341926) (xy 83.586705 -268.294394)
			(xy 83.609395 -268.249862) (xy 83.638771 -268.209429) (xy 83.674111 -268.174089) (xy 83.714544 -268.144713)
			(xy 83.759076 -268.122023) (xy 83.806608 -268.106579) (xy 83.855971 -268.09876) (xy 83.905949 -268.09876)
			(xy 83.955312 -268.106579) (xy 84.002844 -268.122023) (xy 84.047376 -268.144713) (xy 84.087809 -268.174089)
			(xy 84.123149 -268.209429) (xy 84.152525 -268.249862) (xy 84.175215 -268.294394) (xy 84.190659 -268.341926)
			(xy 84.198478 -268.391289) (xy 84.198968 -268.416278) (xy 84.198478 -268.441267) (xy 84.503496 -268.441267)
			(xy 84.503496 -268.391289) (xy 84.511315 -268.341926) (xy 84.526759 -268.294394) (xy 84.549449 -268.249862)
			(xy 84.578825 -268.209429) (xy 84.614165 -268.174089) (xy 84.654598 -268.144713) (xy 84.69913 -268.122023)
			(xy 84.746662 -268.106579) (xy 84.796025 -268.09876) (xy 84.846003 -268.09876) (xy 84.895366 -268.106579)
			(xy 84.942898 -268.122023) (xy 84.98743 -268.144713) (xy 85.027863 -268.174089) (xy 85.063203 -268.209429)
			(xy 85.092579 -268.249862) (xy 85.115269 -268.294394) (xy 85.130713 -268.341926) (xy 85.138532 -268.391289)
			(xy 85.139022 -268.416278) (xy 85.138532 -268.441267) (xy 85.44355 -268.441267) (xy 85.44355 -268.391289)
			(xy 85.451369 -268.341926) (xy 85.466813 -268.294394) (xy 85.489503 -268.249862) (xy 85.518879 -268.209429)
			(xy 85.554219 -268.174089) (xy 85.594652 -268.144713) (xy 85.639184 -268.122023) (xy 85.686716 -268.106579)
			(xy 85.736079 -268.09876) (xy 85.786057 -268.09876) (xy 85.83542 -268.106579) (xy 85.882952 -268.122023)
			(xy 85.927484 -268.144713) (xy 85.967917 -268.174089) (xy 86.003257 -268.209429) (xy 86.032633 -268.249862)
			(xy 86.055323 -268.294394) (xy 86.070767 -268.341926) (xy 86.078586 -268.391289) (xy 86.079076 -268.416278)
			(xy 86.078586 -268.441267) (xy 87.323404 -268.441267) (xy 87.323404 -268.391289) (xy 87.331223 -268.341926)
			(xy 87.346667 -268.294394) (xy 87.369357 -268.249862) (xy 87.398733 -268.209429) (xy 87.434073 -268.174089)
			(xy 87.474506 -268.144713) (xy 87.519038 -268.122023) (xy 87.56657 -268.106579) (xy 87.615933 -268.09876)
			(xy 87.665911 -268.09876) (xy 87.715274 -268.106579) (xy 87.762806 -268.122023) (xy 87.807338 -268.144713)
			(xy 87.847771 -268.174089) (xy 87.883111 -268.209429) (xy 87.912487 -268.249862) (xy 87.935177 -268.294394)
			(xy 87.950621 -268.341926) (xy 87.95844 -268.391289) (xy 87.95893 -268.416278) (xy 87.95844 -268.441267)
			(xy 88.263458 -268.441267) (xy 88.263458 -268.391289) (xy 88.271277 -268.341926) (xy 88.286721 -268.294394)
			(xy 88.309411 -268.249862) (xy 88.338787 -268.209429) (xy 88.374127 -268.174089) (xy 88.41456 -268.144713)
			(xy 88.459092 -268.122023) (xy 88.506624 -268.106579) (xy 88.555987 -268.09876) (xy 88.605965 -268.09876)
			(xy 88.655328 -268.106579) (xy 88.70286 -268.122023) (xy 88.747392 -268.144713) (xy 88.787825 -268.174089)
			(xy 88.823165 -268.209429) (xy 88.852541 -268.249862) (xy 88.875231 -268.294394) (xy 88.890675 -268.341926)
			(xy 88.898494 -268.391289) (xy 88.898984 -268.416278) (xy 88.898494 -268.441267) (xy 89.203512 -268.441267)
			(xy 89.203512 -268.391289) (xy 89.211331 -268.341926) (xy 89.226775 -268.294394) (xy 89.249465 -268.249862)
			(xy 89.278841 -268.209429) (xy 89.314181 -268.174089) (xy 89.354614 -268.144713) (xy 89.399146 -268.122023)
			(xy 89.446678 -268.106579) (xy 89.496041 -268.09876) (xy 89.546019 -268.09876) (xy 89.595382 -268.106579)
			(xy 89.642914 -268.122023) (xy 89.687446 -268.144713) (xy 89.727879 -268.174089) (xy 89.763219 -268.209429)
			(xy 89.792595 -268.249862) (xy 89.815285 -268.294394) (xy 89.830729 -268.341926) (xy 89.838548 -268.391289)
			(xy 89.839038 -268.416278) (xy 89.838548 -268.441267) (xy 90.143566 -268.441267) (xy 90.143566 -268.391289)
			(xy 90.151385 -268.341926) (xy 90.166829 -268.294394) (xy 90.189519 -268.249862) (xy 90.218895 -268.209429)
			(xy 90.254235 -268.174089) (xy 90.294668 -268.144713) (xy 90.3392 -268.122023) (xy 90.386732 -268.106579)
			(xy 90.436095 -268.09876) (xy 90.486073 -268.09876) (xy 90.535436 -268.106579) (xy 90.582968 -268.122023)
			(xy 90.6275 -268.144713) (xy 90.667933 -268.174089) (xy 90.703273 -268.209429) (xy 90.732649 -268.249862)
			(xy 90.755339 -268.294394) (xy 90.770783 -268.341926) (xy 90.778602 -268.391289) (xy 90.779092 -268.416278)
			(xy 90.778602 -268.441267) (xy 91.08362 -268.441267) (xy 91.08362 -268.391289) (xy 91.091439 -268.341926)
			(xy 91.106883 -268.294394) (xy 91.129573 -268.249862) (xy 91.158949 -268.209429) (xy 91.194289 -268.174089)
			(xy 91.234722 -268.144713) (xy 91.279254 -268.122023) (xy 91.326786 -268.106579) (xy 91.376149 -268.09876)
			(xy 91.426127 -268.09876) (xy 91.47549 -268.106579) (xy 91.523022 -268.122023) (xy 91.567554 -268.144713)
			(xy 91.607987 -268.174089) (xy 91.643327 -268.209429) (xy 91.672703 -268.249862) (xy 91.695393 -268.294394)
			(xy 91.710837 -268.341926) (xy 91.718656 -268.391289) (xy 91.719146 -268.416278) (xy 91.718656 -268.441267)
			(xy 92.02342 -268.441267) (xy 92.02342 -268.391289) (xy 92.031239 -268.341926) (xy 92.046683 -268.294394)
			(xy 92.069373 -268.249862) (xy 92.098749 -268.209429) (xy 92.134089 -268.174089) (xy 92.174522 -268.144713)
			(xy 92.219054 -268.122023) (xy 92.266586 -268.106579) (xy 92.315949 -268.09876) (xy 92.365927 -268.09876)
			(xy 92.41529 -268.106579) (xy 92.462822 -268.122023) (xy 92.507354 -268.144713) (xy 92.547787 -268.174089)
			(xy 92.583127 -268.209429) (xy 92.612503 -268.249862) (xy 92.635193 -268.294394) (xy 92.650637 -268.341926)
			(xy 92.658456 -268.391289) (xy 92.658946 -268.416278) (xy 92.658456 -268.441267) (xy 93.903528 -268.441267)
			(xy 93.903528 -268.391289) (xy 93.911347 -268.341926) (xy 93.926791 -268.294394) (xy 93.949481 -268.249862)
			(xy 93.978857 -268.209429) (xy 94.014197 -268.174089) (xy 94.05463 -268.144713) (xy 94.099162 -268.122023)
			(xy 94.146694 -268.106579) (xy 94.196057 -268.09876) (xy 94.246035 -268.09876) (xy 94.295398 -268.106579)
			(xy 94.34293 -268.122023) (xy 94.387462 -268.144713) (xy 94.427895 -268.174089) (xy 94.463235 -268.209429)
			(xy 94.492611 -268.249862) (xy 94.515301 -268.294394) (xy 94.530745 -268.341926) (xy 94.538564 -268.391289)
			(xy 94.539054 -268.416278) (xy 94.538564 -268.441267) (xy 94.843582 -268.441267) (xy 94.843582 -268.391289)
			(xy 94.851401 -268.341926) (xy 94.866845 -268.294394) (xy 94.889535 -268.249862) (xy 94.918911 -268.209429)
			(xy 94.954251 -268.174089) (xy 94.994684 -268.144713) (xy 95.039216 -268.122023) (xy 95.086748 -268.106579)
			(xy 95.136111 -268.09876) (xy 95.186089 -268.09876) (xy 95.235452 -268.106579) (xy 95.282984 -268.122023)
			(xy 95.327516 -268.144713) (xy 95.367949 -268.174089) (xy 95.403289 -268.209429) (xy 95.432665 -268.249862)
			(xy 95.455355 -268.294394) (xy 95.470799 -268.341926) (xy 95.478618 -268.391289) (xy 95.479108 -268.416278)
			(xy 95.478618 -268.441267) (xy 95.470799 -268.49063) (xy 95.455355 -268.538162) (xy 95.432665 -268.582694)
			(xy 95.403289 -268.623127) (xy 95.367949 -268.658467) (xy 95.327516 -268.687843) (xy 95.282984 -268.710533)
			(xy 95.235452 -268.725977) (xy 95.186089 -268.733796) (xy 95.136111 -268.733796) (xy 95.086748 -268.725977)
			(xy 95.039216 -268.710533) (xy 94.994684 -268.687843) (xy 94.954251 -268.658467) (xy 94.918911 -268.623127)
			(xy 94.889535 -268.582694) (xy 94.866845 -268.538162) (xy 94.851401 -268.49063) (xy 94.843582 -268.441267)
			(xy 94.538564 -268.441267) (xy 94.530745 -268.49063) (xy 94.515301 -268.538162) (xy 94.492611 -268.582694)
			(xy 94.463235 -268.623127) (xy 94.427895 -268.658467) (xy 94.387462 -268.687843) (xy 94.34293 -268.710533)
			(xy 94.295398 -268.725977) (xy 94.246035 -268.733796) (xy 94.196057 -268.733796) (xy 94.146694 -268.725977)
			(xy 94.099162 -268.710533) (xy 94.05463 -268.687843) (xy 94.014197 -268.658467) (xy 93.978857 -268.623127)
			(xy 93.949481 -268.582694) (xy 93.926791 -268.538162) (xy 93.911347 -268.49063) (xy 93.903528 -268.441267)
			(xy 92.658456 -268.441267) (xy 92.650637 -268.49063) (xy 92.635193 -268.538162) (xy 92.612503 -268.582694)
			(xy 92.583127 -268.623127) (xy 92.547787 -268.658467) (xy 92.507354 -268.687843) (xy 92.462822 -268.710533)
			(xy 92.41529 -268.725977) (xy 92.365927 -268.733796) (xy 92.315949 -268.733796) (xy 92.266586 -268.725977)
			(xy 92.219054 -268.710533) (xy 92.174522 -268.687843) (xy 92.134089 -268.658467) (xy 92.098749 -268.623127)
			(xy 92.069373 -268.582694) (xy 92.046683 -268.538162) (xy 92.031239 -268.49063) (xy 92.02342 -268.441267)
			(xy 91.718656 -268.441267) (xy 91.710837 -268.49063) (xy 91.695393 -268.538162) (xy 91.672703 -268.582694)
			(xy 91.643327 -268.623127) (xy 91.607987 -268.658467) (xy 91.567554 -268.687843) (xy 91.523022 -268.710533)
			(xy 91.47549 -268.725977) (xy 91.426127 -268.733796) (xy 91.376149 -268.733796) (xy 91.326786 -268.725977)
			(xy 91.279254 -268.710533) (xy 91.234722 -268.687843) (xy 91.194289 -268.658467) (xy 91.158949 -268.623127)
			(xy 91.129573 -268.582694) (xy 91.106883 -268.538162) (xy 91.091439 -268.49063) (xy 91.08362 -268.441267)
			(xy 90.778602 -268.441267) (xy 90.770783 -268.49063) (xy 90.755339 -268.538162) (xy 90.732649 -268.582694)
			(xy 90.703273 -268.623127) (xy 90.667933 -268.658467) (xy 90.6275 -268.687843) (xy 90.582968 -268.710533)
			(xy 90.535436 -268.725977) (xy 90.486073 -268.733796) (xy 90.436095 -268.733796) (xy 90.386732 -268.725977)
			(xy 90.3392 -268.710533) (xy 90.294668 -268.687843) (xy 90.254235 -268.658467) (xy 90.218895 -268.623127)
			(xy 90.189519 -268.582694) (xy 90.166829 -268.538162) (xy 90.151385 -268.49063) (xy 90.143566 -268.441267)
			(xy 89.838548 -268.441267) (xy 89.830729 -268.49063) (xy 89.815285 -268.538162) (xy 89.792595 -268.582694)
			(xy 89.763219 -268.623127) (xy 89.727879 -268.658467) (xy 89.687446 -268.687843) (xy 89.642914 -268.710533)
			(xy 89.595382 -268.725977) (xy 89.546019 -268.733796) (xy 89.496041 -268.733796) (xy 89.446678 -268.725977)
			(xy 89.399146 -268.710533) (xy 89.354614 -268.687843) (xy 89.314181 -268.658467) (xy 89.278841 -268.623127)
			(xy 89.249465 -268.582694) (xy 89.226775 -268.538162) (xy 89.211331 -268.49063) (xy 89.203512 -268.441267)
			(xy 88.898494 -268.441267) (xy 88.890675 -268.49063) (xy 88.875231 -268.538162) (xy 88.852541 -268.582694)
			(xy 88.823165 -268.623127) (xy 88.787825 -268.658467) (xy 88.747392 -268.687843) (xy 88.70286 -268.710533)
			(xy 88.655328 -268.725977) (xy 88.605965 -268.733796) (xy 88.555987 -268.733796) (xy 88.506624 -268.725977)
			(xy 88.459092 -268.710533) (xy 88.41456 -268.687843) (xy 88.374127 -268.658467) (xy 88.338787 -268.623127)
			(xy 88.309411 -268.582694) (xy 88.286721 -268.538162) (xy 88.271277 -268.49063) (xy 88.263458 -268.441267)
			(xy 87.95844 -268.441267) (xy 87.950621 -268.49063) (xy 87.935177 -268.538162) (xy 87.912487 -268.582694)
			(xy 87.883111 -268.623127) (xy 87.847771 -268.658467) (xy 87.807338 -268.687843) (xy 87.762806 -268.710533)
			(xy 87.715274 -268.725977) (xy 87.665911 -268.733796) (xy 87.615933 -268.733796) (xy 87.56657 -268.725977)
			(xy 87.519038 -268.710533) (xy 87.474506 -268.687843) (xy 87.434073 -268.658467) (xy 87.398733 -268.623127)
			(xy 87.369357 -268.582694) (xy 87.346667 -268.538162) (xy 87.331223 -268.49063) (xy 87.323404 -268.441267)
			(xy 86.078586 -268.441267) (xy 86.070767 -268.49063) (xy 86.055323 -268.538162) (xy 86.032633 -268.582694)
			(xy 86.003257 -268.623127) (xy 85.967917 -268.658467) (xy 85.927484 -268.687843) (xy 85.882952 -268.710533)
			(xy 85.83542 -268.725977) (xy 85.786057 -268.733796) (xy 85.736079 -268.733796) (xy 85.686716 -268.725977)
			(xy 85.639184 -268.710533) (xy 85.594652 -268.687843) (xy 85.554219 -268.658467) (xy 85.518879 -268.623127)
			(xy 85.489503 -268.582694) (xy 85.466813 -268.538162) (xy 85.451369 -268.49063) (xy 85.44355 -268.441267)
			(xy 85.138532 -268.441267) (xy 85.130713 -268.49063) (xy 85.115269 -268.538162) (xy 85.092579 -268.582694)
			(xy 85.063203 -268.623127) (xy 85.027863 -268.658467) (xy 84.98743 -268.687843) (xy 84.942898 -268.710533)
			(xy 84.895366 -268.725977) (xy 84.846003 -268.733796) (xy 84.796025 -268.733796) (xy 84.746662 -268.725977)
			(xy 84.69913 -268.710533) (xy 84.654598 -268.687843) (xy 84.614165 -268.658467) (xy 84.578825 -268.623127)
			(xy 84.549449 -268.582694) (xy 84.526759 -268.538162) (xy 84.511315 -268.49063) (xy 84.503496 -268.441267)
			(xy 84.198478 -268.441267) (xy 84.190659 -268.49063) (xy 84.175215 -268.538162) (xy 84.152525 -268.582694)
			(xy 84.123149 -268.623127) (xy 84.087809 -268.658467) (xy 84.047376 -268.687843) (xy 84.002844 -268.710533)
			(xy 83.955312 -268.725977) (xy 83.905949 -268.733796) (xy 83.855971 -268.733796) (xy 83.806608 -268.725977)
			(xy 83.759076 -268.710533) (xy 83.714544 -268.687843) (xy 83.674111 -268.658467) (xy 83.638771 -268.623127)
			(xy 83.609395 -268.582694) (xy 83.586705 -268.538162) (xy 83.571261 -268.49063) (xy 83.563442 -268.441267)
			(xy 83.258424 -268.441267) (xy 83.250605 -268.49063) (xy 83.235161 -268.538162) (xy 83.212471 -268.582694)
			(xy 83.183095 -268.623127) (xy 83.147755 -268.658467) (xy 83.107322 -268.687843) (xy 83.06279 -268.710533)
			(xy 83.015258 -268.725977) (xy 82.965895 -268.733796) (xy 82.915917 -268.733796) (xy 82.866554 -268.725977)
			(xy 82.819022 -268.710533) (xy 82.77449 -268.687843) (xy 82.734057 -268.658467) (xy 82.698717 -268.623127)
			(xy 82.669341 -268.582694) (xy 82.646651 -268.538162) (xy 82.631207 -268.49063) (xy 82.623388 -268.441267)
			(xy 82.318624 -268.441267) (xy 82.310805 -268.49063) (xy 82.295361 -268.538162) (xy 82.272671 -268.582694)
			(xy 82.243295 -268.623127) (xy 82.207955 -268.658467) (xy 82.167522 -268.687843) (xy 82.12299 -268.710533)
			(xy 82.075458 -268.725977) (xy 82.026095 -268.733796) (xy 81.976117 -268.733796) (xy 81.926754 -268.725977)
			(xy 81.879222 -268.710533) (xy 81.83469 -268.687843) (xy 81.794257 -268.658467) (xy 81.758917 -268.623127)
			(xy 81.729541 -268.582694) (xy 81.706851 -268.538162) (xy 81.691407 -268.49063) (xy 81.683588 -268.441267)
			(xy 81.37857 -268.441267) (xy 81.370751 -268.49063) (xy 81.355307 -268.538162) (xy 81.332617 -268.582694)
			(xy 81.303241 -268.623127) (xy 81.267901 -268.658467) (xy 81.227468 -268.687843) (xy 81.182936 -268.710533)
			(xy 81.135404 -268.725977) (xy 81.086041 -268.733796) (xy 81.036063 -268.733796) (xy 80.9867 -268.725977)
			(xy 80.939168 -268.710533) (xy 80.894636 -268.687843) (xy 80.854203 -268.658467) (xy 80.818863 -268.623127)
			(xy 80.789487 -268.582694) (xy 80.766797 -268.538162) (xy 80.751353 -268.49063) (xy 80.743534 -268.441267)
			(xy 79.53248 -268.441267) (xy 79.53248 -268.80693) (xy 79.532961 -268.820568) (xy 79.540262 -268.846852)
			(xy 79.554256 -268.870268) (xy 79.573946 -268.889147) (xy 79.597929 -268.902146) (xy 79.624497 -268.908337)
			(xy 79.638144 -268.908276) (xy 79.651098 -268.908022) (xy 79.676111 -268.908487) (xy 79.72552 -268.916312)
			(xy 79.773096 -268.931771) (xy 79.817669 -268.954481) (xy 79.85814 -268.983885) (xy 79.893513 -269.019258)
			(xy 79.922917 -269.059729) (xy 79.945628 -269.104302) (xy 79.961087 -269.151878) (xy 79.968913 -269.201287)
			(xy 79.968913 -269.251273) (xy 80.273634 -269.251273) (xy 80.273634 -269.201295) (xy 80.281453 -269.151932)
			(xy 80.296897 -269.1044) (xy 80.319587 -269.059868) (xy 80.348963 -269.019435) (xy 80.384303 -268.984095)
			(xy 80.424736 -268.954719) (xy 80.469268 -268.932029) (xy 80.5168 -268.916585) (xy 80.566163 -268.908766)
			(xy 80.616141 -268.908766) (xy 80.665504 -268.916585) (xy 80.713036 -268.932029) (xy 80.757568 -268.954719)
			(xy 80.798001 -268.984095) (xy 80.833341 -269.019435) (xy 80.862717 -269.059868) (xy 80.885407 -269.1044)
			(xy 80.900851 -269.151932) (xy 80.90867 -269.201295) (xy 80.90916 -269.226284) (xy 81.214717 -269.226284)
			(xy 81.218812 -269.175556) (xy 81.230991 -269.126142) (xy 81.250939 -269.079322) (xy 81.27814 -269.036308)
			(xy 81.311888 -268.998214) (xy 81.35131 -268.966027) (xy 81.395384 -268.940581) (xy 81.44297 -268.922534)
			(xy 81.492834 -268.912354) (xy 81.543686 -268.910305) (xy 81.594207 -268.916439) (xy 81.643091 -268.930599)
			(xy 81.68907 -268.952416) (xy 81.730954 -268.981326) (xy 81.767658 -269.016581) (xy 81.798231 -269.057267)
			(xy 81.821882 -269.10233) (xy 81.837998 -269.150604) (xy 81.846162 -269.200838) (xy 81.846674 -269.226284)
			(xy 81.846171 -269.251273) (xy 82.153488 -269.251273) (xy 82.153488 -269.201295) (xy 82.161307 -269.151932)
			(xy 82.176751 -269.1044) (xy 82.199441 -269.059868) (xy 82.228817 -269.019435) (xy 82.264157 -268.984095)
			(xy 82.30459 -268.954719) (xy 82.349122 -268.932029) (xy 82.396654 -268.916585) (xy 82.446017 -268.908766)
			(xy 82.495995 -268.908766) (xy 82.545358 -268.916585) (xy 82.59289 -268.932029) (xy 82.637422 -268.954719)
			(xy 82.677855 -268.984095) (xy 82.713195 -269.019435) (xy 82.742571 -269.059868) (xy 82.765261 -269.1044)
			(xy 82.780705 -269.151932) (xy 82.788524 -269.201295) (xy 82.789014 -269.226284) (xy 82.788524 -269.251273)
			(xy 83.093542 -269.251273) (xy 83.093542 -269.201295) (xy 83.101361 -269.151932) (xy 83.116805 -269.1044)
			(xy 83.139495 -269.059868) (xy 83.168871 -269.019435) (xy 83.204211 -268.984095) (xy 83.244644 -268.954719)
			(xy 83.289176 -268.932029) (xy 83.336708 -268.916585) (xy 83.386071 -268.908766) (xy 83.436049 -268.908766)
			(xy 83.485412 -268.916585) (xy 83.532944 -268.932029) (xy 83.577476 -268.954719) (xy 83.617909 -268.984095)
			(xy 83.653249 -269.019435) (xy 83.682625 -269.059868) (xy 83.705315 -269.1044) (xy 83.720759 -269.151932)
			(xy 83.728578 -269.201295) (xy 83.729068 -269.226284) (xy 84.034879 -269.226284) (xy 84.038974 -269.175556)
			(xy 84.051153 -269.126142) (xy 84.071101 -269.079322) (xy 84.098302 -269.036308) (xy 84.13205 -268.998214)
			(xy 84.171472 -268.966027) (xy 84.215546 -268.940581) (xy 84.263132 -268.922534) (xy 84.312996 -268.912354)
			(xy 84.363848 -268.910305) (xy 84.414369 -268.916439) (xy 84.463253 -268.930599) (xy 84.509232 -268.952416)
			(xy 84.551116 -268.981326) (xy 84.58782 -269.016581) (xy 84.618393 -269.057267) (xy 84.642044 -269.10233)
			(xy 84.65816 -269.150604) (xy 84.666324 -269.200838) (xy 84.666836 -269.226284) (xy 84.666333 -269.251273)
			(xy 84.973396 -269.251273) (xy 84.973396 -269.201295) (xy 84.981215 -269.151932) (xy 84.996659 -269.1044)
			(xy 85.019349 -269.059868) (xy 85.048725 -269.019435) (xy 85.084065 -268.984095) (xy 85.124498 -268.954719)
			(xy 85.16903 -268.932029) (xy 85.216562 -268.916585) (xy 85.265925 -268.908766) (xy 85.315903 -268.908766)
			(xy 85.365266 -268.916585) (xy 85.412798 -268.932029) (xy 85.45733 -268.954719) (xy 85.497763 -268.984095)
			(xy 85.533103 -269.019435) (xy 85.562479 -269.059868) (xy 85.585169 -269.1044) (xy 85.600613 -269.151932)
			(xy 85.608432 -269.201295) (xy 85.608922 -269.226284) (xy 85.608432 -269.251273) (xy 85.91345 -269.251273)
			(xy 85.91345 -269.201295) (xy 85.921269 -269.151932) (xy 85.936713 -269.1044) (xy 85.959403 -269.059868)
			(xy 85.988779 -269.019435) (xy 86.024119 -268.984095) (xy 86.064552 -268.954719) (xy 86.109084 -268.932029)
			(xy 86.156616 -268.916585) (xy 86.205979 -268.908766) (xy 86.255957 -268.908766) (xy 86.30532 -268.916585)
			(xy 86.352852 -268.932029) (xy 86.397384 -268.954719) (xy 86.437817 -268.984095) (xy 86.473157 -269.019435)
			(xy 86.502533 -269.059868) (xy 86.525223 -269.1044) (xy 86.540667 -269.151932) (xy 86.548486 -269.201295)
			(xy 86.548976 -269.226284) (xy 86.548486 -269.251273) (xy 86.853504 -269.251273) (xy 86.853504 -269.201295)
			(xy 86.861323 -269.151932) (xy 86.876767 -269.1044) (xy 86.899457 -269.059868) (xy 86.928833 -269.019435)
			(xy 86.964173 -268.984095) (xy 87.004606 -268.954719) (xy 87.049138 -268.932029) (xy 87.09667 -268.916585)
			(xy 87.146033 -268.908766) (xy 87.196011 -268.908766) (xy 87.245374 -268.916585) (xy 87.292906 -268.932029)
			(xy 87.337438 -268.954719) (xy 87.377871 -268.984095) (xy 87.413211 -269.019435) (xy 87.442587 -269.059868)
			(xy 87.465277 -269.1044) (xy 87.480721 -269.151932) (xy 87.48854 -269.201295) (xy 87.48903 -269.226284)
			(xy 87.794841 -269.226284) (xy 87.798936 -269.175556) (xy 87.811115 -269.126142) (xy 87.831063 -269.079322)
			(xy 87.858264 -269.036308) (xy 87.892012 -268.998214) (xy 87.931434 -268.966027) (xy 87.975508 -268.940581)
			(xy 88.023094 -268.922534) (xy 88.072958 -268.912354) (xy 88.12381 -268.910305) (xy 88.174331 -268.916439)
			(xy 88.223215 -268.930599) (xy 88.269194 -268.952416) (xy 88.311078 -268.981326) (xy 88.347782 -269.016581)
			(xy 88.378355 -269.057267) (xy 88.402006 -269.10233) (xy 88.418122 -269.150604) (xy 88.426286 -269.200838)
			(xy 88.426798 -269.226284) (xy 88.426295 -269.251273) (xy 88.733612 -269.251273) (xy 88.733612 -269.201295)
			(xy 88.741431 -269.151932) (xy 88.756875 -269.1044) (xy 88.779565 -269.059868) (xy 88.808941 -269.019435)
			(xy 88.844281 -268.984095) (xy 88.884714 -268.954719) (xy 88.929246 -268.932029) (xy 88.976778 -268.916585)
			(xy 89.026141 -268.908766) (xy 89.076119 -268.908766) (xy 89.125482 -268.916585) (xy 89.173014 -268.932029)
			(xy 89.217546 -268.954719) (xy 89.257979 -268.984095) (xy 89.293319 -269.019435) (xy 89.322695 -269.059868)
			(xy 89.345385 -269.1044) (xy 89.360829 -269.151932) (xy 89.368648 -269.201295) (xy 89.369138 -269.226284)
			(xy 89.368648 -269.251273) (xy 89.673412 -269.251273) (xy 89.673412 -269.201295) (xy 89.681231 -269.151932)
			(xy 89.696675 -269.1044) (xy 89.719365 -269.059868) (xy 89.748741 -269.019435) (xy 89.784081 -268.984095)
			(xy 89.824514 -268.954719) (xy 89.869046 -268.932029) (xy 89.916578 -268.916585) (xy 89.965941 -268.908766)
			(xy 90.015919 -268.908766) (xy 90.065282 -268.916585) (xy 90.112814 -268.932029) (xy 90.157346 -268.954719)
			(xy 90.197779 -268.984095) (xy 90.233119 -269.019435) (xy 90.262495 -269.059868) (xy 90.285185 -269.1044)
			(xy 90.300629 -269.151932) (xy 90.308448 -269.201295) (xy 90.308938 -269.226284) (xy 90.614749 -269.226284)
			(xy 90.618844 -269.175556) (xy 90.631023 -269.126142) (xy 90.650971 -269.079322) (xy 90.678172 -269.036308)
			(xy 90.71192 -268.998214) (xy 90.751342 -268.966027) (xy 90.795416 -268.940581) (xy 90.843002 -268.922534)
			(xy 90.892866 -268.912354) (xy 90.943718 -268.910305) (xy 90.994239 -268.916439) (xy 91.043123 -268.930599)
			(xy 91.089102 -268.952416) (xy 91.130986 -268.981326) (xy 91.16769 -269.016581) (xy 91.198263 -269.057267)
			(xy 91.221914 -269.10233) (xy 91.23803 -269.150604) (xy 91.246194 -269.200838) (xy 91.246706 -269.226284)
			(xy 91.246203 -269.251273) (xy 91.55352 -269.251273) (xy 91.55352 -269.201295) (xy 91.561339 -269.151932)
			(xy 91.576783 -269.1044) (xy 91.599473 -269.059868) (xy 91.628849 -269.019435) (xy 91.664189 -268.984095)
			(xy 91.704622 -268.954719) (xy 91.749154 -268.932029) (xy 91.796686 -268.916585) (xy 91.846049 -268.908766)
			(xy 91.896027 -268.908766) (xy 91.94539 -268.916585) (xy 91.992922 -268.932029) (xy 92.037454 -268.954719)
			(xy 92.077887 -268.984095) (xy 92.113227 -269.019435) (xy 92.142603 -269.059868) (xy 92.165293 -269.1044)
			(xy 92.180737 -269.151932) (xy 92.188556 -269.201295) (xy 92.189046 -269.226284) (xy 92.188556 -269.251273)
			(xy 92.493574 -269.251273) (xy 92.493574 -269.201295) (xy 92.501393 -269.151932) (xy 92.516837 -269.1044)
			(xy 92.539527 -269.059868) (xy 92.568903 -269.019435) (xy 92.604243 -268.984095) (xy 92.644676 -268.954719)
			(xy 92.689208 -268.932029) (xy 92.73674 -268.916585) (xy 92.786103 -268.908766) (xy 92.836081 -268.908766)
			(xy 92.885444 -268.916585) (xy 92.932976 -268.932029) (xy 92.977508 -268.954719) (xy 93.017941 -268.984095)
			(xy 93.053281 -269.019435) (xy 93.082657 -269.059868) (xy 93.105347 -269.1044) (xy 93.120791 -269.151932)
			(xy 93.12861 -269.201295) (xy 93.1291 -269.226284) (xy 93.12861 -269.251273) (xy 93.433628 -269.251273)
			(xy 93.433628 -269.201295) (xy 93.441447 -269.151932) (xy 93.456891 -269.1044) (xy 93.479581 -269.059868)
			(xy 93.508957 -269.019435) (xy 93.544297 -268.984095) (xy 93.58473 -268.954719) (xy 93.629262 -268.932029)
			(xy 93.676794 -268.916585) (xy 93.726157 -268.908766) (xy 93.776135 -268.908766) (xy 93.825498 -268.916585)
			(xy 93.87303 -268.932029) (xy 93.917562 -268.954719) (xy 93.957995 -268.984095) (xy 93.993335 -269.019435)
			(xy 94.022711 -269.059868) (xy 94.045401 -269.1044) (xy 94.060845 -269.151932) (xy 94.068664 -269.201295)
			(xy 94.069154 -269.226284) (xy 94.374711 -269.226284) (xy 94.378806 -269.175556) (xy 94.390985 -269.126142)
			(xy 94.410933 -269.079322) (xy 94.438134 -269.036308) (xy 94.471882 -268.998214) (xy 94.511304 -268.966027)
			(xy 94.555378 -268.940581) (xy 94.602964 -268.922534) (xy 94.652828 -268.912354) (xy 94.70368 -268.910305)
			(xy 94.754201 -268.916439) (xy 94.803085 -268.930599) (xy 94.849064 -268.952416) (xy 94.890948 -268.981326)
			(xy 94.927652 -269.016581) (xy 94.958225 -269.057267) (xy 94.981876 -269.10233) (xy 94.997992 -269.150604)
			(xy 95.006156 -269.200838) (xy 95.006668 -269.226284) (xy 95.006165 -269.251273) (xy 95.313482 -269.251273)
			(xy 95.313482 -269.201295) (xy 95.321301 -269.151932) (xy 95.336745 -269.1044) (xy 95.359435 -269.059868)
			(xy 95.388811 -269.019435) (xy 95.424151 -268.984095) (xy 95.464584 -268.954719) (xy 95.509116 -268.932029)
			(xy 95.556648 -268.916585) (xy 95.606011 -268.908766) (xy 95.655989 -268.908766) (xy 95.705352 -268.916585)
			(xy 95.752884 -268.932029) (xy 95.797416 -268.954719) (xy 95.837849 -268.984095) (xy 95.873189 -269.019435)
			(xy 95.902565 -269.059868) (xy 95.925255 -269.1044) (xy 95.940699 -269.151932) (xy 95.948518 -269.201295)
			(xy 95.949008 -269.226284) (xy 95.948518 -269.251273) (xy 95.940699 -269.300636) (xy 95.925255 -269.348168)
			(xy 95.902565 -269.3927) (xy 95.873189 -269.433133) (xy 95.837849 -269.468473) (xy 95.797416 -269.497849)
			(xy 95.752884 -269.520539) (xy 95.705352 -269.535983) (xy 95.655989 -269.543802) (xy 95.606011 -269.543802)
			(xy 95.556648 -269.535983) (xy 95.509116 -269.520539) (xy 95.464584 -269.497849) (xy 95.424151 -269.468473)
			(xy 95.388811 -269.433133) (xy 95.359435 -269.3927) (xy 95.336745 -269.348168) (xy 95.321301 -269.300636)
			(xy 95.313482 -269.251273) (xy 95.006165 -269.251273) (xy 95.006156 -269.25173) (xy 94.997992 -269.301964)
			(xy 94.981876 -269.350238) (xy 94.958225 -269.395301) (xy 94.927652 -269.435987) (xy 94.890948 -269.471242)
			(xy 94.849064 -269.500152) (xy 94.803085 -269.521969) (xy 94.754201 -269.536129) (xy 94.70368 -269.542263)
			(xy 94.652828 -269.540214) (xy 94.602964 -269.530034) (xy 94.555378 -269.511987) (xy 94.511304 -269.486541)
			(xy 94.471882 -269.454354) (xy 94.438134 -269.41626) (xy 94.410933 -269.373246) (xy 94.390985 -269.326426)
			(xy 94.378806 -269.277012) (xy 94.374711 -269.226284) (xy 94.069154 -269.226284) (xy 94.068664 -269.251273)
			(xy 94.060845 -269.300636) (xy 94.045401 -269.348168) (xy 94.022711 -269.3927) (xy 93.993335 -269.433133)
			(xy 93.957995 -269.468473) (xy 93.917562 -269.497849) (xy 93.87303 -269.520539) (xy 93.825498 -269.535983)
			(xy 93.776135 -269.543802) (xy 93.726157 -269.543802) (xy 93.676794 -269.535983) (xy 93.629262 -269.520539)
			(xy 93.58473 -269.497849) (xy 93.544297 -269.468473) (xy 93.508957 -269.433133) (xy 93.479581 -269.3927)
			(xy 93.456891 -269.348168) (xy 93.441447 -269.300636) (xy 93.433628 -269.251273) (xy 93.12861 -269.251273)
			(xy 93.120791 -269.300636) (xy 93.105347 -269.348168) (xy 93.082657 -269.3927) (xy 93.053281 -269.433133)
			(xy 93.017941 -269.468473) (xy 92.977508 -269.497849) (xy 92.932976 -269.520539) (xy 92.885444 -269.535983)
			(xy 92.836081 -269.543802) (xy 92.786103 -269.543802) (xy 92.73674 -269.535983) (xy 92.689208 -269.520539)
			(xy 92.644676 -269.497849) (xy 92.604243 -269.468473) (xy 92.568903 -269.433133) (xy 92.539527 -269.3927)
			(xy 92.516837 -269.348168) (xy 92.501393 -269.300636) (xy 92.493574 -269.251273) (xy 92.188556 -269.251273)
			(xy 92.180737 -269.300636) (xy 92.165293 -269.348168) (xy 92.142603 -269.3927) (xy 92.113227 -269.433133)
			(xy 92.077887 -269.468473) (xy 92.037454 -269.497849) (xy 91.992922 -269.520539) (xy 91.94539 -269.535983)
			(xy 91.896027 -269.543802) (xy 91.846049 -269.543802) (xy 91.796686 -269.535983) (xy 91.749154 -269.520539)
			(xy 91.704622 -269.497849) (xy 91.664189 -269.468473) (xy 91.628849 -269.433133) (xy 91.599473 -269.3927)
			(xy 91.576783 -269.348168) (xy 91.561339 -269.300636) (xy 91.55352 -269.251273) (xy 91.246203 -269.251273)
			(xy 91.246194 -269.25173) (xy 91.23803 -269.301964) (xy 91.221914 -269.350238) (xy 91.198263 -269.395301)
			(xy 91.16769 -269.435987) (xy 91.130986 -269.471242) (xy 91.089102 -269.500152) (xy 91.043123 -269.521969)
			(xy 90.994239 -269.536129) (xy 90.943718 -269.542263) (xy 90.892866 -269.540214) (xy 90.843002 -269.530034)
			(xy 90.795416 -269.511987) (xy 90.751342 -269.486541) (xy 90.71192 -269.454354) (xy 90.678172 -269.41626)
			(xy 90.650971 -269.373246) (xy 90.631023 -269.326426) (xy 90.618844 -269.277012) (xy 90.614749 -269.226284)
			(xy 90.308938 -269.226284) (xy 90.308448 -269.251273) (xy 90.300629 -269.300636) (xy 90.285185 -269.348168)
			(xy 90.262495 -269.3927) (xy 90.233119 -269.433133) (xy 90.197779 -269.468473) (xy 90.157346 -269.497849)
			(xy 90.112814 -269.520539) (xy 90.065282 -269.535983) (xy 90.015919 -269.543802) (xy 89.965941 -269.543802)
			(xy 89.916578 -269.535983) (xy 89.869046 -269.520539) (xy 89.824514 -269.497849) (xy 89.784081 -269.468473)
			(xy 89.748741 -269.433133) (xy 89.719365 -269.3927) (xy 89.696675 -269.348168) (xy 89.681231 -269.300636)
			(xy 89.673412 -269.251273) (xy 89.368648 -269.251273) (xy 89.360829 -269.300636) (xy 89.345385 -269.348168)
			(xy 89.322695 -269.3927) (xy 89.293319 -269.433133) (xy 89.257979 -269.468473) (xy 89.217546 -269.497849)
			(xy 89.173014 -269.520539) (xy 89.125482 -269.535983) (xy 89.076119 -269.543802) (xy 89.026141 -269.543802)
			(xy 88.976778 -269.535983) (xy 88.929246 -269.520539) (xy 88.884714 -269.497849) (xy 88.844281 -269.468473)
			(xy 88.808941 -269.433133) (xy 88.779565 -269.3927) (xy 88.756875 -269.348168) (xy 88.741431 -269.300636)
			(xy 88.733612 -269.251273) (xy 88.426295 -269.251273) (xy 88.426286 -269.25173) (xy 88.418122 -269.301964)
			(xy 88.402006 -269.350238) (xy 88.378355 -269.395301) (xy 88.347782 -269.435987) (xy 88.311078 -269.471242)
			(xy 88.269194 -269.500152) (xy 88.223215 -269.521969) (xy 88.174331 -269.536129) (xy 88.12381 -269.542263)
			(xy 88.072958 -269.540214) (xy 88.023094 -269.530034) (xy 87.975508 -269.511987) (xy 87.931434 -269.486541)
			(xy 87.892012 -269.454354) (xy 87.858264 -269.41626) (xy 87.831063 -269.373246) (xy 87.811115 -269.326426)
			(xy 87.798936 -269.277012) (xy 87.794841 -269.226284) (xy 87.48903 -269.226284) (xy 87.48854 -269.251273)
			(xy 87.480721 -269.300636) (xy 87.465277 -269.348168) (xy 87.442587 -269.3927) (xy 87.413211 -269.433133)
			(xy 87.377871 -269.468473) (xy 87.337438 -269.497849) (xy 87.292906 -269.520539) (xy 87.245374 -269.535983)
			(xy 87.196011 -269.543802) (xy 87.146033 -269.543802) (xy 87.09667 -269.535983) (xy 87.049138 -269.520539)
			(xy 87.004606 -269.497849) (xy 86.964173 -269.468473) (xy 86.928833 -269.433133) (xy 86.899457 -269.3927)
			(xy 86.876767 -269.348168) (xy 86.861323 -269.300636) (xy 86.853504 -269.251273) (xy 86.548486 -269.251273)
			(xy 86.540667 -269.300636) (xy 86.525223 -269.348168) (xy 86.502533 -269.3927) (xy 86.473157 -269.433133)
			(xy 86.437817 -269.468473) (xy 86.397384 -269.497849) (xy 86.352852 -269.520539) (xy 86.30532 -269.535983)
			(xy 86.255957 -269.543802) (xy 86.205979 -269.543802) (xy 86.156616 -269.535983) (xy 86.109084 -269.520539)
			(xy 86.064552 -269.497849) (xy 86.024119 -269.468473) (xy 85.988779 -269.433133) (xy 85.959403 -269.3927)
			(xy 85.936713 -269.348168) (xy 85.921269 -269.300636) (xy 85.91345 -269.251273) (xy 85.608432 -269.251273)
			(xy 85.600613 -269.300636) (xy 85.585169 -269.348168) (xy 85.562479 -269.3927) (xy 85.533103 -269.433133)
			(xy 85.497763 -269.468473) (xy 85.45733 -269.497849) (xy 85.412798 -269.520539) (xy 85.365266 -269.535983)
			(xy 85.315903 -269.543802) (xy 85.265925 -269.543802) (xy 85.216562 -269.535983) (xy 85.16903 -269.520539)
			(xy 85.124498 -269.497849) (xy 85.084065 -269.468473) (xy 85.048725 -269.433133) (xy 85.019349 -269.3927)
			(xy 84.996659 -269.348168) (xy 84.981215 -269.300636) (xy 84.973396 -269.251273) (xy 84.666333 -269.251273)
			(xy 84.666324 -269.25173) (xy 84.65816 -269.301964) (xy 84.642044 -269.350238) (xy 84.618393 -269.395301)
			(xy 84.58782 -269.435987) (xy 84.551116 -269.471242) (xy 84.509232 -269.500152) (xy 84.463253 -269.521969)
			(xy 84.414369 -269.536129) (xy 84.363848 -269.542263) (xy 84.312996 -269.540214) (xy 84.263132 -269.530034)
			(xy 84.215546 -269.511987) (xy 84.171472 -269.486541) (xy 84.13205 -269.454354) (xy 84.098302 -269.41626)
			(xy 84.071101 -269.373246) (xy 84.051153 -269.326426) (xy 84.038974 -269.277012) (xy 84.034879 -269.226284)
			(xy 83.729068 -269.226284) (xy 83.728578 -269.251273) (xy 83.720759 -269.300636) (xy 83.705315 -269.348168)
			(xy 83.682625 -269.3927) (xy 83.653249 -269.433133) (xy 83.617909 -269.468473) (xy 83.577476 -269.497849)
			(xy 83.532944 -269.520539) (xy 83.485412 -269.535983) (xy 83.436049 -269.543802) (xy 83.386071 -269.543802)
			(xy 83.336708 -269.535983) (xy 83.289176 -269.520539) (xy 83.244644 -269.497849) (xy 83.204211 -269.468473)
			(xy 83.168871 -269.433133) (xy 83.139495 -269.3927) (xy 83.116805 -269.348168) (xy 83.101361 -269.300636)
			(xy 83.093542 -269.251273) (xy 82.788524 -269.251273) (xy 82.780705 -269.300636) (xy 82.765261 -269.348168)
			(xy 82.742571 -269.3927) (xy 82.713195 -269.433133) (xy 82.677855 -269.468473) (xy 82.637422 -269.497849)
			(xy 82.59289 -269.520539) (xy 82.545358 -269.535983) (xy 82.495995 -269.543802) (xy 82.446017 -269.543802)
			(xy 82.396654 -269.535983) (xy 82.349122 -269.520539) (xy 82.30459 -269.497849) (xy 82.264157 -269.468473)
			(xy 82.228817 -269.433133) (xy 82.199441 -269.3927) (xy 82.176751 -269.348168) (xy 82.161307 -269.300636)
			(xy 82.153488 -269.251273) (xy 81.846171 -269.251273) (xy 81.846162 -269.25173) (xy 81.837998 -269.301964)
			(xy 81.821882 -269.350238) (xy 81.798231 -269.395301) (xy 81.767658 -269.435987) (xy 81.730954 -269.471242)
			(xy 81.68907 -269.500152) (xy 81.643091 -269.521969) (xy 81.594207 -269.536129) (xy 81.543686 -269.542263)
			(xy 81.492834 -269.540214) (xy 81.44297 -269.530034) (xy 81.395384 -269.511987) (xy 81.35131 -269.486541)
			(xy 81.311888 -269.454354) (xy 81.27814 -269.41626) (xy 81.250939 -269.373246) (xy 81.230991 -269.326426)
			(xy 81.218812 -269.277012) (xy 81.214717 -269.226284) (xy 80.90916 -269.226284) (xy 80.90867 -269.251273)
			(xy 80.900851 -269.300636) (xy 80.885407 -269.348168) (xy 80.862717 -269.3927) (xy 80.833341 -269.433133)
			(xy 80.798001 -269.468473) (xy 80.757568 -269.497849) (xy 80.713036 -269.520539) (xy 80.665504 -269.535983)
			(xy 80.616141 -269.543802) (xy 80.566163 -269.543802) (xy 80.5168 -269.535983) (xy 80.469268 -269.520539)
			(xy 80.424736 -269.497849) (xy 80.384303 -269.468473) (xy 80.348963 -269.433133) (xy 80.319587 -269.3927)
			(xy 80.296897 -269.348168) (xy 80.281453 -269.300636) (xy 80.273634 -269.251273) (xy 79.968913 -269.251273)
			(xy 79.968913 -269.251313) (xy 79.961087 -269.300722) (xy 79.945628 -269.348298) (xy 79.922917 -269.392871)
			(xy 79.893513 -269.433342) (xy 79.85814 -269.468715) (xy 79.817669 -269.498119) (xy 79.773096 -269.520829)
			(xy 79.72552 -269.536288) (xy 79.676111 -269.544113) (xy 79.651098 -269.544546) (xy 79.638144 -269.544292)
			(xy 79.624484 -269.544174) (xy 79.597881 -269.550334) (xy 79.573863 -269.563327) (xy 79.55415 -269.582222)
			(xy 79.540151 -269.605667) (xy 79.532869 -269.631985) (xy 79.53248 -269.645638) (xy 79.53248 -270.061279)
			(xy 79.80348 -270.061279) (xy 79.80348 -270.011301) (xy 79.811299 -269.961938) (xy 79.826743 -269.914406)
			(xy 79.849433 -269.869874) (xy 79.878809 -269.829441) (xy 79.914149 -269.794101) (xy 79.954582 -269.764725)
			(xy 79.999114 -269.742035) (xy 80.046646 -269.726591) (xy 80.096009 -269.718772) (xy 80.145987 -269.718772)
			(xy 80.19535 -269.726591) (xy 80.242882 -269.742035) (xy 80.287414 -269.764725) (xy 80.327847 -269.794101)
			(xy 80.363187 -269.829441) (xy 80.392563 -269.869874) (xy 80.415253 -269.914406) (xy 80.430697 -269.961938)
			(xy 80.438516 -270.011301) (xy 80.439006 -270.03629) (xy 80.744817 -270.03629) (xy 80.748912 -269.985562)
			(xy 80.761091 -269.936148) (xy 80.781039 -269.889328) (xy 80.80824 -269.846314) (xy 80.841988 -269.80822)
			(xy 80.88141 -269.776033) (xy 80.925484 -269.750587) (xy 80.97307 -269.73254) (xy 81.022934 -269.72236)
			(xy 81.073786 -269.720311) (xy 81.124307 -269.726445) (xy 81.173191 -269.740605) (xy 81.21917 -269.762422)
			(xy 81.261054 -269.791332) (xy 81.297758 -269.826587) (xy 81.328331 -269.867273) (xy 81.351982 -269.912336)
			(xy 81.368098 -269.96061) (xy 81.376262 -270.010844) (xy 81.376774 -270.03629) (xy 81.376271 -270.061279)
			(xy 81.683588 -270.061279) (xy 81.683588 -270.011301) (xy 81.691407 -269.961938) (xy 81.706851 -269.914406)
			(xy 81.729541 -269.869874) (xy 81.758917 -269.829441) (xy 81.794257 -269.794101) (xy 81.83469 -269.764725)
			(xy 81.879222 -269.742035) (xy 81.926754 -269.726591) (xy 81.976117 -269.718772) (xy 82.026095 -269.718772)
			(xy 82.075458 -269.726591) (xy 82.12299 -269.742035) (xy 82.167522 -269.764725) (xy 82.207955 -269.794101)
			(xy 82.243295 -269.829441) (xy 82.272671 -269.869874) (xy 82.295361 -269.914406) (xy 82.310805 -269.961938)
			(xy 82.318624 -270.011301) (xy 82.319114 -270.03629) (xy 82.624671 -270.03629) (xy 82.628766 -269.985562)
			(xy 82.640945 -269.936148) (xy 82.660893 -269.889328) (xy 82.688094 -269.846314) (xy 82.721842 -269.80822)
			(xy 82.761264 -269.776033) (xy 82.805338 -269.750587) (xy 82.852924 -269.73254) (xy 82.902788 -269.72236)
			(xy 82.95364 -269.720311) (xy 83.004161 -269.726445) (xy 83.053045 -269.740605) (xy 83.099024 -269.762422)
			(xy 83.140908 -269.791332) (xy 83.177612 -269.826587) (xy 83.208185 -269.867273) (xy 83.231836 -269.912336)
			(xy 83.247952 -269.96061) (xy 83.256116 -270.010844) (xy 83.256628 -270.03629) (xy 83.256125 -270.061279)
			(xy 83.563442 -270.061279) (xy 83.563442 -270.011301) (xy 83.571261 -269.961938) (xy 83.586705 -269.914406)
			(xy 83.609395 -269.869874) (xy 83.638771 -269.829441) (xy 83.674111 -269.794101) (xy 83.714544 -269.764725)
			(xy 83.759076 -269.742035) (xy 83.806608 -269.726591) (xy 83.855971 -269.718772) (xy 83.905949 -269.718772)
			(xy 83.955312 -269.726591) (xy 84.002844 -269.742035) (xy 84.047376 -269.764725) (xy 84.087809 -269.794101)
			(xy 84.123149 -269.829441) (xy 84.152525 -269.869874) (xy 84.175215 -269.914406) (xy 84.190659 -269.961938)
			(xy 84.198478 -270.011301) (xy 84.198968 -270.03629) (xy 84.504779 -270.03629) (xy 84.508874 -269.985562)
			(xy 84.521053 -269.936148) (xy 84.541001 -269.889328) (xy 84.568202 -269.846314) (xy 84.60195 -269.80822)
			(xy 84.641372 -269.776033) (xy 84.685446 -269.750587) (xy 84.733032 -269.73254) (xy 84.782896 -269.72236)
			(xy 84.833748 -269.720311) (xy 84.884269 -269.726445) (xy 84.933153 -269.740605) (xy 84.979132 -269.762422)
			(xy 85.021016 -269.791332) (xy 85.05772 -269.826587) (xy 85.088293 -269.867273) (xy 85.111944 -269.912336)
			(xy 85.12806 -269.96061) (xy 85.136224 -270.010844) (xy 85.136736 -270.03629) (xy 85.444833 -270.03629)
			(xy 85.448928 -269.985562) (xy 85.461107 -269.936148) (xy 85.481055 -269.889328) (xy 85.508256 -269.846314)
			(xy 85.542004 -269.80822) (xy 85.581426 -269.776033) (xy 85.6255 -269.750587) (xy 85.673086 -269.73254)
			(xy 85.72295 -269.72236) (xy 85.773802 -269.720311) (xy 85.824323 -269.726445) (xy 85.873207 -269.740605)
			(xy 85.919186 -269.762422) (xy 85.96107 -269.791332) (xy 85.997774 -269.826587) (xy 86.028347 -269.867273)
			(xy 86.051998 -269.912336) (xy 86.068114 -269.96061) (xy 86.076278 -270.010844) (xy 86.07679 -270.03629)
			(xy 86.076287 -270.061279) (xy 86.383604 -270.061279) (xy 86.383604 -270.011301) (xy 86.391423 -269.961938)
			(xy 86.406867 -269.914406) (xy 86.429557 -269.869874) (xy 86.458933 -269.829441) (xy 86.494273 -269.794101)
			(xy 86.534706 -269.764725) (xy 86.579238 -269.742035) (xy 86.62677 -269.726591) (xy 86.676133 -269.718772)
			(xy 86.726111 -269.718772) (xy 86.775474 -269.726591) (xy 86.823006 -269.742035) (xy 86.867538 -269.764725)
			(xy 86.907971 -269.794101) (xy 86.943311 -269.829441) (xy 86.972687 -269.869874) (xy 86.995377 -269.914406)
			(xy 87.010821 -269.961938) (xy 87.01864 -270.011301) (xy 87.01913 -270.03629) (xy 87.324687 -270.03629)
			(xy 87.328782 -269.985562) (xy 87.340961 -269.936148) (xy 87.360909 -269.889328) (xy 87.38811 -269.846314)
			(xy 87.421858 -269.80822) (xy 87.46128 -269.776033) (xy 87.505354 -269.750587) (xy 87.55294 -269.73254)
			(xy 87.602804 -269.72236) (xy 87.653656 -269.720311) (xy 87.704177 -269.726445) (xy 87.753061 -269.740605)
			(xy 87.79904 -269.762422) (xy 87.840924 -269.791332) (xy 87.877628 -269.826587) (xy 87.908201 -269.867273)
			(xy 87.931852 -269.912336) (xy 87.947968 -269.96061) (xy 87.956132 -270.010844) (xy 87.956644 -270.03629)
			(xy 87.956141 -270.061279) (xy 88.263458 -270.061279) (xy 88.263458 -270.011301) (xy 88.271277 -269.961938)
			(xy 88.286721 -269.914406) (xy 88.309411 -269.869874) (xy 88.338787 -269.829441) (xy 88.374127 -269.794101)
			(xy 88.41456 -269.764725) (xy 88.459092 -269.742035) (xy 88.506624 -269.726591) (xy 88.555987 -269.718772)
			(xy 88.605965 -269.718772) (xy 88.655328 -269.726591) (xy 88.70286 -269.742035) (xy 88.747392 -269.764725)
			(xy 88.787825 -269.794101) (xy 88.823165 -269.829441) (xy 88.852541 -269.869874) (xy 88.875231 -269.914406)
			(xy 88.890675 -269.961938) (xy 88.898494 -270.011301) (xy 88.898984 -270.03629) (xy 89.204795 -270.03629)
			(xy 89.20889 -269.985562) (xy 89.221069 -269.936148) (xy 89.241017 -269.889328) (xy 89.268218 -269.846314)
			(xy 89.301966 -269.80822) (xy 89.341388 -269.776033) (xy 89.385462 -269.750587) (xy 89.433048 -269.73254)
			(xy 89.482912 -269.72236) (xy 89.533764 -269.720311) (xy 89.584285 -269.726445) (xy 89.633169 -269.740605)
			(xy 89.679148 -269.762422) (xy 89.721032 -269.791332) (xy 89.757736 -269.826587) (xy 89.788309 -269.867273)
			(xy 89.81196 -269.912336) (xy 89.828076 -269.96061) (xy 89.83624 -270.010844) (xy 89.836752 -270.03629)
			(xy 89.836249 -270.061279) (xy 90.143566 -270.061279) (xy 90.143566 -270.011301) (xy 90.151385 -269.961938)
			(xy 90.166829 -269.914406) (xy 90.189519 -269.869874) (xy 90.218895 -269.829441) (xy 90.254235 -269.794101)
			(xy 90.294668 -269.764725) (xy 90.3392 -269.742035) (xy 90.386732 -269.726591) (xy 90.436095 -269.718772)
			(xy 90.486073 -269.718772) (xy 90.535436 -269.726591) (xy 90.582968 -269.742035) (xy 90.6275 -269.764725)
			(xy 90.667933 -269.794101) (xy 90.703273 -269.829441) (xy 90.732649 -269.869874) (xy 90.755339 -269.914406)
			(xy 90.770783 -269.961938) (xy 90.778602 -270.011301) (xy 90.779092 -270.03629) (xy 91.084903 -270.03629)
			(xy 91.088998 -269.985562) (xy 91.101177 -269.936148) (xy 91.121125 -269.889328) (xy 91.148326 -269.846314)
			(xy 91.182074 -269.80822) (xy 91.221496 -269.776033) (xy 91.26557 -269.750587) (xy 91.313156 -269.73254)
			(xy 91.36302 -269.72236) (xy 91.413872 -269.720311) (xy 91.464393 -269.726445) (xy 91.513277 -269.740605)
			(xy 91.559256 -269.762422) (xy 91.60114 -269.791332) (xy 91.637844 -269.826587) (xy 91.668417 -269.867273)
			(xy 91.692068 -269.912336) (xy 91.708184 -269.96061) (xy 91.716348 -270.010844) (xy 91.71686 -270.03629)
			(xy 92.024703 -270.03629) (xy 92.028798 -269.985562) (xy 92.040977 -269.936148) (xy 92.060925 -269.889328)
			(xy 92.088126 -269.846314) (xy 92.121874 -269.80822) (xy 92.161296 -269.776033) (xy 92.20537 -269.750587)
			(xy 92.252956 -269.73254) (xy 92.30282 -269.72236) (xy 92.353672 -269.720311) (xy 92.404193 -269.726445)
			(xy 92.453077 -269.740605) (xy 92.499056 -269.762422) (xy 92.54094 -269.791332) (xy 92.577644 -269.826587)
			(xy 92.608217 -269.867273) (xy 92.631868 -269.912336) (xy 92.647984 -269.96061) (xy 92.656148 -270.010844)
			(xy 92.65666 -270.03629) (xy 92.656157 -270.061279) (xy 92.963474 -270.061279) (xy 92.963474 -270.011301)
			(xy 92.971293 -269.961938) (xy 92.986737 -269.914406) (xy 93.009427 -269.869874) (xy 93.038803 -269.829441)
			(xy 93.074143 -269.794101) (xy 93.114576 -269.764725) (xy 93.159108 -269.742035) (xy 93.20664 -269.726591)
			(xy 93.256003 -269.718772) (xy 93.305981 -269.718772) (xy 93.355344 -269.726591) (xy 93.402876 -269.742035)
			(xy 93.447408 -269.764725) (xy 93.487841 -269.794101) (xy 93.523181 -269.829441) (xy 93.552557 -269.869874)
			(xy 93.575247 -269.914406) (xy 93.590691 -269.961938) (xy 93.59851 -270.011301) (xy 93.599 -270.03629)
			(xy 93.904811 -270.03629) (xy 93.908906 -269.985562) (xy 93.921085 -269.936148) (xy 93.941033 -269.889328)
			(xy 93.968234 -269.846314) (xy 94.001982 -269.80822) (xy 94.041404 -269.776033) (xy 94.085478 -269.750587)
			(xy 94.133064 -269.73254) (xy 94.182928 -269.72236) (xy 94.23378 -269.720311) (xy 94.284301 -269.726445)
			(xy 94.333185 -269.740605) (xy 94.379164 -269.762422) (xy 94.421048 -269.791332) (xy 94.457752 -269.826587)
			(xy 94.488325 -269.867273) (xy 94.511976 -269.912336) (xy 94.528092 -269.96061) (xy 94.536256 -270.010844)
			(xy 94.536768 -270.03629) (xy 94.536265 -270.061279) (xy 94.843582 -270.061279) (xy 94.843582 -270.011301)
			(xy 94.851401 -269.961938) (xy 94.866845 -269.914406) (xy 94.889535 -269.869874) (xy 94.918911 -269.829441)
			(xy 94.954251 -269.794101) (xy 94.994684 -269.764725) (xy 95.039216 -269.742035) (xy 95.086748 -269.726591)
			(xy 95.136111 -269.718772) (xy 95.186089 -269.718772) (xy 95.235452 -269.726591) (xy 95.282984 -269.742035)
			(xy 95.327516 -269.764725) (xy 95.367949 -269.794101) (xy 95.403289 -269.829441) (xy 95.432665 -269.869874)
			(xy 95.455355 -269.914406) (xy 95.470799 -269.961938) (xy 95.478618 -270.011301) (xy 95.479108 -270.03629)
			(xy 95.478618 -270.061279) (xy 95.470799 -270.110642) (xy 95.455355 -270.158174) (xy 95.432665 -270.202706)
			(xy 95.403289 -270.243139) (xy 95.367949 -270.278479) (xy 95.327516 -270.307855) (xy 95.282984 -270.330545)
			(xy 95.235452 -270.345989) (xy 95.186089 -270.353808) (xy 95.136111 -270.353808) (xy 95.086748 -270.345989)
			(xy 95.039216 -270.330545) (xy 94.994684 -270.307855) (xy 94.954251 -270.278479) (xy 94.918911 -270.243139)
			(xy 94.889535 -270.202706) (xy 94.866845 -270.158174) (xy 94.851401 -270.110642) (xy 94.843582 -270.061279)
			(xy 94.536265 -270.061279) (xy 94.536256 -270.061736) (xy 94.528092 -270.11197) (xy 94.511976 -270.160244)
			(xy 94.488325 -270.205307) (xy 94.457752 -270.245993) (xy 94.421048 -270.281248) (xy 94.379164 -270.310158)
			(xy 94.333185 -270.331975) (xy 94.284301 -270.346135) (xy 94.23378 -270.352269) (xy 94.182928 -270.35022)
			(xy 94.133064 -270.34004) (xy 94.085478 -270.321993) (xy 94.041404 -270.296547) (xy 94.001982 -270.26436)
			(xy 93.968234 -270.226266) (xy 93.941033 -270.183252) (xy 93.921085 -270.136432) (xy 93.908906 -270.087018)
			(xy 93.904811 -270.03629) (xy 93.599 -270.03629) (xy 93.59851 -270.061279) (xy 93.590691 -270.110642)
			(xy 93.575247 -270.158174) (xy 93.552557 -270.202706) (xy 93.523181 -270.243139) (xy 93.487841 -270.278479)
			(xy 93.447408 -270.307855) (xy 93.402876 -270.330545) (xy 93.355344 -270.345989) (xy 93.305981 -270.353808)
			(xy 93.256003 -270.353808) (xy 93.20664 -270.345989) (xy 93.159108 -270.330545) (xy 93.114576 -270.307855)
			(xy 93.074143 -270.278479) (xy 93.038803 -270.243139) (xy 93.009427 -270.202706) (xy 92.986737 -270.158174)
			(xy 92.971293 -270.110642) (xy 92.963474 -270.061279) (xy 92.656157 -270.061279) (xy 92.656148 -270.061736)
			(xy 92.647984 -270.11197) (xy 92.631868 -270.160244) (xy 92.608217 -270.205307) (xy 92.577644 -270.245993)
			(xy 92.54094 -270.281248) (xy 92.499056 -270.310158) (xy 92.453077 -270.331975) (xy 92.404193 -270.346135)
			(xy 92.353672 -270.352269) (xy 92.30282 -270.35022) (xy 92.252956 -270.34004) (xy 92.20537 -270.321993)
			(xy 92.161296 -270.296547) (xy 92.121874 -270.26436) (xy 92.088126 -270.226266) (xy 92.060925 -270.183252)
			(xy 92.040977 -270.136432) (xy 92.028798 -270.087018) (xy 92.024703 -270.03629) (xy 91.71686 -270.03629)
			(xy 91.716348 -270.061736) (xy 91.708184 -270.11197) (xy 91.692068 -270.160244) (xy 91.668417 -270.205307)
			(xy 91.637844 -270.245993) (xy 91.60114 -270.281248) (xy 91.559256 -270.310158) (xy 91.513277 -270.331975)
			(xy 91.464393 -270.346135) (xy 91.413872 -270.352269) (xy 91.36302 -270.35022) (xy 91.313156 -270.34004)
			(xy 91.26557 -270.321993) (xy 91.221496 -270.296547) (xy 91.182074 -270.26436) (xy 91.148326 -270.226266)
			(xy 91.121125 -270.183252) (xy 91.101177 -270.136432) (xy 91.088998 -270.087018) (xy 91.084903 -270.03629)
			(xy 90.779092 -270.03629) (xy 90.778602 -270.061279) (xy 90.770783 -270.110642) (xy 90.755339 -270.158174)
			(xy 90.732649 -270.202706) (xy 90.703273 -270.243139) (xy 90.667933 -270.278479) (xy 90.6275 -270.307855)
			(xy 90.582968 -270.330545) (xy 90.535436 -270.345989) (xy 90.486073 -270.353808) (xy 90.436095 -270.353808)
			(xy 90.386732 -270.345989) (xy 90.3392 -270.330545) (xy 90.294668 -270.307855) (xy 90.254235 -270.278479)
			(xy 90.218895 -270.243139) (xy 90.189519 -270.202706) (xy 90.166829 -270.158174) (xy 90.151385 -270.110642)
			(xy 90.143566 -270.061279) (xy 89.836249 -270.061279) (xy 89.83624 -270.061736) (xy 89.828076 -270.11197)
			(xy 89.81196 -270.160244) (xy 89.788309 -270.205307) (xy 89.757736 -270.245993) (xy 89.721032 -270.281248)
			(xy 89.679148 -270.310158) (xy 89.633169 -270.331975) (xy 89.584285 -270.346135) (xy 89.533764 -270.352269)
			(xy 89.482912 -270.35022) (xy 89.433048 -270.34004) (xy 89.385462 -270.321993) (xy 89.341388 -270.296547)
			(xy 89.301966 -270.26436) (xy 89.268218 -270.226266) (xy 89.241017 -270.183252) (xy 89.221069 -270.136432)
			(xy 89.20889 -270.087018) (xy 89.204795 -270.03629) (xy 88.898984 -270.03629) (xy 88.898494 -270.061279)
			(xy 88.890675 -270.110642) (xy 88.875231 -270.158174) (xy 88.852541 -270.202706) (xy 88.823165 -270.243139)
			(xy 88.787825 -270.278479) (xy 88.747392 -270.307855) (xy 88.70286 -270.330545) (xy 88.655328 -270.345989)
			(xy 88.605965 -270.353808) (xy 88.555987 -270.353808) (xy 88.506624 -270.345989) (xy 88.459092 -270.330545)
			(xy 88.41456 -270.307855) (xy 88.374127 -270.278479) (xy 88.338787 -270.243139) (xy 88.309411 -270.202706)
			(xy 88.286721 -270.158174) (xy 88.271277 -270.110642) (xy 88.263458 -270.061279) (xy 87.956141 -270.061279)
			(xy 87.956132 -270.061736) (xy 87.947968 -270.11197) (xy 87.931852 -270.160244) (xy 87.908201 -270.205307)
			(xy 87.877628 -270.245993) (xy 87.840924 -270.281248) (xy 87.79904 -270.310158) (xy 87.753061 -270.331975)
			(xy 87.704177 -270.346135) (xy 87.653656 -270.352269) (xy 87.602804 -270.35022) (xy 87.55294 -270.34004)
			(xy 87.505354 -270.321993) (xy 87.46128 -270.296547) (xy 87.421858 -270.26436) (xy 87.38811 -270.226266)
			(xy 87.360909 -270.183252) (xy 87.340961 -270.136432) (xy 87.328782 -270.087018) (xy 87.324687 -270.03629)
			(xy 87.01913 -270.03629) (xy 87.01864 -270.061279) (xy 87.010821 -270.110642) (xy 86.995377 -270.158174)
			(xy 86.972687 -270.202706) (xy 86.943311 -270.243139) (xy 86.907971 -270.278479) (xy 86.867538 -270.307855)
			(xy 86.823006 -270.330545) (xy 86.775474 -270.345989) (xy 86.726111 -270.353808) (xy 86.676133 -270.353808)
			(xy 86.62677 -270.345989) (xy 86.579238 -270.330545) (xy 86.534706 -270.307855) (xy 86.494273 -270.278479)
			(xy 86.458933 -270.243139) (xy 86.429557 -270.202706) (xy 86.406867 -270.158174) (xy 86.391423 -270.110642)
			(xy 86.383604 -270.061279) (xy 86.076287 -270.061279) (xy 86.076278 -270.061736) (xy 86.068114 -270.11197)
			(xy 86.051998 -270.160244) (xy 86.028347 -270.205307) (xy 85.997774 -270.245993) (xy 85.96107 -270.281248)
			(xy 85.919186 -270.310158) (xy 85.873207 -270.331975) (xy 85.824323 -270.346135) (xy 85.773802 -270.352269)
			(xy 85.72295 -270.35022) (xy 85.673086 -270.34004) (xy 85.6255 -270.321993) (xy 85.581426 -270.296547)
			(xy 85.542004 -270.26436) (xy 85.508256 -270.226266) (xy 85.481055 -270.183252) (xy 85.461107 -270.136432)
			(xy 85.448928 -270.087018) (xy 85.444833 -270.03629) (xy 85.136736 -270.03629) (xy 85.136224 -270.061736)
			(xy 85.12806 -270.11197) (xy 85.111944 -270.160244) (xy 85.088293 -270.205307) (xy 85.05772 -270.245993)
			(xy 85.021016 -270.281248) (xy 84.979132 -270.310158) (xy 84.933153 -270.331975) (xy 84.884269 -270.346135)
			(xy 84.833748 -270.352269) (xy 84.782896 -270.35022) (xy 84.733032 -270.34004) (xy 84.685446 -270.321993)
			(xy 84.641372 -270.296547) (xy 84.60195 -270.26436) (xy 84.568202 -270.226266) (xy 84.541001 -270.183252)
			(xy 84.521053 -270.136432) (xy 84.508874 -270.087018) (xy 84.504779 -270.03629) (xy 84.198968 -270.03629)
			(xy 84.198478 -270.061279) (xy 84.190659 -270.110642) (xy 84.175215 -270.158174) (xy 84.152525 -270.202706)
			(xy 84.123149 -270.243139) (xy 84.087809 -270.278479) (xy 84.047376 -270.307855) (xy 84.002844 -270.330545)
			(xy 83.955312 -270.345989) (xy 83.905949 -270.353808) (xy 83.855971 -270.353808) (xy 83.806608 -270.345989)
			(xy 83.759076 -270.330545) (xy 83.714544 -270.307855) (xy 83.674111 -270.278479) (xy 83.638771 -270.243139)
			(xy 83.609395 -270.202706) (xy 83.586705 -270.158174) (xy 83.571261 -270.110642) (xy 83.563442 -270.061279)
			(xy 83.256125 -270.061279) (xy 83.256116 -270.061736) (xy 83.247952 -270.11197) (xy 83.231836 -270.160244)
			(xy 83.208185 -270.205307) (xy 83.177612 -270.245993) (xy 83.140908 -270.281248) (xy 83.099024 -270.310158)
			(xy 83.053045 -270.331975) (xy 83.004161 -270.346135) (xy 82.95364 -270.352269) (xy 82.902788 -270.35022)
			(xy 82.852924 -270.34004) (xy 82.805338 -270.321993) (xy 82.761264 -270.296547) (xy 82.721842 -270.26436)
			(xy 82.688094 -270.226266) (xy 82.660893 -270.183252) (xy 82.640945 -270.136432) (xy 82.628766 -270.087018)
			(xy 82.624671 -270.03629) (xy 82.319114 -270.03629) (xy 82.318624 -270.061279) (xy 82.310805 -270.110642)
			(xy 82.295361 -270.158174) (xy 82.272671 -270.202706) (xy 82.243295 -270.243139) (xy 82.207955 -270.278479)
			(xy 82.167522 -270.307855) (xy 82.12299 -270.330545) (xy 82.075458 -270.345989) (xy 82.026095 -270.353808)
			(xy 81.976117 -270.353808) (xy 81.926754 -270.345989) (xy 81.879222 -270.330545) (xy 81.83469 -270.307855)
			(xy 81.794257 -270.278479) (xy 81.758917 -270.243139) (xy 81.729541 -270.202706) (xy 81.706851 -270.158174)
			(xy 81.691407 -270.110642) (xy 81.683588 -270.061279) (xy 81.376271 -270.061279) (xy 81.376262 -270.061736)
			(xy 81.368098 -270.11197) (xy 81.351982 -270.160244) (xy 81.328331 -270.205307) (xy 81.297758 -270.245993)
			(xy 81.261054 -270.281248) (xy 81.21917 -270.310158) (xy 81.173191 -270.331975) (xy 81.124307 -270.346135)
			(xy 81.073786 -270.352269) (xy 81.022934 -270.35022) (xy 80.97307 -270.34004) (xy 80.925484 -270.321993)
			(xy 80.88141 -270.296547) (xy 80.841988 -270.26436) (xy 80.80824 -270.226266) (xy 80.781039 -270.183252)
			(xy 80.761091 -270.136432) (xy 80.748912 -270.087018) (xy 80.744817 -270.03629) (xy 80.439006 -270.03629)
			(xy 80.438516 -270.061279) (xy 80.430697 -270.110642) (xy 80.415253 -270.158174) (xy 80.392563 -270.202706)
			(xy 80.363187 -270.243139) (xy 80.327847 -270.278479) (xy 80.287414 -270.307855) (xy 80.242882 -270.330545)
			(xy 80.19535 -270.345989) (xy 80.145987 -270.353808) (xy 80.096009 -270.353808) (xy 80.046646 -270.345989)
			(xy 79.999114 -270.330545) (xy 79.954582 -270.307855) (xy 79.914149 -270.278479) (xy 79.878809 -270.243139)
			(xy 79.849433 -270.202706) (xy 79.826743 -270.158174) (xy 79.811299 -270.110642) (xy 79.80348 -270.061279)
			(xy 79.53248 -270.061279) (xy 79.53248 -270.846296) (xy 81.214717 -270.846296) (xy 81.218812 -270.795568)
			(xy 81.230991 -270.746154) (xy 81.250939 -270.699334) (xy 81.27814 -270.65632) (xy 81.311888 -270.618226)
			(xy 81.35131 -270.586039) (xy 81.395384 -270.560593) (xy 81.44297 -270.542546) (xy 81.492834 -270.532366)
			(xy 81.543686 -270.530317) (xy 81.594207 -270.536451) (xy 81.643091 -270.550611) (xy 81.68907 -270.572428)
			(xy 81.730954 -270.601338) (xy 81.767658 -270.636593) (xy 81.798231 -270.677279) (xy 81.821882 -270.722342)
			(xy 81.837998 -270.770616) (xy 81.846162 -270.82085) (xy 81.846674 -270.846296) (xy 82.154771 -270.846296)
			(xy 82.158866 -270.795568) (xy 82.171045 -270.746154) (xy 82.190993 -270.699334) (xy 82.218194 -270.65632)
			(xy 82.251942 -270.618226) (xy 82.291364 -270.586039) (xy 82.335438 -270.560593) (xy 82.383024 -270.542546)
			(xy 82.432888 -270.532366) (xy 82.48374 -270.530317) (xy 82.534261 -270.536451) (xy 82.583145 -270.550611)
			(xy 82.629124 -270.572428) (xy 82.671008 -270.601338) (xy 82.707712 -270.636593) (xy 82.738285 -270.677279)
			(xy 82.761936 -270.722342) (xy 82.778052 -270.770616) (xy 82.786216 -270.82085) (xy 82.786728 -270.846296)
			(xy 82.786225 -270.871285) (xy 83.093542 -270.871285) (xy 83.093542 -270.821307) (xy 83.101361 -270.771944)
			(xy 83.116805 -270.724412) (xy 83.139495 -270.67988) (xy 83.168871 -270.639447) (xy 83.204211 -270.604107)
			(xy 83.244644 -270.574731) (xy 83.289176 -270.552041) (xy 83.336708 -270.536597) (xy 83.386071 -270.528778)
			(xy 83.436049 -270.528778) (xy 83.485412 -270.536597) (xy 83.532944 -270.552041) (xy 83.577476 -270.574731)
			(xy 83.617909 -270.604107) (xy 83.653249 -270.639447) (xy 83.682625 -270.67988) (xy 83.705315 -270.724412)
			(xy 83.720759 -270.771944) (xy 83.728578 -270.821307) (xy 83.729068 -270.846296) (xy 84.034879 -270.846296)
			(xy 84.038974 -270.795568) (xy 84.051153 -270.746154) (xy 84.071101 -270.699334) (xy 84.098302 -270.65632)
			(xy 84.13205 -270.618226) (xy 84.171472 -270.586039) (xy 84.215546 -270.560593) (xy 84.263132 -270.542546)
			(xy 84.312996 -270.532366) (xy 84.363848 -270.530317) (xy 84.414369 -270.536451) (xy 84.463253 -270.550611)
			(xy 84.509232 -270.572428) (xy 84.551116 -270.601338) (xy 84.58782 -270.636593) (xy 84.618393 -270.677279)
			(xy 84.642044 -270.722342) (xy 84.65816 -270.770616) (xy 84.666324 -270.82085) (xy 84.666836 -270.846296)
			(xy 84.666333 -270.871285) (xy 84.973396 -270.871285) (xy 84.973396 -270.821307) (xy 84.981215 -270.771944)
			(xy 84.996659 -270.724412) (xy 85.019349 -270.67988) (xy 85.048725 -270.639447) (xy 85.084065 -270.604107)
			(xy 85.124498 -270.574731) (xy 85.16903 -270.552041) (xy 85.216562 -270.536597) (xy 85.265925 -270.528778)
			(xy 85.315903 -270.528778) (xy 85.365266 -270.536597) (xy 85.412798 -270.552041) (xy 85.45733 -270.574731)
			(xy 85.497763 -270.604107) (xy 85.533103 -270.639447) (xy 85.562479 -270.67988) (xy 85.585169 -270.724412)
			(xy 85.600613 -270.771944) (xy 85.608432 -270.821307) (xy 85.608922 -270.846296) (xy 85.914733 -270.846296)
			(xy 85.918828 -270.795568) (xy 85.931007 -270.746154) (xy 85.950955 -270.699334) (xy 85.978156 -270.65632)
			(xy 86.011904 -270.618226) (xy 86.051326 -270.586039) (xy 86.0954 -270.560593) (xy 86.142986 -270.542546)
			(xy 86.19285 -270.532366) (xy 86.243702 -270.530317) (xy 86.294223 -270.536451) (xy 86.343107 -270.550611)
			(xy 86.389086 -270.572428) (xy 86.43097 -270.601338) (xy 86.467674 -270.636593) (xy 86.498247 -270.677279)
			(xy 86.521898 -270.722342) (xy 86.538014 -270.770616) (xy 86.546178 -270.82085) (xy 86.54669 -270.846296)
			(xy 87.794841 -270.846296) (xy 87.798936 -270.795568) (xy 87.811115 -270.746154) (xy 87.831063 -270.699334)
			(xy 87.858264 -270.65632) (xy 87.892012 -270.618226) (xy 87.931434 -270.586039) (xy 87.975508 -270.560593)
			(xy 88.023094 -270.542546) (xy 88.072958 -270.532366) (xy 88.12381 -270.530317) (xy 88.174331 -270.536451)
			(xy 88.223215 -270.550611) (xy 88.269194 -270.572428) (xy 88.311078 -270.601338) (xy 88.347782 -270.636593)
			(xy 88.378355 -270.677279) (xy 88.402006 -270.722342) (xy 88.418122 -270.770616) (xy 88.426286 -270.82085)
			(xy 88.426798 -270.846296) (xy 88.734895 -270.846296) (xy 88.73899 -270.795568) (xy 88.751169 -270.746154)
			(xy 88.771117 -270.699334) (xy 88.798318 -270.65632) (xy 88.832066 -270.618226) (xy 88.871488 -270.586039)
			(xy 88.915562 -270.560593) (xy 88.963148 -270.542546) (xy 89.013012 -270.532366) (xy 89.063864 -270.530317)
			(xy 89.114385 -270.536451) (xy 89.163269 -270.550611) (xy 89.209248 -270.572428) (xy 89.251132 -270.601338)
			(xy 89.287836 -270.636593) (xy 89.318409 -270.677279) (xy 89.34206 -270.722342) (xy 89.358176 -270.770616)
			(xy 89.36634 -270.82085) (xy 89.366852 -270.846296) (xy 89.366349 -270.871285) (xy 89.673412 -270.871285)
			(xy 89.673412 -270.821307) (xy 89.681231 -270.771944) (xy 89.696675 -270.724412) (xy 89.719365 -270.67988)
			(xy 89.748741 -270.639447) (xy 89.784081 -270.604107) (xy 89.824514 -270.574731) (xy 89.869046 -270.552041)
			(xy 89.916578 -270.536597) (xy 89.965941 -270.528778) (xy 90.015919 -270.528778) (xy 90.065282 -270.536597)
			(xy 90.112814 -270.552041) (xy 90.157346 -270.574731) (xy 90.197779 -270.604107) (xy 90.233119 -270.639447)
			(xy 90.262495 -270.67988) (xy 90.285185 -270.724412) (xy 90.300629 -270.771944) (xy 90.308448 -270.821307)
			(xy 90.308938 -270.846296) (xy 90.614749 -270.846296) (xy 90.618844 -270.795568) (xy 90.631023 -270.746154)
			(xy 90.650971 -270.699334) (xy 90.678172 -270.65632) (xy 90.71192 -270.618226) (xy 90.751342 -270.586039)
			(xy 90.795416 -270.560593) (xy 90.843002 -270.542546) (xy 90.892866 -270.532366) (xy 90.943718 -270.530317)
			(xy 90.994239 -270.536451) (xy 91.043123 -270.550611) (xy 91.089102 -270.572428) (xy 91.130986 -270.601338)
			(xy 91.16769 -270.636593) (xy 91.198263 -270.677279) (xy 91.221914 -270.722342) (xy 91.23803 -270.770616)
			(xy 91.246194 -270.82085) (xy 91.246706 -270.846296) (xy 91.246203 -270.871285) (xy 91.55352 -270.871285)
			(xy 91.55352 -270.821307) (xy 91.561339 -270.771944) (xy 91.576783 -270.724412) (xy 91.599473 -270.67988)
			(xy 91.628849 -270.639447) (xy 91.664189 -270.604107) (xy 91.704622 -270.574731) (xy 91.749154 -270.552041)
			(xy 91.796686 -270.536597) (xy 91.846049 -270.528778) (xy 91.896027 -270.528778) (xy 91.94539 -270.536597)
			(xy 91.992922 -270.552041) (xy 92.037454 -270.574731) (xy 92.077887 -270.604107) (xy 92.113227 -270.639447)
			(xy 92.142603 -270.67988) (xy 92.165293 -270.724412) (xy 92.180737 -270.771944) (xy 92.188556 -270.821307)
			(xy 92.189046 -270.846296) (xy 92.494857 -270.846296) (xy 92.498952 -270.795568) (xy 92.511131 -270.746154)
			(xy 92.531079 -270.699334) (xy 92.55828 -270.65632) (xy 92.592028 -270.618226) (xy 92.63145 -270.586039)
			(xy 92.675524 -270.560593) (xy 92.72311 -270.542546) (xy 92.772974 -270.532366) (xy 92.823826 -270.530317)
			(xy 92.874347 -270.536451) (xy 92.923231 -270.550611) (xy 92.96921 -270.572428) (xy 93.011094 -270.601338)
			(xy 93.047798 -270.636593) (xy 93.078371 -270.677279) (xy 93.102022 -270.722342) (xy 93.118138 -270.770616)
			(xy 93.126302 -270.82085) (xy 93.126814 -270.846296) (xy 94.374711 -270.846296) (xy 94.378806 -270.795568)
			(xy 94.390985 -270.746154) (xy 94.410933 -270.699334) (xy 94.438134 -270.65632) (xy 94.471882 -270.618226)
			(xy 94.511304 -270.586039) (xy 94.555378 -270.560593) (xy 94.602964 -270.542546) (xy 94.652828 -270.532366)
			(xy 94.70368 -270.530317) (xy 94.754201 -270.536451) (xy 94.803085 -270.550611) (xy 94.849064 -270.572428)
			(xy 94.890948 -270.601338) (xy 94.927652 -270.636593) (xy 94.958225 -270.677279) (xy 94.981876 -270.722342)
			(xy 94.997992 -270.770616) (xy 95.006156 -270.82085) (xy 95.006668 -270.846296) (xy 95.314765 -270.846296)
			(xy 95.31886 -270.795568) (xy 95.331039 -270.746154) (xy 95.350987 -270.699334) (xy 95.378188 -270.65632)
			(xy 95.411936 -270.618226) (xy 95.451358 -270.586039) (xy 95.495432 -270.560593) (xy 95.543018 -270.542546)
			(xy 95.592882 -270.532366) (xy 95.643734 -270.530317) (xy 95.694255 -270.536451) (xy 95.743139 -270.550611)
			(xy 95.789118 -270.572428) (xy 95.831002 -270.601338) (xy 95.867706 -270.636593) (xy 95.898279 -270.677279)
			(xy 95.92193 -270.722342) (xy 95.938046 -270.770616) (xy 95.94621 -270.82085) (xy 95.946722 -270.846296)
			(xy 95.94621 -270.871742) (xy 95.938046 -270.921976) (xy 95.92193 -270.97025) (xy 95.898279 -271.015313)
			(xy 95.867706 -271.055999) (xy 95.831002 -271.091254) (xy 95.789118 -271.120164) (xy 95.743139 -271.141981)
			(xy 95.694255 -271.156141) (xy 95.643734 -271.162275) (xy 95.592882 -271.160226) (xy 95.543018 -271.150046)
			(xy 95.495432 -271.131999) (xy 95.451358 -271.106553) (xy 95.411936 -271.074366) (xy 95.378188 -271.036272)
			(xy 95.350987 -270.993258) (xy 95.331039 -270.946438) (xy 95.31886 -270.897024) (xy 95.314765 -270.846296)
			(xy 95.006668 -270.846296) (xy 95.006156 -270.871742) (xy 94.997992 -270.921976) (xy 94.981876 -270.97025)
			(xy 94.958225 -271.015313) (xy 94.927652 -271.055999) (xy 94.890948 -271.091254) (xy 94.849064 -271.120164)
			(xy 94.803085 -271.141981) (xy 94.754201 -271.156141) (xy 94.70368 -271.162275) (xy 94.652828 -271.160226)
			(xy 94.602964 -271.150046) (xy 94.555378 -271.131999) (xy 94.511304 -271.106553) (xy 94.471882 -271.074366)
			(xy 94.438134 -271.036272) (xy 94.410933 -270.993258) (xy 94.390985 -270.946438) (xy 94.378806 -270.897024)
			(xy 94.374711 -270.846296) (xy 93.126814 -270.846296) (xy 93.126302 -270.871742) (xy 93.118138 -270.921976)
			(xy 93.102022 -270.97025) (xy 93.078371 -271.015313) (xy 93.047798 -271.055999) (xy 93.011094 -271.091254)
			(xy 92.96921 -271.120164) (xy 92.923231 -271.141981) (xy 92.874347 -271.156141) (xy 92.823826 -271.162275)
			(xy 92.772974 -271.160226) (xy 92.72311 -271.150046) (xy 92.675524 -271.131999) (xy 92.63145 -271.106553)
			(xy 92.592028 -271.074366) (xy 92.55828 -271.036272) (xy 92.531079 -270.993258) (xy 92.511131 -270.946438)
			(xy 92.498952 -270.897024) (xy 92.494857 -270.846296) (xy 92.189046 -270.846296) (xy 92.188556 -270.871285)
			(xy 92.180737 -270.920648) (xy 92.165293 -270.96818) (xy 92.142603 -271.012712) (xy 92.113227 -271.053145)
			(xy 92.077887 -271.088485) (xy 92.037454 -271.117861) (xy 91.992922 -271.140551) (xy 91.94539 -271.155995)
			(xy 91.896027 -271.163814) (xy 91.846049 -271.163814) (xy 91.796686 -271.155995) (xy 91.749154 -271.140551)
			(xy 91.704622 -271.117861) (xy 91.664189 -271.088485) (xy 91.628849 -271.053145) (xy 91.599473 -271.012712)
			(xy 91.576783 -270.96818) (xy 91.561339 -270.920648) (xy 91.55352 -270.871285) (xy 91.246203 -270.871285)
			(xy 91.246194 -270.871742) (xy 91.23803 -270.921976) (xy 91.221914 -270.97025) (xy 91.198263 -271.015313)
			(xy 91.16769 -271.055999) (xy 91.130986 -271.091254) (xy 91.089102 -271.120164) (xy 91.043123 -271.141981)
			(xy 90.994239 -271.156141) (xy 90.943718 -271.162275) (xy 90.892866 -271.160226) (xy 90.843002 -271.150046)
			(xy 90.795416 -271.131999) (xy 90.751342 -271.106553) (xy 90.71192 -271.074366) (xy 90.678172 -271.036272)
			(xy 90.650971 -270.993258) (xy 90.631023 -270.946438) (xy 90.618844 -270.897024) (xy 90.614749 -270.846296)
			(xy 90.308938 -270.846296) (xy 90.308448 -270.871285) (xy 90.300629 -270.920648) (xy 90.285185 -270.96818)
			(xy 90.262495 -271.012712) (xy 90.233119 -271.053145) (xy 90.197779 -271.088485) (xy 90.157346 -271.117861)
			(xy 90.112814 -271.140551) (xy 90.065282 -271.155995) (xy 90.015919 -271.163814) (xy 89.965941 -271.163814)
			(xy 89.916578 -271.155995) (xy 89.869046 -271.140551) (xy 89.824514 -271.117861) (xy 89.784081 -271.088485)
			(xy 89.748741 -271.053145) (xy 89.719365 -271.012712) (xy 89.696675 -270.96818) (xy 89.681231 -270.920648)
			(xy 89.673412 -270.871285) (xy 89.366349 -270.871285) (xy 89.36634 -270.871742) (xy 89.358176 -270.921976)
			(xy 89.34206 -270.97025) (xy 89.318409 -271.015313) (xy 89.287836 -271.055999) (xy 89.251132 -271.091254)
			(xy 89.209248 -271.120164) (xy 89.163269 -271.141981) (xy 89.114385 -271.156141) (xy 89.063864 -271.162275)
			(xy 89.013012 -271.160226) (xy 88.963148 -271.150046) (xy 88.915562 -271.131999) (xy 88.871488 -271.106553)
			(xy 88.832066 -271.074366) (xy 88.798318 -271.036272) (xy 88.771117 -270.993258) (xy 88.751169 -270.946438)
			(xy 88.73899 -270.897024) (xy 88.734895 -270.846296) (xy 88.426798 -270.846296) (xy 88.426286 -270.871742)
			(xy 88.418122 -270.921976) (xy 88.402006 -270.97025) (xy 88.378355 -271.015313) (xy 88.347782 -271.055999)
			(xy 88.311078 -271.091254) (xy 88.269194 -271.120164) (xy 88.223215 -271.141981) (xy 88.174331 -271.156141)
			(xy 88.12381 -271.162275) (xy 88.072958 -271.160226) (xy 88.023094 -271.150046) (xy 87.975508 -271.131999)
			(xy 87.931434 -271.106553) (xy 87.892012 -271.074366) (xy 87.858264 -271.036272) (xy 87.831063 -270.993258)
			(xy 87.811115 -270.946438) (xy 87.798936 -270.897024) (xy 87.794841 -270.846296) (xy 86.54669 -270.846296)
			(xy 86.546178 -270.871742) (xy 86.538014 -270.921976) (xy 86.521898 -270.97025) (xy 86.498247 -271.015313)
			(xy 86.467674 -271.055999) (xy 86.43097 -271.091254) (xy 86.389086 -271.120164) (xy 86.343107 -271.141981)
			(xy 86.294223 -271.156141) (xy 86.243702 -271.162275) (xy 86.19285 -271.160226) (xy 86.142986 -271.150046)
			(xy 86.0954 -271.131999) (xy 86.051326 -271.106553) (xy 86.011904 -271.074366) (xy 85.978156 -271.036272)
			(xy 85.950955 -270.993258) (xy 85.931007 -270.946438) (xy 85.918828 -270.897024) (xy 85.914733 -270.846296)
			(xy 85.608922 -270.846296) (xy 85.608432 -270.871285) (xy 85.600613 -270.920648) (xy 85.585169 -270.96818)
			(xy 85.562479 -271.012712) (xy 85.533103 -271.053145) (xy 85.497763 -271.088485) (xy 85.45733 -271.117861)
			(xy 85.412798 -271.140551) (xy 85.365266 -271.155995) (xy 85.315903 -271.163814) (xy 85.265925 -271.163814)
			(xy 85.216562 -271.155995) (xy 85.16903 -271.140551) (xy 85.124498 -271.117861) (xy 85.084065 -271.088485)
			(xy 85.048725 -271.053145) (xy 85.019349 -271.012712) (xy 84.996659 -270.96818) (xy 84.981215 -270.920648)
			(xy 84.973396 -270.871285) (xy 84.666333 -270.871285) (xy 84.666324 -270.871742) (xy 84.65816 -270.921976)
			(xy 84.642044 -270.97025) (xy 84.618393 -271.015313) (xy 84.58782 -271.055999) (xy 84.551116 -271.091254)
			(xy 84.509232 -271.120164) (xy 84.463253 -271.141981) (xy 84.414369 -271.156141) (xy 84.363848 -271.162275)
			(xy 84.312996 -271.160226) (xy 84.263132 -271.150046) (xy 84.215546 -271.131999) (xy 84.171472 -271.106553)
			(xy 84.13205 -271.074366) (xy 84.098302 -271.036272) (xy 84.071101 -270.993258) (xy 84.051153 -270.946438)
			(xy 84.038974 -270.897024) (xy 84.034879 -270.846296) (xy 83.729068 -270.846296) (xy 83.728578 -270.871285)
			(xy 83.720759 -270.920648) (xy 83.705315 -270.96818) (xy 83.682625 -271.012712) (xy 83.653249 -271.053145)
			(xy 83.617909 -271.088485) (xy 83.577476 -271.117861) (xy 83.532944 -271.140551) (xy 83.485412 -271.155995)
			(xy 83.436049 -271.163814) (xy 83.386071 -271.163814) (xy 83.336708 -271.155995) (xy 83.289176 -271.140551)
			(xy 83.244644 -271.117861) (xy 83.204211 -271.088485) (xy 83.168871 -271.053145) (xy 83.139495 -271.012712)
			(xy 83.116805 -270.96818) (xy 83.101361 -270.920648) (xy 83.093542 -270.871285) (xy 82.786225 -270.871285)
			(xy 82.786216 -270.871742) (xy 82.778052 -270.921976) (xy 82.761936 -270.97025) (xy 82.738285 -271.015313)
			(xy 82.707712 -271.055999) (xy 82.671008 -271.091254) (xy 82.629124 -271.120164) (xy 82.583145 -271.141981)
			(xy 82.534261 -271.156141) (xy 82.48374 -271.162275) (xy 82.432888 -271.160226) (xy 82.383024 -271.150046)
			(xy 82.335438 -271.131999) (xy 82.291364 -271.106553) (xy 82.251942 -271.074366) (xy 82.218194 -271.036272)
			(xy 82.190993 -270.993258) (xy 82.171045 -270.946438) (xy 82.158866 -270.897024) (xy 82.154771 -270.846296)
			(xy 81.846674 -270.846296) (xy 81.846162 -270.871742) (xy 81.837998 -270.921976) (xy 81.821882 -270.97025)
			(xy 81.798231 -271.015313) (xy 81.767658 -271.055999) (xy 81.730954 -271.091254) (xy 81.68907 -271.120164)
			(xy 81.643091 -271.141981) (xy 81.594207 -271.156141) (xy 81.543686 -271.162275) (xy 81.492834 -271.160226)
			(xy 81.44297 -271.150046) (xy 81.395384 -271.131999) (xy 81.35131 -271.106553) (xy 81.311888 -271.074366)
			(xy 81.27814 -271.036272) (xy 81.250939 -270.993258) (xy 81.230991 -270.946438) (xy 81.218812 -270.897024)
			(xy 81.214717 -270.846296) (xy 79.53248 -270.846296) (xy 79.53248 -271.681291) (xy 79.80348 -271.681291)
			(xy 79.80348 -271.631313) (xy 79.811299 -271.58195) (xy 79.826743 -271.534418) (xy 79.849433 -271.489886)
			(xy 79.878809 -271.449453) (xy 79.914149 -271.414113) (xy 79.954582 -271.384737) (xy 79.999114 -271.362047)
			(xy 80.046646 -271.346603) (xy 80.096009 -271.338784) (xy 80.145987 -271.338784) (xy 80.19535 -271.346603)
			(xy 80.242882 -271.362047) (xy 80.287414 -271.384737) (xy 80.327847 -271.414113) (xy 80.363187 -271.449453)
			(xy 80.392563 -271.489886) (xy 80.415253 -271.534418) (xy 80.430697 -271.58195) (xy 80.438516 -271.631313)
			(xy 80.439006 -271.656302) (xy 80.744817 -271.656302) (xy 80.748912 -271.605574) (xy 80.761091 -271.55616)
			(xy 80.781039 -271.50934) (xy 80.80824 -271.466326) (xy 80.841988 -271.428232) (xy 80.88141 -271.396045)
			(xy 80.925484 -271.370599) (xy 80.97307 -271.352552) (xy 81.022934 -271.342372) (xy 81.073786 -271.340323)
			(xy 81.124307 -271.346457) (xy 81.173191 -271.360617) (xy 81.21917 -271.382434) (xy 81.261054 -271.411344)
			(xy 81.297758 -271.446599) (xy 81.328331 -271.487285) (xy 81.351982 -271.532348) (xy 81.368098 -271.580622)
			(xy 81.376262 -271.630856) (xy 81.376774 -271.656302) (xy 81.376271 -271.681291) (xy 81.683588 -271.681291)
			(xy 81.683588 -271.631313) (xy 81.691407 -271.58195) (xy 81.706851 -271.534418) (xy 81.729541 -271.489886)
			(xy 81.758917 -271.449453) (xy 81.794257 -271.414113) (xy 81.83469 -271.384737) (xy 81.879222 -271.362047)
			(xy 81.926754 -271.346603) (xy 81.976117 -271.338784) (xy 82.026095 -271.338784) (xy 82.075458 -271.346603)
			(xy 82.12299 -271.362047) (xy 82.167522 -271.384737) (xy 82.207955 -271.414113) (xy 82.243295 -271.449453)
			(xy 82.272671 -271.489886) (xy 82.295361 -271.534418) (xy 82.310805 -271.58195) (xy 82.318624 -271.631313)
			(xy 82.319114 -271.656302) (xy 82.624671 -271.656302) (xy 82.628766 -271.605574) (xy 82.640945 -271.55616)
			(xy 82.660893 -271.50934) (xy 82.688094 -271.466326) (xy 82.721842 -271.428232) (xy 82.761264 -271.396045)
			(xy 82.805338 -271.370599) (xy 82.852924 -271.352552) (xy 82.902788 -271.342372) (xy 82.95364 -271.340323)
			(xy 83.004161 -271.346457) (xy 83.053045 -271.360617) (xy 83.099024 -271.382434) (xy 83.140908 -271.411344)
			(xy 83.177612 -271.446599) (xy 83.208185 -271.487285) (xy 83.231836 -271.532348) (xy 83.247952 -271.580622)
			(xy 83.256116 -271.630856) (xy 83.256628 -271.656302) (xy 83.256125 -271.681291) (xy 83.563442 -271.681291)
			(xy 83.563442 -271.631313) (xy 83.571261 -271.58195) (xy 83.586705 -271.534418) (xy 83.609395 -271.489886)
			(xy 83.638771 -271.449453) (xy 83.674111 -271.414113) (xy 83.714544 -271.384737) (xy 83.759076 -271.362047)
			(xy 83.806608 -271.346603) (xy 83.855971 -271.338784) (xy 83.905949 -271.338784) (xy 83.955312 -271.346603)
			(xy 84.002844 -271.362047) (xy 84.047376 -271.384737) (xy 84.087809 -271.414113) (xy 84.123149 -271.449453)
			(xy 84.152525 -271.489886) (xy 84.175215 -271.534418) (xy 84.190659 -271.58195) (xy 84.198478 -271.631313)
			(xy 84.198968 -271.656302) (xy 84.504779 -271.656302) (xy 84.508874 -271.605574) (xy 84.521053 -271.55616)
			(xy 84.541001 -271.50934) (xy 84.568202 -271.466326) (xy 84.60195 -271.428232) (xy 84.641372 -271.396045)
			(xy 84.685446 -271.370599) (xy 84.733032 -271.352552) (xy 84.782896 -271.342372) (xy 84.833748 -271.340323)
			(xy 84.884269 -271.346457) (xy 84.933153 -271.360617) (xy 84.979132 -271.382434) (xy 85.021016 -271.411344)
			(xy 85.05772 -271.446599) (xy 85.088293 -271.487285) (xy 85.111944 -271.532348) (xy 85.12806 -271.580622)
			(xy 85.136224 -271.630856) (xy 85.136736 -271.656302) (xy 85.444833 -271.656302) (xy 85.448928 -271.605574)
			(xy 85.461107 -271.55616) (xy 85.481055 -271.50934) (xy 85.508256 -271.466326) (xy 85.542004 -271.428232)
			(xy 85.581426 -271.396045) (xy 85.6255 -271.370599) (xy 85.673086 -271.352552) (xy 85.72295 -271.342372)
			(xy 85.773802 -271.340323) (xy 85.824323 -271.346457) (xy 85.873207 -271.360617) (xy 85.919186 -271.382434)
			(xy 85.96107 -271.411344) (xy 85.997774 -271.446599) (xy 86.028347 -271.487285) (xy 86.051998 -271.532348)
			(xy 86.068114 -271.580622) (xy 86.076278 -271.630856) (xy 86.07679 -271.656302) (xy 86.076287 -271.681291)
			(xy 86.383604 -271.681291) (xy 86.383604 -271.631313) (xy 86.391423 -271.58195) (xy 86.406867 -271.534418)
			(xy 86.429557 -271.489886) (xy 86.458933 -271.449453) (xy 86.494273 -271.414113) (xy 86.534706 -271.384737)
			(xy 86.579238 -271.362047) (xy 86.62677 -271.346603) (xy 86.676133 -271.338784) (xy 86.726111 -271.338784)
			(xy 86.775474 -271.346603) (xy 86.823006 -271.362047) (xy 86.867538 -271.384737) (xy 86.907971 -271.414113)
			(xy 86.943311 -271.449453) (xy 86.972687 -271.489886) (xy 86.995377 -271.534418) (xy 87.010821 -271.58195)
			(xy 87.01864 -271.631313) (xy 87.01913 -271.656302) (xy 87.324687 -271.656302) (xy 87.328782 -271.605574)
			(xy 87.340961 -271.55616) (xy 87.360909 -271.50934) (xy 87.38811 -271.466326) (xy 87.421858 -271.428232)
			(xy 87.46128 -271.396045) (xy 87.505354 -271.370599) (xy 87.55294 -271.352552) (xy 87.602804 -271.342372)
			(xy 87.653656 -271.340323) (xy 87.704177 -271.346457) (xy 87.753061 -271.360617) (xy 87.79904 -271.382434)
			(xy 87.840924 -271.411344) (xy 87.877628 -271.446599) (xy 87.908201 -271.487285) (xy 87.931852 -271.532348)
			(xy 87.947968 -271.580622) (xy 87.956132 -271.630856) (xy 87.956644 -271.656302) (xy 87.956141 -271.681291)
			(xy 88.263458 -271.681291) (xy 88.263458 -271.631313) (xy 88.271277 -271.58195) (xy 88.286721 -271.534418)
			(xy 88.309411 -271.489886) (xy 88.338787 -271.449453) (xy 88.374127 -271.414113) (xy 88.41456 -271.384737)
			(xy 88.459092 -271.362047) (xy 88.506624 -271.346603) (xy 88.555987 -271.338784) (xy 88.605965 -271.338784)
			(xy 88.655328 -271.346603) (xy 88.70286 -271.362047) (xy 88.747392 -271.384737) (xy 88.787825 -271.414113)
			(xy 88.823165 -271.449453) (xy 88.852541 -271.489886) (xy 88.875231 -271.534418) (xy 88.890675 -271.58195)
			(xy 88.898494 -271.631313) (xy 88.898984 -271.656302) (xy 89.204795 -271.656302) (xy 89.20889 -271.605574)
			(xy 89.221069 -271.55616) (xy 89.241017 -271.50934) (xy 89.268218 -271.466326) (xy 89.301966 -271.428232)
			(xy 89.341388 -271.396045) (xy 89.385462 -271.370599) (xy 89.433048 -271.352552) (xy 89.482912 -271.342372)
			(xy 89.533764 -271.340323) (xy 89.584285 -271.346457) (xy 89.633169 -271.360617) (xy 89.679148 -271.382434)
			(xy 89.721032 -271.411344) (xy 89.757736 -271.446599) (xy 89.788309 -271.487285) (xy 89.81196 -271.532348)
			(xy 89.828076 -271.580622) (xy 89.83624 -271.630856) (xy 89.836752 -271.656302) (xy 89.836249 -271.681291)
			(xy 90.143566 -271.681291) (xy 90.143566 -271.631313) (xy 90.151385 -271.58195) (xy 90.166829 -271.534418)
			(xy 90.189519 -271.489886) (xy 90.218895 -271.449453) (xy 90.254235 -271.414113) (xy 90.294668 -271.384737)
			(xy 90.3392 -271.362047) (xy 90.386732 -271.346603) (xy 90.436095 -271.338784) (xy 90.486073 -271.338784)
			(xy 90.535436 -271.346603) (xy 90.582968 -271.362047) (xy 90.6275 -271.384737) (xy 90.667933 -271.414113)
			(xy 90.703273 -271.449453) (xy 90.732649 -271.489886) (xy 90.755339 -271.534418) (xy 90.770783 -271.58195)
			(xy 90.778602 -271.631313) (xy 90.779092 -271.656302) (xy 91.084903 -271.656302) (xy 91.088998 -271.605574)
			(xy 91.101177 -271.55616) (xy 91.121125 -271.50934) (xy 91.148326 -271.466326) (xy 91.182074 -271.428232)
			(xy 91.221496 -271.396045) (xy 91.26557 -271.370599) (xy 91.313156 -271.352552) (xy 91.36302 -271.342372)
			(xy 91.413872 -271.340323) (xy 91.464393 -271.346457) (xy 91.513277 -271.360617) (xy 91.559256 -271.382434)
			(xy 91.60114 -271.411344) (xy 91.637844 -271.446599) (xy 91.668417 -271.487285) (xy 91.692068 -271.532348)
			(xy 91.708184 -271.580622) (xy 91.716348 -271.630856) (xy 91.71686 -271.656302) (xy 92.024703 -271.656302)
			(xy 92.028798 -271.605574) (xy 92.040977 -271.55616) (xy 92.060925 -271.50934) (xy 92.088126 -271.466326)
			(xy 92.121874 -271.428232) (xy 92.161296 -271.396045) (xy 92.20537 -271.370599) (xy 92.252956 -271.352552)
			(xy 92.30282 -271.342372) (xy 92.353672 -271.340323) (xy 92.404193 -271.346457) (xy 92.453077 -271.360617)
			(xy 92.499056 -271.382434) (xy 92.54094 -271.411344) (xy 92.577644 -271.446599) (xy 92.608217 -271.487285)
			(xy 92.631868 -271.532348) (xy 92.647984 -271.580622) (xy 92.656148 -271.630856) (xy 92.65666 -271.656302)
			(xy 92.656157 -271.681291) (xy 92.963474 -271.681291) (xy 92.963474 -271.631313) (xy 92.971293 -271.58195)
			(xy 92.986737 -271.534418) (xy 93.009427 -271.489886) (xy 93.038803 -271.449453) (xy 93.074143 -271.414113)
			(xy 93.114576 -271.384737) (xy 93.159108 -271.362047) (xy 93.20664 -271.346603) (xy 93.256003 -271.338784)
			(xy 93.305981 -271.338784) (xy 93.355344 -271.346603) (xy 93.402876 -271.362047) (xy 93.447408 -271.384737)
			(xy 93.487841 -271.414113) (xy 93.523181 -271.449453) (xy 93.552557 -271.489886) (xy 93.575247 -271.534418)
			(xy 93.590691 -271.58195) (xy 93.59851 -271.631313) (xy 93.599 -271.656302) (xy 93.904811 -271.656302)
			(xy 93.908906 -271.605574) (xy 93.921085 -271.55616) (xy 93.941033 -271.50934) (xy 93.968234 -271.466326)
			(xy 94.001982 -271.428232) (xy 94.041404 -271.396045) (xy 94.085478 -271.370599) (xy 94.133064 -271.352552)
			(xy 94.182928 -271.342372) (xy 94.23378 -271.340323) (xy 94.284301 -271.346457) (xy 94.333185 -271.360617)
			(xy 94.379164 -271.382434) (xy 94.421048 -271.411344) (xy 94.457752 -271.446599) (xy 94.488325 -271.487285)
			(xy 94.511976 -271.532348) (xy 94.528092 -271.580622) (xy 94.536256 -271.630856) (xy 94.536768 -271.656302)
			(xy 94.536256 -271.681748) (xy 94.528092 -271.731982) (xy 94.511976 -271.780256) (xy 94.488325 -271.825319)
			(xy 94.457752 -271.866005) (xy 94.421048 -271.90126) (xy 94.379164 -271.93017) (xy 94.333185 -271.951987)
			(xy 94.284301 -271.966147) (xy 94.23378 -271.972281) (xy 94.182928 -271.970232) (xy 94.133064 -271.960052)
			(xy 94.085478 -271.942005) (xy 94.041404 -271.916559) (xy 94.001982 -271.884372) (xy 93.968234 -271.846278)
			(xy 93.941033 -271.803264) (xy 93.921085 -271.756444) (xy 93.908906 -271.70703) (xy 93.904811 -271.656302)
			(xy 93.599 -271.656302) (xy 93.59851 -271.681291) (xy 93.590691 -271.730654) (xy 93.575247 -271.778186)
			(xy 93.552557 -271.822718) (xy 93.523181 -271.863151) (xy 93.487841 -271.898491) (xy 93.447408 -271.927867)
			(xy 93.402876 -271.950557) (xy 93.355344 -271.966001) (xy 93.305981 -271.97382) (xy 93.256003 -271.97382)
			(xy 93.20664 -271.966001) (xy 93.159108 -271.950557) (xy 93.114576 -271.927867) (xy 93.074143 -271.898491)
			(xy 93.038803 -271.863151) (xy 93.009427 -271.822718) (xy 92.986737 -271.778186) (xy 92.971293 -271.730654)
			(xy 92.963474 -271.681291) (xy 92.656157 -271.681291) (xy 92.656148 -271.681748) (xy 92.647984 -271.731982)
			(xy 92.631868 -271.780256) (xy 92.608217 -271.825319) (xy 92.577644 -271.866005) (xy 92.54094 -271.90126)
			(xy 92.499056 -271.93017) (xy 92.453077 -271.951987) (xy 92.404193 -271.966147) (xy 92.353672 -271.972281)
			(xy 92.30282 -271.970232) (xy 92.252956 -271.960052) (xy 92.20537 -271.942005) (xy 92.161296 -271.916559)
			(xy 92.121874 -271.884372) (xy 92.088126 -271.846278) (xy 92.060925 -271.803264) (xy 92.040977 -271.756444)
			(xy 92.028798 -271.70703) (xy 92.024703 -271.656302) (xy 91.71686 -271.656302) (xy 91.716348 -271.681748)
			(xy 91.708184 -271.731982) (xy 91.692068 -271.780256) (xy 91.668417 -271.825319) (xy 91.637844 -271.866005)
			(xy 91.60114 -271.90126) (xy 91.559256 -271.93017) (xy 91.513277 -271.951987) (xy 91.464393 -271.966147)
			(xy 91.413872 -271.972281) (xy 91.36302 -271.970232) (xy 91.313156 -271.960052) (xy 91.26557 -271.942005)
			(xy 91.221496 -271.916559) (xy 91.182074 -271.884372) (xy 91.148326 -271.846278) (xy 91.121125 -271.803264)
			(xy 91.101177 -271.756444) (xy 91.088998 -271.70703) (xy 91.084903 -271.656302) (xy 90.779092 -271.656302)
			(xy 90.778602 -271.681291) (xy 90.770783 -271.730654) (xy 90.755339 -271.778186) (xy 90.732649 -271.822718)
			(xy 90.703273 -271.863151) (xy 90.667933 -271.898491) (xy 90.6275 -271.927867) (xy 90.582968 -271.950557)
			(xy 90.535436 -271.966001) (xy 90.486073 -271.97382) (xy 90.436095 -271.97382) (xy 90.386732 -271.966001)
			(xy 90.3392 -271.950557) (xy 90.294668 -271.927867) (xy 90.254235 -271.898491) (xy 90.218895 -271.863151)
			(xy 90.189519 -271.822718) (xy 90.166829 -271.778186) (xy 90.151385 -271.730654) (xy 90.143566 -271.681291)
			(xy 89.836249 -271.681291) (xy 89.83624 -271.681748) (xy 89.828076 -271.731982) (xy 89.81196 -271.780256)
			(xy 89.788309 -271.825319) (xy 89.757736 -271.866005) (xy 89.721032 -271.90126) (xy 89.679148 -271.93017)
			(xy 89.633169 -271.951987) (xy 89.584285 -271.966147) (xy 89.533764 -271.972281) (xy 89.482912 -271.970232)
			(xy 89.433048 -271.960052) (xy 89.385462 -271.942005) (xy 89.341388 -271.916559) (xy 89.301966 -271.884372)
			(xy 89.268218 -271.846278) (xy 89.241017 -271.803264) (xy 89.221069 -271.756444) (xy 89.20889 -271.70703)
			(xy 89.204795 -271.656302) (xy 88.898984 -271.656302) (xy 88.898494 -271.681291) (xy 88.890675 -271.730654)
			(xy 88.875231 -271.778186) (xy 88.852541 -271.822718) (xy 88.823165 -271.863151) (xy 88.787825 -271.898491)
			(xy 88.747392 -271.927867) (xy 88.70286 -271.950557) (xy 88.655328 -271.966001) (xy 88.605965 -271.97382)
			(xy 88.555987 -271.97382) (xy 88.506624 -271.966001) (xy 88.459092 -271.950557) (xy 88.41456 -271.927867)
			(xy 88.374127 -271.898491) (xy 88.338787 -271.863151) (xy 88.309411 -271.822718) (xy 88.286721 -271.778186)
			(xy 88.271277 -271.730654) (xy 88.263458 -271.681291) (xy 87.956141 -271.681291) (xy 87.956132 -271.681748)
			(xy 87.947968 -271.731982) (xy 87.931852 -271.780256) (xy 87.908201 -271.825319) (xy 87.877628 -271.866005)
			(xy 87.840924 -271.90126) (xy 87.79904 -271.93017) (xy 87.753061 -271.951987) (xy 87.704177 -271.966147)
			(xy 87.653656 -271.972281) (xy 87.602804 -271.970232) (xy 87.55294 -271.960052) (xy 87.505354 -271.942005)
			(xy 87.46128 -271.916559) (xy 87.421858 -271.884372) (xy 87.38811 -271.846278) (xy 87.360909 -271.803264)
			(xy 87.340961 -271.756444) (xy 87.328782 -271.70703) (xy 87.324687 -271.656302) (xy 87.01913 -271.656302)
			(xy 87.01864 -271.681291) (xy 87.010821 -271.730654) (xy 86.995377 -271.778186) (xy 86.972687 -271.822718)
			(xy 86.943311 -271.863151) (xy 86.907971 -271.898491) (xy 86.867538 -271.927867) (xy 86.823006 -271.950557)
			(xy 86.775474 -271.966001) (xy 86.726111 -271.97382) (xy 86.676133 -271.97382) (xy 86.62677 -271.966001)
			(xy 86.579238 -271.950557) (xy 86.534706 -271.927867) (xy 86.494273 -271.898491) (xy 86.458933 -271.863151)
			(xy 86.429557 -271.822718) (xy 86.406867 -271.778186) (xy 86.391423 -271.730654) (xy 86.383604 -271.681291)
			(xy 86.076287 -271.681291) (xy 86.076278 -271.681748) (xy 86.068114 -271.731982) (xy 86.051998 -271.780256)
			(xy 86.028347 -271.825319) (xy 85.997774 -271.866005) (xy 85.96107 -271.90126) (xy 85.919186 -271.93017)
			(xy 85.873207 -271.951987) (xy 85.824323 -271.966147) (xy 85.773802 -271.972281) (xy 85.72295 -271.970232)
			(xy 85.673086 -271.960052) (xy 85.6255 -271.942005) (xy 85.581426 -271.916559) (xy 85.542004 -271.884372)
			(xy 85.508256 -271.846278) (xy 85.481055 -271.803264) (xy 85.461107 -271.756444) (xy 85.448928 -271.70703)
			(xy 85.444833 -271.656302) (xy 85.136736 -271.656302) (xy 85.136224 -271.681748) (xy 85.12806 -271.731982)
			(xy 85.111944 -271.780256) (xy 85.088293 -271.825319) (xy 85.05772 -271.866005) (xy 85.021016 -271.90126)
			(xy 84.979132 -271.93017) (xy 84.933153 -271.951987) (xy 84.884269 -271.966147) (xy 84.833748 -271.972281)
			(xy 84.782896 -271.970232) (xy 84.733032 -271.960052) (xy 84.685446 -271.942005) (xy 84.641372 -271.916559)
			(xy 84.60195 -271.884372) (xy 84.568202 -271.846278) (xy 84.541001 -271.803264) (xy 84.521053 -271.756444)
			(xy 84.508874 -271.70703) (xy 84.504779 -271.656302) (xy 84.198968 -271.656302) (xy 84.198478 -271.681291)
			(xy 84.190659 -271.730654) (xy 84.175215 -271.778186) (xy 84.152525 -271.822718) (xy 84.123149 -271.863151)
			(xy 84.087809 -271.898491) (xy 84.047376 -271.927867) (xy 84.002844 -271.950557) (xy 83.955312 -271.966001)
			(xy 83.905949 -271.97382) (xy 83.855971 -271.97382) (xy 83.806608 -271.966001) (xy 83.759076 -271.950557)
			(xy 83.714544 -271.927867) (xy 83.674111 -271.898491) (xy 83.638771 -271.863151) (xy 83.609395 -271.822718)
			(xy 83.586705 -271.778186) (xy 83.571261 -271.730654) (xy 83.563442 -271.681291) (xy 83.256125 -271.681291)
			(xy 83.256116 -271.681748) (xy 83.247952 -271.731982) (xy 83.231836 -271.780256) (xy 83.208185 -271.825319)
			(xy 83.177612 -271.866005) (xy 83.140908 -271.90126) (xy 83.099024 -271.93017) (xy 83.053045 -271.951987)
			(xy 83.004161 -271.966147) (xy 82.95364 -271.972281) (xy 82.902788 -271.970232) (xy 82.852924 -271.960052)
			(xy 82.805338 -271.942005) (xy 82.761264 -271.916559) (xy 82.721842 -271.884372) (xy 82.688094 -271.846278)
			(xy 82.660893 -271.803264) (xy 82.640945 -271.756444) (xy 82.628766 -271.70703) (xy 82.624671 -271.656302)
			(xy 82.319114 -271.656302) (xy 82.318624 -271.681291) (xy 82.310805 -271.730654) (xy 82.295361 -271.778186)
			(xy 82.272671 -271.822718) (xy 82.243295 -271.863151) (xy 82.207955 -271.898491) (xy 82.167522 -271.927867)
			(xy 82.12299 -271.950557) (xy 82.075458 -271.966001) (xy 82.026095 -271.97382) (xy 81.976117 -271.97382)
			(xy 81.926754 -271.966001) (xy 81.879222 -271.950557) (xy 81.83469 -271.927867) (xy 81.794257 -271.898491)
			(xy 81.758917 -271.863151) (xy 81.729541 -271.822718) (xy 81.706851 -271.778186) (xy 81.691407 -271.730654)
			(xy 81.683588 -271.681291) (xy 81.376271 -271.681291) (xy 81.376262 -271.681748) (xy 81.368098 -271.731982)
			(xy 81.351982 -271.780256) (xy 81.328331 -271.825319) (xy 81.297758 -271.866005) (xy 81.261054 -271.90126)
			(xy 81.21917 -271.93017) (xy 81.173191 -271.951987) (xy 81.124307 -271.966147) (xy 81.073786 -271.972281)
			(xy 81.022934 -271.970232) (xy 80.97307 -271.960052) (xy 80.925484 -271.942005) (xy 80.88141 -271.916559)
			(xy 80.841988 -271.884372) (xy 80.80824 -271.846278) (xy 80.781039 -271.803264) (xy 80.761091 -271.756444)
			(xy 80.748912 -271.70703) (xy 80.744817 -271.656302) (xy 80.439006 -271.656302) (xy 80.438516 -271.681291)
			(xy 80.430697 -271.730654) (xy 80.415253 -271.778186) (xy 80.392563 -271.822718) (xy 80.363187 -271.863151)
			(xy 80.327847 -271.898491) (xy 80.287414 -271.927867) (xy 80.242882 -271.950557) (xy 80.19535 -271.966001)
			(xy 80.145987 -271.97382) (xy 80.096009 -271.97382) (xy 80.046646 -271.966001) (xy 79.999114 -271.950557)
			(xy 79.954582 -271.927867) (xy 79.914149 -271.898491) (xy 79.878809 -271.863151) (xy 79.849433 -271.822718)
			(xy 79.826743 -271.778186) (xy 79.811299 -271.730654) (xy 79.80348 -271.681291) (xy 79.53248 -271.681291)
			(xy 79.53248 -272.491297) (xy 80.273634 -272.491297) (xy 80.273634 -272.441319) (xy 80.281453 -272.391956)
			(xy 80.296897 -272.344424) (xy 80.319587 -272.299892) (xy 80.348963 -272.259459) (xy 80.384303 -272.224119)
			(xy 80.424736 -272.194743) (xy 80.469268 -272.172053) (xy 80.5168 -272.156609) (xy 80.566163 -272.14879)
			(xy 80.616141 -272.14879) (xy 80.665504 -272.156609) (xy 80.713036 -272.172053) (xy 80.757568 -272.194743)
			(xy 80.798001 -272.224119) (xy 80.833341 -272.259459) (xy 80.862717 -272.299892) (xy 80.885407 -272.344424)
			(xy 80.900851 -272.391956) (xy 80.90867 -272.441319) (xy 80.90916 -272.466308) (xy 81.214717 -272.466308)
			(xy 81.218812 -272.41558) (xy 81.230991 -272.366166) (xy 81.250939 -272.319346) (xy 81.27814 -272.276332)
			(xy 81.311888 -272.238238) (xy 81.35131 -272.206051) (xy 81.395384 -272.180605) (xy 81.44297 -272.162558)
			(xy 81.492834 -272.152378) (xy 81.543686 -272.150329) (xy 81.594207 -272.156463) (xy 81.643091 -272.170623)
			(xy 81.68907 -272.19244) (xy 81.730954 -272.22135) (xy 81.767658 -272.256605) (xy 81.798231 -272.297291)
			(xy 81.821882 -272.342354) (xy 81.837998 -272.390628) (xy 81.846162 -272.440862) (xy 81.846674 -272.466308)
			(xy 82.154771 -272.466308) (xy 82.158866 -272.41558) (xy 82.171045 -272.366166) (xy 82.190993 -272.319346)
			(xy 82.218194 -272.276332) (xy 82.251942 -272.238238) (xy 82.291364 -272.206051) (xy 82.335438 -272.180605)
			(xy 82.383024 -272.162558) (xy 82.432888 -272.152378) (xy 82.48374 -272.150329) (xy 82.534261 -272.156463)
			(xy 82.583145 -272.170623) (xy 82.629124 -272.19244) (xy 82.671008 -272.22135) (xy 82.707712 -272.256605)
			(xy 82.738285 -272.297291) (xy 82.761936 -272.342354) (xy 82.778052 -272.390628) (xy 82.786216 -272.440862)
			(xy 82.786728 -272.466308) (xy 82.786225 -272.491297) (xy 83.093542 -272.491297) (xy 83.093542 -272.441319)
			(xy 83.101361 -272.391956) (xy 83.116805 -272.344424) (xy 83.139495 -272.299892) (xy 83.168871 -272.259459)
			(xy 83.204211 -272.224119) (xy 83.244644 -272.194743) (xy 83.289176 -272.172053) (xy 83.336708 -272.156609)
			(xy 83.386071 -272.14879) (xy 83.436049 -272.14879) (xy 83.485412 -272.156609) (xy 83.532944 -272.172053)
			(xy 83.577476 -272.194743) (xy 83.617909 -272.224119) (xy 83.653249 -272.259459) (xy 83.682625 -272.299892)
			(xy 83.705315 -272.344424) (xy 83.720759 -272.391956) (xy 83.728578 -272.441319) (xy 83.729068 -272.466308)
			(xy 84.034879 -272.466308) (xy 84.038974 -272.41558) (xy 84.051153 -272.366166) (xy 84.071101 -272.319346)
			(xy 84.098302 -272.276332) (xy 84.13205 -272.238238) (xy 84.171472 -272.206051) (xy 84.215546 -272.180605)
			(xy 84.263132 -272.162558) (xy 84.312996 -272.152378) (xy 84.363848 -272.150329) (xy 84.414369 -272.156463)
			(xy 84.463253 -272.170623) (xy 84.509232 -272.19244) (xy 84.551116 -272.22135) (xy 84.58782 -272.256605)
			(xy 84.618393 -272.297291) (xy 84.642044 -272.342354) (xy 84.65816 -272.390628) (xy 84.666324 -272.440862)
			(xy 84.666836 -272.466308) (xy 84.666333 -272.491297) (xy 84.973396 -272.491297) (xy 84.973396 -272.441319)
			(xy 84.981215 -272.391956) (xy 84.996659 -272.344424) (xy 85.019349 -272.299892) (xy 85.048725 -272.259459)
			(xy 85.084065 -272.224119) (xy 85.124498 -272.194743) (xy 85.16903 -272.172053) (xy 85.216562 -272.156609)
			(xy 85.265925 -272.14879) (xy 85.315903 -272.14879) (xy 85.365266 -272.156609) (xy 85.412798 -272.172053)
			(xy 85.45733 -272.194743) (xy 85.497763 -272.224119) (xy 85.533103 -272.259459) (xy 85.562479 -272.299892)
			(xy 85.585169 -272.344424) (xy 85.600613 -272.391956) (xy 85.608432 -272.441319) (xy 85.608922 -272.466308)
			(xy 85.914733 -272.466308) (xy 85.918828 -272.41558) (xy 85.931007 -272.366166) (xy 85.950955 -272.319346)
			(xy 85.978156 -272.276332) (xy 86.011904 -272.238238) (xy 86.051326 -272.206051) (xy 86.0954 -272.180605)
			(xy 86.142986 -272.162558) (xy 86.19285 -272.152378) (xy 86.243702 -272.150329) (xy 86.294223 -272.156463)
			(xy 86.343107 -272.170623) (xy 86.389086 -272.19244) (xy 86.43097 -272.22135) (xy 86.467674 -272.256605)
			(xy 86.498247 -272.297291) (xy 86.521898 -272.342354) (xy 86.538014 -272.390628) (xy 86.546178 -272.440862)
			(xy 86.54669 -272.466308) (xy 86.546187 -272.491297) (xy 86.853504 -272.491297) (xy 86.853504 -272.441319)
			(xy 86.861323 -272.391956) (xy 86.876767 -272.344424) (xy 86.899457 -272.299892) (xy 86.928833 -272.259459)
			(xy 86.964173 -272.224119) (xy 87.004606 -272.194743) (xy 87.049138 -272.172053) (xy 87.09667 -272.156609)
			(xy 87.146033 -272.14879) (xy 87.196011 -272.14879) (xy 87.245374 -272.156609) (xy 87.292906 -272.172053)
			(xy 87.337438 -272.194743) (xy 87.377871 -272.224119) (xy 87.413211 -272.259459) (xy 87.442587 -272.299892)
			(xy 87.465277 -272.344424) (xy 87.480721 -272.391956) (xy 87.48854 -272.441319) (xy 87.48903 -272.466308)
			(xy 87.794841 -272.466308) (xy 87.798936 -272.41558) (xy 87.811115 -272.366166) (xy 87.831063 -272.319346)
			(xy 87.858264 -272.276332) (xy 87.892012 -272.238238) (xy 87.931434 -272.206051) (xy 87.975508 -272.180605)
			(xy 88.023094 -272.162558) (xy 88.072958 -272.152378) (xy 88.12381 -272.150329) (xy 88.174331 -272.156463)
			(xy 88.223215 -272.170623) (xy 88.269194 -272.19244) (xy 88.311078 -272.22135) (xy 88.347782 -272.256605)
			(xy 88.378355 -272.297291) (xy 88.402006 -272.342354) (xy 88.418122 -272.390628) (xy 88.426286 -272.440862)
			(xy 88.426798 -272.466308) (xy 88.734895 -272.466308) (xy 88.73899 -272.41558) (xy 88.751169 -272.366166)
			(xy 88.771117 -272.319346) (xy 88.798318 -272.276332) (xy 88.832066 -272.238238) (xy 88.871488 -272.206051)
			(xy 88.915562 -272.180605) (xy 88.963148 -272.162558) (xy 89.013012 -272.152378) (xy 89.063864 -272.150329)
			(xy 89.114385 -272.156463) (xy 89.163269 -272.170623) (xy 89.209248 -272.19244) (xy 89.251132 -272.22135)
			(xy 89.287836 -272.256605) (xy 89.318409 -272.297291) (xy 89.34206 -272.342354) (xy 89.358176 -272.390628)
			(xy 89.36634 -272.440862) (xy 89.366852 -272.466308) (xy 89.366349 -272.491297) (xy 89.673412 -272.491297)
			(xy 89.673412 -272.441319) (xy 89.681231 -272.391956) (xy 89.696675 -272.344424) (xy 89.719365 -272.299892)
			(xy 89.748741 -272.259459) (xy 89.784081 -272.224119) (xy 89.824514 -272.194743) (xy 89.869046 -272.172053)
			(xy 89.916578 -272.156609) (xy 89.965941 -272.14879) (xy 90.015919 -272.14879) (xy 90.065282 -272.156609)
			(xy 90.112814 -272.172053) (xy 90.157346 -272.194743) (xy 90.197779 -272.224119) (xy 90.233119 -272.259459)
			(xy 90.262495 -272.299892) (xy 90.285185 -272.344424) (xy 90.300629 -272.391956) (xy 90.308448 -272.441319)
			(xy 90.308938 -272.466308) (xy 90.614749 -272.466308) (xy 90.618844 -272.41558) (xy 90.631023 -272.366166)
			(xy 90.650971 -272.319346) (xy 90.678172 -272.276332) (xy 90.71192 -272.238238) (xy 90.751342 -272.206051)
			(xy 90.795416 -272.180605) (xy 90.843002 -272.162558) (xy 90.892866 -272.152378) (xy 90.943718 -272.150329)
			(xy 90.994239 -272.156463) (xy 91.043123 -272.170623) (xy 91.089102 -272.19244) (xy 91.130986 -272.22135)
			(xy 91.16769 -272.256605) (xy 91.198263 -272.297291) (xy 91.221914 -272.342354) (xy 91.23803 -272.390628)
			(xy 91.246194 -272.440862) (xy 91.246706 -272.466308) (xy 91.246203 -272.491297) (xy 91.55352 -272.491297)
			(xy 91.55352 -272.441319) (xy 91.561339 -272.391956) (xy 91.576783 -272.344424) (xy 91.599473 -272.299892)
			(xy 91.628849 -272.259459) (xy 91.664189 -272.224119) (xy 91.704622 -272.194743) (xy 91.749154 -272.172053)
			(xy 91.796686 -272.156609) (xy 91.846049 -272.14879) (xy 91.896027 -272.14879) (xy 91.94539 -272.156609)
			(xy 91.992922 -272.172053) (xy 92.037454 -272.194743) (xy 92.077887 -272.224119) (xy 92.113227 -272.259459)
			(xy 92.142603 -272.299892) (xy 92.165293 -272.344424) (xy 92.180737 -272.391956) (xy 92.188556 -272.441319)
			(xy 92.189046 -272.466308) (xy 92.494857 -272.466308) (xy 92.498952 -272.41558) (xy 92.511131 -272.366166)
			(xy 92.531079 -272.319346) (xy 92.55828 -272.276332) (xy 92.592028 -272.238238) (xy 92.63145 -272.206051)
			(xy 92.675524 -272.180605) (xy 92.72311 -272.162558) (xy 92.772974 -272.152378) (xy 92.823826 -272.150329)
			(xy 92.874347 -272.156463) (xy 92.923231 -272.170623) (xy 92.96921 -272.19244) (xy 93.011094 -272.22135)
			(xy 93.047798 -272.256605) (xy 93.078371 -272.297291) (xy 93.102022 -272.342354) (xy 93.118138 -272.390628)
			(xy 93.126302 -272.440862) (xy 93.126814 -272.466308) (xy 93.126311 -272.491297) (xy 93.433628 -272.491297)
			(xy 93.433628 -272.441319) (xy 93.441447 -272.391956) (xy 93.456891 -272.344424) (xy 93.479581 -272.299892)
			(xy 93.508957 -272.259459) (xy 93.544297 -272.224119) (xy 93.58473 -272.194743) (xy 93.629262 -272.172053)
			(xy 93.676794 -272.156609) (xy 93.726157 -272.14879) (xy 93.776135 -272.14879) (xy 93.825498 -272.156609)
			(xy 93.87303 -272.172053) (xy 93.917562 -272.194743) (xy 93.957995 -272.224119) (xy 93.993335 -272.259459)
			(xy 94.022711 -272.299892) (xy 94.045401 -272.344424) (xy 94.060845 -272.391956) (xy 94.068664 -272.441319)
			(xy 94.069154 -272.466308) (xy 94.068664 -272.491297) (xy 94.060845 -272.54066) (xy 94.045401 -272.588192)
			(xy 94.022711 -272.632724) (xy 93.993335 -272.673157) (xy 93.957995 -272.708497) (xy 93.917562 -272.737873)
			(xy 93.87303 -272.760563) (xy 93.825498 -272.776007) (xy 93.776135 -272.783826) (xy 93.726157 -272.783826)
			(xy 93.676794 -272.776007) (xy 93.629262 -272.760563) (xy 93.58473 -272.737873) (xy 93.544297 -272.708497)
			(xy 93.508957 -272.673157) (xy 93.479581 -272.632724) (xy 93.456891 -272.588192) (xy 93.441447 -272.54066)
			(xy 93.433628 -272.491297) (xy 93.126311 -272.491297) (xy 93.126302 -272.491754) (xy 93.118138 -272.541988)
			(xy 93.102022 -272.590262) (xy 93.078371 -272.635325) (xy 93.047798 -272.676011) (xy 93.011094 -272.711266)
			(xy 92.96921 -272.740176) (xy 92.923231 -272.761993) (xy 92.874347 -272.776153) (xy 92.823826 -272.782287)
			(xy 92.772974 -272.780238) (xy 92.72311 -272.770058) (xy 92.675524 -272.752011) (xy 92.63145 -272.726565)
			(xy 92.592028 -272.694378) (xy 92.55828 -272.656284) (xy 92.531079 -272.61327) (xy 92.511131 -272.56645)
			(xy 92.498952 -272.517036) (xy 92.494857 -272.466308) (xy 92.189046 -272.466308) (xy 92.188556 -272.491297)
			(xy 92.180737 -272.54066) (xy 92.165293 -272.588192) (xy 92.142603 -272.632724) (xy 92.113227 -272.673157)
			(xy 92.077887 -272.708497) (xy 92.037454 -272.737873) (xy 91.992922 -272.760563) (xy 91.94539 -272.776007)
			(xy 91.896027 -272.783826) (xy 91.846049 -272.783826) (xy 91.796686 -272.776007) (xy 91.749154 -272.760563)
			(xy 91.704622 -272.737873) (xy 91.664189 -272.708497) (xy 91.628849 -272.673157) (xy 91.599473 -272.632724)
			(xy 91.576783 -272.588192) (xy 91.561339 -272.54066) (xy 91.55352 -272.491297) (xy 91.246203 -272.491297)
			(xy 91.246194 -272.491754) (xy 91.23803 -272.541988) (xy 91.221914 -272.590262) (xy 91.198263 -272.635325)
			(xy 91.16769 -272.676011) (xy 91.130986 -272.711266) (xy 91.089102 -272.740176) (xy 91.043123 -272.761993)
			(xy 90.994239 -272.776153) (xy 90.943718 -272.782287) (xy 90.892866 -272.780238) (xy 90.843002 -272.770058)
			(xy 90.795416 -272.752011) (xy 90.751342 -272.726565) (xy 90.71192 -272.694378) (xy 90.678172 -272.656284)
			(xy 90.650971 -272.61327) (xy 90.631023 -272.56645) (xy 90.618844 -272.517036) (xy 90.614749 -272.466308)
			(xy 90.308938 -272.466308) (xy 90.308448 -272.491297) (xy 90.300629 -272.54066) (xy 90.285185 -272.588192)
			(xy 90.262495 -272.632724) (xy 90.233119 -272.673157) (xy 90.197779 -272.708497) (xy 90.157346 -272.737873)
			(xy 90.112814 -272.760563) (xy 90.065282 -272.776007) (xy 90.015919 -272.783826) (xy 89.965941 -272.783826)
			(xy 89.916578 -272.776007) (xy 89.869046 -272.760563) (xy 89.824514 -272.737873) (xy 89.784081 -272.708497)
			(xy 89.748741 -272.673157) (xy 89.719365 -272.632724) (xy 89.696675 -272.588192) (xy 89.681231 -272.54066)
			(xy 89.673412 -272.491297) (xy 89.366349 -272.491297) (xy 89.36634 -272.491754) (xy 89.358176 -272.541988)
			(xy 89.34206 -272.590262) (xy 89.318409 -272.635325) (xy 89.287836 -272.676011) (xy 89.251132 -272.711266)
			(xy 89.209248 -272.740176) (xy 89.163269 -272.761993) (xy 89.114385 -272.776153) (xy 89.063864 -272.782287)
			(xy 89.013012 -272.780238) (xy 88.963148 -272.770058) (xy 88.915562 -272.752011) (xy 88.871488 -272.726565)
			(xy 88.832066 -272.694378) (xy 88.798318 -272.656284) (xy 88.771117 -272.61327) (xy 88.751169 -272.56645)
			(xy 88.73899 -272.517036) (xy 88.734895 -272.466308) (xy 88.426798 -272.466308) (xy 88.426286 -272.491754)
			(xy 88.418122 -272.541988) (xy 88.402006 -272.590262) (xy 88.378355 -272.635325) (xy 88.347782 -272.676011)
			(xy 88.311078 -272.711266) (xy 88.269194 -272.740176) (xy 88.223215 -272.761993) (xy 88.174331 -272.776153)
			(xy 88.12381 -272.782287) (xy 88.072958 -272.780238) (xy 88.023094 -272.770058) (xy 87.975508 -272.752011)
			(xy 87.931434 -272.726565) (xy 87.892012 -272.694378) (xy 87.858264 -272.656284) (xy 87.831063 -272.61327)
			(xy 87.811115 -272.56645) (xy 87.798936 -272.517036) (xy 87.794841 -272.466308) (xy 87.48903 -272.466308)
			(xy 87.48854 -272.491297) (xy 87.480721 -272.54066) (xy 87.465277 -272.588192) (xy 87.442587 -272.632724)
			(xy 87.413211 -272.673157) (xy 87.377871 -272.708497) (xy 87.337438 -272.737873) (xy 87.292906 -272.760563)
			(xy 87.245374 -272.776007) (xy 87.196011 -272.783826) (xy 87.146033 -272.783826) (xy 87.09667 -272.776007)
			(xy 87.049138 -272.760563) (xy 87.004606 -272.737873) (xy 86.964173 -272.708497) (xy 86.928833 -272.673157)
			(xy 86.899457 -272.632724) (xy 86.876767 -272.588192) (xy 86.861323 -272.54066) (xy 86.853504 -272.491297)
			(xy 86.546187 -272.491297) (xy 86.546178 -272.491754) (xy 86.538014 -272.541988) (xy 86.521898 -272.590262)
			(xy 86.498247 -272.635325) (xy 86.467674 -272.676011) (xy 86.43097 -272.711266) (xy 86.389086 -272.740176)
			(xy 86.343107 -272.761993) (xy 86.294223 -272.776153) (xy 86.243702 -272.782287) (xy 86.19285 -272.780238)
			(xy 86.142986 -272.770058) (xy 86.0954 -272.752011) (xy 86.051326 -272.726565) (xy 86.011904 -272.694378)
			(xy 85.978156 -272.656284) (xy 85.950955 -272.61327) (xy 85.931007 -272.56645) (xy 85.918828 -272.517036)
			(xy 85.914733 -272.466308) (xy 85.608922 -272.466308) (xy 85.608432 -272.491297) (xy 85.600613 -272.54066)
			(xy 85.585169 -272.588192) (xy 85.562479 -272.632724) (xy 85.533103 -272.673157) (xy 85.497763 -272.708497)
			(xy 85.45733 -272.737873) (xy 85.412798 -272.760563) (xy 85.365266 -272.776007) (xy 85.315903 -272.783826)
			(xy 85.265925 -272.783826) (xy 85.216562 -272.776007) (xy 85.16903 -272.760563) (xy 85.124498 -272.737873)
			(xy 85.084065 -272.708497) (xy 85.048725 -272.673157) (xy 85.019349 -272.632724) (xy 84.996659 -272.588192)
			(xy 84.981215 -272.54066) (xy 84.973396 -272.491297) (xy 84.666333 -272.491297) (xy 84.666324 -272.491754)
			(xy 84.65816 -272.541988) (xy 84.642044 -272.590262) (xy 84.618393 -272.635325) (xy 84.58782 -272.676011)
			(xy 84.551116 -272.711266) (xy 84.509232 -272.740176) (xy 84.463253 -272.761993) (xy 84.414369 -272.776153)
			(xy 84.363848 -272.782287) (xy 84.312996 -272.780238) (xy 84.263132 -272.770058) (xy 84.215546 -272.752011)
			(xy 84.171472 -272.726565) (xy 84.13205 -272.694378) (xy 84.098302 -272.656284) (xy 84.071101 -272.61327)
			(xy 84.051153 -272.56645) (xy 84.038974 -272.517036) (xy 84.034879 -272.466308) (xy 83.729068 -272.466308)
			(xy 83.728578 -272.491297) (xy 83.720759 -272.54066) (xy 83.705315 -272.588192) (xy 83.682625 -272.632724)
			(xy 83.653249 -272.673157) (xy 83.617909 -272.708497) (xy 83.577476 -272.737873) (xy 83.532944 -272.760563)
			(xy 83.485412 -272.776007) (xy 83.436049 -272.783826) (xy 83.386071 -272.783826) (xy 83.336708 -272.776007)
			(xy 83.289176 -272.760563) (xy 83.244644 -272.737873) (xy 83.204211 -272.708497) (xy 83.168871 -272.673157)
			(xy 83.139495 -272.632724) (xy 83.116805 -272.588192) (xy 83.101361 -272.54066) (xy 83.093542 -272.491297)
			(xy 82.786225 -272.491297) (xy 82.786216 -272.491754) (xy 82.778052 -272.541988) (xy 82.761936 -272.590262)
			(xy 82.738285 -272.635325) (xy 82.707712 -272.676011) (xy 82.671008 -272.711266) (xy 82.629124 -272.740176)
			(xy 82.583145 -272.761993) (xy 82.534261 -272.776153) (xy 82.48374 -272.782287) (xy 82.432888 -272.780238)
			(xy 82.383024 -272.770058) (xy 82.335438 -272.752011) (xy 82.291364 -272.726565) (xy 82.251942 -272.694378)
			(xy 82.218194 -272.656284) (xy 82.190993 -272.61327) (xy 82.171045 -272.56645) (xy 82.158866 -272.517036)
			(xy 82.154771 -272.466308) (xy 81.846674 -272.466308) (xy 81.846162 -272.491754) (xy 81.837998 -272.541988)
			(xy 81.821882 -272.590262) (xy 81.798231 -272.635325) (xy 81.767658 -272.676011) (xy 81.730954 -272.711266)
			(xy 81.68907 -272.740176) (xy 81.643091 -272.761993) (xy 81.594207 -272.776153) (xy 81.543686 -272.782287)
			(xy 81.492834 -272.780238) (xy 81.44297 -272.770058) (xy 81.395384 -272.752011) (xy 81.35131 -272.726565)
			(xy 81.311888 -272.694378) (xy 81.27814 -272.656284) (xy 81.250939 -272.61327) (xy 81.230991 -272.56645)
			(xy 81.218812 -272.517036) (xy 81.214717 -272.466308) (xy 80.90916 -272.466308) (xy 80.90867 -272.491297)
			(xy 80.900851 -272.54066) (xy 80.885407 -272.588192) (xy 80.862717 -272.632724) (xy 80.833341 -272.673157)
			(xy 80.798001 -272.708497) (xy 80.757568 -272.737873) (xy 80.713036 -272.760563) (xy 80.665504 -272.776007)
			(xy 80.616141 -272.783826) (xy 80.566163 -272.783826) (xy 80.5168 -272.776007) (xy 80.469268 -272.760563)
			(xy 80.424736 -272.737873) (xy 80.384303 -272.708497) (xy 80.348963 -272.673157) (xy 80.319587 -272.632724)
			(xy 80.296897 -272.588192) (xy 80.281453 -272.54066) (xy 80.273634 -272.491297) (xy 79.53248 -272.491297)
			(xy 79.53248 -273.276314) (xy 80.744817 -273.276314) (xy 80.748912 -273.225586) (xy 80.761091 -273.176172)
			(xy 80.781039 -273.129352) (xy 80.80824 -273.086338) (xy 80.841988 -273.048244) (xy 80.88141 -273.016057)
			(xy 80.925484 -272.990611) (xy 80.97307 -272.972564) (xy 81.022934 -272.962384) (xy 81.073786 -272.960335)
			(xy 81.124307 -272.966469) (xy 81.173191 -272.980629) (xy 81.21917 -273.002446) (xy 81.261054 -273.031356)
			(xy 81.297758 -273.066611) (xy 81.328331 -273.107297) (xy 81.351982 -273.15236) (xy 81.368098 -273.200634)
			(xy 81.376262 -273.250868) (xy 81.376774 -273.276314) (xy 81.376271 -273.301303) (xy 81.683588 -273.301303)
			(xy 81.683588 -273.251325) (xy 81.691407 -273.201962) (xy 81.706851 -273.15443) (xy 81.729541 -273.109898)
			(xy 81.758917 -273.069465) (xy 81.794257 -273.034125) (xy 81.83469 -273.004749) (xy 81.879222 -272.982059)
			(xy 81.926754 -272.966615) (xy 81.976117 -272.958796) (xy 82.026095 -272.958796) (xy 82.075458 -272.966615)
			(xy 82.12299 -272.982059) (xy 82.167522 -273.004749) (xy 82.207955 -273.034125) (xy 82.243295 -273.069465)
			(xy 82.272671 -273.109898) (xy 82.295361 -273.15443) (xy 82.310805 -273.201962) (xy 82.318624 -273.251325)
			(xy 82.319114 -273.276314) (xy 82.624671 -273.276314) (xy 82.628766 -273.225586) (xy 82.640945 -273.176172)
			(xy 82.660893 -273.129352) (xy 82.688094 -273.086338) (xy 82.721842 -273.048244) (xy 82.761264 -273.016057)
			(xy 82.805338 -272.990611) (xy 82.852924 -272.972564) (xy 82.902788 -272.962384) (xy 82.95364 -272.960335)
			(xy 83.004161 -272.966469) (xy 83.053045 -272.980629) (xy 83.099024 -273.002446) (xy 83.140908 -273.031356)
			(xy 83.177612 -273.066611) (xy 83.208185 -273.107297) (xy 83.231836 -273.15236) (xy 83.247952 -273.200634)
			(xy 83.256116 -273.250868) (xy 83.256628 -273.276314) (xy 83.256125 -273.301303) (xy 83.563442 -273.301303)
			(xy 83.563442 -273.251325) (xy 83.571261 -273.201962) (xy 83.586705 -273.15443) (xy 83.609395 -273.109898)
			(xy 83.638771 -273.069465) (xy 83.674111 -273.034125) (xy 83.714544 -273.004749) (xy 83.759076 -272.982059)
			(xy 83.806608 -272.966615) (xy 83.855971 -272.958796) (xy 83.905949 -272.958796) (xy 83.955312 -272.966615)
			(xy 84.002844 -272.982059) (xy 84.047376 -273.004749) (xy 84.087809 -273.034125) (xy 84.123149 -273.069465)
			(xy 84.152525 -273.109898) (xy 84.175215 -273.15443) (xy 84.190659 -273.201962) (xy 84.198478 -273.251325)
			(xy 84.198968 -273.276314) (xy 84.504779 -273.276314) (xy 84.508874 -273.225586) (xy 84.521053 -273.176172)
			(xy 84.541001 -273.129352) (xy 84.568202 -273.086338) (xy 84.60195 -273.048244) (xy 84.641372 -273.016057)
			(xy 84.685446 -272.990611) (xy 84.733032 -272.972564) (xy 84.782896 -272.962384) (xy 84.833748 -272.960335)
			(xy 84.884269 -272.966469) (xy 84.933153 -272.980629) (xy 84.979132 -273.002446) (xy 85.021016 -273.031356)
			(xy 85.05772 -273.066611) (xy 85.088293 -273.107297) (xy 85.111944 -273.15236) (xy 85.12806 -273.200634)
			(xy 85.136224 -273.250868) (xy 85.136736 -273.276314) (xy 85.444833 -273.276314) (xy 85.448928 -273.225586)
			(xy 85.461107 -273.176172) (xy 85.481055 -273.129352) (xy 85.508256 -273.086338) (xy 85.542004 -273.048244)
			(xy 85.581426 -273.016057) (xy 85.6255 -272.990611) (xy 85.673086 -272.972564) (xy 85.72295 -272.962384)
			(xy 85.773802 -272.960335) (xy 85.824323 -272.966469) (xy 85.873207 -272.980629) (xy 85.919186 -273.002446)
			(xy 85.96107 -273.031356) (xy 85.997774 -273.066611) (xy 86.028347 -273.107297) (xy 86.051998 -273.15236)
			(xy 86.068114 -273.200634) (xy 86.076278 -273.250868) (xy 86.07679 -273.276314) (xy 87.324687 -273.276314)
			(xy 87.328782 -273.225586) (xy 87.340961 -273.176172) (xy 87.360909 -273.129352) (xy 87.38811 -273.086338)
			(xy 87.421858 -273.048244) (xy 87.46128 -273.016057) (xy 87.505354 -272.990611) (xy 87.55294 -272.972564)
			(xy 87.602804 -272.962384) (xy 87.653656 -272.960335) (xy 87.704177 -272.966469) (xy 87.753061 -272.980629)
			(xy 87.79904 -273.002446) (xy 87.840924 -273.031356) (xy 87.877628 -273.066611) (xy 87.908201 -273.107297)
			(xy 87.931852 -273.15236) (xy 87.947968 -273.200634) (xy 87.956132 -273.250868) (xy 87.956644 -273.276314)
			(xy 87.956141 -273.301303) (xy 88.263458 -273.301303) (xy 88.263458 -273.251325) (xy 88.271277 -273.201962)
			(xy 88.286721 -273.15443) (xy 88.309411 -273.109898) (xy 88.338787 -273.069465) (xy 88.374127 -273.034125)
			(xy 88.41456 -273.004749) (xy 88.459092 -272.982059) (xy 88.506624 -272.966615) (xy 88.555987 -272.958796)
			(xy 88.605965 -272.958796) (xy 88.655328 -272.966615) (xy 88.70286 -272.982059) (xy 88.747392 -273.004749)
			(xy 88.787825 -273.034125) (xy 88.823165 -273.069465) (xy 88.852541 -273.109898) (xy 88.875231 -273.15443)
			(xy 88.890675 -273.201962) (xy 88.898494 -273.251325) (xy 88.898984 -273.276314) (xy 89.204795 -273.276314)
			(xy 89.20889 -273.225586) (xy 89.221069 -273.176172) (xy 89.241017 -273.129352) (xy 89.268218 -273.086338)
			(xy 89.301966 -273.048244) (xy 89.341388 -273.016057) (xy 89.385462 -272.990611) (xy 89.433048 -272.972564)
			(xy 89.482912 -272.962384) (xy 89.533764 -272.960335) (xy 89.584285 -272.966469) (xy 89.633169 -272.980629)
			(xy 89.679148 -273.002446) (xy 89.721032 -273.031356) (xy 89.757736 -273.066611) (xy 89.788309 -273.107297)
			(xy 89.81196 -273.15236) (xy 89.828076 -273.200634) (xy 89.83624 -273.250868) (xy 89.836752 -273.276314)
			(xy 89.836249 -273.301303) (xy 90.143566 -273.301303) (xy 90.143566 -273.251325) (xy 90.151385 -273.201962)
			(xy 90.166829 -273.15443) (xy 90.189519 -273.109898) (xy 90.218895 -273.069465) (xy 90.254235 -273.034125)
			(xy 90.294668 -273.004749) (xy 90.3392 -272.982059) (xy 90.386732 -272.966615) (xy 90.436095 -272.958796)
			(xy 90.486073 -272.958796) (xy 90.535436 -272.966615) (xy 90.582968 -272.982059) (xy 90.6275 -273.004749)
			(xy 90.667933 -273.034125) (xy 90.703273 -273.069465) (xy 90.732649 -273.109898) (xy 90.755339 -273.15443)
			(xy 90.770783 -273.201962) (xy 90.778602 -273.251325) (xy 90.779092 -273.276314) (xy 91.084903 -273.276314)
			(xy 91.088998 -273.225586) (xy 91.101177 -273.176172) (xy 91.121125 -273.129352) (xy 91.148326 -273.086338)
			(xy 91.182074 -273.048244) (xy 91.221496 -273.016057) (xy 91.26557 -272.990611) (xy 91.313156 -272.972564)
			(xy 91.36302 -272.962384) (xy 91.413872 -272.960335) (xy 91.464393 -272.966469) (xy 91.513277 -272.980629)
			(xy 91.559256 -273.002446) (xy 91.60114 -273.031356) (xy 91.637844 -273.066611) (xy 91.668417 -273.107297)
			(xy 91.692068 -273.15236) (xy 91.708184 -273.200634) (xy 91.716348 -273.250868) (xy 91.71686 -273.276314)
			(xy 92.024703 -273.276314) (xy 92.028798 -273.225586) (xy 92.040977 -273.176172) (xy 92.060925 -273.129352)
			(xy 92.088126 -273.086338) (xy 92.121874 -273.048244) (xy 92.161296 -273.016057) (xy 92.20537 -272.990611)
			(xy 92.252956 -272.972564) (xy 92.30282 -272.962384) (xy 92.353672 -272.960335) (xy 92.404193 -272.966469)
			(xy 92.453077 -272.980629) (xy 92.499056 -273.002446) (xy 92.54094 -273.031356) (xy 92.577644 -273.066611)
			(xy 92.608217 -273.107297) (xy 92.631868 -273.15236) (xy 92.647984 -273.200634) (xy 92.656148 -273.250868)
			(xy 92.65666 -273.276314) (xy 92.656148 -273.30176) (xy 92.647984 -273.351994) (xy 92.631868 -273.400268)
			(xy 92.608217 -273.445331) (xy 92.577644 -273.486017) (xy 92.54094 -273.521272) (xy 92.499056 -273.550182)
			(xy 92.453077 -273.571999) (xy 92.404193 -273.586159) (xy 92.353672 -273.592293) (xy 92.30282 -273.590244)
			(xy 92.252956 -273.580064) (xy 92.20537 -273.562017) (xy 92.161296 -273.536571) (xy 92.121874 -273.504384)
			(xy 92.088126 -273.46629) (xy 92.060925 -273.423276) (xy 92.040977 -273.376456) (xy 92.028798 -273.327042)
			(xy 92.024703 -273.276314) (xy 91.71686 -273.276314) (xy 91.716348 -273.30176) (xy 91.708184 -273.351994)
			(xy 91.692068 -273.400268) (xy 91.668417 -273.445331) (xy 91.637844 -273.486017) (xy 91.60114 -273.521272)
			(xy 91.559256 -273.550182) (xy 91.513277 -273.571999) (xy 91.464393 -273.586159) (xy 91.413872 -273.592293)
			(xy 91.36302 -273.590244) (xy 91.313156 -273.580064) (xy 91.26557 -273.562017) (xy 91.221496 -273.536571)
			(xy 91.182074 -273.504384) (xy 91.148326 -273.46629) (xy 91.121125 -273.423276) (xy 91.101177 -273.376456)
			(xy 91.088998 -273.327042) (xy 91.084903 -273.276314) (xy 90.779092 -273.276314) (xy 90.778602 -273.301303)
			(xy 90.770783 -273.350666) (xy 90.755339 -273.398198) (xy 90.732649 -273.44273) (xy 90.703273 -273.483163)
			(xy 90.667933 -273.518503) (xy 90.6275 -273.547879) (xy 90.582968 -273.570569) (xy 90.535436 -273.586013)
			(xy 90.486073 -273.593832) (xy 90.436095 -273.593832) (xy 90.386732 -273.586013) (xy 90.3392 -273.570569)
			(xy 90.294668 -273.547879) (xy 90.254235 -273.518503) (xy 90.218895 -273.483163) (xy 90.189519 -273.44273)
			(xy 90.166829 -273.398198) (xy 90.151385 -273.350666) (xy 90.143566 -273.301303) (xy 89.836249 -273.301303)
			(xy 89.83624 -273.30176) (xy 89.828076 -273.351994) (xy 89.81196 -273.400268) (xy 89.788309 -273.445331)
			(xy 89.757736 -273.486017) (xy 89.721032 -273.521272) (xy 89.679148 -273.550182) (xy 89.633169 -273.571999)
			(xy 89.584285 -273.586159) (xy 89.533764 -273.592293) (xy 89.482912 -273.590244) (xy 89.433048 -273.580064)
			(xy 89.385462 -273.562017) (xy 89.341388 -273.536571) (xy 89.301966 -273.504384) (xy 89.268218 -273.46629)
			(xy 89.241017 -273.423276) (xy 89.221069 -273.376456) (xy 89.20889 -273.327042) (xy 89.204795 -273.276314)
			(xy 88.898984 -273.276314) (xy 88.898494 -273.301303) (xy 88.890675 -273.350666) (xy 88.875231 -273.398198)
			(xy 88.852541 -273.44273) (xy 88.823165 -273.483163) (xy 88.787825 -273.518503) (xy 88.747392 -273.547879)
			(xy 88.70286 -273.570569) (xy 88.655328 -273.586013) (xy 88.605965 -273.593832) (xy 88.555987 -273.593832)
			(xy 88.506624 -273.586013) (xy 88.459092 -273.570569) (xy 88.41456 -273.547879) (xy 88.374127 -273.518503)
			(xy 88.338787 -273.483163) (xy 88.309411 -273.44273) (xy 88.286721 -273.398198) (xy 88.271277 -273.350666)
			(xy 88.263458 -273.301303) (xy 87.956141 -273.301303) (xy 87.956132 -273.30176) (xy 87.947968 -273.351994)
			(xy 87.931852 -273.400268) (xy 87.908201 -273.445331) (xy 87.877628 -273.486017) (xy 87.840924 -273.521272)
			(xy 87.79904 -273.550182) (xy 87.753061 -273.571999) (xy 87.704177 -273.586159) (xy 87.653656 -273.592293)
			(xy 87.602804 -273.590244) (xy 87.55294 -273.580064) (xy 87.505354 -273.562017) (xy 87.46128 -273.536571)
			(xy 87.421858 -273.504384) (xy 87.38811 -273.46629) (xy 87.360909 -273.423276) (xy 87.340961 -273.376456)
			(xy 87.328782 -273.327042) (xy 87.324687 -273.276314) (xy 86.07679 -273.276314) (xy 86.076278 -273.30176)
			(xy 86.068114 -273.351994) (xy 86.051998 -273.400268) (xy 86.028347 -273.445331) (xy 85.997774 -273.486017)
			(xy 85.96107 -273.521272) (xy 85.919186 -273.550182) (xy 85.873207 -273.571999) (xy 85.824323 -273.586159)
			(xy 85.773802 -273.592293) (xy 85.72295 -273.590244) (xy 85.673086 -273.580064) (xy 85.6255 -273.562017)
			(xy 85.581426 -273.536571) (xy 85.542004 -273.504384) (xy 85.508256 -273.46629) (xy 85.481055 -273.423276)
			(xy 85.461107 -273.376456) (xy 85.448928 -273.327042) (xy 85.444833 -273.276314) (xy 85.136736 -273.276314)
			(xy 85.136224 -273.30176) (xy 85.12806 -273.351994) (xy 85.111944 -273.400268) (xy 85.088293 -273.445331)
			(xy 85.05772 -273.486017) (xy 85.021016 -273.521272) (xy 84.979132 -273.550182) (xy 84.933153 -273.571999)
			(xy 84.884269 -273.586159) (xy 84.833748 -273.592293) (xy 84.782896 -273.590244) (xy 84.733032 -273.580064)
			(xy 84.685446 -273.562017) (xy 84.641372 -273.536571) (xy 84.60195 -273.504384) (xy 84.568202 -273.46629)
			(xy 84.541001 -273.423276) (xy 84.521053 -273.376456) (xy 84.508874 -273.327042) (xy 84.504779 -273.276314)
			(xy 84.198968 -273.276314) (xy 84.198478 -273.301303) (xy 84.190659 -273.350666) (xy 84.175215 -273.398198)
			(xy 84.152525 -273.44273) (xy 84.123149 -273.483163) (xy 84.087809 -273.518503) (xy 84.047376 -273.547879)
			(xy 84.002844 -273.570569) (xy 83.955312 -273.586013) (xy 83.905949 -273.593832) (xy 83.855971 -273.593832)
			(xy 83.806608 -273.586013) (xy 83.759076 -273.570569) (xy 83.714544 -273.547879) (xy 83.674111 -273.518503)
			(xy 83.638771 -273.483163) (xy 83.609395 -273.44273) (xy 83.586705 -273.398198) (xy 83.571261 -273.350666)
			(xy 83.563442 -273.301303) (xy 83.256125 -273.301303) (xy 83.256116 -273.30176) (xy 83.247952 -273.351994)
			(xy 83.231836 -273.400268) (xy 83.208185 -273.445331) (xy 83.177612 -273.486017) (xy 83.140908 -273.521272)
			(xy 83.099024 -273.550182) (xy 83.053045 -273.571999) (xy 83.004161 -273.586159) (xy 82.95364 -273.592293)
			(xy 82.902788 -273.590244) (xy 82.852924 -273.580064) (xy 82.805338 -273.562017) (xy 82.761264 -273.536571)
			(xy 82.721842 -273.504384) (xy 82.688094 -273.46629) (xy 82.660893 -273.423276) (xy 82.640945 -273.376456)
			(xy 82.628766 -273.327042) (xy 82.624671 -273.276314) (xy 82.319114 -273.276314) (xy 82.318624 -273.301303)
			(xy 82.310805 -273.350666) (xy 82.295361 -273.398198) (xy 82.272671 -273.44273) (xy 82.243295 -273.483163)
			(xy 82.207955 -273.518503) (xy 82.167522 -273.547879) (xy 82.12299 -273.570569) (xy 82.075458 -273.586013)
			(xy 82.026095 -273.593832) (xy 81.976117 -273.593832) (xy 81.926754 -273.586013) (xy 81.879222 -273.570569)
			(xy 81.83469 -273.547879) (xy 81.794257 -273.518503) (xy 81.758917 -273.483163) (xy 81.729541 -273.44273)
			(xy 81.706851 -273.398198) (xy 81.691407 -273.350666) (xy 81.683588 -273.301303) (xy 81.376271 -273.301303)
			(xy 81.376262 -273.30176) (xy 81.368098 -273.351994) (xy 81.351982 -273.400268) (xy 81.328331 -273.445331)
			(xy 81.297758 -273.486017) (xy 81.261054 -273.521272) (xy 81.21917 -273.550182) (xy 81.173191 -273.571999)
			(xy 81.124307 -273.586159) (xy 81.073786 -273.592293) (xy 81.022934 -273.590244) (xy 80.97307 -273.580064)
			(xy 80.925484 -273.562017) (xy 80.88141 -273.536571) (xy 80.841988 -273.504384) (xy 80.80824 -273.46629)
			(xy 80.781039 -273.423276) (xy 80.761091 -273.376456) (xy 80.748912 -273.327042) (xy 80.744817 -273.276314)
			(xy 79.53248 -273.276314) (xy 79.53248 -274.111309) (xy 80.273634 -274.111309) (xy 80.273634 -274.061331)
			(xy 80.281453 -274.011968) (xy 80.296897 -273.964436) (xy 80.319587 -273.919904) (xy 80.348963 -273.879471)
			(xy 80.384303 -273.844131) (xy 80.424736 -273.814755) (xy 80.469268 -273.792065) (xy 80.5168 -273.776621)
			(xy 80.566163 -273.768802) (xy 80.616141 -273.768802) (xy 80.665504 -273.776621) (xy 80.713036 -273.792065)
			(xy 80.757568 -273.814755) (xy 80.798001 -273.844131) (xy 80.833341 -273.879471) (xy 80.862717 -273.919904)
			(xy 80.885407 -273.964436) (xy 80.900851 -274.011968) (xy 80.90867 -274.061331) (xy 80.90916 -274.08632)
			(xy 81.214717 -274.08632) (xy 81.218812 -274.035592) (xy 81.230991 -273.986178) (xy 81.250939 -273.939358)
			(xy 81.27814 -273.896344) (xy 81.311888 -273.85825) (xy 81.35131 -273.826063) (xy 81.395384 -273.800617)
			(xy 81.44297 -273.78257) (xy 81.492834 -273.77239) (xy 81.543686 -273.770341) (xy 81.594207 -273.776475)
			(xy 81.643091 -273.790635) (xy 81.68907 -273.812452) (xy 81.730954 -273.841362) (xy 81.767658 -273.876617)
			(xy 81.798231 -273.917303) (xy 81.821882 -273.962366) (xy 81.837998 -274.01064) (xy 81.846162 -274.060874)
			(xy 81.846674 -274.08632) (xy 82.154771 -274.08632) (xy 82.158866 -274.035592) (xy 82.171045 -273.986178)
			(xy 82.190993 -273.939358) (xy 82.218194 -273.896344) (xy 82.251942 -273.85825) (xy 82.291364 -273.826063)
			(xy 82.335438 -273.800617) (xy 82.383024 -273.78257) (xy 82.432888 -273.77239) (xy 82.48374 -273.770341)
			(xy 82.534261 -273.776475) (xy 82.583145 -273.790635) (xy 82.629124 -273.812452) (xy 82.671008 -273.841362)
			(xy 82.707712 -273.876617) (xy 82.738285 -273.917303) (xy 82.761936 -273.962366) (xy 82.778052 -274.01064)
			(xy 82.786216 -274.060874) (xy 82.786728 -274.08632) (xy 82.786225 -274.111309) (xy 83.093542 -274.111309)
			(xy 83.093542 -274.061331) (xy 83.101361 -274.011968) (xy 83.116805 -273.964436) (xy 83.139495 -273.919904)
			(xy 83.168871 -273.879471) (xy 83.204211 -273.844131) (xy 83.244644 -273.814755) (xy 83.289176 -273.792065)
			(xy 83.336708 -273.776621) (xy 83.386071 -273.768802) (xy 83.436049 -273.768802) (xy 83.485412 -273.776621)
			(xy 83.532944 -273.792065) (xy 83.577476 -273.814755) (xy 83.617909 -273.844131) (xy 83.653249 -273.879471)
			(xy 83.682625 -273.919904) (xy 83.705315 -273.964436) (xy 83.720759 -274.011968) (xy 83.728578 -274.061331)
			(xy 83.729068 -274.08632) (xy 84.034879 -274.08632) (xy 84.038974 -274.035592) (xy 84.051153 -273.986178)
			(xy 84.071101 -273.939358) (xy 84.098302 -273.896344) (xy 84.13205 -273.85825) (xy 84.171472 -273.826063)
			(xy 84.215546 -273.800617) (xy 84.263132 -273.78257) (xy 84.312996 -273.77239) (xy 84.363848 -273.770341)
			(xy 84.414369 -273.776475) (xy 84.463253 -273.790635) (xy 84.509232 -273.812452) (xy 84.551116 -273.841362)
			(xy 84.58782 -273.876617) (xy 84.618393 -273.917303) (xy 84.642044 -273.962366) (xy 84.65816 -274.01064)
			(xy 84.666324 -274.060874) (xy 84.666836 -274.08632) (xy 84.666333 -274.111309) (xy 84.973396 -274.111309)
			(xy 84.973396 -274.061331) (xy 84.981215 -274.011968) (xy 84.996659 -273.964436) (xy 85.019349 -273.919904)
			(xy 85.048725 -273.879471) (xy 85.084065 -273.844131) (xy 85.124498 -273.814755) (xy 85.16903 -273.792065)
			(xy 85.216562 -273.776621) (xy 85.265925 -273.768802) (xy 85.315903 -273.768802) (xy 85.365266 -273.776621)
			(xy 85.412798 -273.792065) (xy 85.45733 -273.814755) (xy 85.497763 -273.844131) (xy 85.533103 -273.879471)
			(xy 85.562479 -273.919904) (xy 85.585169 -273.964436) (xy 85.600613 -274.011968) (xy 85.608432 -274.061331)
			(xy 85.608922 -274.08632) (xy 85.914733 -274.08632) (xy 85.918828 -274.035592) (xy 85.931007 -273.986178)
			(xy 85.950955 -273.939358) (xy 85.978156 -273.896344) (xy 86.011904 -273.85825) (xy 86.051326 -273.826063)
			(xy 86.0954 -273.800617) (xy 86.142986 -273.78257) (xy 86.19285 -273.77239) (xy 86.243702 -273.770341)
			(xy 86.294223 -273.776475) (xy 86.343107 -273.790635) (xy 86.389086 -273.812452) (xy 86.43097 -273.841362)
			(xy 86.467674 -273.876617) (xy 86.498247 -273.917303) (xy 86.521898 -273.962366) (xy 86.538014 -274.01064)
			(xy 86.546178 -274.060874) (xy 86.54669 -274.08632) (xy 86.546187 -274.111309) (xy 86.853504 -274.111309)
			(xy 86.853504 -274.061331) (xy 86.861323 -274.011968) (xy 86.876767 -273.964436) (xy 86.899457 -273.919904)
			(xy 86.928833 -273.879471) (xy 86.964173 -273.844131) (xy 87.004606 -273.814755) (xy 87.049138 -273.792065)
			(xy 87.09667 -273.776621) (xy 87.146033 -273.768802) (xy 87.196011 -273.768802) (xy 87.245374 -273.776621)
			(xy 87.292906 -273.792065) (xy 87.337438 -273.814755) (xy 87.377871 -273.844131) (xy 87.413211 -273.879471)
			(xy 87.442587 -273.919904) (xy 87.465277 -273.964436) (xy 87.480721 -274.011968) (xy 87.48854 -274.061331)
			(xy 87.48903 -274.08632) (xy 87.794841 -274.08632) (xy 87.798936 -274.035592) (xy 87.811115 -273.986178)
			(xy 87.831063 -273.939358) (xy 87.858264 -273.896344) (xy 87.892012 -273.85825) (xy 87.931434 -273.826063)
			(xy 87.975508 -273.800617) (xy 88.023094 -273.78257) (xy 88.072958 -273.77239) (xy 88.12381 -273.770341)
			(xy 88.174331 -273.776475) (xy 88.223215 -273.790635) (xy 88.269194 -273.812452) (xy 88.311078 -273.841362)
			(xy 88.347782 -273.876617) (xy 88.378355 -273.917303) (xy 88.402006 -273.962366) (xy 88.418122 -274.01064)
			(xy 88.426286 -274.060874) (xy 88.426798 -274.08632) (xy 88.734895 -274.08632) (xy 88.73899 -274.035592)
			(xy 88.751169 -273.986178) (xy 88.771117 -273.939358) (xy 88.798318 -273.896344) (xy 88.832066 -273.85825)
			(xy 88.871488 -273.826063) (xy 88.915562 -273.800617) (xy 88.963148 -273.78257) (xy 89.013012 -273.77239)
			(xy 89.063864 -273.770341) (xy 89.114385 -273.776475) (xy 89.163269 -273.790635) (xy 89.209248 -273.812452)
			(xy 89.251132 -273.841362) (xy 89.287836 -273.876617) (xy 89.318409 -273.917303) (xy 89.34206 -273.962366)
			(xy 89.358176 -274.01064) (xy 89.36634 -274.060874) (xy 89.366852 -274.08632) (xy 89.366349 -274.111309)
			(xy 89.673412 -274.111309) (xy 89.673412 -274.061331) (xy 89.681231 -274.011968) (xy 89.696675 -273.964436)
			(xy 89.719365 -273.919904) (xy 89.748741 -273.879471) (xy 89.784081 -273.844131) (xy 89.824514 -273.814755)
			(xy 89.869046 -273.792065) (xy 89.916578 -273.776621) (xy 89.965941 -273.768802) (xy 90.015919 -273.768802)
			(xy 90.065282 -273.776621) (xy 90.112814 -273.792065) (xy 90.157346 -273.814755) (xy 90.197779 -273.844131)
			(xy 90.233119 -273.879471) (xy 90.262495 -273.919904) (xy 90.285185 -273.964436) (xy 90.300629 -274.011968)
			(xy 90.308448 -274.061331) (xy 90.308938 -274.08632) (xy 90.614749 -274.08632) (xy 90.618844 -274.035592)
			(xy 90.631023 -273.986178) (xy 90.650971 -273.939358) (xy 90.678172 -273.896344) (xy 90.71192 -273.85825)
			(xy 90.751342 -273.826063) (xy 90.795416 -273.800617) (xy 90.843002 -273.78257) (xy 90.892866 -273.77239)
			(xy 90.943718 -273.770341) (xy 90.994239 -273.776475) (xy 91.043123 -273.790635) (xy 91.089102 -273.812452)
			(xy 91.130986 -273.841362) (xy 91.16769 -273.876617) (xy 91.198263 -273.917303) (xy 91.221914 -273.962366)
			(xy 91.23803 -274.01064) (xy 91.246194 -274.060874) (xy 91.246706 -274.08632) (xy 91.246203 -274.111309)
			(xy 91.55352 -274.111309) (xy 91.55352 -274.061331) (xy 91.561339 -274.011968) (xy 91.576783 -273.964436)
			(xy 91.599473 -273.919904) (xy 91.628849 -273.879471) (xy 91.664189 -273.844131) (xy 91.704622 -273.814755)
			(xy 91.749154 -273.792065) (xy 91.796686 -273.776621) (xy 91.846049 -273.768802) (xy 91.896027 -273.768802)
			(xy 91.94539 -273.776621) (xy 91.992922 -273.792065) (xy 92.037454 -273.814755) (xy 92.077887 -273.844131)
			(xy 92.113227 -273.879471) (xy 92.142603 -273.919904) (xy 92.165293 -273.964436) (xy 92.180737 -274.011968)
			(xy 92.188556 -274.061331) (xy 92.189046 -274.08632) (xy 92.494857 -274.08632) (xy 92.498952 -274.035592)
			(xy 92.511131 -273.986178) (xy 92.531079 -273.939358) (xy 92.55828 -273.896344) (xy 92.592028 -273.85825)
			(xy 92.63145 -273.826063) (xy 92.675524 -273.800617) (xy 92.72311 -273.78257) (xy 92.772974 -273.77239)
			(xy 92.823826 -273.770341) (xy 92.874347 -273.776475) (xy 92.923231 -273.790635) (xy 92.96921 -273.812452)
			(xy 93.011094 -273.841362) (xy 93.047798 -273.876617) (xy 93.078371 -273.917303) (xy 93.102022 -273.962366)
			(xy 93.118138 -274.01064) (xy 93.126302 -274.060874) (xy 93.126814 -274.08632) (xy 93.126302 -274.111766)
			(xy 93.118138 -274.162) (xy 93.102022 -274.210274) (xy 93.078371 -274.255337) (xy 93.047798 -274.296023)
			(xy 93.011094 -274.331278) (xy 92.96921 -274.360188) (xy 92.923231 -274.382005) (xy 92.874347 -274.396165)
			(xy 92.823826 -274.402299) (xy 92.772974 -274.40025) (xy 92.72311 -274.39007) (xy 92.675524 -274.372023)
			(xy 92.63145 -274.346577) (xy 92.592028 -274.31439) (xy 92.55828 -274.276296) (xy 92.531079 -274.233282)
			(xy 92.511131 -274.186462) (xy 92.498952 -274.137048) (xy 92.494857 -274.08632) (xy 92.189046 -274.08632)
			(xy 92.188556 -274.111309) (xy 92.180737 -274.160672) (xy 92.165293 -274.208204) (xy 92.142603 -274.252736)
			(xy 92.113227 -274.293169) (xy 92.077887 -274.328509) (xy 92.037454 -274.357885) (xy 91.992922 -274.380575)
			(xy 91.94539 -274.396019) (xy 91.896027 -274.403838) (xy 91.846049 -274.403838) (xy 91.796686 -274.396019)
			(xy 91.749154 -274.380575) (xy 91.704622 -274.357885) (xy 91.664189 -274.328509) (xy 91.628849 -274.293169)
			(xy 91.599473 -274.252736) (xy 91.576783 -274.208204) (xy 91.561339 -274.160672) (xy 91.55352 -274.111309)
			(xy 91.246203 -274.111309) (xy 91.246194 -274.111766) (xy 91.23803 -274.162) (xy 91.221914 -274.210274)
			(xy 91.198263 -274.255337) (xy 91.16769 -274.296023) (xy 91.130986 -274.331278) (xy 91.089102 -274.360188)
			(xy 91.043123 -274.382005) (xy 90.994239 -274.396165) (xy 90.943718 -274.402299) (xy 90.892866 -274.40025)
			(xy 90.843002 -274.39007) (xy 90.795416 -274.372023) (xy 90.751342 -274.346577) (xy 90.71192 -274.31439)
			(xy 90.678172 -274.276296) (xy 90.650971 -274.233282) (xy 90.631023 -274.186462) (xy 90.618844 -274.137048)
			(xy 90.614749 -274.08632) (xy 90.308938 -274.08632) (xy 90.308448 -274.111309) (xy 90.300629 -274.160672)
			(xy 90.285185 -274.208204) (xy 90.262495 -274.252736) (xy 90.233119 -274.293169) (xy 90.197779 -274.328509)
			(xy 90.157346 -274.357885) (xy 90.112814 -274.380575) (xy 90.065282 -274.396019) (xy 90.015919 -274.403838)
			(xy 89.965941 -274.403838) (xy 89.916578 -274.396019) (xy 89.869046 -274.380575) (xy 89.824514 -274.357885)
			(xy 89.784081 -274.328509) (xy 89.748741 -274.293169) (xy 89.719365 -274.252736) (xy 89.696675 -274.208204)
			(xy 89.681231 -274.160672) (xy 89.673412 -274.111309) (xy 89.366349 -274.111309) (xy 89.36634 -274.111766)
			(xy 89.358176 -274.162) (xy 89.34206 -274.210274) (xy 89.318409 -274.255337) (xy 89.287836 -274.296023)
			(xy 89.251132 -274.331278) (xy 89.209248 -274.360188) (xy 89.163269 -274.382005) (xy 89.114385 -274.396165)
			(xy 89.063864 -274.402299) (xy 89.013012 -274.40025) (xy 88.963148 -274.39007) (xy 88.915562 -274.372023)
			(xy 88.871488 -274.346577) (xy 88.832066 -274.31439) (xy 88.798318 -274.276296) (xy 88.771117 -274.233282)
			(xy 88.751169 -274.186462) (xy 88.73899 -274.137048) (xy 88.734895 -274.08632) (xy 88.426798 -274.08632)
			(xy 88.426286 -274.111766) (xy 88.418122 -274.162) (xy 88.402006 -274.210274) (xy 88.378355 -274.255337)
			(xy 88.347782 -274.296023) (xy 88.311078 -274.331278) (xy 88.269194 -274.360188) (xy 88.223215 -274.382005)
			(xy 88.174331 -274.396165) (xy 88.12381 -274.402299) (xy 88.072958 -274.40025) (xy 88.023094 -274.39007)
			(xy 87.975508 -274.372023) (xy 87.931434 -274.346577) (xy 87.892012 -274.31439) (xy 87.858264 -274.276296)
			(xy 87.831063 -274.233282) (xy 87.811115 -274.186462) (xy 87.798936 -274.137048) (xy 87.794841 -274.08632)
			(xy 87.48903 -274.08632) (xy 87.48854 -274.111309) (xy 87.480721 -274.160672) (xy 87.465277 -274.208204)
			(xy 87.442587 -274.252736) (xy 87.413211 -274.293169) (xy 87.377871 -274.328509) (xy 87.337438 -274.357885)
			(xy 87.292906 -274.380575) (xy 87.245374 -274.396019) (xy 87.196011 -274.403838) (xy 87.146033 -274.403838)
			(xy 87.09667 -274.396019) (xy 87.049138 -274.380575) (xy 87.004606 -274.357885) (xy 86.964173 -274.328509)
			(xy 86.928833 -274.293169) (xy 86.899457 -274.252736) (xy 86.876767 -274.208204) (xy 86.861323 -274.160672)
			(xy 86.853504 -274.111309) (xy 86.546187 -274.111309) (xy 86.546178 -274.111766) (xy 86.538014 -274.162)
			(xy 86.521898 -274.210274) (xy 86.498247 -274.255337) (xy 86.467674 -274.296023) (xy 86.43097 -274.331278)
			(xy 86.389086 -274.360188) (xy 86.343107 -274.382005) (xy 86.294223 -274.396165) (xy 86.243702 -274.402299)
			(xy 86.19285 -274.40025) (xy 86.142986 -274.39007) (xy 86.0954 -274.372023) (xy 86.051326 -274.346577)
			(xy 86.011904 -274.31439) (xy 85.978156 -274.276296) (xy 85.950955 -274.233282) (xy 85.931007 -274.186462)
			(xy 85.918828 -274.137048) (xy 85.914733 -274.08632) (xy 85.608922 -274.08632) (xy 85.608432 -274.111309)
			(xy 85.600613 -274.160672) (xy 85.585169 -274.208204) (xy 85.562479 -274.252736) (xy 85.533103 -274.293169)
			(xy 85.497763 -274.328509) (xy 85.45733 -274.357885) (xy 85.412798 -274.380575) (xy 85.365266 -274.396019)
			(xy 85.315903 -274.403838) (xy 85.265925 -274.403838) (xy 85.216562 -274.396019) (xy 85.16903 -274.380575)
			(xy 85.124498 -274.357885) (xy 85.084065 -274.328509) (xy 85.048725 -274.293169) (xy 85.019349 -274.252736)
			(xy 84.996659 -274.208204) (xy 84.981215 -274.160672) (xy 84.973396 -274.111309) (xy 84.666333 -274.111309)
			(xy 84.666324 -274.111766) (xy 84.65816 -274.162) (xy 84.642044 -274.210274) (xy 84.618393 -274.255337)
			(xy 84.58782 -274.296023) (xy 84.551116 -274.331278) (xy 84.509232 -274.360188) (xy 84.463253 -274.382005)
			(xy 84.414369 -274.396165) (xy 84.363848 -274.402299) (xy 84.312996 -274.40025) (xy 84.263132 -274.39007)
			(xy 84.215546 -274.372023) (xy 84.171472 -274.346577) (xy 84.13205 -274.31439) (xy 84.098302 -274.276296)
			(xy 84.071101 -274.233282) (xy 84.051153 -274.186462) (xy 84.038974 -274.137048) (xy 84.034879 -274.08632)
			(xy 83.729068 -274.08632) (xy 83.728578 -274.111309) (xy 83.720759 -274.160672) (xy 83.705315 -274.208204)
			(xy 83.682625 -274.252736) (xy 83.653249 -274.293169) (xy 83.617909 -274.328509) (xy 83.577476 -274.357885)
			(xy 83.532944 -274.380575) (xy 83.485412 -274.396019) (xy 83.436049 -274.403838) (xy 83.386071 -274.403838)
			(xy 83.336708 -274.396019) (xy 83.289176 -274.380575) (xy 83.244644 -274.357885) (xy 83.204211 -274.328509)
			(xy 83.168871 -274.293169) (xy 83.139495 -274.252736) (xy 83.116805 -274.208204) (xy 83.101361 -274.160672)
			(xy 83.093542 -274.111309) (xy 82.786225 -274.111309) (xy 82.786216 -274.111766) (xy 82.778052 -274.162)
			(xy 82.761936 -274.210274) (xy 82.738285 -274.255337) (xy 82.707712 -274.296023) (xy 82.671008 -274.331278)
			(xy 82.629124 -274.360188) (xy 82.583145 -274.382005) (xy 82.534261 -274.396165) (xy 82.48374 -274.402299)
			(xy 82.432888 -274.40025) (xy 82.383024 -274.39007) (xy 82.335438 -274.372023) (xy 82.291364 -274.346577)
			(xy 82.251942 -274.31439) (xy 82.218194 -274.276296) (xy 82.190993 -274.233282) (xy 82.171045 -274.186462)
			(xy 82.158866 -274.137048) (xy 82.154771 -274.08632) (xy 81.846674 -274.08632) (xy 81.846162 -274.111766)
			(xy 81.837998 -274.162) (xy 81.821882 -274.210274) (xy 81.798231 -274.255337) (xy 81.767658 -274.296023)
			(xy 81.730954 -274.331278) (xy 81.68907 -274.360188) (xy 81.643091 -274.382005) (xy 81.594207 -274.396165)
			(xy 81.543686 -274.402299) (xy 81.492834 -274.40025) (xy 81.44297 -274.39007) (xy 81.395384 -274.372023)
			(xy 81.35131 -274.346577) (xy 81.311888 -274.31439) (xy 81.27814 -274.276296) (xy 81.250939 -274.233282)
			(xy 81.230991 -274.186462) (xy 81.218812 -274.137048) (xy 81.214717 -274.08632) (xy 80.90916 -274.08632)
			(xy 80.90867 -274.111309) (xy 80.900851 -274.160672) (xy 80.885407 -274.208204) (xy 80.862717 -274.252736)
			(xy 80.833341 -274.293169) (xy 80.798001 -274.328509) (xy 80.757568 -274.357885) (xy 80.713036 -274.380575)
			(xy 80.665504 -274.396019) (xy 80.616141 -274.403838) (xy 80.566163 -274.403838) (xy 80.5168 -274.396019)
			(xy 80.469268 -274.380575) (xy 80.424736 -274.357885) (xy 80.384303 -274.328509) (xy 80.348963 -274.293169)
			(xy 80.319587 -274.252736) (xy 80.296897 -274.208204) (xy 80.281453 -274.160672) (xy 80.273634 -274.111309)
			(xy 79.53248 -274.111309) (xy 79.53248 -274.921315) (xy 79.80348 -274.921315) (xy 79.80348 -274.871337)
			(xy 79.811299 -274.821974) (xy 79.826743 -274.774442) (xy 79.849433 -274.72991) (xy 79.878809 -274.689477)
			(xy 79.914149 -274.654137) (xy 79.954582 -274.624761) (xy 79.999114 -274.602071) (xy 80.046646 -274.586627)
			(xy 80.096009 -274.578808) (xy 80.145987 -274.578808) (xy 80.19535 -274.586627) (xy 80.242882 -274.602071)
			(xy 80.287414 -274.624761) (xy 80.327847 -274.654137) (xy 80.363187 -274.689477) (xy 80.392563 -274.72991)
			(xy 80.415253 -274.774442) (xy 80.430697 -274.821974) (xy 80.438516 -274.871337) (xy 80.439006 -274.896326)
			(xy 80.744817 -274.896326) (xy 80.748912 -274.845598) (xy 80.761091 -274.796184) (xy 80.781039 -274.749364)
			(xy 80.80824 -274.70635) (xy 80.841988 -274.668256) (xy 80.88141 -274.636069) (xy 80.925484 -274.610623)
			(xy 80.97307 -274.592576) (xy 81.022934 -274.582396) (xy 81.073786 -274.580347) (xy 81.124307 -274.586481)
			(xy 81.173191 -274.600641) (xy 81.21917 -274.622458) (xy 81.261054 -274.651368) (xy 81.297758 -274.686623)
			(xy 81.328331 -274.727309) (xy 81.351982 -274.772372) (xy 81.368098 -274.820646) (xy 81.376262 -274.87088)
			(xy 81.376774 -274.896326) (xy 81.376271 -274.921315) (xy 81.683588 -274.921315) (xy 81.683588 -274.871337)
			(xy 81.691407 -274.821974) (xy 81.706851 -274.774442) (xy 81.729541 -274.72991) (xy 81.758917 -274.689477)
			(xy 81.794257 -274.654137) (xy 81.83469 -274.624761) (xy 81.879222 -274.602071) (xy 81.926754 -274.586627)
			(xy 81.976117 -274.578808) (xy 82.026095 -274.578808) (xy 82.075458 -274.586627) (xy 82.12299 -274.602071)
			(xy 82.167522 -274.624761) (xy 82.207955 -274.654137) (xy 82.243295 -274.689477) (xy 82.272671 -274.72991)
			(xy 82.295361 -274.774442) (xy 82.310805 -274.821974) (xy 82.318624 -274.871337) (xy 82.319114 -274.896326)
			(xy 82.624671 -274.896326) (xy 82.628766 -274.845598) (xy 82.640945 -274.796184) (xy 82.660893 -274.749364)
			(xy 82.688094 -274.70635) (xy 82.721842 -274.668256) (xy 82.761264 -274.636069) (xy 82.805338 -274.610623)
			(xy 82.852924 -274.592576) (xy 82.902788 -274.582396) (xy 82.95364 -274.580347) (xy 83.004161 -274.586481)
			(xy 83.053045 -274.600641) (xy 83.099024 -274.622458) (xy 83.140908 -274.651368) (xy 83.177612 -274.686623)
			(xy 83.208185 -274.727309) (xy 83.231836 -274.772372) (xy 83.247952 -274.820646) (xy 83.256116 -274.87088)
			(xy 83.256628 -274.896326) (xy 83.256125 -274.921315) (xy 83.563442 -274.921315) (xy 83.563442 -274.871337)
			(xy 83.571261 -274.821974) (xy 83.586705 -274.774442) (xy 83.609395 -274.72991) (xy 83.638771 -274.689477)
			(xy 83.674111 -274.654137) (xy 83.714544 -274.624761) (xy 83.759076 -274.602071) (xy 83.806608 -274.586627)
			(xy 83.855971 -274.578808) (xy 83.905949 -274.578808) (xy 83.955312 -274.586627) (xy 84.002844 -274.602071)
			(xy 84.047376 -274.624761) (xy 84.087809 -274.654137) (xy 84.123149 -274.689477) (xy 84.152525 -274.72991)
			(xy 84.175215 -274.774442) (xy 84.190659 -274.821974) (xy 84.198478 -274.871337) (xy 84.198968 -274.896326)
			(xy 84.504779 -274.896326) (xy 84.508874 -274.845598) (xy 84.521053 -274.796184) (xy 84.541001 -274.749364)
			(xy 84.568202 -274.70635) (xy 84.60195 -274.668256) (xy 84.641372 -274.636069) (xy 84.685446 -274.610623)
			(xy 84.733032 -274.592576) (xy 84.782896 -274.582396) (xy 84.833748 -274.580347) (xy 84.884269 -274.586481)
			(xy 84.933153 -274.600641) (xy 84.979132 -274.622458) (xy 85.021016 -274.651368) (xy 85.05772 -274.686623)
			(xy 85.088293 -274.727309) (xy 85.111944 -274.772372) (xy 85.12806 -274.820646) (xy 85.136224 -274.87088)
			(xy 85.136736 -274.896326) (xy 85.444833 -274.896326) (xy 85.448928 -274.845598) (xy 85.461107 -274.796184)
			(xy 85.481055 -274.749364) (xy 85.508256 -274.70635) (xy 85.542004 -274.668256) (xy 85.581426 -274.636069)
			(xy 85.6255 -274.610623) (xy 85.673086 -274.592576) (xy 85.72295 -274.582396) (xy 85.773802 -274.580347)
			(xy 85.824323 -274.586481) (xy 85.873207 -274.600641) (xy 85.919186 -274.622458) (xy 85.96107 -274.651368)
			(xy 85.997774 -274.686623) (xy 86.028347 -274.727309) (xy 86.051998 -274.772372) (xy 86.068114 -274.820646)
			(xy 86.076278 -274.87088) (xy 86.07679 -274.896326) (xy 86.076287 -274.921315) (xy 86.383604 -274.921315)
			(xy 86.383604 -274.871337) (xy 86.391423 -274.821974) (xy 86.406867 -274.774442) (xy 86.429557 -274.72991)
			(xy 86.458933 -274.689477) (xy 86.494273 -274.654137) (xy 86.534706 -274.624761) (xy 86.579238 -274.602071)
			(xy 86.62677 -274.586627) (xy 86.676133 -274.578808) (xy 86.726111 -274.578808) (xy 86.775474 -274.586627)
			(xy 86.823006 -274.602071) (xy 86.867538 -274.624761) (xy 86.907971 -274.654137) (xy 86.943311 -274.689477)
			(xy 86.972687 -274.72991) (xy 86.995377 -274.774442) (xy 87.010821 -274.821974) (xy 87.01864 -274.871337)
			(xy 87.01913 -274.896326) (xy 87.324687 -274.896326) (xy 87.328782 -274.845598) (xy 87.340961 -274.796184)
			(xy 87.360909 -274.749364) (xy 87.38811 -274.70635) (xy 87.421858 -274.668256) (xy 87.46128 -274.636069)
			(xy 87.505354 -274.610623) (xy 87.55294 -274.592576) (xy 87.602804 -274.582396) (xy 87.653656 -274.580347)
			(xy 87.704177 -274.586481) (xy 87.753061 -274.600641) (xy 87.79904 -274.622458) (xy 87.840924 -274.651368)
			(xy 87.877628 -274.686623) (xy 87.908201 -274.727309) (xy 87.931852 -274.772372) (xy 87.947968 -274.820646)
			(xy 87.956132 -274.87088) (xy 87.956644 -274.896326) (xy 87.956141 -274.921315) (xy 88.263458 -274.921315)
			(xy 88.263458 -274.871337) (xy 88.271277 -274.821974) (xy 88.286721 -274.774442) (xy 88.309411 -274.72991)
			(xy 88.338787 -274.689477) (xy 88.374127 -274.654137) (xy 88.41456 -274.624761) (xy 88.459092 -274.602071)
			(xy 88.506624 -274.586627) (xy 88.555987 -274.578808) (xy 88.605965 -274.578808) (xy 88.655328 -274.586627)
			(xy 88.70286 -274.602071) (xy 88.747392 -274.624761) (xy 88.787825 -274.654137) (xy 88.823165 -274.689477)
			(xy 88.852541 -274.72991) (xy 88.875231 -274.774442) (xy 88.890675 -274.821974) (xy 88.898494 -274.871337)
			(xy 88.898984 -274.896326) (xy 89.204795 -274.896326) (xy 89.20889 -274.845598) (xy 89.221069 -274.796184)
			(xy 89.241017 -274.749364) (xy 89.268218 -274.70635) (xy 89.301966 -274.668256) (xy 89.341388 -274.636069)
			(xy 89.385462 -274.610623) (xy 89.433048 -274.592576) (xy 89.482912 -274.582396) (xy 89.533764 -274.580347)
			(xy 89.584285 -274.586481) (xy 89.633169 -274.600641) (xy 89.679148 -274.622458) (xy 89.721032 -274.651368)
			(xy 89.757736 -274.686623) (xy 89.788309 -274.727309) (xy 89.81196 -274.772372) (xy 89.828076 -274.820646)
			(xy 89.83624 -274.87088) (xy 89.836752 -274.896326) (xy 89.836249 -274.921315) (xy 90.143566 -274.921315)
			(xy 90.143566 -274.871337) (xy 90.151385 -274.821974) (xy 90.166829 -274.774442) (xy 90.189519 -274.72991)
			(xy 90.218895 -274.689477) (xy 90.254235 -274.654137) (xy 90.294668 -274.624761) (xy 90.3392 -274.602071)
			(xy 90.386732 -274.586627) (xy 90.436095 -274.578808) (xy 90.486073 -274.578808) (xy 90.535436 -274.586627)
			(xy 90.582968 -274.602071) (xy 90.6275 -274.624761) (xy 90.667933 -274.654137) (xy 90.703273 -274.689477)
			(xy 90.732649 -274.72991) (xy 90.755339 -274.774442) (xy 90.770783 -274.821974) (xy 90.778602 -274.871337)
			(xy 90.779092 -274.896326) (xy 91.084903 -274.896326) (xy 91.088998 -274.845598) (xy 91.101177 -274.796184)
			(xy 91.121125 -274.749364) (xy 91.148326 -274.70635) (xy 91.182074 -274.668256) (xy 91.221496 -274.636069)
			(xy 91.26557 -274.610623) (xy 91.313156 -274.592576) (xy 91.36302 -274.582396) (xy 91.413872 -274.580347)
			(xy 91.464393 -274.586481) (xy 91.513277 -274.600641) (xy 91.559256 -274.622458) (xy 91.60114 -274.651368)
			(xy 91.637844 -274.686623) (xy 91.668417 -274.727309) (xy 91.692068 -274.772372) (xy 91.708184 -274.820646)
			(xy 91.716348 -274.87088) (xy 91.71686 -274.896326) (xy 92.024703 -274.896326) (xy 92.028798 -274.845598)
			(xy 92.040977 -274.796184) (xy 92.060925 -274.749364) (xy 92.088126 -274.70635) (xy 92.121874 -274.668256)
			(xy 92.161296 -274.636069) (xy 92.20537 -274.610623) (xy 92.252956 -274.592576) (xy 92.30282 -274.582396)
			(xy 92.353672 -274.580347) (xy 92.404193 -274.586481) (xy 92.453077 -274.600641) (xy 92.499056 -274.622458)
			(xy 92.54094 -274.651368) (xy 92.577644 -274.686623) (xy 92.608217 -274.727309) (xy 92.631868 -274.772372)
			(xy 92.647984 -274.820646) (xy 92.656148 -274.87088) (xy 92.65666 -274.896326) (xy 92.656148 -274.921772)
			(xy 92.647984 -274.972006) (xy 92.631868 -275.02028) (xy 92.608217 -275.065343) (xy 92.577644 -275.106029)
			(xy 92.54094 -275.141284) (xy 92.499056 -275.170194) (xy 92.453077 -275.192011) (xy 92.404193 -275.206171)
			(xy 92.353672 -275.212305) (xy 92.30282 -275.210256) (xy 92.252956 -275.200076) (xy 92.20537 -275.182029)
			(xy 92.161296 -275.156583) (xy 92.121874 -275.124396) (xy 92.088126 -275.086302) (xy 92.060925 -275.043288)
			(xy 92.040977 -274.996468) (xy 92.028798 -274.947054) (xy 92.024703 -274.896326) (xy 91.71686 -274.896326)
			(xy 91.716348 -274.921772) (xy 91.708184 -274.972006) (xy 91.692068 -275.02028) (xy 91.668417 -275.065343)
			(xy 91.637844 -275.106029) (xy 91.60114 -275.141284) (xy 91.559256 -275.170194) (xy 91.513277 -275.192011)
			(xy 91.464393 -275.206171) (xy 91.413872 -275.212305) (xy 91.36302 -275.210256) (xy 91.313156 -275.200076)
			(xy 91.26557 -275.182029) (xy 91.221496 -275.156583) (xy 91.182074 -275.124396) (xy 91.148326 -275.086302)
			(xy 91.121125 -275.043288) (xy 91.101177 -274.996468) (xy 91.088998 -274.947054) (xy 91.084903 -274.896326)
			(xy 90.779092 -274.896326) (xy 90.778602 -274.921315) (xy 90.770783 -274.970678) (xy 90.755339 -275.01821)
			(xy 90.732649 -275.062742) (xy 90.703273 -275.103175) (xy 90.667933 -275.138515) (xy 90.6275 -275.167891)
			(xy 90.582968 -275.190581) (xy 90.535436 -275.206025) (xy 90.486073 -275.213844) (xy 90.436095 -275.213844)
			(xy 90.386732 -275.206025) (xy 90.3392 -275.190581) (xy 90.294668 -275.167891) (xy 90.254235 -275.138515)
			(xy 90.218895 -275.103175) (xy 90.189519 -275.062742) (xy 90.166829 -275.01821) (xy 90.151385 -274.970678)
			(xy 90.143566 -274.921315) (xy 89.836249 -274.921315) (xy 89.83624 -274.921772) (xy 89.828076 -274.972006)
			(xy 89.81196 -275.02028) (xy 89.788309 -275.065343) (xy 89.757736 -275.106029) (xy 89.721032 -275.141284)
			(xy 89.679148 -275.170194) (xy 89.633169 -275.192011) (xy 89.584285 -275.206171) (xy 89.533764 -275.212305)
			(xy 89.482912 -275.210256) (xy 89.433048 -275.200076) (xy 89.385462 -275.182029) (xy 89.341388 -275.156583)
			(xy 89.301966 -275.124396) (xy 89.268218 -275.086302) (xy 89.241017 -275.043288) (xy 89.221069 -274.996468)
			(xy 89.20889 -274.947054) (xy 89.204795 -274.896326) (xy 88.898984 -274.896326) (xy 88.898494 -274.921315)
			(xy 88.890675 -274.970678) (xy 88.875231 -275.01821) (xy 88.852541 -275.062742) (xy 88.823165 -275.103175)
			(xy 88.787825 -275.138515) (xy 88.747392 -275.167891) (xy 88.70286 -275.190581) (xy 88.655328 -275.206025)
			(xy 88.605965 -275.213844) (xy 88.555987 -275.213844) (xy 88.506624 -275.206025) (xy 88.459092 -275.190581)
			(xy 88.41456 -275.167891) (xy 88.374127 -275.138515) (xy 88.338787 -275.103175) (xy 88.309411 -275.062742)
			(xy 88.286721 -275.01821) (xy 88.271277 -274.970678) (xy 88.263458 -274.921315) (xy 87.956141 -274.921315)
			(xy 87.956132 -274.921772) (xy 87.947968 -274.972006) (xy 87.931852 -275.02028) (xy 87.908201 -275.065343)
			(xy 87.877628 -275.106029) (xy 87.840924 -275.141284) (xy 87.79904 -275.170194) (xy 87.753061 -275.192011)
			(xy 87.704177 -275.206171) (xy 87.653656 -275.212305) (xy 87.602804 -275.210256) (xy 87.55294 -275.200076)
			(xy 87.505354 -275.182029) (xy 87.46128 -275.156583) (xy 87.421858 -275.124396) (xy 87.38811 -275.086302)
			(xy 87.360909 -275.043288) (xy 87.340961 -274.996468) (xy 87.328782 -274.947054) (xy 87.324687 -274.896326)
			(xy 87.01913 -274.896326) (xy 87.01864 -274.921315) (xy 87.010821 -274.970678) (xy 86.995377 -275.01821)
			(xy 86.972687 -275.062742) (xy 86.943311 -275.103175) (xy 86.907971 -275.138515) (xy 86.867538 -275.167891)
			(xy 86.823006 -275.190581) (xy 86.775474 -275.206025) (xy 86.726111 -275.213844) (xy 86.676133 -275.213844)
			(xy 86.62677 -275.206025) (xy 86.579238 -275.190581) (xy 86.534706 -275.167891) (xy 86.494273 -275.138515)
			(xy 86.458933 -275.103175) (xy 86.429557 -275.062742) (xy 86.406867 -275.01821) (xy 86.391423 -274.970678)
			(xy 86.383604 -274.921315) (xy 86.076287 -274.921315) (xy 86.076278 -274.921772) (xy 86.068114 -274.972006)
			(xy 86.051998 -275.02028) (xy 86.028347 -275.065343) (xy 85.997774 -275.106029) (xy 85.96107 -275.141284)
			(xy 85.919186 -275.170194) (xy 85.873207 -275.192011) (xy 85.824323 -275.206171) (xy 85.773802 -275.212305)
			(xy 85.72295 -275.210256) (xy 85.673086 -275.200076) (xy 85.6255 -275.182029) (xy 85.581426 -275.156583)
			(xy 85.542004 -275.124396) (xy 85.508256 -275.086302) (xy 85.481055 -275.043288) (xy 85.461107 -274.996468)
			(xy 85.448928 -274.947054) (xy 85.444833 -274.896326) (xy 85.136736 -274.896326) (xy 85.136224 -274.921772)
			(xy 85.12806 -274.972006) (xy 85.111944 -275.02028) (xy 85.088293 -275.065343) (xy 85.05772 -275.106029)
			(xy 85.021016 -275.141284) (xy 84.979132 -275.170194) (xy 84.933153 -275.192011) (xy 84.884269 -275.206171)
			(xy 84.833748 -275.212305) (xy 84.782896 -275.210256) (xy 84.733032 -275.200076) (xy 84.685446 -275.182029)
			(xy 84.641372 -275.156583) (xy 84.60195 -275.124396) (xy 84.568202 -275.086302) (xy 84.541001 -275.043288)
			(xy 84.521053 -274.996468) (xy 84.508874 -274.947054) (xy 84.504779 -274.896326) (xy 84.198968 -274.896326)
			(xy 84.198478 -274.921315) (xy 84.190659 -274.970678) (xy 84.175215 -275.01821) (xy 84.152525 -275.062742)
			(xy 84.123149 -275.103175) (xy 84.087809 -275.138515) (xy 84.047376 -275.167891) (xy 84.002844 -275.190581)
			(xy 83.955312 -275.206025) (xy 83.905949 -275.213844) (xy 83.855971 -275.213844) (xy 83.806608 -275.206025)
			(xy 83.759076 -275.190581) (xy 83.714544 -275.167891) (xy 83.674111 -275.138515) (xy 83.638771 -275.103175)
			(xy 83.609395 -275.062742) (xy 83.586705 -275.01821) (xy 83.571261 -274.970678) (xy 83.563442 -274.921315)
			(xy 83.256125 -274.921315) (xy 83.256116 -274.921772) (xy 83.247952 -274.972006) (xy 83.231836 -275.02028)
			(xy 83.208185 -275.065343) (xy 83.177612 -275.106029) (xy 83.140908 -275.141284) (xy 83.099024 -275.170194)
			(xy 83.053045 -275.192011) (xy 83.004161 -275.206171) (xy 82.95364 -275.212305) (xy 82.902788 -275.210256)
			(xy 82.852924 -275.200076) (xy 82.805338 -275.182029) (xy 82.761264 -275.156583) (xy 82.721842 -275.124396)
			(xy 82.688094 -275.086302) (xy 82.660893 -275.043288) (xy 82.640945 -274.996468) (xy 82.628766 -274.947054)
			(xy 82.624671 -274.896326) (xy 82.319114 -274.896326) (xy 82.318624 -274.921315) (xy 82.310805 -274.970678)
			(xy 82.295361 -275.01821) (xy 82.272671 -275.062742) (xy 82.243295 -275.103175) (xy 82.207955 -275.138515)
			(xy 82.167522 -275.167891) (xy 82.12299 -275.190581) (xy 82.075458 -275.206025) (xy 82.026095 -275.213844)
			(xy 81.976117 -275.213844) (xy 81.926754 -275.206025) (xy 81.879222 -275.190581) (xy 81.83469 -275.167891)
			(xy 81.794257 -275.138515) (xy 81.758917 -275.103175) (xy 81.729541 -275.062742) (xy 81.706851 -275.01821)
			(xy 81.691407 -274.970678) (xy 81.683588 -274.921315) (xy 81.376271 -274.921315) (xy 81.376262 -274.921772)
			(xy 81.368098 -274.972006) (xy 81.351982 -275.02028) (xy 81.328331 -275.065343) (xy 81.297758 -275.106029)
			(xy 81.261054 -275.141284) (xy 81.21917 -275.170194) (xy 81.173191 -275.192011) (xy 81.124307 -275.206171)
			(xy 81.073786 -275.212305) (xy 81.022934 -275.210256) (xy 80.97307 -275.200076) (xy 80.925484 -275.182029)
			(xy 80.88141 -275.156583) (xy 80.841988 -275.124396) (xy 80.80824 -275.086302) (xy 80.781039 -275.043288)
			(xy 80.761091 -274.996468) (xy 80.748912 -274.947054) (xy 80.744817 -274.896326) (xy 80.439006 -274.896326)
			(xy 80.438516 -274.921315) (xy 80.430697 -274.970678) (xy 80.415253 -275.01821) (xy 80.392563 -275.062742)
			(xy 80.363187 -275.103175) (xy 80.327847 -275.138515) (xy 80.287414 -275.167891) (xy 80.242882 -275.190581)
			(xy 80.19535 -275.206025) (xy 80.145987 -275.213844) (xy 80.096009 -275.213844) (xy 80.046646 -275.206025)
			(xy 79.999114 -275.190581) (xy 79.954582 -275.167891) (xy 79.914149 -275.138515) (xy 79.878809 -275.103175)
			(xy 79.849433 -275.062742) (xy 79.826743 -275.01821) (xy 79.811299 -274.970678) (xy 79.80348 -274.921315)
			(xy 79.53248 -274.921315) (xy 79.53248 -275.706332) (xy 81.214717 -275.706332) (xy 81.218812 -275.655604)
			(xy 81.230991 -275.60619) (xy 81.250939 -275.55937) (xy 81.27814 -275.516356) (xy 81.311888 -275.478262)
			(xy 81.35131 -275.446075) (xy 81.395384 -275.420629) (xy 81.44297 -275.402582) (xy 81.492834 -275.392402)
			(xy 81.543686 -275.390353) (xy 81.594207 -275.396487) (xy 81.643091 -275.410647) (xy 81.68907 -275.432464)
			(xy 81.730954 -275.461374) (xy 81.767658 -275.496629) (xy 81.798231 -275.537315) (xy 81.821882 -275.582378)
			(xy 81.837998 -275.630652) (xy 81.846162 -275.680886) (xy 81.846674 -275.706332) (xy 82.154771 -275.706332)
			(xy 82.158866 -275.655604) (xy 82.171045 -275.60619) (xy 82.190993 -275.55937) (xy 82.218194 -275.516356)
			(xy 82.251942 -275.478262) (xy 82.291364 -275.446075) (xy 82.335438 -275.420629) (xy 82.383024 -275.402582)
			(xy 82.432888 -275.392402) (xy 82.48374 -275.390353) (xy 82.534261 -275.396487) (xy 82.583145 -275.410647)
			(xy 82.629124 -275.432464) (xy 82.671008 -275.461374) (xy 82.707712 -275.496629) (xy 82.738285 -275.537315)
			(xy 82.761936 -275.582378) (xy 82.778052 -275.630652) (xy 82.786216 -275.680886) (xy 82.786728 -275.706332)
			(xy 82.786225 -275.731321) (xy 83.093542 -275.731321) (xy 83.093542 -275.681343) (xy 83.101361 -275.63198)
			(xy 83.116805 -275.584448) (xy 83.139495 -275.539916) (xy 83.168871 -275.499483) (xy 83.204211 -275.464143)
			(xy 83.244644 -275.434767) (xy 83.289176 -275.412077) (xy 83.336708 -275.396633) (xy 83.386071 -275.388814)
			(xy 83.436049 -275.388814) (xy 83.485412 -275.396633) (xy 83.532944 -275.412077) (xy 83.577476 -275.434767)
			(xy 83.617909 -275.464143) (xy 83.653249 -275.499483) (xy 83.682625 -275.539916) (xy 83.705315 -275.584448)
			(xy 83.720759 -275.63198) (xy 83.728578 -275.681343) (xy 83.729068 -275.706332) (xy 84.034879 -275.706332)
			(xy 84.038974 -275.655604) (xy 84.051153 -275.60619) (xy 84.071101 -275.55937) (xy 84.098302 -275.516356)
			(xy 84.13205 -275.478262) (xy 84.171472 -275.446075) (xy 84.215546 -275.420629) (xy 84.263132 -275.402582)
			(xy 84.312996 -275.392402) (xy 84.363848 -275.390353) (xy 84.414369 -275.396487) (xy 84.463253 -275.410647)
			(xy 84.509232 -275.432464) (xy 84.551116 -275.461374) (xy 84.58782 -275.496629) (xy 84.618393 -275.537315)
			(xy 84.642044 -275.582378) (xy 84.65816 -275.630652) (xy 84.666324 -275.680886) (xy 84.666836 -275.706332)
			(xy 84.666333 -275.731321) (xy 84.973396 -275.731321) (xy 84.973396 -275.681343) (xy 84.981215 -275.63198)
			(xy 84.996659 -275.584448) (xy 85.019349 -275.539916) (xy 85.048725 -275.499483) (xy 85.084065 -275.464143)
			(xy 85.124498 -275.434767) (xy 85.16903 -275.412077) (xy 85.216562 -275.396633) (xy 85.265925 -275.388814)
			(xy 85.315903 -275.388814) (xy 85.365266 -275.396633) (xy 85.412798 -275.412077) (xy 85.45733 -275.434767)
			(xy 85.497763 -275.464143) (xy 85.533103 -275.499483) (xy 85.562479 -275.539916) (xy 85.585169 -275.584448)
			(xy 85.600613 -275.63198) (xy 85.608432 -275.681343) (xy 85.608922 -275.706332) (xy 85.914733 -275.706332)
			(xy 85.918828 -275.655604) (xy 85.931007 -275.60619) (xy 85.950955 -275.55937) (xy 85.978156 -275.516356)
			(xy 86.011904 -275.478262) (xy 86.051326 -275.446075) (xy 86.0954 -275.420629) (xy 86.142986 -275.402582)
			(xy 86.19285 -275.392402) (xy 86.243702 -275.390353) (xy 86.294223 -275.396487) (xy 86.343107 -275.410647)
			(xy 86.389086 -275.432464) (xy 86.43097 -275.461374) (xy 86.467674 -275.496629) (xy 86.498247 -275.537315)
			(xy 86.521898 -275.582378) (xy 86.538014 -275.630652) (xy 86.546178 -275.680886) (xy 86.54669 -275.706332)
			(xy 87.794841 -275.706332) (xy 87.798936 -275.655604) (xy 87.811115 -275.60619) (xy 87.831063 -275.55937)
			(xy 87.858264 -275.516356) (xy 87.892012 -275.478262) (xy 87.931434 -275.446075) (xy 87.975508 -275.420629)
			(xy 88.023094 -275.402582) (xy 88.072958 -275.392402) (xy 88.12381 -275.390353) (xy 88.174331 -275.396487)
			(xy 88.223215 -275.410647) (xy 88.269194 -275.432464) (xy 88.311078 -275.461374) (xy 88.347782 -275.496629)
			(xy 88.378355 -275.537315) (xy 88.402006 -275.582378) (xy 88.418122 -275.630652) (xy 88.426286 -275.680886)
			(xy 88.426798 -275.706332) (xy 88.734895 -275.706332) (xy 88.73899 -275.655604) (xy 88.751169 -275.60619)
			(xy 88.771117 -275.55937) (xy 88.798318 -275.516356) (xy 88.832066 -275.478262) (xy 88.871488 -275.446075)
			(xy 88.915562 -275.420629) (xy 88.963148 -275.402582) (xy 89.013012 -275.392402) (xy 89.063864 -275.390353)
			(xy 89.114385 -275.396487) (xy 89.163269 -275.410647) (xy 89.209248 -275.432464) (xy 89.251132 -275.461374)
			(xy 89.287836 -275.496629) (xy 89.318409 -275.537315) (xy 89.34206 -275.582378) (xy 89.358176 -275.630652)
			(xy 89.36634 -275.680886) (xy 89.366852 -275.706332) (xy 89.366349 -275.731321) (xy 89.673412 -275.731321)
			(xy 89.673412 -275.681343) (xy 89.681231 -275.63198) (xy 89.696675 -275.584448) (xy 89.719365 -275.539916)
			(xy 89.748741 -275.499483) (xy 89.784081 -275.464143) (xy 89.824514 -275.434767) (xy 89.869046 -275.412077)
			(xy 89.916578 -275.396633) (xy 89.965941 -275.388814) (xy 90.015919 -275.388814) (xy 90.065282 -275.396633)
			(xy 90.112814 -275.412077) (xy 90.157346 -275.434767) (xy 90.197779 -275.464143) (xy 90.233119 -275.499483)
			(xy 90.262495 -275.539916) (xy 90.285185 -275.584448) (xy 90.300629 -275.63198) (xy 90.308448 -275.681343)
			(xy 90.308938 -275.706332) (xy 90.614749 -275.706332) (xy 90.618844 -275.655604) (xy 90.631023 -275.60619)
			(xy 90.650971 -275.55937) (xy 90.678172 -275.516356) (xy 90.71192 -275.478262) (xy 90.751342 -275.446075)
			(xy 90.795416 -275.420629) (xy 90.843002 -275.402582) (xy 90.892866 -275.392402) (xy 90.943718 -275.390353)
			(xy 90.994239 -275.396487) (xy 91.043123 -275.410647) (xy 91.089102 -275.432464) (xy 91.130986 -275.461374)
			(xy 91.16769 -275.496629) (xy 91.198263 -275.537315) (xy 91.221914 -275.582378) (xy 91.23803 -275.630652)
			(xy 91.246194 -275.680886) (xy 91.246706 -275.706332) (xy 91.246203 -275.731321) (xy 91.55352 -275.731321)
			(xy 91.55352 -275.681343) (xy 91.561339 -275.63198) (xy 91.576783 -275.584448) (xy 91.599473 -275.539916)
			(xy 91.628849 -275.499483) (xy 91.664189 -275.464143) (xy 91.704622 -275.434767) (xy 91.749154 -275.412077)
			(xy 91.796686 -275.396633) (xy 91.846049 -275.388814) (xy 91.896027 -275.388814) (xy 91.94539 -275.396633)
			(xy 91.992922 -275.412077) (xy 92.037454 -275.434767) (xy 92.077887 -275.464143) (xy 92.113227 -275.499483)
			(xy 92.142603 -275.539916) (xy 92.165293 -275.584448) (xy 92.180737 -275.63198) (xy 92.188556 -275.681343)
			(xy 92.189046 -275.706332) (xy 92.188556 -275.731321) (xy 92.180737 -275.780684) (xy 92.165293 -275.828216)
			(xy 92.142603 -275.872748) (xy 92.113227 -275.913181) (xy 92.077887 -275.948521) (xy 92.037454 -275.977897)
			(xy 91.992922 -276.000587) (xy 91.94539 -276.016031) (xy 91.896027 -276.02385) (xy 91.846049 -276.02385)
			(xy 91.796686 -276.016031) (xy 91.749154 -276.000587) (xy 91.704622 -275.977897) (xy 91.664189 -275.948521)
			(xy 91.628849 -275.913181) (xy 91.599473 -275.872748) (xy 91.576783 -275.828216) (xy 91.561339 -275.780684)
			(xy 91.55352 -275.731321) (xy 91.246203 -275.731321) (xy 91.246194 -275.731778) (xy 91.23803 -275.782012)
			(xy 91.221914 -275.830286) (xy 91.198263 -275.875349) (xy 91.16769 -275.916035) (xy 91.130986 -275.95129)
			(xy 91.089102 -275.9802) (xy 91.043123 -276.002017) (xy 90.994239 -276.016177) (xy 90.943718 -276.022311)
			(xy 90.892866 -276.020262) (xy 90.843002 -276.010082) (xy 90.795416 -275.992035) (xy 90.751342 -275.966589)
			(xy 90.71192 -275.934402) (xy 90.678172 -275.896308) (xy 90.650971 -275.853294) (xy 90.631023 -275.806474)
			(xy 90.618844 -275.75706) (xy 90.614749 -275.706332) (xy 90.308938 -275.706332) (xy 90.308448 -275.731321)
			(xy 90.300629 -275.780684) (xy 90.285185 -275.828216) (xy 90.262495 -275.872748) (xy 90.233119 -275.913181)
			(xy 90.197779 -275.948521) (xy 90.157346 -275.977897) (xy 90.112814 -276.000587) (xy 90.065282 -276.016031)
			(xy 90.015919 -276.02385) (xy 89.965941 -276.02385) (xy 89.916578 -276.016031) (xy 89.869046 -276.000587)
			(xy 89.824514 -275.977897) (xy 89.784081 -275.948521) (xy 89.748741 -275.913181) (xy 89.719365 -275.872748)
			(xy 89.696675 -275.828216) (xy 89.681231 -275.780684) (xy 89.673412 -275.731321) (xy 89.366349 -275.731321)
			(xy 89.36634 -275.731778) (xy 89.358176 -275.782012) (xy 89.34206 -275.830286) (xy 89.318409 -275.875349)
			(xy 89.287836 -275.916035) (xy 89.251132 -275.95129) (xy 89.209248 -275.9802) (xy 89.163269 -276.002017)
			(xy 89.114385 -276.016177) (xy 89.063864 -276.022311) (xy 89.013012 -276.020262) (xy 88.963148 -276.010082)
			(xy 88.915562 -275.992035) (xy 88.871488 -275.966589) (xy 88.832066 -275.934402) (xy 88.798318 -275.896308)
			(xy 88.771117 -275.853294) (xy 88.751169 -275.806474) (xy 88.73899 -275.75706) (xy 88.734895 -275.706332)
			(xy 88.426798 -275.706332) (xy 88.426286 -275.731778) (xy 88.418122 -275.782012) (xy 88.402006 -275.830286)
			(xy 88.378355 -275.875349) (xy 88.347782 -275.916035) (xy 88.311078 -275.95129) (xy 88.269194 -275.9802)
			(xy 88.223215 -276.002017) (xy 88.174331 -276.016177) (xy 88.12381 -276.022311) (xy 88.072958 -276.020262)
			(xy 88.023094 -276.010082) (xy 87.975508 -275.992035) (xy 87.931434 -275.966589) (xy 87.892012 -275.934402)
			(xy 87.858264 -275.896308) (xy 87.831063 -275.853294) (xy 87.811115 -275.806474) (xy 87.798936 -275.75706)
			(xy 87.794841 -275.706332) (xy 86.54669 -275.706332) (xy 86.546178 -275.731778) (xy 86.538014 -275.782012)
			(xy 86.521898 -275.830286) (xy 86.498247 -275.875349) (xy 86.467674 -275.916035) (xy 86.43097 -275.95129)
			(xy 86.389086 -275.9802) (xy 86.343107 -276.002017) (xy 86.294223 -276.016177) (xy 86.243702 -276.022311)
			(xy 86.19285 -276.020262) (xy 86.142986 -276.010082) (xy 86.0954 -275.992035) (xy 86.051326 -275.966589)
			(xy 86.011904 -275.934402) (xy 85.978156 -275.896308) (xy 85.950955 -275.853294) (xy 85.931007 -275.806474)
			(xy 85.918828 -275.75706) (xy 85.914733 -275.706332) (xy 85.608922 -275.706332) (xy 85.608432 -275.731321)
			(xy 85.600613 -275.780684) (xy 85.585169 -275.828216) (xy 85.562479 -275.872748) (xy 85.533103 -275.913181)
			(xy 85.497763 -275.948521) (xy 85.45733 -275.977897) (xy 85.412798 -276.000587) (xy 85.365266 -276.016031)
			(xy 85.315903 -276.02385) (xy 85.265925 -276.02385) (xy 85.216562 -276.016031) (xy 85.16903 -276.000587)
			(xy 85.124498 -275.977897) (xy 85.084065 -275.948521) (xy 85.048725 -275.913181) (xy 85.019349 -275.872748)
			(xy 84.996659 -275.828216) (xy 84.981215 -275.780684) (xy 84.973396 -275.731321) (xy 84.666333 -275.731321)
			(xy 84.666324 -275.731778) (xy 84.65816 -275.782012) (xy 84.642044 -275.830286) (xy 84.618393 -275.875349)
			(xy 84.58782 -275.916035) (xy 84.551116 -275.95129) (xy 84.509232 -275.9802) (xy 84.463253 -276.002017)
			(xy 84.414369 -276.016177) (xy 84.363848 -276.022311) (xy 84.312996 -276.020262) (xy 84.263132 -276.010082)
			(xy 84.215546 -275.992035) (xy 84.171472 -275.966589) (xy 84.13205 -275.934402) (xy 84.098302 -275.896308)
			(xy 84.071101 -275.853294) (xy 84.051153 -275.806474) (xy 84.038974 -275.75706) (xy 84.034879 -275.706332)
			(xy 83.729068 -275.706332) (xy 83.728578 -275.731321) (xy 83.720759 -275.780684) (xy 83.705315 -275.828216)
			(xy 83.682625 -275.872748) (xy 83.653249 -275.913181) (xy 83.617909 -275.948521) (xy 83.577476 -275.977897)
			(xy 83.532944 -276.000587) (xy 83.485412 -276.016031) (xy 83.436049 -276.02385) (xy 83.386071 -276.02385)
			(xy 83.336708 -276.016031) (xy 83.289176 -276.000587) (xy 83.244644 -275.977897) (xy 83.204211 -275.948521)
			(xy 83.168871 -275.913181) (xy 83.139495 -275.872748) (xy 83.116805 -275.828216) (xy 83.101361 -275.780684)
			(xy 83.093542 -275.731321) (xy 82.786225 -275.731321) (xy 82.786216 -275.731778) (xy 82.778052 -275.782012)
			(xy 82.761936 -275.830286) (xy 82.738285 -275.875349) (xy 82.707712 -275.916035) (xy 82.671008 -275.95129)
			(xy 82.629124 -275.9802) (xy 82.583145 -276.002017) (xy 82.534261 -276.016177) (xy 82.48374 -276.022311)
			(xy 82.432888 -276.020262) (xy 82.383024 -276.010082) (xy 82.335438 -275.992035) (xy 82.291364 -275.966589)
			(xy 82.251942 -275.934402) (xy 82.218194 -275.896308) (xy 82.190993 -275.853294) (xy 82.171045 -275.806474)
			(xy 82.158866 -275.75706) (xy 82.154771 -275.706332) (xy 81.846674 -275.706332) (xy 81.846162 -275.731778)
			(xy 81.837998 -275.782012) (xy 81.821882 -275.830286) (xy 81.798231 -275.875349) (xy 81.767658 -275.916035)
			(xy 81.730954 -275.95129) (xy 81.68907 -275.9802) (xy 81.643091 -276.002017) (xy 81.594207 -276.016177)
			(xy 81.543686 -276.022311) (xy 81.492834 -276.020262) (xy 81.44297 -276.010082) (xy 81.395384 -275.992035)
			(xy 81.35131 -275.966589) (xy 81.311888 -275.934402) (xy 81.27814 -275.896308) (xy 81.250939 -275.853294)
			(xy 81.230991 -275.806474) (xy 81.218812 -275.75706) (xy 81.214717 -275.706332) (xy 79.53248 -275.706332)
			(xy 79.53248 -276.541327) (xy 79.80348 -276.541327) (xy 79.80348 -276.491349) (xy 79.811299 -276.441986)
			(xy 79.826743 -276.394454) (xy 79.849433 -276.349922) (xy 79.878809 -276.309489) (xy 79.914149 -276.274149)
			(xy 79.954582 -276.244773) (xy 79.999114 -276.222083) (xy 80.046646 -276.206639) (xy 80.096009 -276.19882)
			(xy 80.145987 -276.19882) (xy 80.19535 -276.206639) (xy 80.242882 -276.222083) (xy 80.287414 -276.244773)
			(xy 80.327847 -276.274149) (xy 80.363187 -276.309489) (xy 80.392563 -276.349922) (xy 80.415253 -276.394454)
			(xy 80.430697 -276.441986) (xy 80.438516 -276.491349) (xy 80.439006 -276.516338) (xy 80.744817 -276.516338)
			(xy 80.748912 -276.46561) (xy 80.761091 -276.416196) (xy 80.781039 -276.369376) (xy 80.80824 -276.326362)
			(xy 80.841988 -276.288268) (xy 80.88141 -276.256081) (xy 80.925484 -276.230635) (xy 80.97307 -276.212588)
			(xy 81.022934 -276.202408) (xy 81.073786 -276.200359) (xy 81.124307 -276.206493) (xy 81.173191 -276.220653)
			(xy 81.21917 -276.24247) (xy 81.261054 -276.27138) (xy 81.297758 -276.306635) (xy 81.328331 -276.347321)
			(xy 81.351982 -276.392384) (xy 81.368098 -276.440658) (xy 81.376262 -276.490892) (xy 81.376774 -276.516338)
			(xy 81.376271 -276.541327) (xy 81.683588 -276.541327) (xy 81.683588 -276.491349) (xy 81.691407 -276.441986)
			(xy 81.706851 -276.394454) (xy 81.729541 -276.349922) (xy 81.758917 -276.309489) (xy 81.794257 -276.274149)
			(xy 81.83469 -276.244773) (xy 81.879222 -276.222083) (xy 81.926754 -276.206639) (xy 81.976117 -276.19882)
			(xy 82.026095 -276.19882) (xy 82.075458 -276.206639) (xy 82.12299 -276.222083) (xy 82.167522 -276.244773)
			(xy 82.207955 -276.274149) (xy 82.243295 -276.309489) (xy 82.272671 -276.349922) (xy 82.295361 -276.394454)
			(xy 82.310805 -276.441986) (xy 82.318624 -276.491349) (xy 82.319114 -276.516338) (xy 82.624671 -276.516338)
			(xy 82.628766 -276.46561) (xy 82.640945 -276.416196) (xy 82.660893 -276.369376) (xy 82.688094 -276.326362)
			(xy 82.721842 -276.288268) (xy 82.761264 -276.256081) (xy 82.805338 -276.230635) (xy 82.852924 -276.212588)
			(xy 82.902788 -276.202408) (xy 82.95364 -276.200359) (xy 83.004161 -276.206493) (xy 83.053045 -276.220653)
			(xy 83.099024 -276.24247) (xy 83.140908 -276.27138) (xy 83.177612 -276.306635) (xy 83.208185 -276.347321)
			(xy 83.231836 -276.392384) (xy 83.247952 -276.440658) (xy 83.256116 -276.490892) (xy 83.256628 -276.516338)
			(xy 83.256125 -276.541327) (xy 83.563442 -276.541327) (xy 83.563442 -276.491349) (xy 83.571261 -276.441986)
			(xy 83.586705 -276.394454) (xy 83.609395 -276.349922) (xy 83.638771 -276.309489) (xy 83.674111 -276.274149)
			(xy 83.714544 -276.244773) (xy 83.759076 -276.222083) (xy 83.806608 -276.206639) (xy 83.855971 -276.19882)
			(xy 83.905949 -276.19882) (xy 83.955312 -276.206639) (xy 84.002844 -276.222083) (xy 84.047376 -276.244773)
			(xy 84.087809 -276.274149) (xy 84.123149 -276.309489) (xy 84.152525 -276.349922) (xy 84.175215 -276.394454)
			(xy 84.190659 -276.441986) (xy 84.198478 -276.491349) (xy 84.198968 -276.516338) (xy 84.504779 -276.516338)
			(xy 84.508874 -276.46561) (xy 84.521053 -276.416196) (xy 84.541001 -276.369376) (xy 84.568202 -276.326362)
			(xy 84.60195 -276.288268) (xy 84.641372 -276.256081) (xy 84.685446 -276.230635) (xy 84.733032 -276.212588)
			(xy 84.782896 -276.202408) (xy 84.833748 -276.200359) (xy 84.884269 -276.206493) (xy 84.933153 -276.220653)
			(xy 84.979132 -276.24247) (xy 85.021016 -276.27138) (xy 85.05772 -276.306635) (xy 85.088293 -276.347321)
			(xy 85.111944 -276.392384) (xy 85.12806 -276.440658) (xy 85.136224 -276.490892) (xy 85.136736 -276.516338)
			(xy 85.444833 -276.516338) (xy 85.448928 -276.46561) (xy 85.461107 -276.416196) (xy 85.481055 -276.369376)
			(xy 85.508256 -276.326362) (xy 85.542004 -276.288268) (xy 85.581426 -276.256081) (xy 85.6255 -276.230635)
			(xy 85.673086 -276.212588) (xy 85.72295 -276.202408) (xy 85.773802 -276.200359) (xy 85.824323 -276.206493)
			(xy 85.873207 -276.220653) (xy 85.919186 -276.24247) (xy 85.96107 -276.27138) (xy 85.997774 -276.306635)
			(xy 86.028347 -276.347321) (xy 86.051998 -276.392384) (xy 86.068114 -276.440658) (xy 86.076278 -276.490892)
			(xy 86.07679 -276.516338) (xy 86.076287 -276.541327) (xy 86.383604 -276.541327) (xy 86.383604 -276.491349)
			(xy 86.391423 -276.441986) (xy 86.406867 -276.394454) (xy 86.429557 -276.349922) (xy 86.458933 -276.309489)
			(xy 86.494273 -276.274149) (xy 86.534706 -276.244773) (xy 86.579238 -276.222083) (xy 86.62677 -276.206639)
			(xy 86.676133 -276.19882) (xy 86.726111 -276.19882) (xy 86.775474 -276.206639) (xy 86.823006 -276.222083)
			(xy 86.867538 -276.244773) (xy 86.907971 -276.274149) (xy 86.943311 -276.309489) (xy 86.972687 -276.349922)
			(xy 86.995377 -276.394454) (xy 87.010821 -276.441986) (xy 87.01864 -276.491349) (xy 87.01913 -276.516338)
			(xy 87.324687 -276.516338) (xy 87.328782 -276.46561) (xy 87.340961 -276.416196) (xy 87.360909 -276.369376)
			(xy 87.38811 -276.326362) (xy 87.421858 -276.288268) (xy 87.46128 -276.256081) (xy 87.505354 -276.230635)
			(xy 87.55294 -276.212588) (xy 87.602804 -276.202408) (xy 87.653656 -276.200359) (xy 87.704177 -276.206493)
			(xy 87.753061 -276.220653) (xy 87.79904 -276.24247) (xy 87.840924 -276.27138) (xy 87.877628 -276.306635)
			(xy 87.908201 -276.347321) (xy 87.931852 -276.392384) (xy 87.947968 -276.440658) (xy 87.956132 -276.490892)
			(xy 87.956644 -276.516338) (xy 87.956141 -276.541327) (xy 88.263458 -276.541327) (xy 88.263458 -276.491349)
			(xy 88.271277 -276.441986) (xy 88.286721 -276.394454) (xy 88.309411 -276.349922) (xy 88.338787 -276.309489)
			(xy 88.374127 -276.274149) (xy 88.41456 -276.244773) (xy 88.459092 -276.222083) (xy 88.506624 -276.206639)
			(xy 88.555987 -276.19882) (xy 88.605965 -276.19882) (xy 88.655328 -276.206639) (xy 88.70286 -276.222083)
			(xy 88.747392 -276.244773) (xy 88.787825 -276.274149) (xy 88.823165 -276.309489) (xy 88.852541 -276.349922)
			(xy 88.875231 -276.394454) (xy 88.890675 -276.441986) (xy 88.898494 -276.491349) (xy 88.898984 -276.516338)
			(xy 89.204795 -276.516338) (xy 89.20889 -276.46561) (xy 89.221069 -276.416196) (xy 89.241017 -276.369376)
			(xy 89.268218 -276.326362) (xy 89.301966 -276.288268) (xy 89.341388 -276.256081) (xy 89.385462 -276.230635)
			(xy 89.433048 -276.212588) (xy 89.482912 -276.202408) (xy 89.533764 -276.200359) (xy 89.584285 -276.206493)
			(xy 89.633169 -276.220653) (xy 89.679148 -276.24247) (xy 89.721032 -276.27138) (xy 89.757736 -276.306635)
			(xy 89.788309 -276.347321) (xy 89.81196 -276.392384) (xy 89.828076 -276.440658) (xy 89.83624 -276.490892)
			(xy 89.836752 -276.516338) (xy 89.836249 -276.541327) (xy 90.143566 -276.541327) (xy 90.143566 -276.491349)
			(xy 90.151385 -276.441986) (xy 90.166829 -276.394454) (xy 90.189519 -276.349922) (xy 90.218895 -276.309489)
			(xy 90.254235 -276.274149) (xy 90.294668 -276.244773) (xy 90.3392 -276.222083) (xy 90.386732 -276.206639)
			(xy 90.436095 -276.19882) (xy 90.486073 -276.19882) (xy 90.535436 -276.206639) (xy 90.582968 -276.222083)
			(xy 90.6275 -276.244773) (xy 90.667933 -276.274149) (xy 90.703273 -276.309489) (xy 90.732649 -276.349922)
			(xy 90.755339 -276.394454) (xy 90.770783 -276.441986) (xy 90.778602 -276.491349) (xy 90.779092 -276.516338)
			(xy 91.084903 -276.516338) (xy 91.088998 -276.46561) (xy 91.101177 -276.416196) (xy 91.121125 -276.369376)
			(xy 91.148326 -276.326362) (xy 91.182074 -276.288268) (xy 91.221496 -276.256081) (xy 91.26557 -276.230635)
			(xy 91.313156 -276.212588) (xy 91.36302 -276.202408) (xy 91.413872 -276.200359) (xy 91.464393 -276.206493)
			(xy 91.513277 -276.220653) (xy 91.559256 -276.24247) (xy 91.60114 -276.27138) (xy 91.637844 -276.306635)
			(xy 91.668417 -276.347321) (xy 91.692068 -276.392384) (xy 91.708184 -276.440658) (xy 91.716348 -276.490892)
			(xy 91.71686 -276.516338) (xy 91.716348 -276.541784) (xy 91.708184 -276.592018) (xy 91.692068 -276.640292)
			(xy 91.668417 -276.685355) (xy 91.637844 -276.726041) (xy 91.60114 -276.761296) (xy 91.559256 -276.790206)
			(xy 91.513277 -276.812023) (xy 91.464393 -276.826183) (xy 91.413872 -276.832317) (xy 91.36302 -276.830268)
			(xy 91.313156 -276.820088) (xy 91.26557 -276.802041) (xy 91.221496 -276.776595) (xy 91.182074 -276.744408)
			(xy 91.148326 -276.706314) (xy 91.121125 -276.6633) (xy 91.101177 -276.61648) (xy 91.088998 -276.567066)
			(xy 91.084903 -276.516338) (xy 90.779092 -276.516338) (xy 90.778602 -276.541327) (xy 90.770783 -276.59069)
			(xy 90.755339 -276.638222) (xy 90.732649 -276.682754) (xy 90.703273 -276.723187) (xy 90.667933 -276.758527)
			(xy 90.6275 -276.787903) (xy 90.582968 -276.810593) (xy 90.535436 -276.826037) (xy 90.486073 -276.833856)
			(xy 90.436095 -276.833856) (xy 90.386732 -276.826037) (xy 90.3392 -276.810593) (xy 90.294668 -276.787903)
			(xy 90.254235 -276.758527) (xy 90.218895 -276.723187) (xy 90.189519 -276.682754) (xy 90.166829 -276.638222)
			(xy 90.151385 -276.59069) (xy 90.143566 -276.541327) (xy 89.836249 -276.541327) (xy 89.83624 -276.541784)
			(xy 89.828076 -276.592018) (xy 89.81196 -276.640292) (xy 89.788309 -276.685355) (xy 89.757736 -276.726041)
			(xy 89.721032 -276.761296) (xy 89.679148 -276.790206) (xy 89.633169 -276.812023) (xy 89.584285 -276.826183)
			(xy 89.533764 -276.832317) (xy 89.482912 -276.830268) (xy 89.433048 -276.820088) (xy 89.385462 -276.802041)
			(xy 89.341388 -276.776595) (xy 89.301966 -276.744408) (xy 89.268218 -276.706314) (xy 89.241017 -276.6633)
			(xy 89.221069 -276.61648) (xy 89.20889 -276.567066) (xy 89.204795 -276.516338) (xy 88.898984 -276.516338)
			(xy 88.898494 -276.541327) (xy 88.890675 -276.59069) (xy 88.875231 -276.638222) (xy 88.852541 -276.682754)
			(xy 88.823165 -276.723187) (xy 88.787825 -276.758527) (xy 88.747392 -276.787903) (xy 88.70286 -276.810593)
			(xy 88.655328 -276.826037) (xy 88.605965 -276.833856) (xy 88.555987 -276.833856) (xy 88.506624 -276.826037)
			(xy 88.459092 -276.810593) (xy 88.41456 -276.787903) (xy 88.374127 -276.758527) (xy 88.338787 -276.723187)
			(xy 88.309411 -276.682754) (xy 88.286721 -276.638222) (xy 88.271277 -276.59069) (xy 88.263458 -276.541327)
			(xy 87.956141 -276.541327) (xy 87.956132 -276.541784) (xy 87.947968 -276.592018) (xy 87.931852 -276.640292)
			(xy 87.908201 -276.685355) (xy 87.877628 -276.726041) (xy 87.840924 -276.761296) (xy 87.79904 -276.790206)
			(xy 87.753061 -276.812023) (xy 87.704177 -276.826183) (xy 87.653656 -276.832317) (xy 87.602804 -276.830268)
			(xy 87.55294 -276.820088) (xy 87.505354 -276.802041) (xy 87.46128 -276.776595) (xy 87.421858 -276.744408)
			(xy 87.38811 -276.706314) (xy 87.360909 -276.6633) (xy 87.340961 -276.61648) (xy 87.328782 -276.567066)
			(xy 87.324687 -276.516338) (xy 87.01913 -276.516338) (xy 87.01864 -276.541327) (xy 87.010821 -276.59069)
			(xy 86.995377 -276.638222) (xy 86.972687 -276.682754) (xy 86.943311 -276.723187) (xy 86.907971 -276.758527)
			(xy 86.867538 -276.787903) (xy 86.823006 -276.810593) (xy 86.775474 -276.826037) (xy 86.726111 -276.833856)
			(xy 86.676133 -276.833856) (xy 86.62677 -276.826037) (xy 86.579238 -276.810593) (xy 86.534706 -276.787903)
			(xy 86.494273 -276.758527) (xy 86.458933 -276.723187) (xy 86.429557 -276.682754) (xy 86.406867 -276.638222)
			(xy 86.391423 -276.59069) (xy 86.383604 -276.541327) (xy 86.076287 -276.541327) (xy 86.076278 -276.541784)
			(xy 86.068114 -276.592018) (xy 86.051998 -276.640292) (xy 86.028347 -276.685355) (xy 85.997774 -276.726041)
			(xy 85.96107 -276.761296) (xy 85.919186 -276.790206) (xy 85.873207 -276.812023) (xy 85.824323 -276.826183)
			(xy 85.773802 -276.832317) (xy 85.72295 -276.830268) (xy 85.673086 -276.820088) (xy 85.6255 -276.802041)
			(xy 85.581426 -276.776595) (xy 85.542004 -276.744408) (xy 85.508256 -276.706314) (xy 85.481055 -276.6633)
			(xy 85.461107 -276.61648) (xy 85.448928 -276.567066) (xy 85.444833 -276.516338) (xy 85.136736 -276.516338)
			(xy 85.136224 -276.541784) (xy 85.12806 -276.592018) (xy 85.111944 -276.640292) (xy 85.088293 -276.685355)
			(xy 85.05772 -276.726041) (xy 85.021016 -276.761296) (xy 84.979132 -276.790206) (xy 84.933153 -276.812023)
			(xy 84.884269 -276.826183) (xy 84.833748 -276.832317) (xy 84.782896 -276.830268) (xy 84.733032 -276.820088)
			(xy 84.685446 -276.802041) (xy 84.641372 -276.776595) (xy 84.60195 -276.744408) (xy 84.568202 -276.706314)
			(xy 84.541001 -276.6633) (xy 84.521053 -276.61648) (xy 84.508874 -276.567066) (xy 84.504779 -276.516338)
			(xy 84.198968 -276.516338) (xy 84.198478 -276.541327) (xy 84.190659 -276.59069) (xy 84.175215 -276.638222)
			(xy 84.152525 -276.682754) (xy 84.123149 -276.723187) (xy 84.087809 -276.758527) (xy 84.047376 -276.787903)
			(xy 84.002844 -276.810593) (xy 83.955312 -276.826037) (xy 83.905949 -276.833856) (xy 83.855971 -276.833856)
			(xy 83.806608 -276.826037) (xy 83.759076 -276.810593) (xy 83.714544 -276.787903) (xy 83.674111 -276.758527)
			(xy 83.638771 -276.723187) (xy 83.609395 -276.682754) (xy 83.586705 -276.638222) (xy 83.571261 -276.59069)
			(xy 83.563442 -276.541327) (xy 83.256125 -276.541327) (xy 83.256116 -276.541784) (xy 83.247952 -276.592018)
			(xy 83.231836 -276.640292) (xy 83.208185 -276.685355) (xy 83.177612 -276.726041) (xy 83.140908 -276.761296)
			(xy 83.099024 -276.790206) (xy 83.053045 -276.812023) (xy 83.004161 -276.826183) (xy 82.95364 -276.832317)
			(xy 82.902788 -276.830268) (xy 82.852924 -276.820088) (xy 82.805338 -276.802041) (xy 82.761264 -276.776595)
			(xy 82.721842 -276.744408) (xy 82.688094 -276.706314) (xy 82.660893 -276.6633) (xy 82.640945 -276.61648)
			(xy 82.628766 -276.567066) (xy 82.624671 -276.516338) (xy 82.319114 -276.516338) (xy 82.318624 -276.541327)
			(xy 82.310805 -276.59069) (xy 82.295361 -276.638222) (xy 82.272671 -276.682754) (xy 82.243295 -276.723187)
			(xy 82.207955 -276.758527) (xy 82.167522 -276.787903) (xy 82.12299 -276.810593) (xy 82.075458 -276.826037)
			(xy 82.026095 -276.833856) (xy 81.976117 -276.833856) (xy 81.926754 -276.826037) (xy 81.879222 -276.810593)
			(xy 81.83469 -276.787903) (xy 81.794257 -276.758527) (xy 81.758917 -276.723187) (xy 81.729541 -276.682754)
			(xy 81.706851 -276.638222) (xy 81.691407 -276.59069) (xy 81.683588 -276.541327) (xy 81.376271 -276.541327)
			(xy 81.376262 -276.541784) (xy 81.368098 -276.592018) (xy 81.351982 -276.640292) (xy 81.328331 -276.685355)
			(xy 81.297758 -276.726041) (xy 81.261054 -276.761296) (xy 81.21917 -276.790206) (xy 81.173191 -276.812023)
			(xy 81.124307 -276.826183) (xy 81.073786 -276.832317) (xy 81.022934 -276.830268) (xy 80.97307 -276.820088)
			(xy 80.925484 -276.802041) (xy 80.88141 -276.776595) (xy 80.841988 -276.744408) (xy 80.80824 -276.706314)
			(xy 80.781039 -276.6633) (xy 80.761091 -276.61648) (xy 80.748912 -276.567066) (xy 80.744817 -276.516338)
			(xy 80.439006 -276.516338) (xy 80.438516 -276.541327) (xy 80.430697 -276.59069) (xy 80.415253 -276.638222)
			(xy 80.392563 -276.682754) (xy 80.363187 -276.723187) (xy 80.327847 -276.758527) (xy 80.287414 -276.787903)
			(xy 80.242882 -276.810593) (xy 80.19535 -276.826037) (xy 80.145987 -276.833856) (xy 80.096009 -276.833856)
			(xy 80.046646 -276.826037) (xy 79.999114 -276.810593) (xy 79.954582 -276.787903) (xy 79.914149 -276.758527)
			(xy 79.878809 -276.723187) (xy 79.849433 -276.682754) (xy 79.826743 -276.638222) (xy 79.811299 -276.59069)
			(xy 79.80348 -276.541327) (xy 79.53248 -276.541327) (xy 79.53248 -277.351333) (xy 80.273634 -277.351333)
			(xy 80.273634 -277.301355) (xy 80.281453 -277.251992) (xy 80.296897 -277.20446) (xy 80.319587 -277.159928)
			(xy 80.348963 -277.119495) (xy 80.384303 -277.084155) (xy 80.424736 -277.054779) (xy 80.469268 -277.032089)
			(xy 80.5168 -277.016645) (xy 80.566163 -277.008826) (xy 80.616141 -277.008826) (xy 80.665504 -277.016645)
			(xy 80.713036 -277.032089) (xy 80.757568 -277.054779) (xy 80.798001 -277.084155) (xy 80.833341 -277.119495)
			(xy 80.862717 -277.159928) (xy 80.885407 -277.20446) (xy 80.900851 -277.251992) (xy 80.90867 -277.301355)
			(xy 80.90916 -277.326344) (xy 81.214717 -277.326344) (xy 81.218812 -277.275616) (xy 81.230991 -277.226202)
			(xy 81.250939 -277.179382) (xy 81.27814 -277.136368) (xy 81.311888 -277.098274) (xy 81.35131 -277.066087)
			(xy 81.395384 -277.040641) (xy 81.44297 -277.022594) (xy 81.492834 -277.012414) (xy 81.543686 -277.010365)
			(xy 81.594207 -277.016499) (xy 81.643091 -277.030659) (xy 81.68907 -277.052476) (xy 81.730954 -277.081386)
			(xy 81.767658 -277.116641) (xy 81.798231 -277.157327) (xy 81.821882 -277.20239) (xy 81.837998 -277.250664)
			(xy 81.846162 -277.300898) (xy 81.846674 -277.326344) (xy 82.154771 -277.326344) (xy 82.158866 -277.275616)
			(xy 82.171045 -277.226202) (xy 82.190993 -277.179382) (xy 82.218194 -277.136368) (xy 82.251942 -277.098274)
			(xy 82.291364 -277.066087) (xy 82.335438 -277.040641) (xy 82.383024 -277.022594) (xy 82.432888 -277.012414)
			(xy 82.48374 -277.010365) (xy 82.534261 -277.016499) (xy 82.583145 -277.030659) (xy 82.629124 -277.052476)
			(xy 82.671008 -277.081386) (xy 82.707712 -277.116641) (xy 82.738285 -277.157327) (xy 82.761936 -277.20239)
			(xy 82.778052 -277.250664) (xy 82.786216 -277.300898) (xy 82.786728 -277.326344) (xy 82.786225 -277.351333)
			(xy 83.093542 -277.351333) (xy 83.093542 -277.301355) (xy 83.101361 -277.251992) (xy 83.116805 -277.20446)
			(xy 83.139495 -277.159928) (xy 83.168871 -277.119495) (xy 83.204211 -277.084155) (xy 83.244644 -277.054779)
			(xy 83.289176 -277.032089) (xy 83.336708 -277.016645) (xy 83.386071 -277.008826) (xy 83.436049 -277.008826)
			(xy 83.485412 -277.016645) (xy 83.532944 -277.032089) (xy 83.577476 -277.054779) (xy 83.617909 -277.084155)
			(xy 83.653249 -277.119495) (xy 83.682625 -277.159928) (xy 83.705315 -277.20446) (xy 83.720759 -277.251992)
			(xy 83.728578 -277.301355) (xy 83.729068 -277.326344) (xy 84.034879 -277.326344) (xy 84.038974 -277.275616)
			(xy 84.051153 -277.226202) (xy 84.071101 -277.179382) (xy 84.098302 -277.136368) (xy 84.13205 -277.098274)
			(xy 84.171472 -277.066087) (xy 84.215546 -277.040641) (xy 84.263132 -277.022594) (xy 84.312996 -277.012414)
			(xy 84.363848 -277.010365) (xy 84.414369 -277.016499) (xy 84.463253 -277.030659) (xy 84.509232 -277.052476)
			(xy 84.551116 -277.081386) (xy 84.58782 -277.116641) (xy 84.618393 -277.157327) (xy 84.642044 -277.20239)
			(xy 84.65816 -277.250664) (xy 84.666324 -277.300898) (xy 84.666836 -277.326344) (xy 84.666333 -277.351333)
			(xy 84.973396 -277.351333) (xy 84.973396 -277.301355) (xy 84.981215 -277.251992) (xy 84.996659 -277.20446)
			(xy 85.019349 -277.159928) (xy 85.048725 -277.119495) (xy 85.084065 -277.084155) (xy 85.124498 -277.054779)
			(xy 85.16903 -277.032089) (xy 85.216562 -277.016645) (xy 85.265925 -277.008826) (xy 85.315903 -277.008826)
			(xy 85.365266 -277.016645) (xy 85.412798 -277.032089) (xy 85.45733 -277.054779) (xy 85.497763 -277.084155)
			(xy 85.533103 -277.119495) (xy 85.562479 -277.159928) (xy 85.585169 -277.20446) (xy 85.600613 -277.251992)
			(xy 85.608432 -277.301355) (xy 85.608922 -277.326344) (xy 85.914733 -277.326344) (xy 85.918828 -277.275616)
			(xy 85.931007 -277.226202) (xy 85.950955 -277.179382) (xy 85.978156 -277.136368) (xy 86.011904 -277.098274)
			(xy 86.051326 -277.066087) (xy 86.0954 -277.040641) (xy 86.142986 -277.022594) (xy 86.19285 -277.012414)
			(xy 86.243702 -277.010365) (xy 86.294223 -277.016499) (xy 86.343107 -277.030659) (xy 86.389086 -277.052476)
			(xy 86.43097 -277.081386) (xy 86.467674 -277.116641) (xy 86.498247 -277.157327) (xy 86.521898 -277.20239)
			(xy 86.538014 -277.250664) (xy 86.546178 -277.300898) (xy 86.54669 -277.326344) (xy 86.546187 -277.351333)
			(xy 86.853504 -277.351333) (xy 86.853504 -277.301355) (xy 86.861323 -277.251992) (xy 86.876767 -277.20446)
			(xy 86.899457 -277.159928) (xy 86.928833 -277.119495) (xy 86.964173 -277.084155) (xy 87.004606 -277.054779)
			(xy 87.049138 -277.032089) (xy 87.09667 -277.016645) (xy 87.146033 -277.008826) (xy 87.196011 -277.008826)
			(xy 87.245374 -277.016645) (xy 87.292906 -277.032089) (xy 87.337438 -277.054779) (xy 87.377871 -277.084155)
			(xy 87.413211 -277.119495) (xy 87.442587 -277.159928) (xy 87.465277 -277.20446) (xy 87.480721 -277.251992)
			(xy 87.48854 -277.301355) (xy 87.48903 -277.326344) (xy 87.794841 -277.326344) (xy 87.798936 -277.275616)
			(xy 87.811115 -277.226202) (xy 87.831063 -277.179382) (xy 87.858264 -277.136368) (xy 87.892012 -277.098274)
			(xy 87.931434 -277.066087) (xy 87.975508 -277.040641) (xy 88.023094 -277.022594) (xy 88.072958 -277.012414)
			(xy 88.12381 -277.010365) (xy 88.174331 -277.016499) (xy 88.223215 -277.030659) (xy 88.269194 -277.052476)
			(xy 88.311078 -277.081386) (xy 88.347782 -277.116641) (xy 88.378355 -277.157327) (xy 88.402006 -277.20239)
			(xy 88.418122 -277.250664) (xy 88.426286 -277.300898) (xy 88.426798 -277.326344) (xy 88.734895 -277.326344)
			(xy 88.73899 -277.275616) (xy 88.751169 -277.226202) (xy 88.771117 -277.179382) (xy 88.798318 -277.136368)
			(xy 88.832066 -277.098274) (xy 88.871488 -277.066087) (xy 88.915562 -277.040641) (xy 88.963148 -277.022594)
			(xy 89.013012 -277.012414) (xy 89.063864 -277.010365) (xy 89.114385 -277.016499) (xy 89.163269 -277.030659)
			(xy 89.209248 -277.052476) (xy 89.251132 -277.081386) (xy 89.287836 -277.116641) (xy 89.318409 -277.157327)
			(xy 89.34206 -277.20239) (xy 89.358176 -277.250664) (xy 89.36634 -277.300898) (xy 89.366852 -277.326344)
			(xy 89.366349 -277.351333) (xy 89.673412 -277.351333) (xy 89.673412 -277.301355) (xy 89.681231 -277.251992)
			(xy 89.696675 -277.20446) (xy 89.719365 -277.159928) (xy 89.748741 -277.119495) (xy 89.784081 -277.084155)
			(xy 89.824514 -277.054779) (xy 89.869046 -277.032089) (xy 89.916578 -277.016645) (xy 89.965941 -277.008826)
			(xy 90.015919 -277.008826) (xy 90.065282 -277.016645) (xy 90.112814 -277.032089) (xy 90.157346 -277.054779)
			(xy 90.197779 -277.084155) (xy 90.233119 -277.119495) (xy 90.262495 -277.159928) (xy 90.285185 -277.20446)
			(xy 90.300629 -277.251992) (xy 90.308448 -277.301355) (xy 90.308938 -277.326344) (xy 90.614749 -277.326344)
			(xy 90.618844 -277.275616) (xy 90.631023 -277.226202) (xy 90.650971 -277.179382) (xy 90.678172 -277.136368)
			(xy 90.71192 -277.098274) (xy 90.751342 -277.066087) (xy 90.795416 -277.040641) (xy 90.843002 -277.022594)
			(xy 90.892866 -277.012414) (xy 90.943718 -277.010365) (xy 90.994239 -277.016499) (xy 91.043123 -277.030659)
			(xy 91.089102 -277.052476) (xy 91.130986 -277.081386) (xy 91.16769 -277.116641) (xy 91.198263 -277.157327)
			(xy 91.221914 -277.20239) (xy 91.23803 -277.250664) (xy 91.246194 -277.300898) (xy 91.246706 -277.326344)
			(xy 91.246194 -277.35179) (xy 91.23803 -277.402024) (xy 91.221914 -277.450298) (xy 91.198263 -277.495361)
			(xy 91.16769 -277.536047) (xy 91.130986 -277.571302) (xy 91.089102 -277.600212) (xy 91.043123 -277.622029)
			(xy 90.994239 -277.636189) (xy 90.943718 -277.642323) (xy 90.892866 -277.640274) (xy 90.843002 -277.630094)
			(xy 90.795416 -277.612047) (xy 90.751342 -277.586601) (xy 90.71192 -277.554414) (xy 90.678172 -277.51632)
			(xy 90.650971 -277.473306) (xy 90.631023 -277.426486) (xy 90.618844 -277.377072) (xy 90.614749 -277.326344)
			(xy 90.308938 -277.326344) (xy 90.308448 -277.351333) (xy 90.300629 -277.400696) (xy 90.285185 -277.448228)
			(xy 90.262495 -277.49276) (xy 90.233119 -277.533193) (xy 90.197779 -277.568533) (xy 90.157346 -277.597909)
			(xy 90.112814 -277.620599) (xy 90.065282 -277.636043) (xy 90.015919 -277.643862) (xy 89.965941 -277.643862)
			(xy 89.916578 -277.636043) (xy 89.869046 -277.620599) (xy 89.824514 -277.597909) (xy 89.784081 -277.568533)
			(xy 89.748741 -277.533193) (xy 89.719365 -277.49276) (xy 89.696675 -277.448228) (xy 89.681231 -277.400696)
			(xy 89.673412 -277.351333) (xy 89.366349 -277.351333) (xy 89.36634 -277.35179) (xy 89.358176 -277.402024)
			(xy 89.34206 -277.450298) (xy 89.318409 -277.495361) (xy 89.287836 -277.536047) (xy 89.251132 -277.571302)
			(xy 89.209248 -277.600212) (xy 89.163269 -277.622029) (xy 89.114385 -277.636189) (xy 89.063864 -277.642323)
			(xy 89.013012 -277.640274) (xy 88.963148 -277.630094) (xy 88.915562 -277.612047) (xy 88.871488 -277.586601)
			(xy 88.832066 -277.554414) (xy 88.798318 -277.51632) (xy 88.771117 -277.473306) (xy 88.751169 -277.426486)
			(xy 88.73899 -277.377072) (xy 88.734895 -277.326344) (xy 88.426798 -277.326344) (xy 88.426286 -277.35179)
			(xy 88.418122 -277.402024) (xy 88.402006 -277.450298) (xy 88.378355 -277.495361) (xy 88.347782 -277.536047)
			(xy 88.311078 -277.571302) (xy 88.269194 -277.600212) (xy 88.223215 -277.622029) (xy 88.174331 -277.636189)
			(xy 88.12381 -277.642323) (xy 88.072958 -277.640274) (xy 88.023094 -277.630094) (xy 87.975508 -277.612047)
			(xy 87.931434 -277.586601) (xy 87.892012 -277.554414) (xy 87.858264 -277.51632) (xy 87.831063 -277.473306)
			(xy 87.811115 -277.426486) (xy 87.798936 -277.377072) (xy 87.794841 -277.326344) (xy 87.48903 -277.326344)
			(xy 87.48854 -277.351333) (xy 87.480721 -277.400696) (xy 87.465277 -277.448228) (xy 87.442587 -277.49276)
			(xy 87.413211 -277.533193) (xy 87.377871 -277.568533) (xy 87.337438 -277.597909) (xy 87.292906 -277.620599)
			(xy 87.245374 -277.636043) (xy 87.196011 -277.643862) (xy 87.146033 -277.643862) (xy 87.09667 -277.636043)
			(xy 87.049138 -277.620599) (xy 87.004606 -277.597909) (xy 86.964173 -277.568533) (xy 86.928833 -277.533193)
			(xy 86.899457 -277.49276) (xy 86.876767 -277.448228) (xy 86.861323 -277.400696) (xy 86.853504 -277.351333)
			(xy 86.546187 -277.351333) (xy 86.546178 -277.35179) (xy 86.538014 -277.402024) (xy 86.521898 -277.450298)
			(xy 86.498247 -277.495361) (xy 86.467674 -277.536047) (xy 86.43097 -277.571302) (xy 86.389086 -277.600212)
			(xy 86.343107 -277.622029) (xy 86.294223 -277.636189) (xy 86.243702 -277.642323) (xy 86.19285 -277.640274)
			(xy 86.142986 -277.630094) (xy 86.0954 -277.612047) (xy 86.051326 -277.586601) (xy 86.011904 -277.554414)
			(xy 85.978156 -277.51632) (xy 85.950955 -277.473306) (xy 85.931007 -277.426486) (xy 85.918828 -277.377072)
			(xy 85.914733 -277.326344) (xy 85.608922 -277.326344) (xy 85.608432 -277.351333) (xy 85.600613 -277.400696)
			(xy 85.585169 -277.448228) (xy 85.562479 -277.49276) (xy 85.533103 -277.533193) (xy 85.497763 -277.568533)
			(xy 85.45733 -277.597909) (xy 85.412798 -277.620599) (xy 85.365266 -277.636043) (xy 85.315903 -277.643862)
			(xy 85.265925 -277.643862) (xy 85.216562 -277.636043) (xy 85.16903 -277.620599) (xy 85.124498 -277.597909)
			(xy 85.084065 -277.568533) (xy 85.048725 -277.533193) (xy 85.019349 -277.49276) (xy 84.996659 -277.448228)
			(xy 84.981215 -277.400696) (xy 84.973396 -277.351333) (xy 84.666333 -277.351333) (xy 84.666324 -277.35179)
			(xy 84.65816 -277.402024) (xy 84.642044 -277.450298) (xy 84.618393 -277.495361) (xy 84.58782 -277.536047)
			(xy 84.551116 -277.571302) (xy 84.509232 -277.600212) (xy 84.463253 -277.622029) (xy 84.414369 -277.636189)
			(xy 84.363848 -277.642323) (xy 84.312996 -277.640274) (xy 84.263132 -277.630094) (xy 84.215546 -277.612047)
			(xy 84.171472 -277.586601) (xy 84.13205 -277.554414) (xy 84.098302 -277.51632) (xy 84.071101 -277.473306)
			(xy 84.051153 -277.426486) (xy 84.038974 -277.377072) (xy 84.034879 -277.326344) (xy 83.729068 -277.326344)
			(xy 83.728578 -277.351333) (xy 83.720759 -277.400696) (xy 83.705315 -277.448228) (xy 83.682625 -277.49276)
			(xy 83.653249 -277.533193) (xy 83.617909 -277.568533) (xy 83.577476 -277.597909) (xy 83.532944 -277.620599)
			(xy 83.485412 -277.636043) (xy 83.436049 -277.643862) (xy 83.386071 -277.643862) (xy 83.336708 -277.636043)
			(xy 83.289176 -277.620599) (xy 83.244644 -277.597909) (xy 83.204211 -277.568533) (xy 83.168871 -277.533193)
			(xy 83.139495 -277.49276) (xy 83.116805 -277.448228) (xy 83.101361 -277.400696) (xy 83.093542 -277.351333)
			(xy 82.786225 -277.351333) (xy 82.786216 -277.35179) (xy 82.778052 -277.402024) (xy 82.761936 -277.450298)
			(xy 82.738285 -277.495361) (xy 82.707712 -277.536047) (xy 82.671008 -277.571302) (xy 82.629124 -277.600212)
			(xy 82.583145 -277.622029) (xy 82.534261 -277.636189) (xy 82.48374 -277.642323) (xy 82.432888 -277.640274)
			(xy 82.383024 -277.630094) (xy 82.335438 -277.612047) (xy 82.291364 -277.586601) (xy 82.251942 -277.554414)
			(xy 82.218194 -277.51632) (xy 82.190993 -277.473306) (xy 82.171045 -277.426486) (xy 82.158866 -277.377072)
			(xy 82.154771 -277.326344) (xy 81.846674 -277.326344) (xy 81.846162 -277.35179) (xy 81.837998 -277.402024)
			(xy 81.821882 -277.450298) (xy 81.798231 -277.495361) (xy 81.767658 -277.536047) (xy 81.730954 -277.571302)
			(xy 81.68907 -277.600212) (xy 81.643091 -277.622029) (xy 81.594207 -277.636189) (xy 81.543686 -277.642323)
			(xy 81.492834 -277.640274) (xy 81.44297 -277.630094) (xy 81.395384 -277.612047) (xy 81.35131 -277.586601)
			(xy 81.311888 -277.554414) (xy 81.27814 -277.51632) (xy 81.250939 -277.473306) (xy 81.230991 -277.426486)
			(xy 81.218812 -277.377072) (xy 81.214717 -277.326344) (xy 80.90916 -277.326344) (xy 80.90867 -277.351333)
			(xy 80.900851 -277.400696) (xy 80.885407 -277.448228) (xy 80.862717 -277.49276) (xy 80.833341 -277.533193)
			(xy 80.798001 -277.568533) (xy 80.757568 -277.597909) (xy 80.713036 -277.620599) (xy 80.665504 -277.636043)
			(xy 80.616141 -277.643862) (xy 80.566163 -277.643862) (xy 80.5168 -277.636043) (xy 80.469268 -277.620599)
			(xy 80.424736 -277.597909) (xy 80.384303 -277.568533) (xy 80.348963 -277.533193) (xy 80.319587 -277.49276)
			(xy 80.296897 -277.448228) (xy 80.281453 -277.400696) (xy 80.273634 -277.351333) (xy 79.53248 -277.351333)
			(xy 79.53248 -278.13635) (xy 80.744817 -278.13635) (xy 80.748912 -278.085622) (xy 80.761091 -278.036208)
			(xy 80.781039 -277.989388) (xy 80.80824 -277.946374) (xy 80.841988 -277.90828) (xy 80.88141 -277.876093)
			(xy 80.925484 -277.850647) (xy 80.97307 -277.8326) (xy 81.022934 -277.82242) (xy 81.073786 -277.820371)
			(xy 81.124307 -277.826505) (xy 81.173191 -277.840665) (xy 81.21917 -277.862482) (xy 81.261054 -277.891392)
			(xy 81.297758 -277.926647) (xy 81.328331 -277.967333) (xy 81.351982 -278.012396) (xy 81.368098 -278.06067)
			(xy 81.376262 -278.110904) (xy 81.376774 -278.13635) (xy 81.376271 -278.161339) (xy 81.683588 -278.161339)
			(xy 81.683588 -278.111361) (xy 81.691407 -278.061998) (xy 81.706851 -278.014466) (xy 81.729541 -277.969934)
			(xy 81.758917 -277.929501) (xy 81.794257 -277.894161) (xy 81.83469 -277.864785) (xy 81.879222 -277.842095)
			(xy 81.926754 -277.826651) (xy 81.976117 -277.818832) (xy 82.026095 -277.818832) (xy 82.075458 -277.826651)
			(xy 82.12299 -277.842095) (xy 82.167522 -277.864785) (xy 82.207955 -277.894161) (xy 82.243295 -277.929501)
			(xy 82.272671 -277.969934) (xy 82.295361 -278.014466) (xy 82.310805 -278.061998) (xy 82.318624 -278.111361)
			(xy 82.319114 -278.13635) (xy 82.624671 -278.13635) (xy 82.628766 -278.085622) (xy 82.640945 -278.036208)
			(xy 82.660893 -277.989388) (xy 82.688094 -277.946374) (xy 82.721842 -277.90828) (xy 82.761264 -277.876093)
			(xy 82.805338 -277.850647) (xy 82.852924 -277.8326) (xy 82.902788 -277.82242) (xy 82.95364 -277.820371)
			(xy 83.004161 -277.826505) (xy 83.053045 -277.840665) (xy 83.099024 -277.862482) (xy 83.140908 -277.891392)
			(xy 83.177612 -277.926647) (xy 83.208185 -277.967333) (xy 83.231836 -278.012396) (xy 83.247952 -278.06067)
			(xy 83.256116 -278.110904) (xy 83.256628 -278.13635) (xy 83.256125 -278.161339) (xy 83.563442 -278.161339)
			(xy 83.563442 -278.111361) (xy 83.571261 -278.061998) (xy 83.586705 -278.014466) (xy 83.609395 -277.969934)
			(xy 83.638771 -277.929501) (xy 83.674111 -277.894161) (xy 83.714544 -277.864785) (xy 83.759076 -277.842095)
			(xy 83.806608 -277.826651) (xy 83.855971 -277.818832) (xy 83.905949 -277.818832) (xy 83.955312 -277.826651)
			(xy 84.002844 -277.842095) (xy 84.047376 -277.864785) (xy 84.087809 -277.894161) (xy 84.123149 -277.929501)
			(xy 84.152525 -277.969934) (xy 84.175215 -278.014466) (xy 84.190659 -278.061998) (xy 84.198478 -278.111361)
			(xy 84.198968 -278.13635) (xy 84.504779 -278.13635) (xy 84.508874 -278.085622) (xy 84.521053 -278.036208)
			(xy 84.541001 -277.989388) (xy 84.568202 -277.946374) (xy 84.60195 -277.90828) (xy 84.641372 -277.876093)
			(xy 84.685446 -277.850647) (xy 84.733032 -277.8326) (xy 84.782896 -277.82242) (xy 84.833748 -277.820371)
			(xy 84.884269 -277.826505) (xy 84.933153 -277.840665) (xy 84.979132 -277.862482) (xy 85.021016 -277.891392)
			(xy 85.05772 -277.926647) (xy 85.088293 -277.967333) (xy 85.111944 -278.012396) (xy 85.12806 -278.06067)
			(xy 85.136224 -278.110904) (xy 85.136736 -278.13635) (xy 85.444833 -278.13635) (xy 85.448928 -278.085622)
			(xy 85.461107 -278.036208) (xy 85.481055 -277.989388) (xy 85.508256 -277.946374) (xy 85.542004 -277.90828)
			(xy 85.581426 -277.876093) (xy 85.6255 -277.850647) (xy 85.673086 -277.8326) (xy 85.72295 -277.82242)
			(xy 85.773802 -277.820371) (xy 85.824323 -277.826505) (xy 85.873207 -277.840665) (xy 85.919186 -277.862482)
			(xy 85.96107 -277.891392) (xy 85.997774 -277.926647) (xy 86.028347 -277.967333) (xy 86.051998 -278.012396)
			(xy 86.068114 -278.06067) (xy 86.076278 -278.110904) (xy 86.07679 -278.13635) (xy 87.324687 -278.13635)
			(xy 87.328782 -278.085622) (xy 87.340961 -278.036208) (xy 87.360909 -277.989388) (xy 87.38811 -277.946374)
			(xy 87.421858 -277.90828) (xy 87.46128 -277.876093) (xy 87.505354 -277.850647) (xy 87.55294 -277.8326)
			(xy 87.602804 -277.82242) (xy 87.653656 -277.820371) (xy 87.704177 -277.826505) (xy 87.753061 -277.840665)
			(xy 87.79904 -277.862482) (xy 87.840924 -277.891392) (xy 87.877628 -277.926647) (xy 87.908201 -277.967333)
			(xy 87.931852 -278.012396) (xy 87.947968 -278.06067) (xy 87.956132 -278.110904) (xy 87.956644 -278.13635)
			(xy 87.956141 -278.161339) (xy 88.263458 -278.161339) (xy 88.263458 -278.111361) (xy 88.271277 -278.061998)
			(xy 88.286721 -278.014466) (xy 88.309411 -277.969934) (xy 88.338787 -277.929501) (xy 88.374127 -277.894161)
			(xy 88.41456 -277.864785) (xy 88.459092 -277.842095) (xy 88.506624 -277.826651) (xy 88.555987 -277.818832)
			(xy 88.605965 -277.818832) (xy 88.655328 -277.826651) (xy 88.70286 -277.842095) (xy 88.747392 -277.864785)
			(xy 88.787825 -277.894161) (xy 88.823165 -277.929501) (xy 88.852541 -277.969934) (xy 88.875231 -278.014466)
			(xy 88.890675 -278.061998) (xy 88.898494 -278.111361) (xy 88.898984 -278.13635) (xy 89.204795 -278.13635)
			(xy 89.20889 -278.085622) (xy 89.221069 -278.036208) (xy 89.241017 -277.989388) (xy 89.268218 -277.946374)
			(xy 89.301966 -277.90828) (xy 89.341388 -277.876093) (xy 89.385462 -277.850647) (xy 89.433048 -277.8326)
			(xy 89.482912 -277.82242) (xy 89.533764 -277.820371) (xy 89.584285 -277.826505) (xy 89.633169 -277.840665)
			(xy 89.679148 -277.862482) (xy 89.721032 -277.891392) (xy 89.757736 -277.926647) (xy 89.788309 -277.967333)
			(xy 89.81196 -278.012396) (xy 89.828076 -278.06067) (xy 89.83624 -278.110904) (xy 89.836752 -278.13635)
			(xy 89.836249 -278.161339) (xy 90.143566 -278.161339) (xy 90.143566 -278.111361) (xy 90.151385 -278.061998)
			(xy 90.166829 -278.014466) (xy 90.189519 -277.969934) (xy 90.218895 -277.929501) (xy 90.254235 -277.894161)
			(xy 90.294668 -277.864785) (xy 90.3392 -277.842095) (xy 90.386732 -277.826651) (xy 90.436095 -277.818832)
			(xy 90.486073 -277.818832) (xy 90.535436 -277.826651) (xy 90.582968 -277.842095) (xy 90.6275 -277.864785)
			(xy 90.667933 -277.894161) (xy 90.703273 -277.929501) (xy 90.732649 -277.969934) (xy 90.755339 -278.014466)
			(xy 90.770783 -278.061998) (xy 90.778602 -278.111361) (xy 90.779092 -278.13635) (xy 90.778602 -278.161339)
			(xy 90.770783 -278.210702) (xy 90.755339 -278.258234) (xy 90.732649 -278.302766) (xy 90.703273 -278.343199)
			(xy 90.667933 -278.378539) (xy 90.6275 -278.407915) (xy 90.582968 -278.430605) (xy 90.535436 -278.446049)
			(xy 90.486073 -278.453868) (xy 90.436095 -278.453868) (xy 90.386732 -278.446049) (xy 90.3392 -278.430605)
			(xy 90.294668 -278.407915) (xy 90.254235 -278.378539) (xy 90.218895 -278.343199) (xy 90.189519 -278.302766)
			(xy 90.166829 -278.258234) (xy 90.151385 -278.210702) (xy 90.143566 -278.161339) (xy 89.836249 -278.161339)
			(xy 89.83624 -278.161796) (xy 89.828076 -278.21203) (xy 89.81196 -278.260304) (xy 89.788309 -278.305367)
			(xy 89.757736 -278.346053) (xy 89.721032 -278.381308) (xy 89.679148 -278.410218) (xy 89.633169 -278.432035)
			(xy 89.584285 -278.446195) (xy 89.533764 -278.452329) (xy 89.482912 -278.45028) (xy 89.433048 -278.4401)
			(xy 89.385462 -278.422053) (xy 89.341388 -278.396607) (xy 89.301966 -278.36442) (xy 89.268218 -278.326326)
			(xy 89.241017 -278.283312) (xy 89.221069 -278.236492) (xy 89.20889 -278.187078) (xy 89.204795 -278.13635)
			(xy 88.898984 -278.13635) (xy 88.898494 -278.161339) (xy 88.890675 -278.210702) (xy 88.875231 -278.258234)
			(xy 88.852541 -278.302766) (xy 88.823165 -278.343199) (xy 88.787825 -278.378539) (xy 88.747392 -278.407915)
			(xy 88.70286 -278.430605) (xy 88.655328 -278.446049) (xy 88.605965 -278.453868) (xy 88.555987 -278.453868)
			(xy 88.506624 -278.446049) (xy 88.459092 -278.430605) (xy 88.41456 -278.407915) (xy 88.374127 -278.378539)
			(xy 88.338787 -278.343199) (xy 88.309411 -278.302766) (xy 88.286721 -278.258234) (xy 88.271277 -278.210702)
			(xy 88.263458 -278.161339) (xy 87.956141 -278.161339) (xy 87.956132 -278.161796) (xy 87.947968 -278.21203)
			(xy 87.931852 -278.260304) (xy 87.908201 -278.305367) (xy 87.877628 -278.346053) (xy 87.840924 -278.381308)
			(xy 87.79904 -278.410218) (xy 87.753061 -278.432035) (xy 87.704177 -278.446195) (xy 87.653656 -278.452329)
			(xy 87.602804 -278.45028) (xy 87.55294 -278.4401) (xy 87.505354 -278.422053) (xy 87.46128 -278.396607)
			(xy 87.421858 -278.36442) (xy 87.38811 -278.326326) (xy 87.360909 -278.283312) (xy 87.340961 -278.236492)
			(xy 87.328782 -278.187078) (xy 87.324687 -278.13635) (xy 86.07679 -278.13635) (xy 86.076278 -278.161796)
			(xy 86.068114 -278.21203) (xy 86.051998 -278.260304) (xy 86.028347 -278.305367) (xy 85.997774 -278.346053)
			(xy 85.96107 -278.381308) (xy 85.919186 -278.410218) (xy 85.873207 -278.432035) (xy 85.824323 -278.446195)
			(xy 85.773802 -278.452329) (xy 85.72295 -278.45028) (xy 85.673086 -278.4401) (xy 85.6255 -278.422053)
			(xy 85.581426 -278.396607) (xy 85.542004 -278.36442) (xy 85.508256 -278.326326) (xy 85.481055 -278.283312)
			(xy 85.461107 -278.236492) (xy 85.448928 -278.187078) (xy 85.444833 -278.13635) (xy 85.136736 -278.13635)
			(xy 85.136224 -278.161796) (xy 85.12806 -278.21203) (xy 85.111944 -278.260304) (xy 85.088293 -278.305367)
			(xy 85.05772 -278.346053) (xy 85.021016 -278.381308) (xy 84.979132 -278.410218) (xy 84.933153 -278.432035)
			(xy 84.884269 -278.446195) (xy 84.833748 -278.452329) (xy 84.782896 -278.45028) (xy 84.733032 -278.4401)
			(xy 84.685446 -278.422053) (xy 84.641372 -278.396607) (xy 84.60195 -278.36442) (xy 84.568202 -278.326326)
			(xy 84.541001 -278.283312) (xy 84.521053 -278.236492) (xy 84.508874 -278.187078) (xy 84.504779 -278.13635)
			(xy 84.198968 -278.13635) (xy 84.198478 -278.161339) (xy 84.190659 -278.210702) (xy 84.175215 -278.258234)
			(xy 84.152525 -278.302766) (xy 84.123149 -278.343199) (xy 84.087809 -278.378539) (xy 84.047376 -278.407915)
			(xy 84.002844 -278.430605) (xy 83.955312 -278.446049) (xy 83.905949 -278.453868) (xy 83.855971 -278.453868)
			(xy 83.806608 -278.446049) (xy 83.759076 -278.430605) (xy 83.714544 -278.407915) (xy 83.674111 -278.378539)
			(xy 83.638771 -278.343199) (xy 83.609395 -278.302766) (xy 83.586705 -278.258234) (xy 83.571261 -278.210702)
			(xy 83.563442 -278.161339) (xy 83.256125 -278.161339) (xy 83.256116 -278.161796) (xy 83.247952 -278.21203)
			(xy 83.231836 -278.260304) (xy 83.208185 -278.305367) (xy 83.177612 -278.346053) (xy 83.140908 -278.381308)
			(xy 83.099024 -278.410218) (xy 83.053045 -278.432035) (xy 83.004161 -278.446195) (xy 82.95364 -278.452329)
			(xy 82.902788 -278.45028) (xy 82.852924 -278.4401) (xy 82.805338 -278.422053) (xy 82.761264 -278.396607)
			(xy 82.721842 -278.36442) (xy 82.688094 -278.326326) (xy 82.660893 -278.283312) (xy 82.640945 -278.236492)
			(xy 82.628766 -278.187078) (xy 82.624671 -278.13635) (xy 82.319114 -278.13635) (xy 82.318624 -278.161339)
			(xy 82.310805 -278.210702) (xy 82.295361 -278.258234) (xy 82.272671 -278.302766) (xy 82.243295 -278.343199)
			(xy 82.207955 -278.378539) (xy 82.167522 -278.407915) (xy 82.12299 -278.430605) (xy 82.075458 -278.446049)
			(xy 82.026095 -278.453868) (xy 81.976117 -278.453868) (xy 81.926754 -278.446049) (xy 81.879222 -278.430605)
			(xy 81.83469 -278.407915) (xy 81.794257 -278.378539) (xy 81.758917 -278.343199) (xy 81.729541 -278.302766)
			(xy 81.706851 -278.258234) (xy 81.691407 -278.210702) (xy 81.683588 -278.161339) (xy 81.376271 -278.161339)
			(xy 81.376262 -278.161796) (xy 81.368098 -278.21203) (xy 81.351982 -278.260304) (xy 81.328331 -278.305367)
			(xy 81.297758 -278.346053) (xy 81.261054 -278.381308) (xy 81.21917 -278.410218) (xy 81.173191 -278.432035)
			(xy 81.124307 -278.446195) (xy 81.073786 -278.452329) (xy 81.022934 -278.45028) (xy 80.97307 -278.4401)
			(xy 80.925484 -278.422053) (xy 80.88141 -278.396607) (xy 80.841988 -278.36442) (xy 80.80824 -278.326326)
			(xy 80.781039 -278.283312) (xy 80.761091 -278.236492) (xy 80.748912 -278.187078) (xy 80.744817 -278.13635)
			(xy 79.53248 -278.13635) (xy 79.53248 -278.971345) (xy 80.273634 -278.971345) (xy 80.273634 -278.921367)
			(xy 80.281453 -278.872004) (xy 80.296897 -278.824472) (xy 80.319587 -278.77994) (xy 80.348963 -278.739507)
			(xy 80.384303 -278.704167) (xy 80.424736 -278.674791) (xy 80.469268 -278.652101) (xy 80.5168 -278.636657)
			(xy 80.566163 -278.628838) (xy 80.616141 -278.628838) (xy 80.665504 -278.636657) (xy 80.713036 -278.652101)
			(xy 80.757568 -278.674791) (xy 80.798001 -278.704167) (xy 80.833341 -278.739507) (xy 80.862717 -278.77994)
			(xy 80.885407 -278.824472) (xy 80.900851 -278.872004) (xy 80.90867 -278.921367) (xy 80.90916 -278.946356)
			(xy 81.214717 -278.946356) (xy 81.218812 -278.895628) (xy 81.230991 -278.846214) (xy 81.250939 -278.799394)
			(xy 81.27814 -278.75638) (xy 81.311888 -278.718286) (xy 81.35131 -278.686099) (xy 81.395384 -278.660653)
			(xy 81.44297 -278.642606) (xy 81.492834 -278.632426) (xy 81.543686 -278.630377) (xy 81.594207 -278.636511)
			(xy 81.643091 -278.650671) (xy 81.68907 -278.672488) (xy 81.730954 -278.701398) (xy 81.767658 -278.736653)
			(xy 81.798231 -278.777339) (xy 81.821882 -278.822402) (xy 81.837998 -278.870676) (xy 81.846162 -278.92091)
			(xy 81.846674 -278.946356) (xy 82.154771 -278.946356) (xy 82.158866 -278.895628) (xy 82.171045 -278.846214)
			(xy 82.190993 -278.799394) (xy 82.218194 -278.75638) (xy 82.251942 -278.718286) (xy 82.291364 -278.686099)
			(xy 82.335438 -278.660653) (xy 82.383024 -278.642606) (xy 82.432888 -278.632426) (xy 82.48374 -278.630377)
			(xy 82.534261 -278.636511) (xy 82.583145 -278.650671) (xy 82.629124 -278.672488) (xy 82.671008 -278.701398)
			(xy 82.707712 -278.736653) (xy 82.738285 -278.777339) (xy 82.761936 -278.822402) (xy 82.778052 -278.870676)
			(xy 82.786216 -278.92091) (xy 82.786728 -278.946356) (xy 82.786225 -278.971345) (xy 83.093542 -278.971345)
			(xy 83.093542 -278.921367) (xy 83.101361 -278.872004) (xy 83.116805 -278.824472) (xy 83.139495 -278.77994)
			(xy 83.168871 -278.739507) (xy 83.204211 -278.704167) (xy 83.244644 -278.674791) (xy 83.289176 -278.652101)
			(xy 83.336708 -278.636657) (xy 83.386071 -278.628838) (xy 83.436049 -278.628838) (xy 83.485412 -278.636657)
			(xy 83.532944 -278.652101) (xy 83.577476 -278.674791) (xy 83.617909 -278.704167) (xy 83.653249 -278.739507)
			(xy 83.682625 -278.77994) (xy 83.705315 -278.824472) (xy 83.720759 -278.872004) (xy 83.728578 -278.921367)
			(xy 83.729068 -278.946356) (xy 84.034879 -278.946356) (xy 84.038974 -278.895628) (xy 84.051153 -278.846214)
			(xy 84.071101 -278.799394) (xy 84.098302 -278.75638) (xy 84.13205 -278.718286) (xy 84.171472 -278.686099)
			(xy 84.215546 -278.660653) (xy 84.263132 -278.642606) (xy 84.312996 -278.632426) (xy 84.363848 -278.630377)
			(xy 84.414369 -278.636511) (xy 84.463253 -278.650671) (xy 84.509232 -278.672488) (xy 84.551116 -278.701398)
			(xy 84.58782 -278.736653) (xy 84.618393 -278.777339) (xy 84.642044 -278.822402) (xy 84.65816 -278.870676)
			(xy 84.666324 -278.92091) (xy 84.666836 -278.946356) (xy 84.666333 -278.971345) (xy 84.973396 -278.971345)
			(xy 84.973396 -278.921367) (xy 84.981215 -278.872004) (xy 84.996659 -278.824472) (xy 85.019349 -278.77994)
			(xy 85.048725 -278.739507) (xy 85.084065 -278.704167) (xy 85.124498 -278.674791) (xy 85.16903 -278.652101)
			(xy 85.216562 -278.636657) (xy 85.265925 -278.628838) (xy 85.315903 -278.628838) (xy 85.365266 -278.636657)
			(xy 85.412798 -278.652101) (xy 85.45733 -278.674791) (xy 85.497763 -278.704167) (xy 85.533103 -278.739507)
			(xy 85.562479 -278.77994) (xy 85.585169 -278.824472) (xy 85.600613 -278.872004) (xy 85.608432 -278.921367)
			(xy 85.608922 -278.946356) (xy 85.914733 -278.946356) (xy 85.918828 -278.895628) (xy 85.931007 -278.846214)
			(xy 85.950955 -278.799394) (xy 85.978156 -278.75638) (xy 86.011904 -278.718286) (xy 86.051326 -278.686099)
			(xy 86.0954 -278.660653) (xy 86.142986 -278.642606) (xy 86.19285 -278.632426) (xy 86.243702 -278.630377)
			(xy 86.294223 -278.636511) (xy 86.343107 -278.650671) (xy 86.389086 -278.672488) (xy 86.43097 -278.701398)
			(xy 86.467674 -278.736653) (xy 86.498247 -278.777339) (xy 86.521898 -278.822402) (xy 86.538014 -278.870676)
			(xy 86.546178 -278.92091) (xy 86.54669 -278.946356) (xy 86.546187 -278.971345) (xy 86.853504 -278.971345)
			(xy 86.853504 -278.921367) (xy 86.861323 -278.872004) (xy 86.876767 -278.824472) (xy 86.899457 -278.77994)
			(xy 86.928833 -278.739507) (xy 86.964173 -278.704167) (xy 87.004606 -278.674791) (xy 87.049138 -278.652101)
			(xy 87.09667 -278.636657) (xy 87.146033 -278.628838) (xy 87.196011 -278.628838) (xy 87.245374 -278.636657)
			(xy 87.292906 -278.652101) (xy 87.337438 -278.674791) (xy 87.377871 -278.704167) (xy 87.413211 -278.739507)
			(xy 87.442587 -278.77994) (xy 87.465277 -278.824472) (xy 87.480721 -278.872004) (xy 87.48854 -278.921367)
			(xy 87.48903 -278.946356) (xy 87.794841 -278.946356) (xy 87.798936 -278.895628) (xy 87.811115 -278.846214)
			(xy 87.831063 -278.799394) (xy 87.858264 -278.75638) (xy 87.892012 -278.718286) (xy 87.931434 -278.686099)
			(xy 87.975508 -278.660653) (xy 88.023094 -278.642606) (xy 88.072958 -278.632426) (xy 88.12381 -278.630377)
			(xy 88.174331 -278.636511) (xy 88.223215 -278.650671) (xy 88.269194 -278.672488) (xy 88.311078 -278.701398)
			(xy 88.347782 -278.736653) (xy 88.378355 -278.777339) (xy 88.402006 -278.822402) (xy 88.418122 -278.870676)
			(xy 88.426286 -278.92091) (xy 88.426798 -278.946356) (xy 88.734895 -278.946356) (xy 88.73899 -278.895628)
			(xy 88.751169 -278.846214) (xy 88.771117 -278.799394) (xy 88.798318 -278.75638) (xy 88.832066 -278.718286)
			(xy 88.871488 -278.686099) (xy 88.915562 -278.660653) (xy 88.963148 -278.642606) (xy 89.013012 -278.632426)
			(xy 89.063864 -278.630377) (xy 89.114385 -278.636511) (xy 89.163269 -278.650671) (xy 89.209248 -278.672488)
			(xy 89.251132 -278.701398) (xy 89.287836 -278.736653) (xy 89.318409 -278.777339) (xy 89.34206 -278.822402)
			(xy 89.358176 -278.870676) (xy 89.36634 -278.92091) (xy 89.366852 -278.946356) (xy 89.366349 -278.971345)
			(xy 89.673412 -278.971345) (xy 89.673412 -278.921367) (xy 89.681231 -278.872004) (xy 89.696675 -278.824472)
			(xy 89.719365 -278.77994) (xy 89.748741 -278.739507) (xy 89.784081 -278.704167) (xy 89.824514 -278.674791)
			(xy 89.869046 -278.652101) (xy 89.916578 -278.636657) (xy 89.965941 -278.628838) (xy 90.015919 -278.628838)
			(xy 90.065282 -278.636657) (xy 90.112814 -278.652101) (xy 90.157346 -278.674791) (xy 90.197779 -278.704167)
			(xy 90.233119 -278.739507) (xy 90.262495 -278.77994) (xy 90.285185 -278.824472) (xy 90.300629 -278.872004)
			(xy 90.308448 -278.921367) (xy 90.308938 -278.946356) (xy 90.308448 -278.971345) (xy 90.300629 -279.020708)
			(xy 90.285185 -279.06824) (xy 90.262495 -279.112772) (xy 90.233119 -279.153205) (xy 90.197779 -279.188545)
			(xy 90.157346 -279.217921) (xy 90.112814 -279.240611) (xy 90.065282 -279.256055) (xy 90.015919 -279.263874)
			(xy 89.965941 -279.263874) (xy 89.916578 -279.256055) (xy 89.869046 -279.240611) (xy 89.824514 -279.217921)
			(xy 89.784081 -279.188545) (xy 89.748741 -279.153205) (xy 89.719365 -279.112772) (xy 89.696675 -279.06824)
			(xy 89.681231 -279.020708) (xy 89.673412 -278.971345) (xy 89.366349 -278.971345) (xy 89.36634 -278.971802)
			(xy 89.358176 -279.022036) (xy 89.34206 -279.07031) (xy 89.318409 -279.115373) (xy 89.287836 -279.156059)
			(xy 89.251132 -279.191314) (xy 89.209248 -279.220224) (xy 89.163269 -279.242041) (xy 89.114385 -279.256201)
			(xy 89.063864 -279.262335) (xy 89.013012 -279.260286) (xy 88.963148 -279.250106) (xy 88.915562 -279.232059)
			(xy 88.871488 -279.206613) (xy 88.832066 -279.174426) (xy 88.798318 -279.136332) (xy 88.771117 -279.093318)
			(xy 88.751169 -279.046498) (xy 88.73899 -278.997084) (xy 88.734895 -278.946356) (xy 88.426798 -278.946356)
			(xy 88.426286 -278.971802) (xy 88.418122 -279.022036) (xy 88.402006 -279.07031) (xy 88.378355 -279.115373)
			(xy 88.347782 -279.156059) (xy 88.311078 -279.191314) (xy 88.269194 -279.220224) (xy 88.223215 -279.242041)
			(xy 88.174331 -279.256201) (xy 88.12381 -279.262335) (xy 88.072958 -279.260286) (xy 88.023094 -279.250106)
			(xy 87.975508 -279.232059) (xy 87.931434 -279.206613) (xy 87.892012 -279.174426) (xy 87.858264 -279.136332)
			(xy 87.831063 -279.093318) (xy 87.811115 -279.046498) (xy 87.798936 -278.997084) (xy 87.794841 -278.946356)
			(xy 87.48903 -278.946356) (xy 87.48854 -278.971345) (xy 87.480721 -279.020708) (xy 87.465277 -279.06824)
			(xy 87.442587 -279.112772) (xy 87.413211 -279.153205) (xy 87.377871 -279.188545) (xy 87.337438 -279.217921)
			(xy 87.292906 -279.240611) (xy 87.245374 -279.256055) (xy 87.196011 -279.263874) (xy 87.146033 -279.263874)
			(xy 87.09667 -279.256055) (xy 87.049138 -279.240611) (xy 87.004606 -279.217921) (xy 86.964173 -279.188545)
			(xy 86.928833 -279.153205) (xy 86.899457 -279.112772) (xy 86.876767 -279.06824) (xy 86.861323 -279.020708)
			(xy 86.853504 -278.971345) (xy 86.546187 -278.971345) (xy 86.546178 -278.971802) (xy 86.538014 -279.022036)
			(xy 86.521898 -279.07031) (xy 86.498247 -279.115373) (xy 86.467674 -279.156059) (xy 86.43097 -279.191314)
			(xy 86.389086 -279.220224) (xy 86.343107 -279.242041) (xy 86.294223 -279.256201) (xy 86.243702 -279.262335)
			(xy 86.19285 -279.260286) (xy 86.142986 -279.250106) (xy 86.0954 -279.232059) (xy 86.051326 -279.206613)
			(xy 86.011904 -279.174426) (xy 85.978156 -279.136332) (xy 85.950955 -279.093318) (xy 85.931007 -279.046498)
			(xy 85.918828 -278.997084) (xy 85.914733 -278.946356) (xy 85.608922 -278.946356) (xy 85.608432 -278.971345)
			(xy 85.600613 -279.020708) (xy 85.585169 -279.06824) (xy 85.562479 -279.112772) (xy 85.533103 -279.153205)
			(xy 85.497763 -279.188545) (xy 85.45733 -279.217921) (xy 85.412798 -279.240611) (xy 85.365266 -279.256055)
			(xy 85.315903 -279.263874) (xy 85.265925 -279.263874) (xy 85.216562 -279.256055) (xy 85.16903 -279.240611)
			(xy 85.124498 -279.217921) (xy 85.084065 -279.188545) (xy 85.048725 -279.153205) (xy 85.019349 -279.112772)
			(xy 84.996659 -279.06824) (xy 84.981215 -279.020708) (xy 84.973396 -278.971345) (xy 84.666333 -278.971345)
			(xy 84.666324 -278.971802) (xy 84.65816 -279.022036) (xy 84.642044 -279.07031) (xy 84.618393 -279.115373)
			(xy 84.58782 -279.156059) (xy 84.551116 -279.191314) (xy 84.509232 -279.220224) (xy 84.463253 -279.242041)
			(xy 84.414369 -279.256201) (xy 84.363848 -279.262335) (xy 84.312996 -279.260286) (xy 84.263132 -279.250106)
			(xy 84.215546 -279.232059) (xy 84.171472 -279.206613) (xy 84.13205 -279.174426) (xy 84.098302 -279.136332)
			(xy 84.071101 -279.093318) (xy 84.051153 -279.046498) (xy 84.038974 -278.997084) (xy 84.034879 -278.946356)
			(xy 83.729068 -278.946356) (xy 83.728578 -278.971345) (xy 83.720759 -279.020708) (xy 83.705315 -279.06824)
			(xy 83.682625 -279.112772) (xy 83.653249 -279.153205) (xy 83.617909 -279.188545) (xy 83.577476 -279.217921)
			(xy 83.532944 -279.240611) (xy 83.485412 -279.256055) (xy 83.436049 -279.263874) (xy 83.386071 -279.263874)
			(xy 83.336708 -279.256055) (xy 83.289176 -279.240611) (xy 83.244644 -279.217921) (xy 83.204211 -279.188545)
			(xy 83.168871 -279.153205) (xy 83.139495 -279.112772) (xy 83.116805 -279.06824) (xy 83.101361 -279.020708)
			(xy 83.093542 -278.971345) (xy 82.786225 -278.971345) (xy 82.786216 -278.971802) (xy 82.778052 -279.022036)
			(xy 82.761936 -279.07031) (xy 82.738285 -279.115373) (xy 82.707712 -279.156059) (xy 82.671008 -279.191314)
			(xy 82.629124 -279.220224) (xy 82.583145 -279.242041) (xy 82.534261 -279.256201) (xy 82.48374 -279.262335)
			(xy 82.432888 -279.260286) (xy 82.383024 -279.250106) (xy 82.335438 -279.232059) (xy 82.291364 -279.206613)
			(xy 82.251942 -279.174426) (xy 82.218194 -279.136332) (xy 82.190993 -279.093318) (xy 82.171045 -279.046498)
			(xy 82.158866 -278.997084) (xy 82.154771 -278.946356) (xy 81.846674 -278.946356) (xy 81.846162 -278.971802)
			(xy 81.837998 -279.022036) (xy 81.821882 -279.07031) (xy 81.798231 -279.115373) (xy 81.767658 -279.156059)
			(xy 81.730954 -279.191314) (xy 81.68907 -279.220224) (xy 81.643091 -279.242041) (xy 81.594207 -279.256201)
			(xy 81.543686 -279.262335) (xy 81.492834 -279.260286) (xy 81.44297 -279.250106) (xy 81.395384 -279.232059)
			(xy 81.35131 -279.206613) (xy 81.311888 -279.174426) (xy 81.27814 -279.136332) (xy 81.250939 -279.093318)
			(xy 81.230991 -279.046498) (xy 81.218812 -278.997084) (xy 81.214717 -278.946356) (xy 80.90916 -278.946356)
			(xy 80.90867 -278.971345) (xy 80.900851 -279.020708) (xy 80.885407 -279.06824) (xy 80.862717 -279.112772)
			(xy 80.833341 -279.153205) (xy 80.798001 -279.188545) (xy 80.757568 -279.217921) (xy 80.713036 -279.240611)
			(xy 80.665504 -279.256055) (xy 80.616141 -279.263874) (xy 80.566163 -279.263874) (xy 80.5168 -279.256055)
			(xy 80.469268 -279.240611) (xy 80.424736 -279.217921) (xy 80.384303 -279.188545) (xy 80.348963 -279.153205)
			(xy 80.319587 -279.112772) (xy 80.296897 -279.06824) (xy 80.281453 -279.020708) (xy 80.273634 -278.971345)
			(xy 79.53248 -278.971345) (xy 79.53248 -279.781351) (xy 79.80348 -279.781351) (xy 79.80348 -279.731373)
			(xy 79.811299 -279.68201) (xy 79.826743 -279.634478) (xy 79.849433 -279.589946) (xy 79.878809 -279.549513)
			(xy 79.914149 -279.514173) (xy 79.954582 -279.484797) (xy 79.999114 -279.462107) (xy 80.046646 -279.446663)
			(xy 80.096009 -279.438844) (xy 80.145987 -279.438844) (xy 80.19535 -279.446663) (xy 80.242882 -279.462107)
			(xy 80.287414 -279.484797) (xy 80.327847 -279.514173) (xy 80.363187 -279.549513) (xy 80.392563 -279.589946)
			(xy 80.415253 -279.634478) (xy 80.430697 -279.68201) (xy 80.438516 -279.731373) (xy 80.439006 -279.756362)
			(xy 80.744817 -279.756362) (xy 80.748912 -279.705634) (xy 80.761091 -279.65622) (xy 80.781039 -279.6094)
			(xy 80.80824 -279.566386) (xy 80.841988 -279.528292) (xy 80.88141 -279.496105) (xy 80.925484 -279.470659)
			(xy 80.97307 -279.452612) (xy 81.022934 -279.442432) (xy 81.073786 -279.440383) (xy 81.124307 -279.446517)
			(xy 81.173191 -279.460677) (xy 81.21917 -279.482494) (xy 81.261054 -279.511404) (xy 81.297758 -279.546659)
			(xy 81.328331 -279.587345) (xy 81.351982 -279.632408) (xy 81.368098 -279.680682) (xy 81.376262 -279.730916)
			(xy 81.376774 -279.756362) (xy 81.376271 -279.781351) (xy 81.683588 -279.781351) (xy 81.683588 -279.731373)
			(xy 81.691407 -279.68201) (xy 81.706851 -279.634478) (xy 81.729541 -279.589946) (xy 81.758917 -279.549513)
			(xy 81.794257 -279.514173) (xy 81.83469 -279.484797) (xy 81.879222 -279.462107) (xy 81.926754 -279.446663)
			(xy 81.976117 -279.438844) (xy 82.026095 -279.438844) (xy 82.075458 -279.446663) (xy 82.12299 -279.462107)
			(xy 82.167522 -279.484797) (xy 82.207955 -279.514173) (xy 82.243295 -279.549513) (xy 82.272671 -279.589946)
			(xy 82.295361 -279.634478) (xy 82.310805 -279.68201) (xy 82.318624 -279.731373) (xy 82.319114 -279.756362)
			(xy 82.624671 -279.756362) (xy 82.628766 -279.705634) (xy 82.640945 -279.65622) (xy 82.660893 -279.6094)
			(xy 82.688094 -279.566386) (xy 82.721842 -279.528292) (xy 82.761264 -279.496105) (xy 82.805338 -279.470659)
			(xy 82.852924 -279.452612) (xy 82.902788 -279.442432) (xy 82.95364 -279.440383) (xy 83.004161 -279.446517)
			(xy 83.053045 -279.460677) (xy 83.099024 -279.482494) (xy 83.140908 -279.511404) (xy 83.177612 -279.546659)
			(xy 83.208185 -279.587345) (xy 83.231836 -279.632408) (xy 83.247952 -279.680682) (xy 83.256116 -279.730916)
			(xy 83.256628 -279.756362) (xy 83.256125 -279.781351) (xy 83.563442 -279.781351) (xy 83.563442 -279.731373)
			(xy 83.571261 -279.68201) (xy 83.586705 -279.634478) (xy 83.609395 -279.589946) (xy 83.638771 -279.549513)
			(xy 83.674111 -279.514173) (xy 83.714544 -279.484797) (xy 83.759076 -279.462107) (xy 83.806608 -279.446663)
			(xy 83.855971 -279.438844) (xy 83.905949 -279.438844) (xy 83.955312 -279.446663) (xy 84.002844 -279.462107)
			(xy 84.047376 -279.484797) (xy 84.087809 -279.514173) (xy 84.123149 -279.549513) (xy 84.152525 -279.589946)
			(xy 84.175215 -279.634478) (xy 84.190659 -279.68201) (xy 84.198478 -279.731373) (xy 84.198968 -279.756362)
			(xy 84.504779 -279.756362) (xy 84.508874 -279.705634) (xy 84.521053 -279.65622) (xy 84.541001 -279.6094)
			(xy 84.568202 -279.566386) (xy 84.60195 -279.528292) (xy 84.641372 -279.496105) (xy 84.685446 -279.470659)
			(xy 84.733032 -279.452612) (xy 84.782896 -279.442432) (xy 84.833748 -279.440383) (xy 84.884269 -279.446517)
			(xy 84.933153 -279.460677) (xy 84.979132 -279.482494) (xy 85.021016 -279.511404) (xy 85.05772 -279.546659)
			(xy 85.088293 -279.587345) (xy 85.111944 -279.632408) (xy 85.12806 -279.680682) (xy 85.136224 -279.730916)
			(xy 85.136736 -279.756362) (xy 85.444833 -279.756362) (xy 85.448928 -279.705634) (xy 85.461107 -279.65622)
			(xy 85.481055 -279.6094) (xy 85.508256 -279.566386) (xy 85.542004 -279.528292) (xy 85.581426 -279.496105)
			(xy 85.6255 -279.470659) (xy 85.673086 -279.452612) (xy 85.72295 -279.442432) (xy 85.773802 -279.440383)
			(xy 85.824323 -279.446517) (xy 85.873207 -279.460677) (xy 85.919186 -279.482494) (xy 85.96107 -279.511404)
			(xy 85.997774 -279.546659) (xy 86.028347 -279.587345) (xy 86.051998 -279.632408) (xy 86.068114 -279.680682)
			(xy 86.076278 -279.730916) (xy 86.07679 -279.756362) (xy 86.076287 -279.781351) (xy 86.383604 -279.781351)
			(xy 86.383604 -279.731373) (xy 86.391423 -279.68201) (xy 86.406867 -279.634478) (xy 86.429557 -279.589946)
			(xy 86.458933 -279.549513) (xy 86.494273 -279.514173) (xy 86.534706 -279.484797) (xy 86.579238 -279.462107)
			(xy 86.62677 -279.446663) (xy 86.676133 -279.438844) (xy 86.726111 -279.438844) (xy 86.775474 -279.446663)
			(xy 86.823006 -279.462107) (xy 86.867538 -279.484797) (xy 86.907971 -279.514173) (xy 86.943311 -279.549513)
			(xy 86.972687 -279.589946) (xy 86.995377 -279.634478) (xy 87.010821 -279.68201) (xy 87.01864 -279.731373)
			(xy 87.01913 -279.756362) (xy 87.324687 -279.756362) (xy 87.328782 -279.705634) (xy 87.340961 -279.65622)
			(xy 87.360909 -279.6094) (xy 87.38811 -279.566386) (xy 87.421858 -279.528292) (xy 87.46128 -279.496105)
			(xy 87.505354 -279.470659) (xy 87.55294 -279.452612) (xy 87.602804 -279.442432) (xy 87.653656 -279.440383)
			(xy 87.704177 -279.446517) (xy 87.753061 -279.460677) (xy 87.79904 -279.482494) (xy 87.840924 -279.511404)
			(xy 87.877628 -279.546659) (xy 87.908201 -279.587345) (xy 87.931852 -279.632408) (xy 87.947968 -279.680682)
			(xy 87.956132 -279.730916) (xy 87.956644 -279.756362) (xy 87.956141 -279.781351) (xy 88.263458 -279.781351)
			(xy 88.263458 -279.731373) (xy 88.271277 -279.68201) (xy 88.286721 -279.634478) (xy 88.309411 -279.589946)
			(xy 88.338787 -279.549513) (xy 88.374127 -279.514173) (xy 88.41456 -279.484797) (xy 88.459092 -279.462107)
			(xy 88.506624 -279.446663) (xy 88.555987 -279.438844) (xy 88.605965 -279.438844) (xy 88.655328 -279.446663)
			(xy 88.70286 -279.462107) (xy 88.747392 -279.484797) (xy 88.787825 -279.514173) (xy 88.823165 -279.549513)
			(xy 88.852541 -279.589946) (xy 88.875231 -279.634478) (xy 88.890675 -279.68201) (xy 88.898494 -279.731373)
			(xy 88.898984 -279.756362) (xy 89.204795 -279.756362) (xy 89.20889 -279.705634) (xy 89.221069 -279.65622)
			(xy 89.241017 -279.6094) (xy 89.268218 -279.566386) (xy 89.301966 -279.528292) (xy 89.341388 -279.496105)
			(xy 89.385462 -279.470659) (xy 89.433048 -279.452612) (xy 89.482912 -279.442432) (xy 89.533764 -279.440383)
			(xy 89.584285 -279.446517) (xy 89.633169 -279.460677) (xy 89.679148 -279.482494) (xy 89.721032 -279.511404)
			(xy 89.757736 -279.546659) (xy 89.788309 -279.587345) (xy 89.81196 -279.632408) (xy 89.828076 -279.680682)
			(xy 89.83624 -279.730916) (xy 89.836752 -279.756362) (xy 89.83624 -279.781808) (xy 89.828076 -279.832042)
			(xy 89.81196 -279.880316) (xy 89.788309 -279.925379) (xy 89.757736 -279.966065) (xy 89.721032 -280.00132)
			(xy 89.679148 -280.03023) (xy 89.633169 -280.052047) (xy 89.584285 -280.066207) (xy 89.533764 -280.072341)
			(xy 89.482912 -280.070292) (xy 89.433048 -280.060112) (xy 89.385462 -280.042065) (xy 89.341388 -280.016619)
			(xy 89.301966 -279.984432) (xy 89.268218 -279.946338) (xy 89.241017 -279.903324) (xy 89.221069 -279.856504)
			(xy 89.20889 -279.80709) (xy 89.204795 -279.756362) (xy 88.898984 -279.756362) (xy 88.898494 -279.781351)
			(xy 88.890675 -279.830714) (xy 88.875231 -279.878246) (xy 88.852541 -279.922778) (xy 88.823165 -279.963211)
			(xy 88.787825 -279.998551) (xy 88.747392 -280.027927) (xy 88.70286 -280.050617) (xy 88.655328 -280.066061)
			(xy 88.605965 -280.07388) (xy 88.555987 -280.07388) (xy 88.506624 -280.066061) (xy 88.459092 -280.050617)
			(xy 88.41456 -280.027927) (xy 88.374127 -279.998551) (xy 88.338787 -279.963211) (xy 88.309411 -279.922778)
			(xy 88.286721 -279.878246) (xy 88.271277 -279.830714) (xy 88.263458 -279.781351) (xy 87.956141 -279.781351)
			(xy 87.956132 -279.781808) (xy 87.947968 -279.832042) (xy 87.931852 -279.880316) (xy 87.908201 -279.925379)
			(xy 87.877628 -279.966065) (xy 87.840924 -280.00132) (xy 87.79904 -280.03023) (xy 87.753061 -280.052047)
			(xy 87.704177 -280.066207) (xy 87.653656 -280.072341) (xy 87.602804 -280.070292) (xy 87.55294 -280.060112)
			(xy 87.505354 -280.042065) (xy 87.46128 -280.016619) (xy 87.421858 -279.984432) (xy 87.38811 -279.946338)
			(xy 87.360909 -279.903324) (xy 87.340961 -279.856504) (xy 87.328782 -279.80709) (xy 87.324687 -279.756362)
			(xy 87.01913 -279.756362) (xy 87.01864 -279.781351) (xy 87.010821 -279.830714) (xy 86.995377 -279.878246)
			(xy 86.972687 -279.922778) (xy 86.943311 -279.963211) (xy 86.907971 -279.998551) (xy 86.867538 -280.027927)
			(xy 86.823006 -280.050617) (xy 86.775474 -280.066061) (xy 86.726111 -280.07388) (xy 86.676133 -280.07388)
			(xy 86.62677 -280.066061) (xy 86.579238 -280.050617) (xy 86.534706 -280.027927) (xy 86.494273 -279.998551)
			(xy 86.458933 -279.963211) (xy 86.429557 -279.922778) (xy 86.406867 -279.878246) (xy 86.391423 -279.830714)
			(xy 86.383604 -279.781351) (xy 86.076287 -279.781351) (xy 86.076278 -279.781808) (xy 86.068114 -279.832042)
			(xy 86.051998 -279.880316) (xy 86.028347 -279.925379) (xy 85.997774 -279.966065) (xy 85.96107 -280.00132)
			(xy 85.919186 -280.03023) (xy 85.873207 -280.052047) (xy 85.824323 -280.066207) (xy 85.773802 -280.072341)
			(xy 85.72295 -280.070292) (xy 85.673086 -280.060112) (xy 85.6255 -280.042065) (xy 85.581426 -280.016619)
			(xy 85.542004 -279.984432) (xy 85.508256 -279.946338) (xy 85.481055 -279.903324) (xy 85.461107 -279.856504)
			(xy 85.448928 -279.80709) (xy 85.444833 -279.756362) (xy 85.136736 -279.756362) (xy 85.136224 -279.781808)
			(xy 85.12806 -279.832042) (xy 85.111944 -279.880316) (xy 85.088293 -279.925379) (xy 85.05772 -279.966065)
			(xy 85.021016 -280.00132) (xy 84.979132 -280.03023) (xy 84.933153 -280.052047) (xy 84.884269 -280.066207)
			(xy 84.833748 -280.072341) (xy 84.782896 -280.070292) (xy 84.733032 -280.060112) (xy 84.685446 -280.042065)
			(xy 84.641372 -280.016619) (xy 84.60195 -279.984432) (xy 84.568202 -279.946338) (xy 84.541001 -279.903324)
			(xy 84.521053 -279.856504) (xy 84.508874 -279.80709) (xy 84.504779 -279.756362) (xy 84.198968 -279.756362)
			(xy 84.198478 -279.781351) (xy 84.190659 -279.830714) (xy 84.175215 -279.878246) (xy 84.152525 -279.922778)
			(xy 84.123149 -279.963211) (xy 84.087809 -279.998551) (xy 84.047376 -280.027927) (xy 84.002844 -280.050617)
			(xy 83.955312 -280.066061) (xy 83.905949 -280.07388) (xy 83.855971 -280.07388) (xy 83.806608 -280.066061)
			(xy 83.759076 -280.050617) (xy 83.714544 -280.027927) (xy 83.674111 -279.998551) (xy 83.638771 -279.963211)
			(xy 83.609395 -279.922778) (xy 83.586705 -279.878246) (xy 83.571261 -279.830714) (xy 83.563442 -279.781351)
			(xy 83.256125 -279.781351) (xy 83.256116 -279.781808) (xy 83.247952 -279.832042) (xy 83.231836 -279.880316)
			(xy 83.208185 -279.925379) (xy 83.177612 -279.966065) (xy 83.140908 -280.00132) (xy 83.099024 -280.03023)
			(xy 83.053045 -280.052047) (xy 83.004161 -280.066207) (xy 82.95364 -280.072341) (xy 82.902788 -280.070292)
			(xy 82.852924 -280.060112) (xy 82.805338 -280.042065) (xy 82.761264 -280.016619) (xy 82.721842 -279.984432)
			(xy 82.688094 -279.946338) (xy 82.660893 -279.903324) (xy 82.640945 -279.856504) (xy 82.628766 -279.80709)
			(xy 82.624671 -279.756362) (xy 82.319114 -279.756362) (xy 82.318624 -279.781351) (xy 82.310805 -279.830714)
			(xy 82.295361 -279.878246) (xy 82.272671 -279.922778) (xy 82.243295 -279.963211) (xy 82.207955 -279.998551)
			(xy 82.167522 -280.027927) (xy 82.12299 -280.050617) (xy 82.075458 -280.066061) (xy 82.026095 -280.07388)
			(xy 81.976117 -280.07388) (xy 81.926754 -280.066061) (xy 81.879222 -280.050617) (xy 81.83469 -280.027927)
			(xy 81.794257 -279.998551) (xy 81.758917 -279.963211) (xy 81.729541 -279.922778) (xy 81.706851 -279.878246)
			(xy 81.691407 -279.830714) (xy 81.683588 -279.781351) (xy 81.376271 -279.781351) (xy 81.376262 -279.781808)
			(xy 81.368098 -279.832042) (xy 81.351982 -279.880316) (xy 81.328331 -279.925379) (xy 81.297758 -279.966065)
			(xy 81.261054 -280.00132) (xy 81.21917 -280.03023) (xy 81.173191 -280.052047) (xy 81.124307 -280.066207)
			(xy 81.073786 -280.072341) (xy 81.022934 -280.070292) (xy 80.97307 -280.060112) (xy 80.925484 -280.042065)
			(xy 80.88141 -280.016619) (xy 80.841988 -279.984432) (xy 80.80824 -279.946338) (xy 80.781039 -279.903324)
			(xy 80.761091 -279.856504) (xy 80.748912 -279.80709) (xy 80.744817 -279.756362) (xy 80.439006 -279.756362)
			(xy 80.438516 -279.781351) (xy 80.430697 -279.830714) (xy 80.415253 -279.878246) (xy 80.392563 -279.922778)
			(xy 80.363187 -279.963211) (xy 80.327847 -279.998551) (xy 80.287414 -280.027927) (xy 80.242882 -280.050617)
			(xy 80.19535 -280.066061) (xy 80.145987 -280.07388) (xy 80.096009 -280.07388) (xy 80.046646 -280.066061)
			(xy 79.999114 -280.050617) (xy 79.954582 -280.027927) (xy 79.914149 -279.998551) (xy 79.878809 -279.963211)
			(xy 79.849433 -279.922778) (xy 79.826743 -279.878246) (xy 79.811299 -279.830714) (xy 79.80348 -279.781351)
			(xy 79.53248 -279.781351) (xy 79.53248 -280.566368) (xy 81.214717 -280.566368) (xy 81.218812 -280.51564)
			(xy 81.230991 -280.466226) (xy 81.250939 -280.419406) (xy 81.27814 -280.376392) (xy 81.311888 -280.338298)
			(xy 81.35131 -280.306111) (xy 81.395384 -280.280665) (xy 81.44297 -280.262618) (xy 81.492834 -280.252438)
			(xy 81.543686 -280.250389) (xy 81.594207 -280.256523) (xy 81.643091 -280.270683) (xy 81.68907 -280.2925)
			(xy 81.730954 -280.32141) (xy 81.767658 -280.356665) (xy 81.798231 -280.397351) (xy 81.821882 -280.442414)
			(xy 81.837998 -280.490688) (xy 81.846162 -280.540922) (xy 81.846674 -280.566368) (xy 82.154771 -280.566368)
			(xy 82.158866 -280.51564) (xy 82.171045 -280.466226) (xy 82.190993 -280.419406) (xy 82.218194 -280.376392)
			(xy 82.251942 -280.338298) (xy 82.291364 -280.306111) (xy 82.335438 -280.280665) (xy 82.383024 -280.262618)
			(xy 82.432888 -280.252438) (xy 82.48374 -280.250389) (xy 82.534261 -280.256523) (xy 82.583145 -280.270683)
			(xy 82.629124 -280.2925) (xy 82.671008 -280.32141) (xy 82.707712 -280.356665) (xy 82.738285 -280.397351)
			(xy 82.761936 -280.442414) (xy 82.778052 -280.490688) (xy 82.786216 -280.540922) (xy 82.786728 -280.566368)
			(xy 82.786225 -280.591357) (xy 83.093542 -280.591357) (xy 83.093542 -280.541379) (xy 83.101361 -280.492016)
			(xy 83.116805 -280.444484) (xy 83.139495 -280.399952) (xy 83.168871 -280.359519) (xy 83.204211 -280.324179)
			(xy 83.244644 -280.294803) (xy 83.289176 -280.272113) (xy 83.336708 -280.256669) (xy 83.386071 -280.24885)
			(xy 83.436049 -280.24885) (xy 83.485412 -280.256669) (xy 83.532944 -280.272113) (xy 83.577476 -280.294803)
			(xy 83.617909 -280.324179) (xy 83.653249 -280.359519) (xy 83.682625 -280.399952) (xy 83.705315 -280.444484)
			(xy 83.720759 -280.492016) (xy 83.728578 -280.541379) (xy 83.729068 -280.566368) (xy 84.034879 -280.566368)
			(xy 84.038974 -280.51564) (xy 84.051153 -280.466226) (xy 84.071101 -280.419406) (xy 84.098302 -280.376392)
			(xy 84.13205 -280.338298) (xy 84.171472 -280.306111) (xy 84.215546 -280.280665) (xy 84.263132 -280.262618)
			(xy 84.312996 -280.252438) (xy 84.363848 -280.250389) (xy 84.414369 -280.256523) (xy 84.463253 -280.270683)
			(xy 84.509232 -280.2925) (xy 84.551116 -280.32141) (xy 84.58782 -280.356665) (xy 84.618393 -280.397351)
			(xy 84.642044 -280.442414) (xy 84.65816 -280.490688) (xy 84.666324 -280.540922) (xy 84.666836 -280.566368)
			(xy 84.666333 -280.591357) (xy 84.973396 -280.591357) (xy 84.973396 -280.541379) (xy 84.981215 -280.492016)
			(xy 84.996659 -280.444484) (xy 85.019349 -280.399952) (xy 85.048725 -280.359519) (xy 85.084065 -280.324179)
			(xy 85.124498 -280.294803) (xy 85.16903 -280.272113) (xy 85.216562 -280.256669) (xy 85.265925 -280.24885)
			(xy 85.315903 -280.24885) (xy 85.365266 -280.256669) (xy 85.412798 -280.272113) (xy 85.45733 -280.294803)
			(xy 85.497763 -280.324179) (xy 85.533103 -280.359519) (xy 85.562479 -280.399952) (xy 85.585169 -280.444484)
			(xy 85.600613 -280.492016) (xy 85.608432 -280.541379) (xy 85.608922 -280.566368) (xy 85.914733 -280.566368)
			(xy 85.918828 -280.51564) (xy 85.931007 -280.466226) (xy 85.950955 -280.419406) (xy 85.978156 -280.376392)
			(xy 86.011904 -280.338298) (xy 86.051326 -280.306111) (xy 86.0954 -280.280665) (xy 86.142986 -280.262618)
			(xy 86.19285 -280.252438) (xy 86.243702 -280.250389) (xy 86.294223 -280.256523) (xy 86.343107 -280.270683)
			(xy 86.389086 -280.2925) (xy 86.43097 -280.32141) (xy 86.467674 -280.356665) (xy 86.498247 -280.397351)
			(xy 86.521898 -280.442414) (xy 86.538014 -280.490688) (xy 86.546178 -280.540922) (xy 86.54669 -280.566368)
			(xy 87.794841 -280.566368) (xy 87.798936 -280.51564) (xy 87.811115 -280.466226) (xy 87.831063 -280.419406)
			(xy 87.858264 -280.376392) (xy 87.892012 -280.338298) (xy 87.931434 -280.306111) (xy 87.975508 -280.280665)
			(xy 88.023094 -280.262618) (xy 88.072958 -280.252438) (xy 88.12381 -280.250389) (xy 88.174331 -280.256523)
			(xy 88.223215 -280.270683) (xy 88.269194 -280.2925) (xy 88.311078 -280.32141) (xy 88.347782 -280.356665)
			(xy 88.378355 -280.397351) (xy 88.402006 -280.442414) (xy 88.418122 -280.490688) (xy 88.426286 -280.540922)
			(xy 88.426798 -280.566368) (xy 88.734895 -280.566368) (xy 88.73899 -280.51564) (xy 88.751169 -280.466226)
			(xy 88.771117 -280.419406) (xy 88.798318 -280.376392) (xy 88.832066 -280.338298) (xy 88.871488 -280.306111)
			(xy 88.915562 -280.280665) (xy 88.963148 -280.262618) (xy 89.013012 -280.252438) (xy 89.063864 -280.250389)
			(xy 89.114385 -280.256523) (xy 89.163269 -280.270683) (xy 89.209248 -280.2925) (xy 89.251132 -280.32141)
			(xy 89.287836 -280.356665) (xy 89.318409 -280.397351) (xy 89.34206 -280.442414) (xy 89.358176 -280.490688)
			(xy 89.36634 -280.540922) (xy 89.366852 -280.566368) (xy 89.36634 -280.591814) (xy 89.358176 -280.642048)
			(xy 89.34206 -280.690322) (xy 89.318409 -280.735385) (xy 89.287836 -280.776071) (xy 89.251132 -280.811326)
			(xy 89.209248 -280.840236) (xy 89.163269 -280.862053) (xy 89.114385 -280.876213) (xy 89.063864 -280.882347)
			(xy 89.013012 -280.880298) (xy 88.963148 -280.870118) (xy 88.915562 -280.852071) (xy 88.871488 -280.826625)
			(xy 88.832066 -280.794438) (xy 88.798318 -280.756344) (xy 88.771117 -280.71333) (xy 88.751169 -280.66651)
			(xy 88.73899 -280.617096) (xy 88.734895 -280.566368) (xy 88.426798 -280.566368) (xy 88.426286 -280.591814)
			(xy 88.418122 -280.642048) (xy 88.402006 -280.690322) (xy 88.378355 -280.735385) (xy 88.347782 -280.776071)
			(xy 88.311078 -280.811326) (xy 88.269194 -280.840236) (xy 88.223215 -280.862053) (xy 88.174331 -280.876213)
			(xy 88.12381 -280.882347) (xy 88.072958 -280.880298) (xy 88.023094 -280.870118) (xy 87.975508 -280.852071)
			(xy 87.931434 -280.826625) (xy 87.892012 -280.794438) (xy 87.858264 -280.756344) (xy 87.831063 -280.71333)
			(xy 87.811115 -280.66651) (xy 87.798936 -280.617096) (xy 87.794841 -280.566368) (xy 86.54669 -280.566368)
			(xy 86.546178 -280.591814) (xy 86.538014 -280.642048) (xy 86.521898 -280.690322) (xy 86.498247 -280.735385)
			(xy 86.467674 -280.776071) (xy 86.43097 -280.811326) (xy 86.389086 -280.840236) (xy 86.343107 -280.862053)
			(xy 86.294223 -280.876213) (xy 86.243702 -280.882347) (xy 86.19285 -280.880298) (xy 86.142986 -280.870118)
			(xy 86.0954 -280.852071) (xy 86.051326 -280.826625) (xy 86.011904 -280.794438) (xy 85.978156 -280.756344)
			(xy 85.950955 -280.71333) (xy 85.931007 -280.66651) (xy 85.918828 -280.617096) (xy 85.914733 -280.566368)
			(xy 85.608922 -280.566368) (xy 85.608432 -280.591357) (xy 85.600613 -280.64072) (xy 85.585169 -280.688252)
			(xy 85.562479 -280.732784) (xy 85.533103 -280.773217) (xy 85.497763 -280.808557) (xy 85.45733 -280.837933)
			(xy 85.412798 -280.860623) (xy 85.365266 -280.876067) (xy 85.315903 -280.883886) (xy 85.265925 -280.883886)
			(xy 85.216562 -280.876067) (xy 85.16903 -280.860623) (xy 85.124498 -280.837933) (xy 85.084065 -280.808557)
			(xy 85.048725 -280.773217) (xy 85.019349 -280.732784) (xy 84.996659 -280.688252) (xy 84.981215 -280.64072)
			(xy 84.973396 -280.591357) (xy 84.666333 -280.591357) (xy 84.666324 -280.591814) (xy 84.65816 -280.642048)
			(xy 84.642044 -280.690322) (xy 84.618393 -280.735385) (xy 84.58782 -280.776071) (xy 84.551116 -280.811326)
			(xy 84.509232 -280.840236) (xy 84.463253 -280.862053) (xy 84.414369 -280.876213) (xy 84.363848 -280.882347)
			(xy 84.312996 -280.880298) (xy 84.263132 -280.870118) (xy 84.215546 -280.852071) (xy 84.171472 -280.826625)
			(xy 84.13205 -280.794438) (xy 84.098302 -280.756344) (xy 84.071101 -280.71333) (xy 84.051153 -280.66651)
			(xy 84.038974 -280.617096) (xy 84.034879 -280.566368) (xy 83.729068 -280.566368) (xy 83.728578 -280.591357)
			(xy 83.720759 -280.64072) (xy 83.705315 -280.688252) (xy 83.682625 -280.732784) (xy 83.653249 -280.773217)
			(xy 83.617909 -280.808557) (xy 83.577476 -280.837933) (xy 83.532944 -280.860623) (xy 83.485412 -280.876067)
			(xy 83.436049 -280.883886) (xy 83.386071 -280.883886) (xy 83.336708 -280.876067) (xy 83.289176 -280.860623)
			(xy 83.244644 -280.837933) (xy 83.204211 -280.808557) (xy 83.168871 -280.773217) (xy 83.139495 -280.732784)
			(xy 83.116805 -280.688252) (xy 83.101361 -280.64072) (xy 83.093542 -280.591357) (xy 82.786225 -280.591357)
			(xy 82.786216 -280.591814) (xy 82.778052 -280.642048) (xy 82.761936 -280.690322) (xy 82.738285 -280.735385)
			(xy 82.707712 -280.776071) (xy 82.671008 -280.811326) (xy 82.629124 -280.840236) (xy 82.583145 -280.862053)
			(xy 82.534261 -280.876213) (xy 82.48374 -280.882347) (xy 82.432888 -280.880298) (xy 82.383024 -280.870118)
			(xy 82.335438 -280.852071) (xy 82.291364 -280.826625) (xy 82.251942 -280.794438) (xy 82.218194 -280.756344)
			(xy 82.190993 -280.71333) (xy 82.171045 -280.66651) (xy 82.158866 -280.617096) (xy 82.154771 -280.566368)
			(xy 81.846674 -280.566368) (xy 81.846162 -280.591814) (xy 81.837998 -280.642048) (xy 81.821882 -280.690322)
			(xy 81.798231 -280.735385) (xy 81.767658 -280.776071) (xy 81.730954 -280.811326) (xy 81.68907 -280.840236)
			(xy 81.643091 -280.862053) (xy 81.594207 -280.876213) (xy 81.543686 -280.882347) (xy 81.492834 -280.880298)
			(xy 81.44297 -280.870118) (xy 81.395384 -280.852071) (xy 81.35131 -280.826625) (xy 81.311888 -280.794438)
			(xy 81.27814 -280.756344) (xy 81.250939 -280.71333) (xy 81.230991 -280.66651) (xy 81.218812 -280.617096)
			(xy 81.214717 -280.566368) (xy 79.53248 -280.566368) (xy 79.53248 -281.401363) (xy 79.80348 -281.401363)
			(xy 79.80348 -281.351385) (xy 79.811299 -281.302022) (xy 79.826743 -281.25449) (xy 79.849433 -281.209958)
			(xy 79.878809 -281.169525) (xy 79.914149 -281.134185) (xy 79.954582 -281.104809) (xy 79.999114 -281.082119)
			(xy 80.046646 -281.066675) (xy 80.096009 -281.058856) (xy 80.145987 -281.058856) (xy 80.19535 -281.066675)
			(xy 80.242882 -281.082119) (xy 80.287414 -281.104809) (xy 80.327847 -281.134185) (xy 80.363187 -281.169525)
			(xy 80.392563 -281.209958) (xy 80.415253 -281.25449) (xy 80.430697 -281.302022) (xy 80.438516 -281.351385)
			(xy 80.439006 -281.376374) (xy 80.744817 -281.376374) (xy 80.748912 -281.325646) (xy 80.761091 -281.276232)
			(xy 80.781039 -281.229412) (xy 80.80824 -281.186398) (xy 80.841988 -281.148304) (xy 80.88141 -281.116117)
			(xy 80.925484 -281.090671) (xy 80.97307 -281.072624) (xy 81.022934 -281.062444) (xy 81.073786 -281.060395)
			(xy 81.124307 -281.066529) (xy 81.173191 -281.080689) (xy 81.21917 -281.102506) (xy 81.261054 -281.131416)
			(xy 81.297758 -281.166671) (xy 81.328331 -281.207357) (xy 81.351982 -281.25242) (xy 81.368098 -281.300694)
			(xy 81.376262 -281.350928) (xy 81.376774 -281.376374) (xy 81.376271 -281.401363) (xy 81.683588 -281.401363)
			(xy 81.683588 -281.351385) (xy 81.691407 -281.302022) (xy 81.706851 -281.25449) (xy 81.729541 -281.209958)
			(xy 81.758917 -281.169525) (xy 81.794257 -281.134185) (xy 81.83469 -281.104809) (xy 81.879222 -281.082119)
			(xy 81.926754 -281.066675) (xy 81.976117 -281.058856) (xy 82.026095 -281.058856) (xy 82.075458 -281.066675)
			(xy 82.12299 -281.082119) (xy 82.167522 -281.104809) (xy 82.207955 -281.134185) (xy 82.243295 -281.169525)
			(xy 82.272671 -281.209958) (xy 82.295361 -281.25449) (xy 82.310805 -281.302022) (xy 82.318624 -281.351385)
			(xy 82.319114 -281.376374) (xy 82.624671 -281.376374) (xy 82.628766 -281.325646) (xy 82.640945 -281.276232)
			(xy 82.660893 -281.229412) (xy 82.688094 -281.186398) (xy 82.721842 -281.148304) (xy 82.761264 -281.116117)
			(xy 82.805338 -281.090671) (xy 82.852924 -281.072624) (xy 82.902788 -281.062444) (xy 82.95364 -281.060395)
			(xy 83.004161 -281.066529) (xy 83.053045 -281.080689) (xy 83.099024 -281.102506) (xy 83.140908 -281.131416)
			(xy 83.177612 -281.166671) (xy 83.208185 -281.207357) (xy 83.231836 -281.25242) (xy 83.247952 -281.300694)
			(xy 83.256116 -281.350928) (xy 83.256628 -281.376374) (xy 83.256125 -281.401363) (xy 83.563442 -281.401363)
			(xy 83.563442 -281.351385) (xy 83.571261 -281.302022) (xy 83.586705 -281.25449) (xy 83.609395 -281.209958)
			(xy 83.638771 -281.169525) (xy 83.674111 -281.134185) (xy 83.714544 -281.104809) (xy 83.759076 -281.082119)
			(xy 83.806608 -281.066675) (xy 83.855971 -281.058856) (xy 83.905949 -281.058856) (xy 83.955312 -281.066675)
			(xy 84.002844 -281.082119) (xy 84.047376 -281.104809) (xy 84.087809 -281.134185) (xy 84.123149 -281.169525)
			(xy 84.152525 -281.209958) (xy 84.175215 -281.25449) (xy 84.190659 -281.302022) (xy 84.198478 -281.351385)
			(xy 84.198968 -281.376374) (xy 84.504779 -281.376374) (xy 84.508874 -281.325646) (xy 84.521053 -281.276232)
			(xy 84.541001 -281.229412) (xy 84.568202 -281.186398) (xy 84.60195 -281.148304) (xy 84.641372 -281.116117)
			(xy 84.685446 -281.090671) (xy 84.733032 -281.072624) (xy 84.782896 -281.062444) (xy 84.833748 -281.060395)
			(xy 84.884269 -281.066529) (xy 84.933153 -281.080689) (xy 84.979132 -281.102506) (xy 85.021016 -281.131416)
			(xy 85.05772 -281.166671) (xy 85.088293 -281.207357) (xy 85.111944 -281.25242) (xy 85.12806 -281.300694)
			(xy 85.136224 -281.350928) (xy 85.136736 -281.376374) (xy 85.444833 -281.376374) (xy 85.448928 -281.325646)
			(xy 85.461107 -281.276232) (xy 85.481055 -281.229412) (xy 85.508256 -281.186398) (xy 85.542004 -281.148304)
			(xy 85.581426 -281.116117) (xy 85.6255 -281.090671) (xy 85.673086 -281.072624) (xy 85.72295 -281.062444)
			(xy 85.773802 -281.060395) (xy 85.824323 -281.066529) (xy 85.873207 -281.080689) (xy 85.919186 -281.102506)
			(xy 85.96107 -281.131416) (xy 85.997774 -281.166671) (xy 86.028347 -281.207357) (xy 86.051998 -281.25242)
			(xy 86.068114 -281.300694) (xy 86.076278 -281.350928) (xy 86.07679 -281.376374) (xy 86.076287 -281.401363)
			(xy 86.383604 -281.401363) (xy 86.383604 -281.351385) (xy 86.391423 -281.302022) (xy 86.406867 -281.25449)
			(xy 86.429557 -281.209958) (xy 86.458933 -281.169525) (xy 86.494273 -281.134185) (xy 86.534706 -281.104809)
			(xy 86.579238 -281.082119) (xy 86.62677 -281.066675) (xy 86.676133 -281.058856) (xy 86.726111 -281.058856)
			(xy 86.775474 -281.066675) (xy 86.823006 -281.082119) (xy 86.867538 -281.104809) (xy 86.907971 -281.134185)
			(xy 86.943311 -281.169525) (xy 86.972687 -281.209958) (xy 86.995377 -281.25449) (xy 87.010821 -281.302022)
			(xy 87.01864 -281.351385) (xy 87.01913 -281.376374) (xy 87.324687 -281.376374) (xy 87.328782 -281.325646)
			(xy 87.340961 -281.276232) (xy 87.360909 -281.229412) (xy 87.38811 -281.186398) (xy 87.421858 -281.148304)
			(xy 87.46128 -281.116117) (xy 87.505354 -281.090671) (xy 87.55294 -281.072624) (xy 87.602804 -281.062444)
			(xy 87.653656 -281.060395) (xy 87.704177 -281.066529) (xy 87.753061 -281.080689) (xy 87.79904 -281.102506)
			(xy 87.840924 -281.131416) (xy 87.877628 -281.166671) (xy 87.908201 -281.207357) (xy 87.931852 -281.25242)
			(xy 87.947968 -281.300694) (xy 87.956132 -281.350928) (xy 87.956644 -281.376374) (xy 87.956141 -281.401363)
			(xy 88.263458 -281.401363) (xy 88.263458 -281.351385) (xy 88.271277 -281.302022) (xy 88.286721 -281.25449)
			(xy 88.309411 -281.209958) (xy 88.338787 -281.169525) (xy 88.374127 -281.134185) (xy 88.41456 -281.104809)
			(xy 88.459092 -281.082119) (xy 88.506624 -281.066675) (xy 88.555987 -281.058856) (xy 88.605965 -281.058856)
			(xy 88.655328 -281.066675) (xy 88.70286 -281.082119) (xy 88.747392 -281.104809) (xy 88.787825 -281.134185)
			(xy 88.823165 -281.169525) (xy 88.852541 -281.209958) (xy 88.875231 -281.25449) (xy 88.890675 -281.302022)
			(xy 88.898494 -281.351385) (xy 88.898984 -281.376374) (xy 88.898494 -281.401363) (xy 88.890675 -281.450726)
			(xy 88.875231 -281.498258) (xy 88.852541 -281.54279) (xy 88.823165 -281.583223) (xy 88.787825 -281.618563)
			(xy 88.747392 -281.647939) (xy 88.70286 -281.670629) (xy 88.655328 -281.686073) (xy 88.605965 -281.693892)
			(xy 88.555987 -281.693892) (xy 88.506624 -281.686073) (xy 88.459092 -281.670629) (xy 88.41456 -281.647939)
			(xy 88.374127 -281.618563) (xy 88.338787 -281.583223) (xy 88.309411 -281.54279) (xy 88.286721 -281.498258)
			(xy 88.271277 -281.450726) (xy 88.263458 -281.401363) (xy 87.956141 -281.401363) (xy 87.956132 -281.40182)
			(xy 87.947968 -281.452054) (xy 87.931852 -281.500328) (xy 87.908201 -281.545391) (xy 87.877628 -281.586077)
			(xy 87.840924 -281.621332) (xy 87.79904 -281.650242) (xy 87.753061 -281.672059) (xy 87.704177 -281.686219)
			(xy 87.653656 -281.692353) (xy 87.602804 -281.690304) (xy 87.55294 -281.680124) (xy 87.505354 -281.662077)
			(xy 87.46128 -281.636631) (xy 87.421858 -281.604444) (xy 87.38811 -281.56635) (xy 87.360909 -281.523336)
			(xy 87.340961 -281.476516) (xy 87.328782 -281.427102) (xy 87.324687 -281.376374) (xy 87.01913 -281.376374)
			(xy 87.01864 -281.401363) (xy 87.010821 -281.450726) (xy 86.995377 -281.498258) (xy 86.972687 -281.54279)
			(xy 86.943311 -281.583223) (xy 86.907971 -281.618563) (xy 86.867538 -281.647939) (xy 86.823006 -281.670629)
			(xy 86.775474 -281.686073) (xy 86.726111 -281.693892) (xy 86.676133 -281.693892) (xy 86.62677 -281.686073)
			(xy 86.579238 -281.670629) (xy 86.534706 -281.647939) (xy 86.494273 -281.618563) (xy 86.458933 -281.583223)
			(xy 86.429557 -281.54279) (xy 86.406867 -281.498258) (xy 86.391423 -281.450726) (xy 86.383604 -281.401363)
			(xy 86.076287 -281.401363) (xy 86.076278 -281.40182) (xy 86.068114 -281.452054) (xy 86.051998 -281.500328)
			(xy 86.028347 -281.545391) (xy 85.997774 -281.586077) (xy 85.96107 -281.621332) (xy 85.919186 -281.650242)
			(xy 85.873207 -281.672059) (xy 85.824323 -281.686219) (xy 85.773802 -281.692353) (xy 85.72295 -281.690304)
			(xy 85.673086 -281.680124) (xy 85.6255 -281.662077) (xy 85.581426 -281.636631) (xy 85.542004 -281.604444)
			(xy 85.508256 -281.56635) (xy 85.481055 -281.523336) (xy 85.461107 -281.476516) (xy 85.448928 -281.427102)
			(xy 85.444833 -281.376374) (xy 85.136736 -281.376374) (xy 85.136224 -281.40182) (xy 85.12806 -281.452054)
			(xy 85.111944 -281.500328) (xy 85.088293 -281.545391) (xy 85.05772 -281.586077) (xy 85.021016 -281.621332)
			(xy 84.979132 -281.650242) (xy 84.933153 -281.672059) (xy 84.884269 -281.686219) (xy 84.833748 -281.692353)
			(xy 84.782896 -281.690304) (xy 84.733032 -281.680124) (xy 84.685446 -281.662077) (xy 84.641372 -281.636631)
			(xy 84.60195 -281.604444) (xy 84.568202 -281.56635) (xy 84.541001 -281.523336) (xy 84.521053 -281.476516)
			(xy 84.508874 -281.427102) (xy 84.504779 -281.376374) (xy 84.198968 -281.376374) (xy 84.198478 -281.401363)
			(xy 84.190659 -281.450726) (xy 84.175215 -281.498258) (xy 84.152525 -281.54279) (xy 84.123149 -281.583223)
			(xy 84.087809 -281.618563) (xy 84.047376 -281.647939) (xy 84.002844 -281.670629) (xy 83.955312 -281.686073)
			(xy 83.905949 -281.693892) (xy 83.855971 -281.693892) (xy 83.806608 -281.686073) (xy 83.759076 -281.670629)
			(xy 83.714544 -281.647939) (xy 83.674111 -281.618563) (xy 83.638771 -281.583223) (xy 83.609395 -281.54279)
			(xy 83.586705 -281.498258) (xy 83.571261 -281.450726) (xy 83.563442 -281.401363) (xy 83.256125 -281.401363)
			(xy 83.256116 -281.40182) (xy 83.247952 -281.452054) (xy 83.231836 -281.500328) (xy 83.208185 -281.545391)
			(xy 83.177612 -281.586077) (xy 83.140908 -281.621332) (xy 83.099024 -281.650242) (xy 83.053045 -281.672059)
			(xy 83.004161 -281.686219) (xy 82.95364 -281.692353) (xy 82.902788 -281.690304) (xy 82.852924 -281.680124)
			(xy 82.805338 -281.662077) (xy 82.761264 -281.636631) (xy 82.721842 -281.604444) (xy 82.688094 -281.56635)
			(xy 82.660893 -281.523336) (xy 82.640945 -281.476516) (xy 82.628766 -281.427102) (xy 82.624671 -281.376374)
			(xy 82.319114 -281.376374) (xy 82.318624 -281.401363) (xy 82.310805 -281.450726) (xy 82.295361 -281.498258)
			(xy 82.272671 -281.54279) (xy 82.243295 -281.583223) (xy 82.207955 -281.618563) (xy 82.167522 -281.647939)
			(xy 82.12299 -281.670629) (xy 82.075458 -281.686073) (xy 82.026095 -281.693892) (xy 81.976117 -281.693892)
			(xy 81.926754 -281.686073) (xy 81.879222 -281.670629) (xy 81.83469 -281.647939) (xy 81.794257 -281.618563)
			(xy 81.758917 -281.583223) (xy 81.729541 -281.54279) (xy 81.706851 -281.498258) (xy 81.691407 -281.450726)
			(xy 81.683588 -281.401363) (xy 81.376271 -281.401363) (xy 81.376262 -281.40182) (xy 81.368098 -281.452054)
			(xy 81.351982 -281.500328) (xy 81.328331 -281.545391) (xy 81.297758 -281.586077) (xy 81.261054 -281.621332)
			(xy 81.21917 -281.650242) (xy 81.173191 -281.672059) (xy 81.124307 -281.686219) (xy 81.073786 -281.692353)
			(xy 81.022934 -281.690304) (xy 80.97307 -281.680124) (xy 80.925484 -281.662077) (xy 80.88141 -281.636631)
			(xy 80.841988 -281.604444) (xy 80.80824 -281.56635) (xy 80.781039 -281.523336) (xy 80.761091 -281.476516)
			(xy 80.748912 -281.427102) (xy 80.744817 -281.376374) (xy 80.439006 -281.376374) (xy 80.438516 -281.401363)
			(xy 80.430697 -281.450726) (xy 80.415253 -281.498258) (xy 80.392563 -281.54279) (xy 80.363187 -281.583223)
			(xy 80.327847 -281.618563) (xy 80.287414 -281.647939) (xy 80.242882 -281.670629) (xy 80.19535 -281.686073)
			(xy 80.145987 -281.693892) (xy 80.096009 -281.693892) (xy 80.046646 -281.686073) (xy 79.999114 -281.670629)
			(xy 79.954582 -281.647939) (xy 79.914149 -281.618563) (xy 79.878809 -281.583223) (xy 79.849433 -281.54279)
			(xy 79.826743 -281.498258) (xy 79.811299 -281.450726) (xy 79.80348 -281.401363) (xy 79.53248 -281.401363)
			(xy 79.53248 -282.211369) (xy 80.273634 -282.211369) (xy 80.273634 -282.161391) (xy 80.281453 -282.112028)
			(xy 80.296897 -282.064496) (xy 80.319587 -282.019964) (xy 80.348963 -281.979531) (xy 80.384303 -281.944191)
			(xy 80.424736 -281.914815) (xy 80.469268 -281.892125) (xy 80.5168 -281.876681) (xy 80.566163 -281.868862)
			(xy 80.616141 -281.868862) (xy 80.665504 -281.876681) (xy 80.713036 -281.892125) (xy 80.757568 -281.914815)
			(xy 80.798001 -281.944191) (xy 80.833341 -281.979531) (xy 80.862717 -282.019964) (xy 80.885407 -282.064496)
			(xy 80.900851 -282.112028) (xy 80.90867 -282.161391) (xy 80.90916 -282.18638) (xy 81.214717 -282.18638)
			(xy 81.218812 -282.135652) (xy 81.230991 -282.086238) (xy 81.250939 -282.039418) (xy 81.27814 -281.996404)
			(xy 81.311888 -281.95831) (xy 81.35131 -281.926123) (xy 81.395384 -281.900677) (xy 81.44297 -281.88263)
			(xy 81.492834 -281.87245) (xy 81.543686 -281.870401) (xy 81.594207 -281.876535) (xy 81.643091 -281.890695)
			(xy 81.68907 -281.912512) (xy 81.730954 -281.941422) (xy 81.767658 -281.976677) (xy 81.798231 -282.017363)
			(xy 81.821882 -282.062426) (xy 81.837998 -282.1107) (xy 81.846162 -282.160934) (xy 81.846674 -282.18638)
			(xy 82.154771 -282.18638) (xy 82.158866 -282.135652) (xy 82.171045 -282.086238) (xy 82.190993 -282.039418)
			(xy 82.218194 -281.996404) (xy 82.251942 -281.95831) (xy 82.291364 -281.926123) (xy 82.335438 -281.900677)
			(xy 82.383024 -281.88263) (xy 82.432888 -281.87245) (xy 82.48374 -281.870401) (xy 82.534261 -281.876535)
			(xy 82.583145 -281.890695) (xy 82.629124 -281.912512) (xy 82.671008 -281.941422) (xy 82.707712 -281.976677)
			(xy 82.738285 -282.017363) (xy 82.761936 -282.062426) (xy 82.778052 -282.1107) (xy 82.786216 -282.160934)
			(xy 82.786728 -282.18638) (xy 82.786225 -282.211369) (xy 83.093542 -282.211369) (xy 83.093542 -282.161391)
			(xy 83.101361 -282.112028) (xy 83.116805 -282.064496) (xy 83.139495 -282.019964) (xy 83.168871 -281.979531)
			(xy 83.204211 -281.944191) (xy 83.244644 -281.914815) (xy 83.289176 -281.892125) (xy 83.336708 -281.876681)
			(xy 83.386071 -281.868862) (xy 83.436049 -281.868862) (xy 83.485412 -281.876681) (xy 83.532944 -281.892125)
			(xy 83.577476 -281.914815) (xy 83.617909 -281.944191) (xy 83.653249 -281.979531) (xy 83.682625 -282.019964)
			(xy 83.705315 -282.064496) (xy 83.720759 -282.112028) (xy 83.728578 -282.161391) (xy 83.729068 -282.18638)
			(xy 84.034879 -282.18638) (xy 84.038974 -282.135652) (xy 84.051153 -282.086238) (xy 84.071101 -282.039418)
			(xy 84.098302 -281.996404) (xy 84.13205 -281.95831) (xy 84.171472 -281.926123) (xy 84.215546 -281.900677)
			(xy 84.263132 -281.88263) (xy 84.312996 -281.87245) (xy 84.363848 -281.870401) (xy 84.414369 -281.876535)
			(xy 84.463253 -281.890695) (xy 84.509232 -281.912512) (xy 84.551116 -281.941422) (xy 84.58782 -281.976677)
			(xy 84.618393 -282.017363) (xy 84.642044 -282.062426) (xy 84.65816 -282.1107) (xy 84.666324 -282.160934)
			(xy 84.666836 -282.18638) (xy 84.666333 -282.211369) (xy 84.973396 -282.211369) (xy 84.973396 -282.161391)
			(xy 84.981215 -282.112028) (xy 84.996659 -282.064496) (xy 85.019349 -282.019964) (xy 85.048725 -281.979531)
			(xy 85.084065 -281.944191) (xy 85.124498 -281.914815) (xy 85.16903 -281.892125) (xy 85.216562 -281.876681)
			(xy 85.265925 -281.868862) (xy 85.315903 -281.868862) (xy 85.365266 -281.876681) (xy 85.412798 -281.892125)
			(xy 85.45733 -281.914815) (xy 85.497763 -281.944191) (xy 85.533103 -281.979531) (xy 85.562479 -282.019964)
			(xy 85.585169 -282.064496) (xy 85.600613 -282.112028) (xy 85.608432 -282.161391) (xy 85.608922 -282.18638)
			(xy 85.914733 -282.18638) (xy 85.918828 -282.135652) (xy 85.931007 -282.086238) (xy 85.950955 -282.039418)
			(xy 85.978156 -281.996404) (xy 86.011904 -281.95831) (xy 86.051326 -281.926123) (xy 86.0954 -281.900677)
			(xy 86.142986 -281.88263) (xy 86.19285 -281.87245) (xy 86.243702 -281.870401) (xy 86.294223 -281.876535)
			(xy 86.343107 -281.890695) (xy 86.389086 -281.912512) (xy 86.43097 -281.941422) (xy 86.467674 -281.976677)
			(xy 86.498247 -282.017363) (xy 86.521898 -282.062426) (xy 86.538014 -282.1107) (xy 86.546178 -282.160934)
			(xy 86.54669 -282.18638) (xy 86.546187 -282.211369) (xy 86.853504 -282.211369) (xy 86.853504 -282.161391)
			(xy 86.861323 -282.112028) (xy 86.876767 -282.064496) (xy 86.899457 -282.019964) (xy 86.928833 -281.979531)
			(xy 86.964173 -281.944191) (xy 87.004606 -281.914815) (xy 87.049138 -281.892125) (xy 87.09667 -281.876681)
			(xy 87.146033 -281.868862) (xy 87.196011 -281.868862) (xy 87.245374 -281.876681) (xy 87.292906 -281.892125)
			(xy 87.337438 -281.914815) (xy 87.377871 -281.944191) (xy 87.413211 -281.979531) (xy 87.442587 -282.019964)
			(xy 87.465277 -282.064496) (xy 87.480721 -282.112028) (xy 87.48854 -282.161391) (xy 87.48903 -282.18638)
			(xy 87.794841 -282.18638) (xy 87.798936 -282.135652) (xy 87.811115 -282.086238) (xy 87.831063 -282.039418)
			(xy 87.858264 -281.996404) (xy 87.892012 -281.95831) (xy 87.931434 -281.926123) (xy 87.975508 -281.900677)
			(xy 88.023094 -281.88263) (xy 88.072958 -281.87245) (xy 88.12381 -281.870401) (xy 88.174331 -281.876535)
			(xy 88.223215 -281.890695) (xy 88.269194 -281.912512) (xy 88.311078 -281.941422) (xy 88.347782 -281.976677)
			(xy 88.378355 -282.017363) (xy 88.402006 -282.062426) (xy 88.418122 -282.1107) (xy 88.426286 -282.160934)
			(xy 88.426798 -282.18638) (xy 88.734895 -282.18638) (xy 88.73899 -282.135652) (xy 88.751169 -282.086238)
			(xy 88.771117 -282.039418) (xy 88.798318 -281.996404) (xy 88.832066 -281.95831) (xy 88.871488 -281.926123)
			(xy 88.915562 -281.900677) (xy 88.963148 -281.88263) (xy 89.013012 -281.87245) (xy 89.063864 -281.870401)
			(xy 89.114385 -281.876535) (xy 89.163269 -281.890695) (xy 89.209248 -281.912512) (xy 89.251132 -281.941422)
			(xy 89.287836 -281.976677) (xy 89.318409 -282.017363) (xy 89.34206 -282.062426) (xy 89.358176 -282.1107)
			(xy 89.36634 -282.160934) (xy 89.366852 -282.18638) (xy 89.36634 -282.211826) (xy 89.358176 -282.26206)
			(xy 89.34206 -282.310334) (xy 89.318409 -282.355397) (xy 89.287836 -282.396083) (xy 89.251132 -282.431338)
			(xy 89.209248 -282.460248) (xy 89.163269 -282.482065) (xy 89.114385 -282.496225) (xy 89.063864 -282.502359)
			(xy 89.013012 -282.50031) (xy 88.963148 -282.49013) (xy 88.915562 -282.472083) (xy 88.871488 -282.446637)
			(xy 88.832066 -282.41445) (xy 88.798318 -282.376356) (xy 88.771117 -282.333342) (xy 88.751169 -282.286522)
			(xy 88.73899 -282.237108) (xy 88.734895 -282.18638) (xy 88.426798 -282.18638) (xy 88.426286 -282.211826)
			(xy 88.418122 -282.26206) (xy 88.402006 -282.310334) (xy 88.378355 -282.355397) (xy 88.347782 -282.396083)
			(xy 88.311078 -282.431338) (xy 88.269194 -282.460248) (xy 88.223215 -282.482065) (xy 88.174331 -282.496225)
			(xy 88.12381 -282.502359) (xy 88.072958 -282.50031) (xy 88.023094 -282.49013) (xy 87.975508 -282.472083)
			(xy 87.931434 -282.446637) (xy 87.892012 -282.41445) (xy 87.858264 -282.376356) (xy 87.831063 -282.333342)
			(xy 87.811115 -282.286522) (xy 87.798936 -282.237108) (xy 87.794841 -282.18638) (xy 87.48903 -282.18638)
			(xy 87.48854 -282.211369) (xy 87.480721 -282.260732) (xy 87.465277 -282.308264) (xy 87.442587 -282.352796)
			(xy 87.413211 -282.393229) (xy 87.377871 -282.428569) (xy 87.337438 -282.457945) (xy 87.292906 -282.480635)
			(xy 87.245374 -282.496079) (xy 87.196011 -282.503898) (xy 87.146033 -282.503898) (xy 87.09667 -282.496079)
			(xy 87.049138 -282.480635) (xy 87.004606 -282.457945) (xy 86.964173 -282.428569) (xy 86.928833 -282.393229)
			(xy 86.899457 -282.352796) (xy 86.876767 -282.308264) (xy 86.861323 -282.260732) (xy 86.853504 -282.211369)
			(xy 86.546187 -282.211369) (xy 86.546178 -282.211826) (xy 86.538014 -282.26206) (xy 86.521898 -282.310334)
			(xy 86.498247 -282.355397) (xy 86.467674 -282.396083) (xy 86.43097 -282.431338) (xy 86.389086 -282.460248)
			(xy 86.343107 -282.482065) (xy 86.294223 -282.496225) (xy 86.243702 -282.502359) (xy 86.19285 -282.50031)
			(xy 86.142986 -282.49013) (xy 86.0954 -282.472083) (xy 86.051326 -282.446637) (xy 86.011904 -282.41445)
			(xy 85.978156 -282.376356) (xy 85.950955 -282.333342) (xy 85.931007 -282.286522) (xy 85.918828 -282.237108)
			(xy 85.914733 -282.18638) (xy 85.608922 -282.18638) (xy 85.608432 -282.211369) (xy 85.600613 -282.260732)
			(xy 85.585169 -282.308264) (xy 85.562479 -282.352796) (xy 85.533103 -282.393229) (xy 85.497763 -282.428569)
			(xy 85.45733 -282.457945) (xy 85.412798 -282.480635) (xy 85.365266 -282.496079) (xy 85.315903 -282.503898)
			(xy 85.265925 -282.503898) (xy 85.216562 -282.496079) (xy 85.16903 -282.480635) (xy 85.124498 -282.457945)
			(xy 85.084065 -282.428569) (xy 85.048725 -282.393229) (xy 85.019349 -282.352796) (xy 84.996659 -282.308264)
			(xy 84.981215 -282.260732) (xy 84.973396 -282.211369) (xy 84.666333 -282.211369) (xy 84.666324 -282.211826)
			(xy 84.65816 -282.26206) (xy 84.642044 -282.310334) (xy 84.618393 -282.355397) (xy 84.58782 -282.396083)
			(xy 84.551116 -282.431338) (xy 84.509232 -282.460248) (xy 84.463253 -282.482065) (xy 84.414369 -282.496225)
			(xy 84.363848 -282.502359) (xy 84.312996 -282.50031) (xy 84.263132 -282.49013) (xy 84.215546 -282.472083)
			(xy 84.171472 -282.446637) (xy 84.13205 -282.41445) (xy 84.098302 -282.376356) (xy 84.071101 -282.333342)
			(xy 84.051153 -282.286522) (xy 84.038974 -282.237108) (xy 84.034879 -282.18638) (xy 83.729068 -282.18638)
			(xy 83.728578 -282.211369) (xy 83.720759 -282.260732) (xy 83.705315 -282.308264) (xy 83.682625 -282.352796)
			(xy 83.653249 -282.393229) (xy 83.617909 -282.428569) (xy 83.577476 -282.457945) (xy 83.532944 -282.480635)
			(xy 83.485412 -282.496079) (xy 83.436049 -282.503898) (xy 83.386071 -282.503898) (xy 83.336708 -282.496079)
			(xy 83.289176 -282.480635) (xy 83.244644 -282.457945) (xy 83.204211 -282.428569) (xy 83.168871 -282.393229)
			(xy 83.139495 -282.352796) (xy 83.116805 -282.308264) (xy 83.101361 -282.260732) (xy 83.093542 -282.211369)
			(xy 82.786225 -282.211369) (xy 82.786216 -282.211826) (xy 82.778052 -282.26206) (xy 82.761936 -282.310334)
			(xy 82.738285 -282.355397) (xy 82.707712 -282.396083) (xy 82.671008 -282.431338) (xy 82.629124 -282.460248)
			(xy 82.583145 -282.482065) (xy 82.534261 -282.496225) (xy 82.48374 -282.502359) (xy 82.432888 -282.50031)
			(xy 82.383024 -282.49013) (xy 82.335438 -282.472083) (xy 82.291364 -282.446637) (xy 82.251942 -282.41445)
			(xy 82.218194 -282.376356) (xy 82.190993 -282.333342) (xy 82.171045 -282.286522) (xy 82.158866 -282.237108)
			(xy 82.154771 -282.18638) (xy 81.846674 -282.18638) (xy 81.846162 -282.211826) (xy 81.837998 -282.26206)
			(xy 81.821882 -282.310334) (xy 81.798231 -282.355397) (xy 81.767658 -282.396083) (xy 81.730954 -282.431338)
			(xy 81.68907 -282.460248) (xy 81.643091 -282.482065) (xy 81.594207 -282.496225) (xy 81.543686 -282.502359)
			(xy 81.492834 -282.50031) (xy 81.44297 -282.49013) (xy 81.395384 -282.472083) (xy 81.35131 -282.446637)
			(xy 81.311888 -282.41445) (xy 81.27814 -282.376356) (xy 81.250939 -282.333342) (xy 81.230991 -282.286522)
			(xy 81.218812 -282.237108) (xy 81.214717 -282.18638) (xy 80.90916 -282.18638) (xy 80.90867 -282.211369)
			(xy 80.900851 -282.260732) (xy 80.885407 -282.308264) (xy 80.862717 -282.352796) (xy 80.833341 -282.393229)
			(xy 80.798001 -282.428569) (xy 80.757568 -282.457945) (xy 80.713036 -282.480635) (xy 80.665504 -282.496079)
			(xy 80.616141 -282.503898) (xy 80.566163 -282.503898) (xy 80.5168 -282.496079) (xy 80.469268 -282.480635)
			(xy 80.424736 -282.457945) (xy 80.384303 -282.428569) (xy 80.348963 -282.393229) (xy 80.319587 -282.352796)
			(xy 80.296897 -282.308264) (xy 80.281453 -282.260732) (xy 80.273634 -282.211369) (xy 79.53248 -282.211369)
			(xy 79.53248 -282.996386) (xy 80.744817 -282.996386) (xy 80.748912 -282.945658) (xy 80.761091 -282.896244)
			(xy 80.781039 -282.849424) (xy 80.80824 -282.80641) (xy 80.841988 -282.768316) (xy 80.88141 -282.736129)
			(xy 80.925484 -282.710683) (xy 80.97307 -282.692636) (xy 81.022934 -282.682456) (xy 81.073786 -282.680407)
			(xy 81.124307 -282.686541) (xy 81.173191 -282.700701) (xy 81.21917 -282.722518) (xy 81.261054 -282.751428)
			(xy 81.297758 -282.786683) (xy 81.328331 -282.827369) (xy 81.351982 -282.872432) (xy 81.368098 -282.920706)
			(xy 81.376262 -282.97094) (xy 81.376774 -282.996386) (xy 81.376271 -283.021375) (xy 81.683588 -283.021375)
			(xy 81.683588 -282.971397) (xy 81.691407 -282.922034) (xy 81.706851 -282.874502) (xy 81.729541 -282.82997)
			(xy 81.758917 -282.789537) (xy 81.794257 -282.754197) (xy 81.83469 -282.724821) (xy 81.879222 -282.702131)
			(xy 81.926754 -282.686687) (xy 81.976117 -282.678868) (xy 82.026095 -282.678868) (xy 82.075458 -282.686687)
			(xy 82.12299 -282.702131) (xy 82.167522 -282.724821) (xy 82.207955 -282.754197) (xy 82.243295 -282.789537)
			(xy 82.272671 -282.82997) (xy 82.295361 -282.874502) (xy 82.310805 -282.922034) (xy 82.318624 -282.971397)
			(xy 82.319114 -282.996386) (xy 82.624671 -282.996386) (xy 82.628766 -282.945658) (xy 82.640945 -282.896244)
			(xy 82.660893 -282.849424) (xy 82.688094 -282.80641) (xy 82.721842 -282.768316) (xy 82.761264 -282.736129)
			(xy 82.805338 -282.710683) (xy 82.852924 -282.692636) (xy 82.902788 -282.682456) (xy 82.95364 -282.680407)
			(xy 83.004161 -282.686541) (xy 83.053045 -282.700701) (xy 83.099024 -282.722518) (xy 83.140908 -282.751428)
			(xy 83.177612 -282.786683) (xy 83.208185 -282.827369) (xy 83.231836 -282.872432) (xy 83.247952 -282.920706)
			(xy 83.256116 -282.97094) (xy 83.256628 -282.996386) (xy 83.256125 -283.021375) (xy 83.563442 -283.021375)
			(xy 83.563442 -282.971397) (xy 83.571261 -282.922034) (xy 83.586705 -282.874502) (xy 83.609395 -282.82997)
			(xy 83.638771 -282.789537) (xy 83.674111 -282.754197) (xy 83.714544 -282.724821) (xy 83.759076 -282.702131)
			(xy 83.806608 -282.686687) (xy 83.855971 -282.678868) (xy 83.905949 -282.678868) (xy 83.955312 -282.686687)
			(xy 84.002844 -282.702131) (xy 84.047376 -282.724821) (xy 84.087809 -282.754197) (xy 84.123149 -282.789537)
			(xy 84.152525 -282.82997) (xy 84.175215 -282.874502) (xy 84.190659 -282.922034) (xy 84.198478 -282.971397)
			(xy 84.198968 -282.996386) (xy 84.504779 -282.996386) (xy 84.508874 -282.945658) (xy 84.521053 -282.896244)
			(xy 84.541001 -282.849424) (xy 84.568202 -282.80641) (xy 84.60195 -282.768316) (xy 84.641372 -282.736129)
			(xy 84.685446 -282.710683) (xy 84.733032 -282.692636) (xy 84.782896 -282.682456) (xy 84.833748 -282.680407)
			(xy 84.884269 -282.686541) (xy 84.933153 -282.700701) (xy 84.979132 -282.722518) (xy 85.021016 -282.751428)
			(xy 85.05772 -282.786683) (xy 85.088293 -282.827369) (xy 85.111944 -282.872432) (xy 85.12806 -282.920706)
			(xy 85.136224 -282.97094) (xy 85.136736 -282.996386) (xy 85.444833 -282.996386) (xy 85.448928 -282.945658)
			(xy 85.461107 -282.896244) (xy 85.481055 -282.849424) (xy 85.508256 -282.80641) (xy 85.542004 -282.768316)
			(xy 85.581426 -282.736129) (xy 85.6255 -282.710683) (xy 85.673086 -282.692636) (xy 85.72295 -282.682456)
			(xy 85.773802 -282.680407) (xy 85.824323 -282.686541) (xy 85.873207 -282.700701) (xy 85.919186 -282.722518)
			(xy 85.96107 -282.751428) (xy 85.997774 -282.786683) (xy 86.028347 -282.827369) (xy 86.051998 -282.872432)
			(xy 86.068114 -282.920706) (xy 86.076278 -282.97094) (xy 86.07679 -282.996386) (xy 87.324687 -282.996386)
			(xy 87.328782 -282.945658) (xy 87.340961 -282.896244) (xy 87.360909 -282.849424) (xy 87.38811 -282.80641)
			(xy 87.421858 -282.768316) (xy 87.46128 -282.736129) (xy 87.505354 -282.710683) (xy 87.55294 -282.692636)
			(xy 87.602804 -282.682456) (xy 87.653656 -282.680407) (xy 87.704177 -282.686541) (xy 87.753061 -282.700701)
			(xy 87.79904 -282.722518) (xy 87.840924 -282.751428) (xy 87.877628 -282.786683) (xy 87.908201 -282.827369)
			(xy 87.931852 -282.872432) (xy 87.947968 -282.920706) (xy 87.956132 -282.97094) (xy 87.956644 -282.996386)
			(xy 87.956141 -283.021375) (xy 88.263458 -283.021375) (xy 88.263458 -282.971397) (xy 88.271277 -282.922034)
			(xy 88.286721 -282.874502) (xy 88.309411 -282.82997) (xy 88.338787 -282.789537) (xy 88.374127 -282.754197)
			(xy 88.41456 -282.724821) (xy 88.459092 -282.702131) (xy 88.506624 -282.686687) (xy 88.555987 -282.678868)
			(xy 88.605965 -282.678868) (xy 88.655328 -282.686687) (xy 88.70286 -282.702131) (xy 88.747392 -282.724821)
			(xy 88.787825 -282.754197) (xy 88.823165 -282.789537) (xy 88.852541 -282.82997) (xy 88.875231 -282.874502)
			(xy 88.890675 -282.922034) (xy 88.898494 -282.971397) (xy 88.898984 -282.996386) (xy 88.898494 -283.021375)
			(xy 88.890675 -283.070738) (xy 88.875231 -283.11827) (xy 88.852541 -283.162802) (xy 88.823165 -283.203235)
			(xy 88.787825 -283.238575) (xy 88.747392 -283.267951) (xy 88.70286 -283.290641) (xy 88.655328 -283.306085)
			(xy 88.605965 -283.313904) (xy 88.555987 -283.313904) (xy 88.506624 -283.306085) (xy 88.459092 -283.290641)
			(xy 88.41456 -283.267951) (xy 88.374127 -283.238575) (xy 88.338787 -283.203235) (xy 88.309411 -283.162802)
			(xy 88.286721 -283.11827) (xy 88.271277 -283.070738) (xy 88.263458 -283.021375) (xy 87.956141 -283.021375)
			(xy 87.956132 -283.021832) (xy 87.947968 -283.072066) (xy 87.931852 -283.12034) (xy 87.908201 -283.165403)
			(xy 87.877628 -283.206089) (xy 87.840924 -283.241344) (xy 87.79904 -283.270254) (xy 87.753061 -283.292071)
			(xy 87.704177 -283.306231) (xy 87.653656 -283.312365) (xy 87.602804 -283.310316) (xy 87.55294 -283.300136)
			(xy 87.505354 -283.282089) (xy 87.46128 -283.256643) (xy 87.421858 -283.224456) (xy 87.38811 -283.186362)
			(xy 87.360909 -283.143348) (xy 87.340961 -283.096528) (xy 87.328782 -283.047114) (xy 87.324687 -282.996386)
			(xy 86.07679 -282.996386) (xy 86.076278 -283.021832) (xy 86.068114 -283.072066) (xy 86.051998 -283.12034)
			(xy 86.028347 -283.165403) (xy 85.997774 -283.206089) (xy 85.96107 -283.241344) (xy 85.919186 -283.270254)
			(xy 85.873207 -283.292071) (xy 85.824323 -283.306231) (xy 85.773802 -283.312365) (xy 85.72295 -283.310316)
			(xy 85.673086 -283.300136) (xy 85.6255 -283.282089) (xy 85.581426 -283.256643) (xy 85.542004 -283.224456)
			(xy 85.508256 -283.186362) (xy 85.481055 -283.143348) (xy 85.461107 -283.096528) (xy 85.448928 -283.047114)
			(xy 85.444833 -282.996386) (xy 85.136736 -282.996386) (xy 85.136224 -283.021832) (xy 85.12806 -283.072066)
			(xy 85.111944 -283.12034) (xy 85.088293 -283.165403) (xy 85.05772 -283.206089) (xy 85.021016 -283.241344)
			(xy 84.979132 -283.270254) (xy 84.933153 -283.292071) (xy 84.884269 -283.306231) (xy 84.833748 -283.312365)
			(xy 84.782896 -283.310316) (xy 84.733032 -283.300136) (xy 84.685446 -283.282089) (xy 84.641372 -283.256643)
			(xy 84.60195 -283.224456) (xy 84.568202 -283.186362) (xy 84.541001 -283.143348) (xy 84.521053 -283.096528)
			(xy 84.508874 -283.047114) (xy 84.504779 -282.996386) (xy 84.198968 -282.996386) (xy 84.198478 -283.021375)
			(xy 84.190659 -283.070738) (xy 84.175215 -283.11827) (xy 84.152525 -283.162802) (xy 84.123149 -283.203235)
			(xy 84.087809 -283.238575) (xy 84.047376 -283.267951) (xy 84.002844 -283.290641) (xy 83.955312 -283.306085)
			(xy 83.905949 -283.313904) (xy 83.855971 -283.313904) (xy 83.806608 -283.306085) (xy 83.759076 -283.290641)
			(xy 83.714544 -283.267951) (xy 83.674111 -283.238575) (xy 83.638771 -283.203235) (xy 83.609395 -283.162802)
			(xy 83.586705 -283.11827) (xy 83.571261 -283.070738) (xy 83.563442 -283.021375) (xy 83.256125 -283.021375)
			(xy 83.256116 -283.021832) (xy 83.247952 -283.072066) (xy 83.231836 -283.12034) (xy 83.208185 -283.165403)
			(xy 83.177612 -283.206089) (xy 83.140908 -283.241344) (xy 83.099024 -283.270254) (xy 83.053045 -283.292071)
			(xy 83.004161 -283.306231) (xy 82.95364 -283.312365) (xy 82.902788 -283.310316) (xy 82.852924 -283.300136)
			(xy 82.805338 -283.282089) (xy 82.761264 -283.256643) (xy 82.721842 -283.224456) (xy 82.688094 -283.186362)
			(xy 82.660893 -283.143348) (xy 82.640945 -283.096528) (xy 82.628766 -283.047114) (xy 82.624671 -282.996386)
			(xy 82.319114 -282.996386) (xy 82.318624 -283.021375) (xy 82.310805 -283.070738) (xy 82.295361 -283.11827)
			(xy 82.272671 -283.162802) (xy 82.243295 -283.203235) (xy 82.207955 -283.238575) (xy 82.167522 -283.267951)
			(xy 82.12299 -283.290641) (xy 82.075458 -283.306085) (xy 82.026095 -283.313904) (xy 81.976117 -283.313904)
			(xy 81.926754 -283.306085) (xy 81.879222 -283.290641) (xy 81.83469 -283.267951) (xy 81.794257 -283.238575)
			(xy 81.758917 -283.203235) (xy 81.729541 -283.162802) (xy 81.706851 -283.11827) (xy 81.691407 -283.070738)
			(xy 81.683588 -283.021375) (xy 81.376271 -283.021375) (xy 81.376262 -283.021832) (xy 81.368098 -283.072066)
			(xy 81.351982 -283.12034) (xy 81.328331 -283.165403) (xy 81.297758 -283.206089) (xy 81.261054 -283.241344)
			(xy 81.21917 -283.270254) (xy 81.173191 -283.292071) (xy 81.124307 -283.306231) (xy 81.073786 -283.312365)
			(xy 81.022934 -283.310316) (xy 80.97307 -283.300136) (xy 80.925484 -283.282089) (xy 80.88141 -283.256643)
			(xy 80.841988 -283.224456) (xy 80.80824 -283.186362) (xy 80.781039 -283.143348) (xy 80.761091 -283.096528)
			(xy 80.748912 -283.047114) (xy 80.744817 -282.996386) (xy 79.53248 -282.996386) (xy 79.53248 -283.831381)
			(xy 80.273634 -283.831381) (xy 80.273634 -283.781403) (xy 80.281453 -283.73204) (xy 80.296897 -283.684508)
			(xy 80.319587 -283.639976) (xy 80.348963 -283.599543) (xy 80.384303 -283.564203) (xy 80.424736 -283.534827)
			(xy 80.469268 -283.512137) (xy 80.5168 -283.496693) (xy 80.566163 -283.488874) (xy 80.616141 -283.488874)
			(xy 80.665504 -283.496693) (xy 80.713036 -283.512137) (xy 80.757568 -283.534827) (xy 80.798001 -283.564203)
			(xy 80.833341 -283.599543) (xy 80.862717 -283.639976) (xy 80.885407 -283.684508) (xy 80.900851 -283.73204)
			(xy 80.90867 -283.781403) (xy 80.90916 -283.806392) (xy 81.214717 -283.806392) (xy 81.218812 -283.755664)
			(xy 81.230991 -283.70625) (xy 81.250939 -283.65943) (xy 81.27814 -283.616416) (xy 81.311888 -283.578322)
			(xy 81.35131 -283.546135) (xy 81.395384 -283.520689) (xy 81.44297 -283.502642) (xy 81.492834 -283.492462)
			(xy 81.543686 -283.490413) (xy 81.594207 -283.496547) (xy 81.643091 -283.510707) (xy 81.68907 -283.532524)
			(xy 81.730954 -283.561434) (xy 81.767658 -283.596689) (xy 81.798231 -283.637375) (xy 81.821882 -283.682438)
			(xy 81.837998 -283.730712) (xy 81.846162 -283.780946) (xy 81.846674 -283.806392) (xy 82.154771 -283.806392)
			(xy 82.158866 -283.755664) (xy 82.171045 -283.70625) (xy 82.190993 -283.65943) (xy 82.218194 -283.616416)
			(xy 82.251942 -283.578322) (xy 82.291364 -283.546135) (xy 82.335438 -283.520689) (xy 82.383024 -283.502642)
			(xy 82.432888 -283.492462) (xy 82.48374 -283.490413) (xy 82.534261 -283.496547) (xy 82.583145 -283.510707)
			(xy 82.629124 -283.532524) (xy 82.671008 -283.561434) (xy 82.707712 -283.596689) (xy 82.738285 -283.637375)
			(xy 82.761936 -283.682438) (xy 82.778052 -283.730712) (xy 82.786216 -283.780946) (xy 82.786728 -283.806392)
			(xy 82.786225 -283.831381) (xy 83.093542 -283.831381) (xy 83.093542 -283.781403) (xy 83.101361 -283.73204)
			(xy 83.116805 -283.684508) (xy 83.139495 -283.639976) (xy 83.168871 -283.599543) (xy 83.204211 -283.564203)
			(xy 83.244644 -283.534827) (xy 83.289176 -283.512137) (xy 83.336708 -283.496693) (xy 83.386071 -283.488874)
			(xy 83.436049 -283.488874) (xy 83.485412 -283.496693) (xy 83.532944 -283.512137) (xy 83.577476 -283.534827)
			(xy 83.617909 -283.564203) (xy 83.653249 -283.599543) (xy 83.682625 -283.639976) (xy 83.705315 -283.684508)
			(xy 83.720759 -283.73204) (xy 83.728578 -283.781403) (xy 83.729068 -283.806392) (xy 84.034879 -283.806392)
			(xy 84.038974 -283.755664) (xy 84.051153 -283.70625) (xy 84.071101 -283.65943) (xy 84.098302 -283.616416)
			(xy 84.13205 -283.578322) (xy 84.171472 -283.546135) (xy 84.215546 -283.520689) (xy 84.263132 -283.502642)
			(xy 84.312996 -283.492462) (xy 84.363848 -283.490413) (xy 84.414369 -283.496547) (xy 84.463253 -283.510707)
			(xy 84.509232 -283.532524) (xy 84.551116 -283.561434) (xy 84.58782 -283.596689) (xy 84.618393 -283.637375)
			(xy 84.642044 -283.682438) (xy 84.65816 -283.730712) (xy 84.666324 -283.780946) (xy 84.666836 -283.806392)
			(xy 84.666333 -283.831381) (xy 84.973396 -283.831381) (xy 84.973396 -283.781403) (xy 84.981215 -283.73204)
			(xy 84.996659 -283.684508) (xy 85.019349 -283.639976) (xy 85.048725 -283.599543) (xy 85.084065 -283.564203)
			(xy 85.124498 -283.534827) (xy 85.16903 -283.512137) (xy 85.216562 -283.496693) (xy 85.265925 -283.488874)
			(xy 85.315903 -283.488874) (xy 85.365266 -283.496693) (xy 85.412798 -283.512137) (xy 85.45733 -283.534827)
			(xy 85.497763 -283.564203) (xy 85.533103 -283.599543) (xy 85.562479 -283.639976) (xy 85.585169 -283.684508)
			(xy 85.600613 -283.73204) (xy 85.608432 -283.781403) (xy 85.608922 -283.806392) (xy 85.914733 -283.806392)
			(xy 85.918828 -283.755664) (xy 85.931007 -283.70625) (xy 85.950955 -283.65943) (xy 85.978156 -283.616416)
			(xy 86.011904 -283.578322) (xy 86.051326 -283.546135) (xy 86.0954 -283.520689) (xy 86.142986 -283.502642)
			(xy 86.19285 -283.492462) (xy 86.243702 -283.490413) (xy 86.294223 -283.496547) (xy 86.343107 -283.510707)
			(xy 86.389086 -283.532524) (xy 86.43097 -283.561434) (xy 86.467674 -283.596689) (xy 86.498247 -283.637375)
			(xy 86.521898 -283.682438) (xy 86.538014 -283.730712) (xy 86.546178 -283.780946) (xy 86.54669 -283.806392)
			(xy 86.546187 -283.831381) (xy 86.853504 -283.831381) (xy 86.853504 -283.781403) (xy 86.861323 -283.73204)
			(xy 86.876767 -283.684508) (xy 86.899457 -283.639976) (xy 86.928833 -283.599543) (xy 86.964173 -283.564203)
			(xy 87.004606 -283.534827) (xy 87.049138 -283.512137) (xy 87.09667 -283.496693) (xy 87.146033 -283.488874)
			(xy 87.196011 -283.488874) (xy 87.245374 -283.496693) (xy 87.292906 -283.512137) (xy 87.337438 -283.534827)
			(xy 87.377871 -283.564203) (xy 87.413211 -283.599543) (xy 87.442587 -283.639976) (xy 87.465277 -283.684508)
			(xy 87.480721 -283.73204) (xy 87.48854 -283.781403) (xy 87.48903 -283.806392) (xy 87.794841 -283.806392)
			(xy 87.798936 -283.755664) (xy 87.811115 -283.70625) (xy 87.831063 -283.65943) (xy 87.858264 -283.616416)
			(xy 87.892012 -283.578322) (xy 87.931434 -283.546135) (xy 87.975508 -283.520689) (xy 88.023094 -283.502642)
			(xy 88.072958 -283.492462) (xy 88.12381 -283.490413) (xy 88.174331 -283.496547) (xy 88.223215 -283.510707)
			(xy 88.269194 -283.532524) (xy 88.311078 -283.561434) (xy 88.347782 -283.596689) (xy 88.378355 -283.637375)
			(xy 88.402006 -283.682438) (xy 88.418122 -283.730712) (xy 88.426286 -283.780946) (xy 88.426798 -283.806392)
			(xy 88.734895 -283.806392) (xy 88.73899 -283.755664) (xy 88.751169 -283.70625) (xy 88.771117 -283.65943)
			(xy 88.798318 -283.616416) (xy 88.832066 -283.578322) (xy 88.871488 -283.546135) (xy 88.915562 -283.520689)
			(xy 88.963148 -283.502642) (xy 89.013012 -283.492462) (xy 89.063864 -283.490413) (xy 89.114385 -283.496547)
			(xy 89.163269 -283.510707) (xy 89.209248 -283.532524) (xy 89.251132 -283.561434) (xy 89.287836 -283.596689)
			(xy 89.318409 -283.637375) (xy 89.34206 -283.682438) (xy 89.358176 -283.730712) (xy 89.36634 -283.780946)
			(xy 89.366852 -283.806392) (xy 89.36634 -283.831838) (xy 89.358176 -283.882072) (xy 89.34206 -283.930346)
			(xy 89.318409 -283.975409) (xy 89.287836 -284.016095) (xy 89.251132 -284.05135) (xy 89.209248 -284.08026)
			(xy 89.163269 -284.102077) (xy 89.114385 -284.116237) (xy 89.063864 -284.122371) (xy 89.013012 -284.120322)
			(xy 88.963148 -284.110142) (xy 88.915562 -284.092095) (xy 88.871488 -284.066649) (xy 88.832066 -284.034462)
			(xy 88.798318 -283.996368) (xy 88.771117 -283.953354) (xy 88.751169 -283.906534) (xy 88.73899 -283.85712)
			(xy 88.734895 -283.806392) (xy 88.426798 -283.806392) (xy 88.426286 -283.831838) (xy 88.418122 -283.882072)
			(xy 88.402006 -283.930346) (xy 88.378355 -283.975409) (xy 88.347782 -284.016095) (xy 88.311078 -284.05135)
			(xy 88.269194 -284.08026) (xy 88.223215 -284.102077) (xy 88.174331 -284.116237) (xy 88.12381 -284.122371)
			(xy 88.072958 -284.120322) (xy 88.023094 -284.110142) (xy 87.975508 -284.092095) (xy 87.931434 -284.066649)
			(xy 87.892012 -284.034462) (xy 87.858264 -283.996368) (xy 87.831063 -283.953354) (xy 87.811115 -283.906534)
			(xy 87.798936 -283.85712) (xy 87.794841 -283.806392) (xy 87.48903 -283.806392) (xy 87.48854 -283.831381)
			(xy 87.480721 -283.880744) (xy 87.465277 -283.928276) (xy 87.442587 -283.972808) (xy 87.413211 -284.013241)
			(xy 87.377871 -284.048581) (xy 87.337438 -284.077957) (xy 87.292906 -284.100647) (xy 87.245374 -284.116091)
			(xy 87.196011 -284.12391) (xy 87.146033 -284.12391) (xy 87.09667 -284.116091) (xy 87.049138 -284.100647)
			(xy 87.004606 -284.077957) (xy 86.964173 -284.048581) (xy 86.928833 -284.013241) (xy 86.899457 -283.972808)
			(xy 86.876767 -283.928276) (xy 86.861323 -283.880744) (xy 86.853504 -283.831381) (xy 86.546187 -283.831381)
			(xy 86.546178 -283.831838) (xy 86.538014 -283.882072) (xy 86.521898 -283.930346) (xy 86.498247 -283.975409)
			(xy 86.467674 -284.016095) (xy 86.43097 -284.05135) (xy 86.389086 -284.08026) (xy 86.343107 -284.102077)
			(xy 86.294223 -284.116237) (xy 86.243702 -284.122371) (xy 86.19285 -284.120322) (xy 86.142986 -284.110142)
			(xy 86.0954 -284.092095) (xy 86.051326 -284.066649) (xy 86.011904 -284.034462) (xy 85.978156 -283.996368)
			(xy 85.950955 -283.953354) (xy 85.931007 -283.906534) (xy 85.918828 -283.85712) (xy 85.914733 -283.806392)
			(xy 85.608922 -283.806392) (xy 85.608432 -283.831381) (xy 85.600613 -283.880744) (xy 85.585169 -283.928276)
			(xy 85.562479 -283.972808) (xy 85.533103 -284.013241) (xy 85.497763 -284.048581) (xy 85.45733 -284.077957)
			(xy 85.412798 -284.100647) (xy 85.365266 -284.116091) (xy 85.315903 -284.12391) (xy 85.265925 -284.12391)
			(xy 85.216562 -284.116091) (xy 85.16903 -284.100647) (xy 85.124498 -284.077957) (xy 85.084065 -284.048581)
			(xy 85.048725 -284.013241) (xy 85.019349 -283.972808) (xy 84.996659 -283.928276) (xy 84.981215 -283.880744)
			(xy 84.973396 -283.831381) (xy 84.666333 -283.831381) (xy 84.666324 -283.831838) (xy 84.65816 -283.882072)
			(xy 84.642044 -283.930346) (xy 84.618393 -283.975409) (xy 84.58782 -284.016095) (xy 84.551116 -284.05135)
			(xy 84.509232 -284.08026) (xy 84.463253 -284.102077) (xy 84.414369 -284.116237) (xy 84.363848 -284.122371)
			(xy 84.312996 -284.120322) (xy 84.263132 -284.110142) (xy 84.215546 -284.092095) (xy 84.171472 -284.066649)
			(xy 84.13205 -284.034462) (xy 84.098302 -283.996368) (xy 84.071101 -283.953354) (xy 84.051153 -283.906534)
			(xy 84.038974 -283.85712) (xy 84.034879 -283.806392) (xy 83.729068 -283.806392) (xy 83.728578 -283.831381)
			(xy 83.720759 -283.880744) (xy 83.705315 -283.928276) (xy 83.682625 -283.972808) (xy 83.653249 -284.013241)
			(xy 83.617909 -284.048581) (xy 83.577476 -284.077957) (xy 83.532944 -284.100647) (xy 83.485412 -284.116091)
			(xy 83.436049 -284.12391) (xy 83.386071 -284.12391) (xy 83.336708 -284.116091) (xy 83.289176 -284.100647)
			(xy 83.244644 -284.077957) (xy 83.204211 -284.048581) (xy 83.168871 -284.013241) (xy 83.139495 -283.972808)
			(xy 83.116805 -283.928276) (xy 83.101361 -283.880744) (xy 83.093542 -283.831381) (xy 82.786225 -283.831381)
			(xy 82.786216 -283.831838) (xy 82.778052 -283.882072) (xy 82.761936 -283.930346) (xy 82.738285 -283.975409)
			(xy 82.707712 -284.016095) (xy 82.671008 -284.05135) (xy 82.629124 -284.08026) (xy 82.583145 -284.102077)
			(xy 82.534261 -284.116237) (xy 82.48374 -284.122371) (xy 82.432888 -284.120322) (xy 82.383024 -284.110142)
			(xy 82.335438 -284.092095) (xy 82.291364 -284.066649) (xy 82.251942 -284.034462) (xy 82.218194 -283.996368)
			(xy 82.190993 -283.953354) (xy 82.171045 -283.906534) (xy 82.158866 -283.85712) (xy 82.154771 -283.806392)
			(xy 81.846674 -283.806392) (xy 81.846162 -283.831838) (xy 81.837998 -283.882072) (xy 81.821882 -283.930346)
			(xy 81.798231 -283.975409) (xy 81.767658 -284.016095) (xy 81.730954 -284.05135) (xy 81.68907 -284.08026)
			(xy 81.643091 -284.102077) (xy 81.594207 -284.116237) (xy 81.543686 -284.122371) (xy 81.492834 -284.120322)
			(xy 81.44297 -284.110142) (xy 81.395384 -284.092095) (xy 81.35131 -284.066649) (xy 81.311888 -284.034462)
			(xy 81.27814 -283.996368) (xy 81.250939 -283.953354) (xy 81.230991 -283.906534) (xy 81.218812 -283.85712)
			(xy 81.214717 -283.806392) (xy 80.90916 -283.806392) (xy 80.90867 -283.831381) (xy 80.900851 -283.880744)
			(xy 80.885407 -283.928276) (xy 80.862717 -283.972808) (xy 80.833341 -284.013241) (xy 80.798001 -284.048581)
			(xy 80.757568 -284.077957) (xy 80.713036 -284.100647) (xy 80.665504 -284.116091) (xy 80.616141 -284.12391)
			(xy 80.566163 -284.12391) (xy 80.5168 -284.116091) (xy 80.469268 -284.100647) (xy 80.424736 -284.077957)
			(xy 80.384303 -284.048581) (xy 80.348963 -284.013241) (xy 80.319587 -283.972808) (xy 80.296897 -283.928276)
			(xy 80.281453 -283.880744) (xy 80.273634 -283.831381) (xy 79.53248 -283.831381) (xy 79.53248 -284.641387)
			(xy 79.80348 -284.641387) (xy 79.80348 -284.591409) (xy 79.811299 -284.542046) (xy 79.826743 -284.494514)
			(xy 79.849433 -284.449982) (xy 79.878809 -284.409549) (xy 79.914149 -284.374209) (xy 79.954582 -284.344833)
			(xy 79.999114 -284.322143) (xy 80.046646 -284.306699) (xy 80.096009 -284.29888) (xy 80.145987 -284.29888)
			(xy 80.19535 -284.306699) (xy 80.242882 -284.322143) (xy 80.287414 -284.344833) (xy 80.327847 -284.374209)
			(xy 80.363187 -284.409549) (xy 80.392563 -284.449982) (xy 80.415253 -284.494514) (xy 80.430697 -284.542046)
			(xy 80.438516 -284.591409) (xy 80.439006 -284.616398) (xy 80.744817 -284.616398) (xy 80.748912 -284.56567)
			(xy 80.761091 -284.516256) (xy 80.781039 -284.469436) (xy 80.80824 -284.426422) (xy 80.841988 -284.388328)
			(xy 80.88141 -284.356141) (xy 80.925484 -284.330695) (xy 80.97307 -284.312648) (xy 81.022934 -284.302468)
			(xy 81.073786 -284.300419) (xy 81.124307 -284.306553) (xy 81.173191 -284.320713) (xy 81.21917 -284.34253)
			(xy 81.261054 -284.37144) (xy 81.297758 -284.406695) (xy 81.328331 -284.447381) (xy 81.351982 -284.492444)
			(xy 81.368098 -284.540718) (xy 81.376262 -284.590952) (xy 81.376774 -284.616398) (xy 81.376271 -284.641387)
			(xy 81.683588 -284.641387) (xy 81.683588 -284.591409) (xy 81.691407 -284.542046) (xy 81.706851 -284.494514)
			(xy 81.729541 -284.449982) (xy 81.758917 -284.409549) (xy 81.794257 -284.374209) (xy 81.83469 -284.344833)
			(xy 81.879222 -284.322143) (xy 81.926754 -284.306699) (xy 81.976117 -284.29888) (xy 82.026095 -284.29888)
			(xy 82.075458 -284.306699) (xy 82.12299 -284.322143) (xy 82.167522 -284.344833) (xy 82.207955 -284.374209)
			(xy 82.243295 -284.409549) (xy 82.272671 -284.449982) (xy 82.295361 -284.494514) (xy 82.310805 -284.542046)
			(xy 82.318624 -284.591409) (xy 82.319114 -284.616398) (xy 82.624671 -284.616398) (xy 82.628766 -284.56567)
			(xy 82.640945 -284.516256) (xy 82.660893 -284.469436) (xy 82.688094 -284.426422) (xy 82.721842 -284.388328)
			(xy 82.761264 -284.356141) (xy 82.805338 -284.330695) (xy 82.852924 -284.312648) (xy 82.902788 -284.302468)
			(xy 82.95364 -284.300419) (xy 83.004161 -284.306553) (xy 83.053045 -284.320713) (xy 83.099024 -284.34253)
			(xy 83.140908 -284.37144) (xy 83.177612 -284.406695) (xy 83.208185 -284.447381) (xy 83.231836 -284.492444)
			(xy 83.247952 -284.540718) (xy 83.256116 -284.590952) (xy 83.256628 -284.616398) (xy 83.256125 -284.641387)
			(xy 83.563442 -284.641387) (xy 83.563442 -284.591409) (xy 83.571261 -284.542046) (xy 83.586705 -284.494514)
			(xy 83.609395 -284.449982) (xy 83.638771 -284.409549) (xy 83.674111 -284.374209) (xy 83.714544 -284.344833)
			(xy 83.759076 -284.322143) (xy 83.806608 -284.306699) (xy 83.855971 -284.29888) (xy 83.905949 -284.29888)
			(xy 83.955312 -284.306699) (xy 84.002844 -284.322143) (xy 84.047376 -284.344833) (xy 84.087809 -284.374209)
			(xy 84.123149 -284.409549) (xy 84.152525 -284.449982) (xy 84.175215 -284.494514) (xy 84.190659 -284.542046)
			(xy 84.198478 -284.591409) (xy 84.198968 -284.616398) (xy 84.504779 -284.616398) (xy 84.508874 -284.56567)
			(xy 84.521053 -284.516256) (xy 84.541001 -284.469436) (xy 84.568202 -284.426422) (xy 84.60195 -284.388328)
			(xy 84.641372 -284.356141) (xy 84.685446 -284.330695) (xy 84.733032 -284.312648) (xy 84.782896 -284.302468)
			(xy 84.833748 -284.300419) (xy 84.884269 -284.306553) (xy 84.933153 -284.320713) (xy 84.979132 -284.34253)
			(xy 85.021016 -284.37144) (xy 85.05772 -284.406695) (xy 85.088293 -284.447381) (xy 85.111944 -284.492444)
			(xy 85.12806 -284.540718) (xy 85.136224 -284.590952) (xy 85.136736 -284.616398) (xy 85.444833 -284.616398)
			(xy 85.448928 -284.56567) (xy 85.461107 -284.516256) (xy 85.481055 -284.469436) (xy 85.508256 -284.426422)
			(xy 85.542004 -284.388328) (xy 85.581426 -284.356141) (xy 85.6255 -284.330695) (xy 85.673086 -284.312648)
			(xy 85.72295 -284.302468) (xy 85.773802 -284.300419) (xy 85.824323 -284.306553) (xy 85.873207 -284.320713)
			(xy 85.919186 -284.34253) (xy 85.96107 -284.37144) (xy 85.997774 -284.406695) (xy 86.028347 -284.447381)
			(xy 86.051998 -284.492444) (xy 86.068114 -284.540718) (xy 86.076278 -284.590952) (xy 86.07679 -284.616398)
			(xy 86.076287 -284.641387) (xy 86.383604 -284.641387) (xy 86.383604 -284.591409) (xy 86.391423 -284.542046)
			(xy 86.406867 -284.494514) (xy 86.429557 -284.449982) (xy 86.458933 -284.409549) (xy 86.494273 -284.374209)
			(xy 86.534706 -284.344833) (xy 86.579238 -284.322143) (xy 86.62677 -284.306699) (xy 86.676133 -284.29888)
			(xy 86.726111 -284.29888) (xy 86.775474 -284.306699) (xy 86.823006 -284.322143) (xy 86.867538 -284.344833)
			(xy 86.907971 -284.374209) (xy 86.943311 -284.409549) (xy 86.972687 -284.449982) (xy 86.995377 -284.494514)
			(xy 87.010821 -284.542046) (xy 87.01864 -284.591409) (xy 87.01913 -284.616398) (xy 87.324687 -284.616398)
			(xy 87.328782 -284.56567) (xy 87.340961 -284.516256) (xy 87.360909 -284.469436) (xy 87.38811 -284.426422)
			(xy 87.421858 -284.388328) (xy 87.46128 -284.356141) (xy 87.505354 -284.330695) (xy 87.55294 -284.312648)
			(xy 87.602804 -284.302468) (xy 87.653656 -284.300419) (xy 87.704177 -284.306553) (xy 87.753061 -284.320713)
			(xy 87.79904 -284.34253) (xy 87.840924 -284.37144) (xy 87.877628 -284.406695) (xy 87.908201 -284.447381)
			(xy 87.931852 -284.492444) (xy 87.947968 -284.540718) (xy 87.956132 -284.590952) (xy 87.956644 -284.616398)
			(xy 87.956141 -284.641387) (xy 88.263458 -284.641387) (xy 88.263458 -284.591409) (xy 88.271277 -284.542046)
			(xy 88.286721 -284.494514) (xy 88.309411 -284.449982) (xy 88.338787 -284.409549) (xy 88.374127 -284.374209)
			(xy 88.41456 -284.344833) (xy 88.459092 -284.322143) (xy 88.506624 -284.306699) (xy 88.555987 -284.29888)
			(xy 88.605965 -284.29888) (xy 88.655328 -284.306699) (xy 88.70286 -284.322143) (xy 88.747392 -284.344833)
			(xy 88.787825 -284.374209) (xy 88.823165 -284.409549) (xy 88.852541 -284.449982) (xy 88.875231 -284.494514)
			(xy 88.890675 -284.542046) (xy 88.898494 -284.591409) (xy 88.898984 -284.616398) (xy 88.898494 -284.641387)
			(xy 88.890675 -284.69075) (xy 88.875231 -284.738282) (xy 88.852541 -284.782814) (xy 88.823165 -284.823247)
			(xy 88.787825 -284.858587) (xy 88.747392 -284.887963) (xy 88.70286 -284.910653) (xy 88.655328 -284.926097)
			(xy 88.605965 -284.933916) (xy 88.555987 -284.933916) (xy 88.506624 -284.926097) (xy 88.459092 -284.910653)
			(xy 88.41456 -284.887963) (xy 88.374127 -284.858587) (xy 88.338787 -284.823247) (xy 88.309411 -284.782814)
			(xy 88.286721 -284.738282) (xy 88.271277 -284.69075) (xy 88.263458 -284.641387) (xy 87.956141 -284.641387)
			(xy 87.956132 -284.641844) (xy 87.947968 -284.692078) (xy 87.931852 -284.740352) (xy 87.908201 -284.785415)
			(xy 87.877628 -284.826101) (xy 87.840924 -284.861356) (xy 87.79904 -284.890266) (xy 87.753061 -284.912083)
			(xy 87.704177 -284.926243) (xy 87.653656 -284.932377) (xy 87.602804 -284.930328) (xy 87.55294 -284.920148)
			(xy 87.505354 -284.902101) (xy 87.46128 -284.876655) (xy 87.421858 -284.844468) (xy 87.38811 -284.806374)
			(xy 87.360909 -284.76336) (xy 87.340961 -284.71654) (xy 87.328782 -284.667126) (xy 87.324687 -284.616398)
			(xy 87.01913 -284.616398) (xy 87.01864 -284.641387) (xy 87.010821 -284.69075) (xy 86.995377 -284.738282)
			(xy 86.972687 -284.782814) (xy 86.943311 -284.823247) (xy 86.907971 -284.858587) (xy 86.867538 -284.887963)
			(xy 86.823006 -284.910653) (xy 86.775474 -284.926097) (xy 86.726111 -284.933916) (xy 86.676133 -284.933916)
			(xy 86.62677 -284.926097) (xy 86.579238 -284.910653) (xy 86.534706 -284.887963) (xy 86.494273 -284.858587)
			(xy 86.458933 -284.823247) (xy 86.429557 -284.782814) (xy 86.406867 -284.738282) (xy 86.391423 -284.69075)
			(xy 86.383604 -284.641387) (xy 86.076287 -284.641387) (xy 86.076278 -284.641844) (xy 86.068114 -284.692078)
			(xy 86.051998 -284.740352) (xy 86.028347 -284.785415) (xy 85.997774 -284.826101) (xy 85.96107 -284.861356)
			(xy 85.919186 -284.890266) (xy 85.873207 -284.912083) (xy 85.824323 -284.926243) (xy 85.773802 -284.932377)
			(xy 85.72295 -284.930328) (xy 85.673086 -284.920148) (xy 85.6255 -284.902101) (xy 85.581426 -284.876655)
			(xy 85.542004 -284.844468) (xy 85.508256 -284.806374) (xy 85.481055 -284.76336) (xy 85.461107 -284.71654)
			(xy 85.448928 -284.667126) (xy 85.444833 -284.616398) (xy 85.136736 -284.616398) (xy 85.136224 -284.641844)
			(xy 85.12806 -284.692078) (xy 85.111944 -284.740352) (xy 85.088293 -284.785415) (xy 85.05772 -284.826101)
			(xy 85.021016 -284.861356) (xy 84.979132 -284.890266) (xy 84.933153 -284.912083) (xy 84.884269 -284.926243)
			(xy 84.833748 -284.932377) (xy 84.782896 -284.930328) (xy 84.733032 -284.920148) (xy 84.685446 -284.902101)
			(xy 84.641372 -284.876655) (xy 84.60195 -284.844468) (xy 84.568202 -284.806374) (xy 84.541001 -284.76336)
			(xy 84.521053 -284.71654) (xy 84.508874 -284.667126) (xy 84.504779 -284.616398) (xy 84.198968 -284.616398)
			(xy 84.198478 -284.641387) (xy 84.190659 -284.69075) (xy 84.175215 -284.738282) (xy 84.152525 -284.782814)
			(xy 84.123149 -284.823247) (xy 84.087809 -284.858587) (xy 84.047376 -284.887963) (xy 84.002844 -284.910653)
			(xy 83.955312 -284.926097) (xy 83.905949 -284.933916) (xy 83.855971 -284.933916) (xy 83.806608 -284.926097)
			(xy 83.759076 -284.910653) (xy 83.714544 -284.887963) (xy 83.674111 -284.858587) (xy 83.638771 -284.823247)
			(xy 83.609395 -284.782814) (xy 83.586705 -284.738282) (xy 83.571261 -284.69075) (xy 83.563442 -284.641387)
			(xy 83.256125 -284.641387) (xy 83.256116 -284.641844) (xy 83.247952 -284.692078) (xy 83.231836 -284.740352)
			(xy 83.208185 -284.785415) (xy 83.177612 -284.826101) (xy 83.140908 -284.861356) (xy 83.099024 -284.890266)
			(xy 83.053045 -284.912083) (xy 83.004161 -284.926243) (xy 82.95364 -284.932377) (xy 82.902788 -284.930328)
			(xy 82.852924 -284.920148) (xy 82.805338 -284.902101) (xy 82.761264 -284.876655) (xy 82.721842 -284.844468)
			(xy 82.688094 -284.806374) (xy 82.660893 -284.76336) (xy 82.640945 -284.71654) (xy 82.628766 -284.667126)
			(xy 82.624671 -284.616398) (xy 82.319114 -284.616398) (xy 82.318624 -284.641387) (xy 82.310805 -284.69075)
			(xy 82.295361 -284.738282) (xy 82.272671 -284.782814) (xy 82.243295 -284.823247) (xy 82.207955 -284.858587)
			(xy 82.167522 -284.887963) (xy 82.12299 -284.910653) (xy 82.075458 -284.926097) (xy 82.026095 -284.933916)
			(xy 81.976117 -284.933916) (xy 81.926754 -284.926097) (xy 81.879222 -284.910653) (xy 81.83469 -284.887963)
			(xy 81.794257 -284.858587) (xy 81.758917 -284.823247) (xy 81.729541 -284.782814) (xy 81.706851 -284.738282)
			(xy 81.691407 -284.69075) (xy 81.683588 -284.641387) (xy 81.376271 -284.641387) (xy 81.376262 -284.641844)
			(xy 81.368098 -284.692078) (xy 81.351982 -284.740352) (xy 81.328331 -284.785415) (xy 81.297758 -284.826101)
			(xy 81.261054 -284.861356) (xy 81.21917 -284.890266) (xy 81.173191 -284.912083) (xy 81.124307 -284.926243)
			(xy 81.073786 -284.932377) (xy 81.022934 -284.930328) (xy 80.97307 -284.920148) (xy 80.925484 -284.902101)
			(xy 80.88141 -284.876655) (xy 80.841988 -284.844468) (xy 80.80824 -284.806374) (xy 80.781039 -284.76336)
			(xy 80.761091 -284.71654) (xy 80.748912 -284.667126) (xy 80.744817 -284.616398) (xy 80.439006 -284.616398)
			(xy 80.438516 -284.641387) (xy 80.430697 -284.69075) (xy 80.415253 -284.738282) (xy 80.392563 -284.782814)
			(xy 80.363187 -284.823247) (xy 80.327847 -284.858587) (xy 80.287414 -284.887963) (xy 80.242882 -284.910653)
			(xy 80.19535 -284.926097) (xy 80.145987 -284.933916) (xy 80.096009 -284.933916) (xy 80.046646 -284.926097)
			(xy 79.999114 -284.910653) (xy 79.954582 -284.887963) (xy 79.914149 -284.858587) (xy 79.878809 -284.823247)
			(xy 79.849433 -284.782814) (xy 79.826743 -284.738282) (xy 79.811299 -284.69075) (xy 79.80348 -284.641387)
			(xy 79.53248 -284.641387) (xy 79.53248 -285.426404) (xy 81.214717 -285.426404) (xy 81.218812 -285.375676)
			(xy 81.230991 -285.326262) (xy 81.250939 -285.279442) (xy 81.27814 -285.236428) (xy 81.311888 -285.198334)
			(xy 81.35131 -285.166147) (xy 81.395384 -285.140701) (xy 81.44297 -285.122654) (xy 81.492834 -285.112474)
			(xy 81.543686 -285.110425) (xy 81.594207 -285.116559) (xy 81.643091 -285.130719) (xy 81.68907 -285.152536)
			(xy 81.730954 -285.181446) (xy 81.767658 -285.216701) (xy 81.798231 -285.257387) (xy 81.821882 -285.30245)
			(xy 81.837998 -285.350724) (xy 81.846162 -285.400958) (xy 81.846674 -285.426404) (xy 82.154771 -285.426404)
			(xy 82.158866 -285.375676) (xy 82.171045 -285.326262) (xy 82.190993 -285.279442) (xy 82.218194 -285.236428)
			(xy 82.251942 -285.198334) (xy 82.291364 -285.166147) (xy 82.335438 -285.140701) (xy 82.383024 -285.122654)
			(xy 82.432888 -285.112474) (xy 82.48374 -285.110425) (xy 82.534261 -285.116559) (xy 82.583145 -285.130719)
			(xy 82.629124 -285.152536) (xy 82.671008 -285.181446) (xy 82.707712 -285.216701) (xy 82.738285 -285.257387)
			(xy 82.761936 -285.30245) (xy 82.778052 -285.350724) (xy 82.786216 -285.400958) (xy 82.786728 -285.426404)
			(xy 82.786225 -285.451393) (xy 83.093542 -285.451393) (xy 83.093542 -285.401415) (xy 83.101361 -285.352052)
			(xy 83.116805 -285.30452) (xy 83.139495 -285.259988) (xy 83.168871 -285.219555) (xy 83.204211 -285.184215)
			(xy 83.244644 -285.154839) (xy 83.289176 -285.132149) (xy 83.336708 -285.116705) (xy 83.386071 -285.108886)
			(xy 83.436049 -285.108886) (xy 83.485412 -285.116705) (xy 83.532944 -285.132149) (xy 83.577476 -285.154839)
			(xy 83.617909 -285.184215) (xy 83.653249 -285.219555) (xy 83.682625 -285.259988) (xy 83.705315 -285.30452)
			(xy 83.720759 -285.352052) (xy 83.728578 -285.401415) (xy 83.729068 -285.426404) (xy 84.034879 -285.426404)
			(xy 84.038974 -285.375676) (xy 84.051153 -285.326262) (xy 84.071101 -285.279442) (xy 84.098302 -285.236428)
			(xy 84.13205 -285.198334) (xy 84.171472 -285.166147) (xy 84.215546 -285.140701) (xy 84.263132 -285.122654)
			(xy 84.312996 -285.112474) (xy 84.363848 -285.110425) (xy 84.414369 -285.116559) (xy 84.463253 -285.130719)
			(xy 84.509232 -285.152536) (xy 84.551116 -285.181446) (xy 84.58782 -285.216701) (xy 84.618393 -285.257387)
			(xy 84.642044 -285.30245) (xy 84.65816 -285.350724) (xy 84.666324 -285.400958) (xy 84.666836 -285.426404)
			(xy 84.666333 -285.451393) (xy 84.973396 -285.451393) (xy 84.973396 -285.401415) (xy 84.981215 -285.352052)
			(xy 84.996659 -285.30452) (xy 85.019349 -285.259988) (xy 85.048725 -285.219555) (xy 85.084065 -285.184215)
			(xy 85.124498 -285.154839) (xy 85.16903 -285.132149) (xy 85.216562 -285.116705) (xy 85.265925 -285.108886)
			(xy 85.315903 -285.108886) (xy 85.365266 -285.116705) (xy 85.412798 -285.132149) (xy 85.45733 -285.154839)
			(xy 85.497763 -285.184215) (xy 85.533103 -285.219555) (xy 85.562479 -285.259988) (xy 85.585169 -285.30452)
			(xy 85.600613 -285.352052) (xy 85.608432 -285.401415) (xy 85.608922 -285.426404) (xy 85.914733 -285.426404)
			(xy 85.918828 -285.375676) (xy 85.931007 -285.326262) (xy 85.950955 -285.279442) (xy 85.978156 -285.236428)
			(xy 86.011904 -285.198334) (xy 86.051326 -285.166147) (xy 86.0954 -285.140701) (xy 86.142986 -285.122654)
			(xy 86.19285 -285.112474) (xy 86.243702 -285.110425) (xy 86.294223 -285.116559) (xy 86.343107 -285.130719)
			(xy 86.389086 -285.152536) (xy 86.43097 -285.181446) (xy 86.467674 -285.216701) (xy 86.498247 -285.257387)
			(xy 86.521898 -285.30245) (xy 86.538014 -285.350724) (xy 86.546178 -285.400958) (xy 86.54669 -285.426404)
			(xy 87.794841 -285.426404) (xy 87.798936 -285.375676) (xy 87.811115 -285.326262) (xy 87.831063 -285.279442)
			(xy 87.858264 -285.236428) (xy 87.892012 -285.198334) (xy 87.931434 -285.166147) (xy 87.975508 -285.140701)
			(xy 88.023094 -285.122654) (xy 88.072958 -285.112474) (xy 88.12381 -285.110425) (xy 88.174331 -285.116559)
			(xy 88.223215 -285.130719) (xy 88.269194 -285.152536) (xy 88.311078 -285.181446) (xy 88.347782 -285.216701)
			(xy 88.378355 -285.257387) (xy 88.402006 -285.30245) (xy 88.418122 -285.350724) (xy 88.426286 -285.400958)
			(xy 88.426798 -285.426404) (xy 88.734895 -285.426404) (xy 88.73899 -285.375676) (xy 88.751169 -285.326262)
			(xy 88.771117 -285.279442) (xy 88.798318 -285.236428) (xy 88.832066 -285.198334) (xy 88.871488 -285.166147)
			(xy 88.915562 -285.140701) (xy 88.963148 -285.122654) (xy 89.013012 -285.112474) (xy 89.063864 -285.110425)
			(xy 89.114385 -285.116559) (xy 89.163269 -285.130719) (xy 89.209248 -285.152536) (xy 89.251132 -285.181446)
			(xy 89.287836 -285.216701) (xy 89.318409 -285.257387) (xy 89.34206 -285.30245) (xy 89.358176 -285.350724)
			(xy 89.36634 -285.400958) (xy 89.366852 -285.426404) (xy 89.36634 -285.45185) (xy 89.358176 -285.502084)
			(xy 89.34206 -285.550358) (xy 89.318409 -285.595421) (xy 89.287836 -285.636107) (xy 89.251132 -285.671362)
			(xy 89.209248 -285.700272) (xy 89.163269 -285.722089) (xy 89.114385 -285.736249) (xy 89.063864 -285.742383)
			(xy 89.013012 -285.740334) (xy 88.963148 -285.730154) (xy 88.915562 -285.712107) (xy 88.871488 -285.686661)
			(xy 88.832066 -285.654474) (xy 88.798318 -285.61638) (xy 88.771117 -285.573366) (xy 88.751169 -285.526546)
			(xy 88.73899 -285.477132) (xy 88.734895 -285.426404) (xy 88.426798 -285.426404) (xy 88.426286 -285.45185)
			(xy 88.418122 -285.502084) (xy 88.402006 -285.550358) (xy 88.378355 -285.595421) (xy 88.347782 -285.636107)
			(xy 88.311078 -285.671362) (xy 88.269194 -285.700272) (xy 88.223215 -285.722089) (xy 88.174331 -285.736249)
			(xy 88.12381 -285.742383) (xy 88.072958 -285.740334) (xy 88.023094 -285.730154) (xy 87.975508 -285.712107)
			(xy 87.931434 -285.686661) (xy 87.892012 -285.654474) (xy 87.858264 -285.61638) (xy 87.831063 -285.573366)
			(xy 87.811115 -285.526546) (xy 87.798936 -285.477132) (xy 87.794841 -285.426404) (xy 86.54669 -285.426404)
			(xy 86.546178 -285.45185) (xy 86.538014 -285.502084) (xy 86.521898 -285.550358) (xy 86.498247 -285.595421)
			(xy 86.467674 -285.636107) (xy 86.43097 -285.671362) (xy 86.389086 -285.700272) (xy 86.343107 -285.722089)
			(xy 86.294223 -285.736249) (xy 86.243702 -285.742383) (xy 86.19285 -285.740334) (xy 86.142986 -285.730154)
			(xy 86.0954 -285.712107) (xy 86.051326 -285.686661) (xy 86.011904 -285.654474) (xy 85.978156 -285.61638)
			(xy 85.950955 -285.573366) (xy 85.931007 -285.526546) (xy 85.918828 -285.477132) (xy 85.914733 -285.426404)
			(xy 85.608922 -285.426404) (xy 85.608432 -285.451393) (xy 85.600613 -285.500756) (xy 85.585169 -285.548288)
			(xy 85.562479 -285.59282) (xy 85.533103 -285.633253) (xy 85.497763 -285.668593) (xy 85.45733 -285.697969)
			(xy 85.412798 -285.720659) (xy 85.365266 -285.736103) (xy 85.315903 -285.743922) (xy 85.265925 -285.743922)
			(xy 85.216562 -285.736103) (xy 85.16903 -285.720659) (xy 85.124498 -285.697969) (xy 85.084065 -285.668593)
			(xy 85.048725 -285.633253) (xy 85.019349 -285.59282) (xy 84.996659 -285.548288) (xy 84.981215 -285.500756)
			(xy 84.973396 -285.451393) (xy 84.666333 -285.451393) (xy 84.666324 -285.45185) (xy 84.65816 -285.502084)
			(xy 84.642044 -285.550358) (xy 84.618393 -285.595421) (xy 84.58782 -285.636107) (xy 84.551116 -285.671362)
			(xy 84.509232 -285.700272) (xy 84.463253 -285.722089) (xy 84.414369 -285.736249) (xy 84.363848 -285.742383)
			(xy 84.312996 -285.740334) (xy 84.263132 -285.730154) (xy 84.215546 -285.712107) (xy 84.171472 -285.686661)
			(xy 84.13205 -285.654474) (xy 84.098302 -285.61638) (xy 84.071101 -285.573366) (xy 84.051153 -285.526546)
			(xy 84.038974 -285.477132) (xy 84.034879 -285.426404) (xy 83.729068 -285.426404) (xy 83.728578 -285.451393)
			(xy 83.720759 -285.500756) (xy 83.705315 -285.548288) (xy 83.682625 -285.59282) (xy 83.653249 -285.633253)
			(xy 83.617909 -285.668593) (xy 83.577476 -285.697969) (xy 83.532944 -285.720659) (xy 83.485412 -285.736103)
			(xy 83.436049 -285.743922) (xy 83.386071 -285.743922) (xy 83.336708 -285.736103) (xy 83.289176 -285.720659)
			(xy 83.244644 -285.697969) (xy 83.204211 -285.668593) (xy 83.168871 -285.633253) (xy 83.139495 -285.59282)
			(xy 83.116805 -285.548288) (xy 83.101361 -285.500756) (xy 83.093542 -285.451393) (xy 82.786225 -285.451393)
			(xy 82.786216 -285.45185) (xy 82.778052 -285.502084) (xy 82.761936 -285.550358) (xy 82.738285 -285.595421)
			(xy 82.707712 -285.636107) (xy 82.671008 -285.671362) (xy 82.629124 -285.700272) (xy 82.583145 -285.722089)
			(xy 82.534261 -285.736249) (xy 82.48374 -285.742383) (xy 82.432888 -285.740334) (xy 82.383024 -285.730154)
			(xy 82.335438 -285.712107) (xy 82.291364 -285.686661) (xy 82.251942 -285.654474) (xy 82.218194 -285.61638)
			(xy 82.190993 -285.573366) (xy 82.171045 -285.526546) (xy 82.158866 -285.477132) (xy 82.154771 -285.426404)
			(xy 81.846674 -285.426404) (xy 81.846162 -285.45185) (xy 81.837998 -285.502084) (xy 81.821882 -285.550358)
			(xy 81.798231 -285.595421) (xy 81.767658 -285.636107) (xy 81.730954 -285.671362) (xy 81.68907 -285.700272)
			(xy 81.643091 -285.722089) (xy 81.594207 -285.736249) (xy 81.543686 -285.742383) (xy 81.492834 -285.740334)
			(xy 81.44297 -285.730154) (xy 81.395384 -285.712107) (xy 81.35131 -285.686661) (xy 81.311888 -285.654474)
			(xy 81.27814 -285.61638) (xy 81.250939 -285.573366) (xy 81.230991 -285.526546) (xy 81.218812 -285.477132)
			(xy 81.214717 -285.426404) (xy 79.53248 -285.426404) (xy 79.53248 -286.261399) (xy 79.80348 -286.261399)
			(xy 79.80348 -286.211421) (xy 79.811299 -286.162058) (xy 79.826743 -286.114526) (xy 79.849433 -286.069994)
			(xy 79.878809 -286.029561) (xy 79.914149 -285.994221) (xy 79.954582 -285.964845) (xy 79.999114 -285.942155)
			(xy 80.046646 -285.926711) (xy 80.096009 -285.918892) (xy 80.145987 -285.918892) (xy 80.19535 -285.926711)
			(xy 80.242882 -285.942155) (xy 80.287414 -285.964845) (xy 80.327847 -285.994221) (xy 80.363187 -286.029561)
			(xy 80.392563 -286.069994) (xy 80.415253 -286.114526) (xy 80.430697 -286.162058) (xy 80.438516 -286.211421)
			(xy 80.439006 -286.23641) (xy 80.744817 -286.23641) (xy 80.748912 -286.185682) (xy 80.761091 -286.136268)
			(xy 80.781039 -286.089448) (xy 80.80824 -286.046434) (xy 80.841988 -286.00834) (xy 80.88141 -285.976153)
			(xy 80.925484 -285.950707) (xy 80.97307 -285.93266) (xy 81.022934 -285.92248) (xy 81.073786 -285.920431)
			(xy 81.124307 -285.926565) (xy 81.173191 -285.940725) (xy 81.21917 -285.962542) (xy 81.261054 -285.991452)
			(xy 81.297758 -286.026707) (xy 81.328331 -286.067393) (xy 81.351982 -286.112456) (xy 81.368098 -286.16073)
			(xy 81.376262 -286.210964) (xy 81.376774 -286.23641) (xy 81.376271 -286.261399) (xy 81.683588 -286.261399)
			(xy 81.683588 -286.211421) (xy 81.691407 -286.162058) (xy 81.706851 -286.114526) (xy 81.729541 -286.069994)
			(xy 81.758917 -286.029561) (xy 81.794257 -285.994221) (xy 81.83469 -285.964845) (xy 81.879222 -285.942155)
			(xy 81.926754 -285.926711) (xy 81.976117 -285.918892) (xy 82.026095 -285.918892) (xy 82.075458 -285.926711)
			(xy 82.12299 -285.942155) (xy 82.167522 -285.964845) (xy 82.207955 -285.994221) (xy 82.243295 -286.029561)
			(xy 82.272671 -286.069994) (xy 82.295361 -286.114526) (xy 82.310805 -286.162058) (xy 82.318624 -286.211421)
			(xy 82.319114 -286.23641) (xy 82.624671 -286.23641) (xy 82.628766 -286.185682) (xy 82.640945 -286.136268)
			(xy 82.660893 -286.089448) (xy 82.688094 -286.046434) (xy 82.721842 -286.00834) (xy 82.761264 -285.976153)
			(xy 82.805338 -285.950707) (xy 82.852924 -285.93266) (xy 82.902788 -285.92248) (xy 82.95364 -285.920431)
			(xy 83.004161 -285.926565) (xy 83.053045 -285.940725) (xy 83.099024 -285.962542) (xy 83.140908 -285.991452)
			(xy 83.177612 -286.026707) (xy 83.208185 -286.067393) (xy 83.231836 -286.112456) (xy 83.247952 -286.16073)
			(xy 83.256116 -286.210964) (xy 83.256628 -286.23641) (xy 83.256125 -286.261399) (xy 83.563442 -286.261399)
			(xy 83.563442 -286.211421) (xy 83.571261 -286.162058) (xy 83.586705 -286.114526) (xy 83.609395 -286.069994)
			(xy 83.638771 -286.029561) (xy 83.674111 -285.994221) (xy 83.714544 -285.964845) (xy 83.759076 -285.942155)
			(xy 83.806608 -285.926711) (xy 83.855971 -285.918892) (xy 83.905949 -285.918892) (xy 83.955312 -285.926711)
			(xy 84.002844 -285.942155) (xy 84.047376 -285.964845) (xy 84.087809 -285.994221) (xy 84.123149 -286.029561)
			(xy 84.152525 -286.069994) (xy 84.175215 -286.114526) (xy 84.190659 -286.162058) (xy 84.198478 -286.211421)
			(xy 84.198968 -286.23641) (xy 84.504779 -286.23641) (xy 84.508874 -286.185682) (xy 84.521053 -286.136268)
			(xy 84.541001 -286.089448) (xy 84.568202 -286.046434) (xy 84.60195 -286.00834) (xy 84.641372 -285.976153)
			(xy 84.685446 -285.950707) (xy 84.733032 -285.93266) (xy 84.782896 -285.92248) (xy 84.833748 -285.920431)
			(xy 84.884269 -285.926565) (xy 84.933153 -285.940725) (xy 84.979132 -285.962542) (xy 85.021016 -285.991452)
			(xy 85.05772 -286.026707) (xy 85.088293 -286.067393) (xy 85.111944 -286.112456) (xy 85.12806 -286.16073)
			(xy 85.136224 -286.210964) (xy 85.136736 -286.23641) (xy 85.444833 -286.23641) (xy 85.448928 -286.185682)
			(xy 85.461107 -286.136268) (xy 85.481055 -286.089448) (xy 85.508256 -286.046434) (xy 85.542004 -286.00834)
			(xy 85.581426 -285.976153) (xy 85.6255 -285.950707) (xy 85.673086 -285.93266) (xy 85.72295 -285.92248)
			(xy 85.773802 -285.920431) (xy 85.824323 -285.926565) (xy 85.873207 -285.940725) (xy 85.919186 -285.962542)
			(xy 85.96107 -285.991452) (xy 85.997774 -286.026707) (xy 86.028347 -286.067393) (xy 86.051998 -286.112456)
			(xy 86.068114 -286.16073) (xy 86.076278 -286.210964) (xy 86.07679 -286.23641) (xy 86.076287 -286.261399)
			(xy 86.383604 -286.261399) (xy 86.383604 -286.211421) (xy 86.391423 -286.162058) (xy 86.406867 -286.114526)
			(xy 86.429557 -286.069994) (xy 86.458933 -286.029561) (xy 86.494273 -285.994221) (xy 86.534706 -285.964845)
			(xy 86.579238 -285.942155) (xy 86.62677 -285.926711) (xy 86.676133 -285.918892) (xy 86.726111 -285.918892)
			(xy 86.775474 -285.926711) (xy 86.823006 -285.942155) (xy 86.867538 -285.964845) (xy 86.907971 -285.994221)
			(xy 86.943311 -286.029561) (xy 86.972687 -286.069994) (xy 86.995377 -286.114526) (xy 87.010821 -286.162058)
			(xy 87.01864 -286.211421) (xy 87.01913 -286.23641) (xy 87.324687 -286.23641) (xy 87.328782 -286.185682)
			(xy 87.340961 -286.136268) (xy 87.360909 -286.089448) (xy 87.38811 -286.046434) (xy 87.421858 -286.00834)
			(xy 87.46128 -285.976153) (xy 87.505354 -285.950707) (xy 87.55294 -285.93266) (xy 87.602804 -285.92248)
			(xy 87.653656 -285.920431) (xy 87.704177 -285.926565) (xy 87.753061 -285.940725) (xy 87.79904 -285.962542)
			(xy 87.840924 -285.991452) (xy 87.877628 -286.026707) (xy 87.908201 -286.067393) (xy 87.931852 -286.112456)
			(xy 87.947968 -286.16073) (xy 87.956132 -286.210964) (xy 87.956644 -286.23641) (xy 87.956141 -286.261399)
			(xy 88.263458 -286.261399) (xy 88.263458 -286.211421) (xy 88.271277 -286.162058) (xy 88.286721 -286.114526)
			(xy 88.309411 -286.069994) (xy 88.338787 -286.029561) (xy 88.374127 -285.994221) (xy 88.41456 -285.964845)
			(xy 88.459092 -285.942155) (xy 88.506624 -285.926711) (xy 88.555987 -285.918892) (xy 88.605965 -285.918892)
			(xy 88.655328 -285.926711) (xy 88.70286 -285.942155) (xy 88.747392 -285.964845) (xy 88.787825 -285.994221)
			(xy 88.823165 -286.029561) (xy 88.852541 -286.069994) (xy 88.875231 -286.114526) (xy 88.890675 -286.162058)
			(xy 88.898494 -286.211421) (xy 88.898984 -286.23641) (xy 88.898494 -286.261399) (xy 88.890675 -286.310762)
			(xy 88.875231 -286.358294) (xy 88.852541 -286.402826) (xy 88.823165 -286.443259) (xy 88.787825 -286.478599)
			(xy 88.747392 -286.507975) (xy 88.70286 -286.530665) (xy 88.655328 -286.546109) (xy 88.605965 -286.553928)
			(xy 88.555987 -286.553928) (xy 88.506624 -286.546109) (xy 88.459092 -286.530665) (xy 88.41456 -286.507975)
			(xy 88.374127 -286.478599) (xy 88.338787 -286.443259) (xy 88.309411 -286.402826) (xy 88.286721 -286.358294)
			(xy 88.271277 -286.310762) (xy 88.263458 -286.261399) (xy 87.956141 -286.261399) (xy 87.956132 -286.261856)
			(xy 87.947968 -286.31209) (xy 87.931852 -286.360364) (xy 87.908201 -286.405427) (xy 87.877628 -286.446113)
			(xy 87.840924 -286.481368) (xy 87.79904 -286.510278) (xy 87.753061 -286.532095) (xy 87.704177 -286.546255)
			(xy 87.653656 -286.552389) (xy 87.602804 -286.55034) (xy 87.55294 -286.54016) (xy 87.505354 -286.522113)
			(xy 87.46128 -286.496667) (xy 87.421858 -286.46448) (xy 87.38811 -286.426386) (xy 87.360909 -286.383372)
			(xy 87.340961 -286.336552) (xy 87.328782 -286.287138) (xy 87.324687 -286.23641) (xy 87.01913 -286.23641)
			(xy 87.01864 -286.261399) (xy 87.010821 -286.310762) (xy 86.995377 -286.358294) (xy 86.972687 -286.402826)
			(xy 86.943311 -286.443259) (xy 86.907971 -286.478599) (xy 86.867538 -286.507975) (xy 86.823006 -286.530665)
			(xy 86.775474 -286.546109) (xy 86.726111 -286.553928) (xy 86.676133 -286.553928) (xy 86.62677 -286.546109)
			(xy 86.579238 -286.530665) (xy 86.534706 -286.507975) (xy 86.494273 -286.478599) (xy 86.458933 -286.443259)
			(xy 86.429557 -286.402826) (xy 86.406867 -286.358294) (xy 86.391423 -286.310762) (xy 86.383604 -286.261399)
			(xy 86.076287 -286.261399) (xy 86.076278 -286.261856) (xy 86.068114 -286.31209) (xy 86.051998 -286.360364)
			(xy 86.028347 -286.405427) (xy 85.997774 -286.446113) (xy 85.96107 -286.481368) (xy 85.919186 -286.510278)
			(xy 85.873207 -286.532095) (xy 85.824323 -286.546255) (xy 85.773802 -286.552389) (xy 85.72295 -286.55034)
			(xy 85.673086 -286.54016) (xy 85.6255 -286.522113) (xy 85.581426 -286.496667) (xy 85.542004 -286.46448)
			(xy 85.508256 -286.426386) (xy 85.481055 -286.383372) (xy 85.461107 -286.336552) (xy 85.448928 -286.287138)
			(xy 85.444833 -286.23641) (xy 85.136736 -286.23641) (xy 85.136224 -286.261856) (xy 85.12806 -286.31209)
			(xy 85.111944 -286.360364) (xy 85.088293 -286.405427) (xy 85.05772 -286.446113) (xy 85.021016 -286.481368)
			(xy 84.979132 -286.510278) (xy 84.933153 -286.532095) (xy 84.884269 -286.546255) (xy 84.833748 -286.552389)
			(xy 84.782896 -286.55034) (xy 84.733032 -286.54016) (xy 84.685446 -286.522113) (xy 84.641372 -286.496667)
			(xy 84.60195 -286.46448) (xy 84.568202 -286.426386) (xy 84.541001 -286.383372) (xy 84.521053 -286.336552)
			(xy 84.508874 -286.287138) (xy 84.504779 -286.23641) (xy 84.198968 -286.23641) (xy 84.198478 -286.261399)
			(xy 84.190659 -286.310762) (xy 84.175215 -286.358294) (xy 84.152525 -286.402826) (xy 84.123149 -286.443259)
			(xy 84.087809 -286.478599) (xy 84.047376 -286.507975) (xy 84.002844 -286.530665) (xy 83.955312 -286.546109)
			(xy 83.905949 -286.553928) (xy 83.855971 -286.553928) (xy 83.806608 -286.546109) (xy 83.759076 -286.530665)
			(xy 83.714544 -286.507975) (xy 83.674111 -286.478599) (xy 83.638771 -286.443259) (xy 83.609395 -286.402826)
			(xy 83.586705 -286.358294) (xy 83.571261 -286.310762) (xy 83.563442 -286.261399) (xy 83.256125 -286.261399)
			(xy 83.256116 -286.261856) (xy 83.247952 -286.31209) (xy 83.231836 -286.360364) (xy 83.208185 -286.405427)
			(xy 83.177612 -286.446113) (xy 83.140908 -286.481368) (xy 83.099024 -286.510278) (xy 83.053045 -286.532095)
			(xy 83.004161 -286.546255) (xy 82.95364 -286.552389) (xy 82.902788 -286.55034) (xy 82.852924 -286.54016)
			(xy 82.805338 -286.522113) (xy 82.761264 -286.496667) (xy 82.721842 -286.46448) (xy 82.688094 -286.426386)
			(xy 82.660893 -286.383372) (xy 82.640945 -286.336552) (xy 82.628766 -286.287138) (xy 82.624671 -286.23641)
			(xy 82.319114 -286.23641) (xy 82.318624 -286.261399) (xy 82.310805 -286.310762) (xy 82.295361 -286.358294)
			(xy 82.272671 -286.402826) (xy 82.243295 -286.443259) (xy 82.207955 -286.478599) (xy 82.167522 -286.507975)
			(xy 82.12299 -286.530665) (xy 82.075458 -286.546109) (xy 82.026095 -286.553928) (xy 81.976117 -286.553928)
			(xy 81.926754 -286.546109) (xy 81.879222 -286.530665) (xy 81.83469 -286.507975) (xy 81.794257 -286.478599)
			(xy 81.758917 -286.443259) (xy 81.729541 -286.402826) (xy 81.706851 -286.358294) (xy 81.691407 -286.310762)
			(xy 81.683588 -286.261399) (xy 81.376271 -286.261399) (xy 81.376262 -286.261856) (xy 81.368098 -286.31209)
			(xy 81.351982 -286.360364) (xy 81.328331 -286.405427) (xy 81.297758 -286.446113) (xy 81.261054 -286.481368)
			(xy 81.21917 -286.510278) (xy 81.173191 -286.532095) (xy 81.124307 -286.546255) (xy 81.073786 -286.552389)
			(xy 81.022934 -286.55034) (xy 80.97307 -286.54016) (xy 80.925484 -286.522113) (xy 80.88141 -286.496667)
			(xy 80.841988 -286.46448) (xy 80.80824 -286.426386) (xy 80.781039 -286.383372) (xy 80.761091 -286.336552)
			(xy 80.748912 -286.287138) (xy 80.744817 -286.23641) (xy 80.439006 -286.23641) (xy 80.438516 -286.261399)
			(xy 80.430697 -286.310762) (xy 80.415253 -286.358294) (xy 80.392563 -286.402826) (xy 80.363187 -286.443259)
			(xy 80.327847 -286.478599) (xy 80.287414 -286.507975) (xy 80.242882 -286.530665) (xy 80.19535 -286.546109)
			(xy 80.145987 -286.553928) (xy 80.096009 -286.553928) (xy 80.046646 -286.546109) (xy 79.999114 -286.530665)
			(xy 79.954582 -286.507975) (xy 79.914149 -286.478599) (xy 79.878809 -286.443259) (xy 79.849433 -286.402826)
			(xy 79.826743 -286.358294) (xy 79.811299 -286.310762) (xy 79.80348 -286.261399) (xy 79.53248 -286.261399)
			(xy 79.53248 -287.071151) (xy 80.273634 -287.071151) (xy 80.273634 -287.021173) (xy 80.281453 -286.97181)
			(xy 80.296897 -286.924278) (xy 80.319587 -286.879746) (xy 80.348963 -286.839313) (xy 80.384303 -286.803973)
			(xy 80.424736 -286.774597) (xy 80.469268 -286.751907) (xy 80.5168 -286.736463) (xy 80.566163 -286.728644)
			(xy 80.616141 -286.728644) (xy 80.665504 -286.736463) (xy 80.713036 -286.751907) (xy 80.757568 -286.774597)
			(xy 80.798001 -286.803973) (xy 80.833341 -286.839313) (xy 80.862717 -286.879746) (xy 80.885407 -286.924278)
			(xy 80.900851 -286.97181) (xy 80.90867 -287.021173) (xy 80.90916 -287.046162) (xy 81.214717 -287.046162)
			(xy 81.218812 -286.995434) (xy 81.230991 -286.94602) (xy 81.250939 -286.8992) (xy 81.27814 -286.856186)
			(xy 81.311888 -286.818092) (xy 81.35131 -286.785905) (xy 81.395384 -286.760459) (xy 81.44297 -286.742412)
			(xy 81.492834 -286.732232) (xy 81.543686 -286.730183) (xy 81.594207 -286.736317) (xy 81.643091 -286.750477)
			(xy 81.68907 -286.772294) (xy 81.730954 -286.801204) (xy 81.767658 -286.836459) (xy 81.798231 -286.877145)
			(xy 81.821882 -286.922208) (xy 81.837998 -286.970482) (xy 81.846162 -287.020716) (xy 81.846674 -287.046162)
			(xy 82.154771 -287.046162) (xy 82.158866 -286.995434) (xy 82.171045 -286.94602) (xy 82.190993 -286.8992)
			(xy 82.218194 -286.856186) (xy 82.251942 -286.818092) (xy 82.291364 -286.785905) (xy 82.335438 -286.760459)
			(xy 82.383024 -286.742412) (xy 82.432888 -286.732232) (xy 82.48374 -286.730183) (xy 82.534261 -286.736317)
			(xy 82.583145 -286.750477) (xy 82.629124 -286.772294) (xy 82.671008 -286.801204) (xy 82.707712 -286.836459)
			(xy 82.738285 -286.877145) (xy 82.761936 -286.922208) (xy 82.778052 -286.970482) (xy 82.786216 -287.020716)
			(xy 82.786728 -287.046162) (xy 82.786225 -287.071151) (xy 83.093542 -287.071151) (xy 83.093542 -287.021173)
			(xy 83.101361 -286.97181) (xy 83.116805 -286.924278) (xy 83.139495 -286.879746) (xy 83.168871 -286.839313)
			(xy 83.204211 -286.803973) (xy 83.244644 -286.774597) (xy 83.289176 -286.751907) (xy 83.336708 -286.736463)
			(xy 83.386071 -286.728644) (xy 83.436049 -286.728644) (xy 83.485412 -286.736463) (xy 83.532944 -286.751907)
			(xy 83.577476 -286.774597) (xy 83.617909 -286.803973) (xy 83.653249 -286.839313) (xy 83.682625 -286.879746)
			(xy 83.705315 -286.924278) (xy 83.720759 -286.97181) (xy 83.728578 -287.021173) (xy 83.729068 -287.046162)
			(xy 84.034879 -287.046162) (xy 84.038974 -286.995434) (xy 84.051153 -286.94602) (xy 84.071101 -286.8992)
			(xy 84.098302 -286.856186) (xy 84.13205 -286.818092) (xy 84.171472 -286.785905) (xy 84.215546 -286.760459)
			(xy 84.263132 -286.742412) (xy 84.312996 -286.732232) (xy 84.363848 -286.730183) (xy 84.414369 -286.736317)
			(xy 84.463253 -286.750477) (xy 84.509232 -286.772294) (xy 84.551116 -286.801204) (xy 84.58782 -286.836459)
			(xy 84.618393 -286.877145) (xy 84.642044 -286.922208) (xy 84.65816 -286.970482) (xy 84.666324 -287.020716)
			(xy 84.666836 -287.046162) (xy 84.666324 -287.071608) (xy 84.666316 -287.071659) (xy 84.97365 -287.071659)
			(xy 84.97365 -287.021681) (xy 84.981469 -286.972318) (xy 84.996913 -286.924786) (xy 85.019603 -286.880254)
			(xy 85.048979 -286.839821) (xy 85.084319 -286.804481) (xy 85.124752 -286.775105) (xy 85.169284 -286.752415)
			(xy 85.216816 -286.736971) (xy 85.266179 -286.729152) (xy 85.316157 -286.729152) (xy 85.36552 -286.736971)
			(xy 85.413052 -286.752415) (xy 85.457584 -286.775105) (xy 85.498017 -286.804481) (xy 85.533357 -286.839821)
			(xy 85.562733 -286.880254) (xy 85.585423 -286.924786) (xy 85.600867 -286.972318) (xy 85.608686 -287.021681)
			(xy 85.609166 -287.046162) (xy 85.914733 -287.046162) (xy 85.918828 -286.995434) (xy 85.931007 -286.94602)
			(xy 85.950955 -286.8992) (xy 85.978156 -286.856186) (xy 86.011904 -286.818092) (xy 86.051326 -286.785905)
			(xy 86.0954 -286.760459) (xy 86.142986 -286.742412) (xy 86.19285 -286.732232) (xy 86.243702 -286.730183)
			(xy 86.294223 -286.736317) (xy 86.343107 -286.750477) (xy 86.389086 -286.772294) (xy 86.43097 -286.801204)
			(xy 86.467674 -286.836459) (xy 86.498247 -286.877145) (xy 86.521898 -286.922208) (xy 86.538014 -286.970482)
			(xy 86.546178 -287.020716) (xy 86.54669 -287.046162) (xy 86.546187 -287.071151) (xy 86.853504 -287.071151)
			(xy 86.853504 -287.021173) (xy 86.861323 -286.97181) (xy 86.876767 -286.924278) (xy 86.899457 -286.879746)
			(xy 86.928833 -286.839313) (xy 86.964173 -286.803973) (xy 87.004606 -286.774597) (xy 87.049138 -286.751907)
			(xy 87.09667 -286.736463) (xy 87.146033 -286.728644) (xy 87.196011 -286.728644) (xy 87.245374 -286.736463)
			(xy 87.292906 -286.751907) (xy 87.337438 -286.774597) (xy 87.377871 -286.803973) (xy 87.413211 -286.839313)
			(xy 87.442587 -286.879746) (xy 87.465277 -286.924278) (xy 87.480721 -286.97181) (xy 87.48854 -287.021173)
			(xy 87.48903 -287.046162) (xy 87.794841 -287.046162) (xy 87.798936 -286.995434) (xy 87.811115 -286.94602)
			(xy 87.831063 -286.8992) (xy 87.858264 -286.856186) (xy 87.892012 -286.818092) (xy 87.931434 -286.785905)
			(xy 87.975508 -286.760459) (xy 88.023094 -286.742412) (xy 88.072958 -286.732232) (xy 88.12381 -286.730183)
			(xy 88.174331 -286.736317) (xy 88.223215 -286.750477) (xy 88.269194 -286.772294) (xy 88.311078 -286.801204)
			(xy 88.347782 -286.836459) (xy 88.378355 -286.877145) (xy 88.402006 -286.922208) (xy 88.418122 -286.970482)
			(xy 88.426286 -287.020716) (xy 88.426798 -287.046162) (xy 88.734895 -287.046162) (xy 88.73899 -286.995434)
			(xy 88.751169 -286.94602) (xy 88.771117 -286.8992) (xy 88.798318 -286.856186) (xy 88.832066 -286.818092)
			(xy 88.871488 -286.785905) (xy 88.915562 -286.760459) (xy 88.963148 -286.742412) (xy 89.013012 -286.732232)
			(xy 89.063864 -286.730183) (xy 89.114385 -286.736317) (xy 89.163269 -286.750477) (xy 89.209248 -286.772294)
			(xy 89.251132 -286.801204) (xy 89.287836 -286.836459) (xy 89.318409 -286.877145) (xy 89.34206 -286.922208)
			(xy 89.358176 -286.970482) (xy 89.36634 -287.020716) (xy 89.366852 -287.046162) (xy 89.36634 -287.071608)
			(xy 89.358176 -287.121842) (xy 89.34206 -287.170116) (xy 89.318409 -287.215179) (xy 89.287836 -287.255865)
			(xy 89.251132 -287.29112) (xy 89.209248 -287.32003) (xy 89.163269 -287.341847) (xy 89.114385 -287.356007)
			(xy 89.063864 -287.362141) (xy 89.013012 -287.360092) (xy 88.963148 -287.349912) (xy 88.915562 -287.331865)
			(xy 88.871488 -287.306419) (xy 88.832066 -287.274232) (xy 88.798318 -287.236138) (xy 88.771117 -287.193124)
			(xy 88.751169 -287.146304) (xy 88.73899 -287.09689) (xy 88.734895 -287.046162) (xy 88.426798 -287.046162)
			(xy 88.426286 -287.071608) (xy 88.418122 -287.121842) (xy 88.402006 -287.170116) (xy 88.378355 -287.215179)
			(xy 88.347782 -287.255865) (xy 88.311078 -287.29112) (xy 88.269194 -287.32003) (xy 88.223215 -287.341847)
			(xy 88.174331 -287.356007) (xy 88.12381 -287.362141) (xy 88.072958 -287.360092) (xy 88.023094 -287.349912)
			(xy 87.975508 -287.331865) (xy 87.931434 -287.306419) (xy 87.892012 -287.274232) (xy 87.858264 -287.236138)
			(xy 87.831063 -287.193124) (xy 87.811115 -287.146304) (xy 87.798936 -287.09689) (xy 87.794841 -287.046162)
			(xy 87.48903 -287.046162) (xy 87.48854 -287.071151) (xy 87.480721 -287.120514) (xy 87.465277 -287.168046)
			(xy 87.442587 -287.212578) (xy 87.413211 -287.253011) (xy 87.377871 -287.288351) (xy 87.337438 -287.317727)
			(xy 87.292906 -287.340417) (xy 87.245374 -287.355861) (xy 87.196011 -287.36368) (xy 87.146033 -287.36368)
			(xy 87.09667 -287.355861) (xy 87.049138 -287.340417) (xy 87.004606 -287.317727) (xy 86.964173 -287.288351)
			(xy 86.928833 -287.253011) (xy 86.899457 -287.212578) (xy 86.876767 -287.168046) (xy 86.861323 -287.120514)
			(xy 86.853504 -287.071151) (xy 86.546187 -287.071151) (xy 86.546178 -287.071608) (xy 86.538014 -287.121842)
			(xy 86.521898 -287.170116) (xy 86.498247 -287.215179) (xy 86.467674 -287.255865) (xy 86.43097 -287.29112)
			(xy 86.389086 -287.32003) (xy 86.343107 -287.341847) (xy 86.294223 -287.356007) (xy 86.243702 -287.362141)
			(xy 86.19285 -287.360092) (xy 86.142986 -287.349912) (xy 86.0954 -287.331865) (xy 86.051326 -287.306419)
			(xy 86.011904 -287.274232) (xy 85.978156 -287.236138) (xy 85.950955 -287.193124) (xy 85.931007 -287.146304)
			(xy 85.918828 -287.09689) (xy 85.914733 -287.046162) (xy 85.609166 -287.046162) (xy 85.609176 -287.04667)
			(xy 85.608686 -287.071659) (xy 85.600867 -287.121022) (xy 85.585423 -287.168554) (xy 85.562733 -287.213086)
			(xy 85.533357 -287.253519) (xy 85.498017 -287.288859) (xy 85.457584 -287.318235) (xy 85.413052 -287.340925)
			(xy 85.36552 -287.356369) (xy 85.316157 -287.364188) (xy 85.266179 -287.364188) (xy 85.216816 -287.356369)
			(xy 85.169284 -287.340925) (xy 85.124752 -287.318235) (xy 85.084319 -287.288859) (xy 85.048979 -287.253519)
			(xy 85.019603 -287.213086) (xy 84.996913 -287.168554) (xy 84.981469 -287.121022) (xy 84.97365 -287.071659)
			(xy 84.666316 -287.071659) (xy 84.65816 -287.121842) (xy 84.642044 -287.170116) (xy 84.618393 -287.215179)
			(xy 84.58782 -287.255865) (xy 84.551116 -287.29112) (xy 84.509232 -287.32003) (xy 84.463253 -287.341847)
			(xy 84.414369 -287.356007) (xy 84.363848 -287.362141) (xy 84.312996 -287.360092) (xy 84.263132 -287.349912)
			(xy 84.215546 -287.331865) (xy 84.171472 -287.306419) (xy 84.13205 -287.274232) (xy 84.098302 -287.236138)
			(xy 84.071101 -287.193124) (xy 84.051153 -287.146304) (xy 84.038974 -287.09689) (xy 84.034879 -287.046162)
			(xy 83.729068 -287.046162) (xy 83.728578 -287.071151) (xy 83.720759 -287.120514) (xy 83.705315 -287.168046)
			(xy 83.682625 -287.212578) (xy 83.653249 -287.253011) (xy 83.617909 -287.288351) (xy 83.577476 -287.317727)
			(xy 83.532944 -287.340417) (xy 83.485412 -287.355861) (xy 83.436049 -287.36368) (xy 83.386071 -287.36368)
			(xy 83.336708 -287.355861) (xy 83.289176 -287.340417) (xy 83.244644 -287.317727) (xy 83.204211 -287.288351)
			(xy 83.168871 -287.253011) (xy 83.139495 -287.212578) (xy 83.116805 -287.168046) (xy 83.101361 -287.120514)
			(xy 83.093542 -287.071151) (xy 82.786225 -287.071151) (xy 82.786216 -287.071608) (xy 82.778052 -287.121842)
			(xy 82.761936 -287.170116) (xy 82.738285 -287.215179) (xy 82.707712 -287.255865) (xy 82.671008 -287.29112)
			(xy 82.629124 -287.32003) (xy 82.583145 -287.341847) (xy 82.534261 -287.356007) (xy 82.48374 -287.362141)
			(xy 82.432888 -287.360092) (xy 82.383024 -287.349912) (xy 82.335438 -287.331865) (xy 82.291364 -287.306419)
			(xy 82.251942 -287.274232) (xy 82.218194 -287.236138) (xy 82.190993 -287.193124) (xy 82.171045 -287.146304)
			(xy 82.158866 -287.09689) (xy 82.154771 -287.046162) (xy 81.846674 -287.046162) (xy 81.846162 -287.071608)
			(xy 81.837998 -287.121842) (xy 81.821882 -287.170116) (xy 81.798231 -287.215179) (xy 81.767658 -287.255865)
			(xy 81.730954 -287.29112) (xy 81.68907 -287.32003) (xy 81.643091 -287.341847) (xy 81.594207 -287.356007)
			(xy 81.543686 -287.362141) (xy 81.492834 -287.360092) (xy 81.44297 -287.349912) (xy 81.395384 -287.331865)
			(xy 81.35131 -287.306419) (xy 81.311888 -287.274232) (xy 81.27814 -287.236138) (xy 81.250939 -287.193124)
			(xy 81.230991 -287.146304) (xy 81.218812 -287.09689) (xy 81.214717 -287.046162) (xy 80.90916 -287.046162)
			(xy 80.90867 -287.071151) (xy 80.900851 -287.120514) (xy 80.885407 -287.168046) (xy 80.862717 -287.212578)
			(xy 80.833341 -287.253011) (xy 80.798001 -287.288351) (xy 80.757568 -287.317727) (xy 80.713036 -287.340417)
			(xy 80.665504 -287.355861) (xy 80.616141 -287.36368) (xy 80.566163 -287.36368) (xy 80.5168 -287.355861)
			(xy 80.469268 -287.340417) (xy 80.424736 -287.317727) (xy 80.384303 -287.288351) (xy 80.348963 -287.253011)
			(xy 80.319587 -287.212578) (xy 80.296897 -287.168046) (xy 80.281453 -287.120514) (xy 80.273634 -287.071151)
			(xy 79.53248 -287.071151) (xy 79.53248 -287.856422) (xy 80.744817 -287.856422) (xy 80.748912 -287.805694)
			(xy 80.761091 -287.75628) (xy 80.781039 -287.70946) (xy 80.80824 -287.666446) (xy 80.841988 -287.628352)
			(xy 80.88141 -287.596165) (xy 80.925484 -287.570719) (xy 80.97307 -287.552672) (xy 81.022934 -287.542492)
			(xy 81.073786 -287.540443) (xy 81.124307 -287.546577) (xy 81.173191 -287.560737) (xy 81.21917 -287.582554)
			(xy 81.261054 -287.611464) (xy 81.297758 -287.646719) (xy 81.328331 -287.687405) (xy 81.351982 -287.732468)
			(xy 81.368098 -287.780742) (xy 81.376262 -287.830976) (xy 81.376774 -287.856422) (xy 81.376271 -287.881411)
			(xy 81.683588 -287.881411) (xy 81.683588 -287.831433) (xy 81.691407 -287.78207) (xy 81.706851 -287.734538)
			(xy 81.729541 -287.690006) (xy 81.758917 -287.649573) (xy 81.794257 -287.614233) (xy 81.83469 -287.584857)
			(xy 81.879222 -287.562167) (xy 81.926754 -287.546723) (xy 81.976117 -287.538904) (xy 82.026095 -287.538904)
			(xy 82.075458 -287.546723) (xy 82.12299 -287.562167) (xy 82.167522 -287.584857) (xy 82.207955 -287.614233)
			(xy 82.243295 -287.649573) (xy 82.272671 -287.690006) (xy 82.295361 -287.734538) (xy 82.310805 -287.78207)
			(xy 82.318624 -287.831433) (xy 82.319114 -287.856422) (xy 82.624671 -287.856422) (xy 82.628766 -287.805694)
			(xy 82.640945 -287.75628) (xy 82.660893 -287.70946) (xy 82.688094 -287.666446) (xy 82.721842 -287.628352)
			(xy 82.761264 -287.596165) (xy 82.805338 -287.570719) (xy 82.852924 -287.552672) (xy 82.902788 -287.542492)
			(xy 82.95364 -287.540443) (xy 83.004161 -287.546577) (xy 83.053045 -287.560737) (xy 83.099024 -287.582554)
			(xy 83.140908 -287.611464) (xy 83.177612 -287.646719) (xy 83.208185 -287.687405) (xy 83.231836 -287.732468)
			(xy 83.247952 -287.780742) (xy 83.256116 -287.830976) (xy 83.256628 -287.856422) (xy 83.256125 -287.881411)
			(xy 83.563442 -287.881411) (xy 83.563442 -287.831433) (xy 83.571261 -287.78207) (xy 83.586705 -287.734538)
			(xy 83.609395 -287.690006) (xy 83.638771 -287.649573) (xy 83.674111 -287.614233) (xy 83.714544 -287.584857)
			(xy 83.759076 -287.562167) (xy 83.806608 -287.546723) (xy 83.855971 -287.538904) (xy 83.905949 -287.538904)
			(xy 83.955312 -287.546723) (xy 84.002844 -287.562167) (xy 84.047376 -287.584857) (xy 84.087809 -287.614233)
			(xy 84.123149 -287.649573) (xy 84.152525 -287.690006) (xy 84.175215 -287.734538) (xy 84.190659 -287.78207)
			(xy 84.198478 -287.831433) (xy 84.198968 -287.856422) (xy 84.504779 -287.856422) (xy 84.508874 -287.805694)
			(xy 84.521053 -287.75628) (xy 84.541001 -287.70946) (xy 84.568202 -287.666446) (xy 84.60195 -287.628352)
			(xy 84.641372 -287.596165) (xy 84.685446 -287.570719) (xy 84.733032 -287.552672) (xy 84.782896 -287.542492)
			(xy 84.833748 -287.540443) (xy 84.884269 -287.546577) (xy 84.933153 -287.560737) (xy 84.979132 -287.582554)
			(xy 85.021016 -287.611464) (xy 85.05772 -287.646719) (xy 85.088293 -287.687405) (xy 85.111944 -287.732468)
			(xy 85.12806 -287.780742) (xy 85.136224 -287.830976) (xy 85.136736 -287.856422) (xy 85.444833 -287.856422)
			(xy 85.448928 -287.805694) (xy 85.461107 -287.75628) (xy 85.481055 -287.70946) (xy 85.508256 -287.666446)
			(xy 85.542004 -287.628352) (xy 85.581426 -287.596165) (xy 85.6255 -287.570719) (xy 85.673086 -287.552672)
			(xy 85.72295 -287.542492) (xy 85.773802 -287.540443) (xy 85.824323 -287.546577) (xy 85.873207 -287.560737)
			(xy 85.919186 -287.582554) (xy 85.96107 -287.611464) (xy 85.997774 -287.646719) (xy 86.028347 -287.687405)
			(xy 86.051998 -287.732468) (xy 86.068114 -287.780742) (xy 86.076278 -287.830976) (xy 86.07679 -287.856422)
			(xy 87.324687 -287.856422) (xy 87.328782 -287.805694) (xy 87.340961 -287.75628) (xy 87.360909 -287.70946)
			(xy 87.38811 -287.666446) (xy 87.421858 -287.628352) (xy 87.46128 -287.596165) (xy 87.505354 -287.570719)
			(xy 87.55294 -287.552672) (xy 87.602804 -287.542492) (xy 87.653656 -287.540443) (xy 87.704177 -287.546577)
			(xy 87.753061 -287.560737) (xy 87.79904 -287.582554) (xy 87.840924 -287.611464) (xy 87.877628 -287.646719)
			(xy 87.908201 -287.687405) (xy 87.931852 -287.732468) (xy 87.947968 -287.780742) (xy 87.956132 -287.830976)
			(xy 87.956644 -287.856422) (xy 87.956141 -287.881411) (xy 88.263458 -287.881411) (xy 88.263458 -287.831433)
			(xy 88.271277 -287.78207) (xy 88.286721 -287.734538) (xy 88.309411 -287.690006) (xy 88.338787 -287.649573)
			(xy 88.374127 -287.614233) (xy 88.41456 -287.584857) (xy 88.459092 -287.562167) (xy 88.506624 -287.546723)
			(xy 88.555987 -287.538904) (xy 88.605965 -287.538904) (xy 88.655328 -287.546723) (xy 88.70286 -287.562167)
			(xy 88.747392 -287.584857) (xy 88.787825 -287.614233) (xy 88.823165 -287.649573) (xy 88.852541 -287.690006)
			(xy 88.875231 -287.734538) (xy 88.890675 -287.78207) (xy 88.898494 -287.831433) (xy 88.898984 -287.856422)
			(xy 88.898494 -287.881411) (xy 88.890675 -287.930774) (xy 88.875231 -287.978306) (xy 88.852541 -288.022838)
			(xy 88.823165 -288.063271) (xy 88.787825 -288.098611) (xy 88.747392 -288.127987) (xy 88.70286 -288.150677)
			(xy 88.655328 -288.166121) (xy 88.605965 -288.17394) (xy 88.555987 -288.17394) (xy 88.506624 -288.166121)
			(xy 88.459092 -288.150677) (xy 88.41456 -288.127987) (xy 88.374127 -288.098611) (xy 88.338787 -288.063271)
			(xy 88.309411 -288.022838) (xy 88.286721 -287.978306) (xy 88.271277 -287.930774) (xy 88.263458 -287.881411)
			(xy 87.956141 -287.881411) (xy 87.956132 -287.881868) (xy 87.947968 -287.932102) (xy 87.931852 -287.980376)
			(xy 87.908201 -288.025439) (xy 87.877628 -288.066125) (xy 87.840924 -288.10138) (xy 87.79904 -288.13029)
			(xy 87.753061 -288.152107) (xy 87.704177 -288.166267) (xy 87.653656 -288.172401) (xy 87.602804 -288.170352)
			(xy 87.55294 -288.160172) (xy 87.505354 -288.142125) (xy 87.46128 -288.116679) (xy 87.421858 -288.084492)
			(xy 87.38811 -288.046398) (xy 87.360909 -288.003384) (xy 87.340961 -287.956564) (xy 87.328782 -287.90715)
			(xy 87.324687 -287.856422) (xy 86.07679 -287.856422) (xy 86.076278 -287.881868) (xy 86.068114 -287.932102)
			(xy 86.051998 -287.980376) (xy 86.028347 -288.025439) (xy 85.997774 -288.066125) (xy 85.96107 -288.10138)
			(xy 85.919186 -288.13029) (xy 85.873207 -288.152107) (xy 85.824323 -288.166267) (xy 85.773802 -288.172401)
			(xy 85.72295 -288.170352) (xy 85.673086 -288.160172) (xy 85.6255 -288.142125) (xy 85.581426 -288.116679)
			(xy 85.542004 -288.084492) (xy 85.508256 -288.046398) (xy 85.481055 -288.003384) (xy 85.461107 -287.956564)
			(xy 85.448928 -287.90715) (xy 85.444833 -287.856422) (xy 85.136736 -287.856422) (xy 85.136224 -287.881868)
			(xy 85.12806 -287.932102) (xy 85.111944 -287.980376) (xy 85.088293 -288.025439) (xy 85.05772 -288.066125)
			(xy 85.021016 -288.10138) (xy 84.979132 -288.13029) (xy 84.933153 -288.152107) (xy 84.884269 -288.166267)
			(xy 84.833748 -288.172401) (xy 84.782896 -288.170352) (xy 84.733032 -288.160172) (xy 84.685446 -288.142125)
			(xy 84.641372 -288.116679) (xy 84.60195 -288.084492) (xy 84.568202 -288.046398) (xy 84.541001 -288.003384)
			(xy 84.521053 -287.956564) (xy 84.508874 -287.90715) (xy 84.504779 -287.856422) (xy 84.198968 -287.856422)
			(xy 84.198478 -287.881411) (xy 84.190659 -287.930774) (xy 84.175215 -287.978306) (xy 84.152525 -288.022838)
			(xy 84.123149 -288.063271) (xy 84.087809 -288.098611) (xy 84.047376 -288.127987) (xy 84.002844 -288.150677)
			(xy 83.955312 -288.166121) (xy 83.905949 -288.17394) (xy 83.855971 -288.17394) (xy 83.806608 -288.166121)
			(xy 83.759076 -288.150677) (xy 83.714544 -288.127987) (xy 83.674111 -288.098611) (xy 83.638771 -288.063271)
			(xy 83.609395 -288.022838) (xy 83.586705 -287.978306) (xy 83.571261 -287.930774) (xy 83.563442 -287.881411)
			(xy 83.256125 -287.881411) (xy 83.256116 -287.881868) (xy 83.247952 -287.932102) (xy 83.231836 -287.980376)
			(xy 83.208185 -288.025439) (xy 83.177612 -288.066125) (xy 83.140908 -288.10138) (xy 83.099024 -288.13029)
			(xy 83.053045 -288.152107) (xy 83.004161 -288.166267) (xy 82.95364 -288.172401) (xy 82.902788 -288.170352)
			(xy 82.852924 -288.160172) (xy 82.805338 -288.142125) (xy 82.761264 -288.116679) (xy 82.721842 -288.084492)
			(xy 82.688094 -288.046398) (xy 82.660893 -288.003384) (xy 82.640945 -287.956564) (xy 82.628766 -287.90715)
			(xy 82.624671 -287.856422) (xy 82.319114 -287.856422) (xy 82.318624 -287.881411) (xy 82.310805 -287.930774)
			(xy 82.295361 -287.978306) (xy 82.272671 -288.022838) (xy 82.243295 -288.063271) (xy 82.207955 -288.098611)
			(xy 82.167522 -288.127987) (xy 82.12299 -288.150677) (xy 82.075458 -288.166121) (xy 82.026095 -288.17394)
			(xy 81.976117 -288.17394) (xy 81.926754 -288.166121) (xy 81.879222 -288.150677) (xy 81.83469 -288.127987)
			(xy 81.794257 -288.098611) (xy 81.758917 -288.063271) (xy 81.729541 -288.022838) (xy 81.706851 -287.978306)
			(xy 81.691407 -287.930774) (xy 81.683588 -287.881411) (xy 81.376271 -287.881411) (xy 81.376262 -287.881868)
			(xy 81.368098 -287.932102) (xy 81.351982 -287.980376) (xy 81.328331 -288.025439) (xy 81.297758 -288.066125)
			(xy 81.261054 -288.10138) (xy 81.21917 -288.13029) (xy 81.173191 -288.152107) (xy 81.124307 -288.166267)
			(xy 81.073786 -288.172401) (xy 81.022934 -288.170352) (xy 80.97307 -288.160172) (xy 80.925484 -288.142125)
			(xy 80.88141 -288.116679) (xy 80.841988 -288.084492) (xy 80.80824 -288.046398) (xy 80.781039 -288.003384)
			(xy 80.761091 -287.956564) (xy 80.748912 -287.90715) (xy 80.744817 -287.856422) (xy 79.53248 -287.856422)
			(xy 79.53248 -288.691163) (xy 80.273634 -288.691163) (xy 80.273634 -288.641185) (xy 80.281453 -288.591822)
			(xy 80.296897 -288.54429) (xy 80.319587 -288.499758) (xy 80.348963 -288.459325) (xy 80.384303 -288.423985)
			(xy 80.424736 -288.394609) (xy 80.469268 -288.371919) (xy 80.5168 -288.356475) (xy 80.566163 -288.348656)
			(xy 80.616141 -288.348656) (xy 80.665504 -288.356475) (xy 80.713036 -288.371919) (xy 80.757568 -288.394609)
			(xy 80.798001 -288.423985) (xy 80.833341 -288.459325) (xy 80.862717 -288.499758) (xy 80.885407 -288.54429)
			(xy 80.900851 -288.591822) (xy 80.90867 -288.641185) (xy 80.90916 -288.666174) (xy 81.214717 -288.666174)
			(xy 81.218812 -288.615446) (xy 81.230991 -288.566032) (xy 81.250939 -288.519212) (xy 81.27814 -288.476198)
			(xy 81.311888 -288.438104) (xy 81.35131 -288.405917) (xy 81.395384 -288.380471) (xy 81.44297 -288.362424)
			(xy 81.492834 -288.352244) (xy 81.543686 -288.350195) (xy 81.594207 -288.356329) (xy 81.643091 -288.370489)
			(xy 81.68907 -288.392306) (xy 81.730954 -288.421216) (xy 81.767658 -288.456471) (xy 81.798231 -288.497157)
			(xy 81.821882 -288.54222) (xy 81.837998 -288.590494) (xy 81.846162 -288.640728) (xy 81.846674 -288.666174)
			(xy 82.154771 -288.666174) (xy 82.158866 -288.615446) (xy 82.171045 -288.566032) (xy 82.190993 -288.519212)
			(xy 82.218194 -288.476198) (xy 82.251942 -288.438104) (xy 82.291364 -288.405917) (xy 82.335438 -288.380471)
			(xy 82.383024 -288.362424) (xy 82.432888 -288.352244) (xy 82.48374 -288.350195) (xy 82.534261 -288.356329)
			(xy 82.583145 -288.370489) (xy 82.629124 -288.392306) (xy 82.671008 -288.421216) (xy 82.707712 -288.456471)
			(xy 82.738285 -288.497157) (xy 82.761936 -288.54222) (xy 82.778052 -288.590494) (xy 82.786216 -288.640728)
			(xy 82.786728 -288.666174) (xy 82.786225 -288.691163) (xy 83.093542 -288.691163) (xy 83.093542 -288.641185)
			(xy 83.101361 -288.591822) (xy 83.116805 -288.54429) (xy 83.139495 -288.499758) (xy 83.168871 -288.459325)
			(xy 83.204211 -288.423985) (xy 83.244644 -288.394609) (xy 83.289176 -288.371919) (xy 83.336708 -288.356475)
			(xy 83.386071 -288.348656) (xy 83.436049 -288.348656) (xy 83.485412 -288.356475) (xy 83.532944 -288.371919)
			(xy 83.577476 -288.394609) (xy 83.617909 -288.423985) (xy 83.653249 -288.459325) (xy 83.682625 -288.499758)
			(xy 83.705315 -288.54429) (xy 83.720759 -288.591822) (xy 83.728578 -288.641185) (xy 83.729068 -288.666174)
			(xy 84.034879 -288.666174) (xy 84.038974 -288.615446) (xy 84.051153 -288.566032) (xy 84.071101 -288.519212)
			(xy 84.098302 -288.476198) (xy 84.13205 -288.438104) (xy 84.171472 -288.405917) (xy 84.215546 -288.380471)
			(xy 84.263132 -288.362424) (xy 84.312996 -288.352244) (xy 84.363848 -288.350195) (xy 84.414369 -288.356329)
			(xy 84.463253 -288.370489) (xy 84.509232 -288.392306) (xy 84.551116 -288.421216) (xy 84.58782 -288.456471)
			(xy 84.618393 -288.497157) (xy 84.642044 -288.54222) (xy 84.65816 -288.590494) (xy 84.666324 -288.640728)
			(xy 84.666836 -288.666174) (xy 84.666333 -288.691163) (xy 84.973396 -288.691163) (xy 84.973396 -288.641185)
			(xy 84.981215 -288.591822) (xy 84.996659 -288.54429) (xy 85.019349 -288.499758) (xy 85.048725 -288.459325)
			(xy 85.084065 -288.423985) (xy 85.124498 -288.394609) (xy 85.16903 -288.371919) (xy 85.216562 -288.356475)
			(xy 85.265925 -288.348656) (xy 85.315903 -288.348656) (xy 85.365266 -288.356475) (xy 85.412798 -288.371919)
			(xy 85.45733 -288.394609) (xy 85.497763 -288.423985) (xy 85.533103 -288.459325) (xy 85.562479 -288.499758)
			(xy 85.585169 -288.54429) (xy 85.600613 -288.591822) (xy 85.608432 -288.641185) (xy 85.608922 -288.666174)
			(xy 85.914733 -288.666174) (xy 85.918828 -288.615446) (xy 85.931007 -288.566032) (xy 85.950955 -288.519212)
			(xy 85.978156 -288.476198) (xy 86.011904 -288.438104) (xy 86.051326 -288.405917) (xy 86.0954 -288.380471)
			(xy 86.142986 -288.362424) (xy 86.19285 -288.352244) (xy 86.243702 -288.350195) (xy 86.294223 -288.356329)
			(xy 86.343107 -288.370489) (xy 86.389086 -288.392306) (xy 86.43097 -288.421216) (xy 86.467674 -288.456471)
			(xy 86.498247 -288.497157) (xy 86.521898 -288.54222) (xy 86.538014 -288.590494) (xy 86.546178 -288.640728)
			(xy 86.54669 -288.666174) (xy 86.546187 -288.691163) (xy 86.853504 -288.691163) (xy 86.853504 -288.641185)
			(xy 86.861323 -288.591822) (xy 86.876767 -288.54429) (xy 86.899457 -288.499758) (xy 86.928833 -288.459325)
			(xy 86.964173 -288.423985) (xy 87.004606 -288.394609) (xy 87.049138 -288.371919) (xy 87.09667 -288.356475)
			(xy 87.146033 -288.348656) (xy 87.196011 -288.348656) (xy 87.245374 -288.356475) (xy 87.292906 -288.371919)
			(xy 87.337438 -288.394609) (xy 87.377871 -288.423985) (xy 87.413211 -288.459325) (xy 87.442587 -288.499758)
			(xy 87.465277 -288.54429) (xy 87.480721 -288.591822) (xy 87.48854 -288.641185) (xy 87.48903 -288.666174)
			(xy 87.794841 -288.666174) (xy 87.798936 -288.615446) (xy 87.811115 -288.566032) (xy 87.831063 -288.519212)
			(xy 87.858264 -288.476198) (xy 87.892012 -288.438104) (xy 87.931434 -288.405917) (xy 87.975508 -288.380471)
			(xy 88.023094 -288.362424) (xy 88.072958 -288.352244) (xy 88.12381 -288.350195) (xy 88.174331 -288.356329)
			(xy 88.223215 -288.370489) (xy 88.269194 -288.392306) (xy 88.311078 -288.421216) (xy 88.347782 -288.456471)
			(xy 88.378355 -288.497157) (xy 88.402006 -288.54222) (xy 88.418122 -288.590494) (xy 88.426286 -288.640728)
			(xy 88.426798 -288.666174) (xy 88.734895 -288.666174) (xy 88.73899 -288.615446) (xy 88.751169 -288.566032)
			(xy 88.771117 -288.519212) (xy 88.798318 -288.476198) (xy 88.832066 -288.438104) (xy 88.871488 -288.405917)
			(xy 88.915562 -288.380471) (xy 88.963148 -288.362424) (xy 89.013012 -288.352244) (xy 89.063864 -288.350195)
			(xy 89.114385 -288.356329) (xy 89.163269 -288.370489) (xy 89.209248 -288.392306) (xy 89.251132 -288.421216)
			(xy 89.287836 -288.456471) (xy 89.318409 -288.497157) (xy 89.34206 -288.54222) (xy 89.358176 -288.590494)
			(xy 89.36634 -288.640728) (xy 89.366852 -288.666174) (xy 89.36634 -288.69162) (xy 89.358176 -288.741854)
			(xy 89.34206 -288.790128) (xy 89.318409 -288.835191) (xy 89.287836 -288.875877) (xy 89.251132 -288.911132)
			(xy 89.209248 -288.940042) (xy 89.163269 -288.961859) (xy 89.114385 -288.976019) (xy 89.063864 -288.982153)
			(xy 89.013012 -288.980104) (xy 88.963148 -288.969924) (xy 88.915562 -288.951877) (xy 88.871488 -288.926431)
			(xy 88.832066 -288.894244) (xy 88.798318 -288.85615) (xy 88.771117 -288.813136) (xy 88.751169 -288.766316)
			(xy 88.73899 -288.716902) (xy 88.734895 -288.666174) (xy 88.426798 -288.666174) (xy 88.426286 -288.69162)
			(xy 88.418122 -288.741854) (xy 88.402006 -288.790128) (xy 88.378355 -288.835191) (xy 88.347782 -288.875877)
			(xy 88.311078 -288.911132) (xy 88.269194 -288.940042) (xy 88.223215 -288.961859) (xy 88.174331 -288.976019)
			(xy 88.12381 -288.982153) (xy 88.072958 -288.980104) (xy 88.023094 -288.969924) (xy 87.975508 -288.951877)
			(xy 87.931434 -288.926431) (xy 87.892012 -288.894244) (xy 87.858264 -288.85615) (xy 87.831063 -288.813136)
			(xy 87.811115 -288.766316) (xy 87.798936 -288.716902) (xy 87.794841 -288.666174) (xy 87.48903 -288.666174)
			(xy 87.48854 -288.691163) (xy 87.480721 -288.740526) (xy 87.465277 -288.788058) (xy 87.442587 -288.83259)
			(xy 87.413211 -288.873023) (xy 87.377871 -288.908363) (xy 87.337438 -288.937739) (xy 87.292906 -288.960429)
			(xy 87.245374 -288.975873) (xy 87.196011 -288.983692) (xy 87.146033 -288.983692) (xy 87.09667 -288.975873)
			(xy 87.049138 -288.960429) (xy 87.004606 -288.937739) (xy 86.964173 -288.908363) (xy 86.928833 -288.873023)
			(xy 86.899457 -288.83259) (xy 86.876767 -288.788058) (xy 86.861323 -288.740526) (xy 86.853504 -288.691163)
			(xy 86.546187 -288.691163) (xy 86.546178 -288.69162) (xy 86.538014 -288.741854) (xy 86.521898 -288.790128)
			(xy 86.498247 -288.835191) (xy 86.467674 -288.875877) (xy 86.43097 -288.911132) (xy 86.389086 -288.940042)
			(xy 86.343107 -288.961859) (xy 86.294223 -288.976019) (xy 86.243702 -288.982153) (xy 86.19285 -288.980104)
			(xy 86.142986 -288.969924) (xy 86.0954 -288.951877) (xy 86.051326 -288.926431) (xy 86.011904 -288.894244)
			(xy 85.978156 -288.85615) (xy 85.950955 -288.813136) (xy 85.931007 -288.766316) (xy 85.918828 -288.716902)
			(xy 85.914733 -288.666174) (xy 85.608922 -288.666174) (xy 85.608432 -288.691163) (xy 85.600613 -288.740526)
			(xy 85.585169 -288.788058) (xy 85.562479 -288.83259) (xy 85.533103 -288.873023) (xy 85.497763 -288.908363)
			(xy 85.45733 -288.937739) (xy 85.412798 -288.960429) (xy 85.365266 -288.975873) (xy 85.315903 -288.983692)
			(xy 85.265925 -288.983692) (xy 85.216562 -288.975873) (xy 85.16903 -288.960429) (xy 85.124498 -288.937739)
			(xy 85.084065 -288.908363) (xy 85.048725 -288.873023) (xy 85.019349 -288.83259) (xy 84.996659 -288.788058)
			(xy 84.981215 -288.740526) (xy 84.973396 -288.691163) (xy 84.666333 -288.691163) (xy 84.666324 -288.69162)
			(xy 84.65816 -288.741854) (xy 84.642044 -288.790128) (xy 84.618393 -288.835191) (xy 84.58782 -288.875877)
			(xy 84.551116 -288.911132) (xy 84.509232 -288.940042) (xy 84.463253 -288.961859) (xy 84.414369 -288.976019)
			(xy 84.363848 -288.982153) (xy 84.312996 -288.980104) (xy 84.263132 -288.969924) (xy 84.215546 -288.951877)
			(xy 84.171472 -288.926431) (xy 84.13205 -288.894244) (xy 84.098302 -288.85615) (xy 84.071101 -288.813136)
			(xy 84.051153 -288.766316) (xy 84.038974 -288.716902) (xy 84.034879 -288.666174) (xy 83.729068 -288.666174)
			(xy 83.728578 -288.691163) (xy 83.720759 -288.740526) (xy 83.705315 -288.788058) (xy 83.682625 -288.83259)
			(xy 83.653249 -288.873023) (xy 83.617909 -288.908363) (xy 83.577476 -288.937739) (xy 83.532944 -288.960429)
			(xy 83.485412 -288.975873) (xy 83.436049 -288.983692) (xy 83.386071 -288.983692) (xy 83.336708 -288.975873)
			(xy 83.289176 -288.960429) (xy 83.244644 -288.937739) (xy 83.204211 -288.908363) (xy 83.168871 -288.873023)
			(xy 83.139495 -288.83259) (xy 83.116805 -288.788058) (xy 83.101361 -288.740526) (xy 83.093542 -288.691163)
			(xy 82.786225 -288.691163) (xy 82.786216 -288.69162) (xy 82.778052 -288.741854) (xy 82.761936 -288.790128)
			(xy 82.738285 -288.835191) (xy 82.707712 -288.875877) (xy 82.671008 -288.911132) (xy 82.629124 -288.940042)
			(xy 82.583145 -288.961859) (xy 82.534261 -288.976019) (xy 82.48374 -288.982153) (xy 82.432888 -288.980104)
			(xy 82.383024 -288.969924) (xy 82.335438 -288.951877) (xy 82.291364 -288.926431) (xy 82.251942 -288.894244)
			(xy 82.218194 -288.85615) (xy 82.190993 -288.813136) (xy 82.171045 -288.766316) (xy 82.158866 -288.716902)
			(xy 82.154771 -288.666174) (xy 81.846674 -288.666174) (xy 81.846162 -288.69162) (xy 81.837998 -288.741854)
			(xy 81.821882 -288.790128) (xy 81.798231 -288.835191) (xy 81.767658 -288.875877) (xy 81.730954 -288.911132)
			(xy 81.68907 -288.940042) (xy 81.643091 -288.961859) (xy 81.594207 -288.976019) (xy 81.543686 -288.982153)
			(xy 81.492834 -288.980104) (xy 81.44297 -288.969924) (xy 81.395384 -288.951877) (xy 81.35131 -288.926431)
			(xy 81.311888 -288.894244) (xy 81.27814 -288.85615) (xy 81.250939 -288.813136) (xy 81.230991 -288.766316)
			(xy 81.218812 -288.716902) (xy 81.214717 -288.666174) (xy 80.90916 -288.666174) (xy 80.90867 -288.691163)
			(xy 80.900851 -288.740526) (xy 80.885407 -288.788058) (xy 80.862717 -288.83259) (xy 80.833341 -288.873023)
			(xy 80.798001 -288.908363) (xy 80.757568 -288.937739) (xy 80.713036 -288.960429) (xy 80.665504 -288.975873)
			(xy 80.616141 -288.983692) (xy 80.566163 -288.983692) (xy 80.5168 -288.975873) (xy 80.469268 -288.960429)
			(xy 80.424736 -288.937739) (xy 80.384303 -288.908363) (xy 80.348963 -288.873023) (xy 80.319587 -288.83259)
			(xy 80.296897 -288.788058) (xy 80.281453 -288.740526) (xy 80.273634 -288.691163) (xy 79.53248 -288.691163)
			(xy 79.53248 -289.501169) (xy 79.80348 -289.501169) (xy 79.80348 -289.451191) (xy 79.811299 -289.401828)
			(xy 79.826743 -289.354296) (xy 79.849433 -289.309764) (xy 79.878809 -289.269331) (xy 79.914149 -289.233991)
			(xy 79.954582 -289.204615) (xy 79.999114 -289.181925) (xy 80.046646 -289.166481) (xy 80.096009 -289.158662)
			(xy 80.145987 -289.158662) (xy 80.19535 -289.166481) (xy 80.242882 -289.181925) (xy 80.287414 -289.204615)
			(xy 80.327847 -289.233991) (xy 80.363187 -289.269331) (xy 80.392563 -289.309764) (xy 80.415253 -289.354296)
			(xy 80.430697 -289.401828) (xy 80.438516 -289.451191) (xy 80.439006 -289.47618) (xy 80.744817 -289.47618)
			(xy 80.748912 -289.425452) (xy 80.761091 -289.376038) (xy 80.781039 -289.329218) (xy 80.80824 -289.286204)
			(xy 80.841988 -289.24811) (xy 80.88141 -289.215923) (xy 80.925484 -289.190477) (xy 80.97307 -289.17243)
			(xy 81.022934 -289.16225) (xy 81.073786 -289.160201) (xy 81.124307 -289.166335) (xy 81.173191 -289.180495)
			(xy 81.21917 -289.202312) (xy 81.261054 -289.231222) (xy 81.297758 -289.266477) (xy 81.328331 -289.307163)
			(xy 81.351982 -289.352226) (xy 81.368098 -289.4005) (xy 81.376262 -289.450734) (xy 81.376774 -289.47618)
			(xy 81.376271 -289.501169) (xy 81.683588 -289.501169) (xy 81.683588 -289.451191) (xy 81.691407 -289.401828)
			(xy 81.706851 -289.354296) (xy 81.729541 -289.309764) (xy 81.758917 -289.269331) (xy 81.794257 -289.233991)
			(xy 81.83469 -289.204615) (xy 81.879222 -289.181925) (xy 81.926754 -289.166481) (xy 81.976117 -289.158662)
			(xy 82.026095 -289.158662) (xy 82.075458 -289.166481) (xy 82.12299 -289.181925) (xy 82.167522 -289.204615)
			(xy 82.207955 -289.233991) (xy 82.243295 -289.269331) (xy 82.272671 -289.309764) (xy 82.295361 -289.354296)
			(xy 82.310805 -289.401828) (xy 82.318624 -289.451191) (xy 82.319114 -289.47618) (xy 82.624671 -289.47618)
			(xy 82.628766 -289.425452) (xy 82.640945 -289.376038) (xy 82.660893 -289.329218) (xy 82.688094 -289.286204)
			(xy 82.721842 -289.24811) (xy 82.761264 -289.215923) (xy 82.805338 -289.190477) (xy 82.852924 -289.17243)
			(xy 82.902788 -289.16225) (xy 82.95364 -289.160201) (xy 83.004161 -289.166335) (xy 83.053045 -289.180495)
			(xy 83.099024 -289.202312) (xy 83.140908 -289.231222) (xy 83.177612 -289.266477) (xy 83.208185 -289.307163)
			(xy 83.231836 -289.352226) (xy 83.247952 -289.4005) (xy 83.256116 -289.450734) (xy 83.256628 -289.47618)
			(xy 83.256125 -289.501169) (xy 83.563442 -289.501169) (xy 83.563442 -289.451191) (xy 83.571261 -289.401828)
			(xy 83.586705 -289.354296) (xy 83.609395 -289.309764) (xy 83.638771 -289.269331) (xy 83.674111 -289.233991)
			(xy 83.714544 -289.204615) (xy 83.759076 -289.181925) (xy 83.806608 -289.166481) (xy 83.855971 -289.158662)
			(xy 83.905949 -289.158662) (xy 83.955312 -289.166481) (xy 84.002844 -289.181925) (xy 84.047376 -289.204615)
			(xy 84.087809 -289.233991) (xy 84.123149 -289.269331) (xy 84.152525 -289.309764) (xy 84.175215 -289.354296)
			(xy 84.190659 -289.401828) (xy 84.198478 -289.451191) (xy 84.198968 -289.47618) (xy 84.504779 -289.47618)
			(xy 84.508874 -289.425452) (xy 84.521053 -289.376038) (xy 84.541001 -289.329218) (xy 84.568202 -289.286204)
			(xy 84.60195 -289.24811) (xy 84.641372 -289.215923) (xy 84.685446 -289.190477) (xy 84.733032 -289.17243)
			(xy 84.782896 -289.16225) (xy 84.833748 -289.160201) (xy 84.884269 -289.166335) (xy 84.933153 -289.180495)
			(xy 84.979132 -289.202312) (xy 85.021016 -289.231222) (xy 85.05772 -289.266477) (xy 85.088293 -289.307163)
			(xy 85.111944 -289.352226) (xy 85.12806 -289.4005) (xy 85.136224 -289.450734) (xy 85.136736 -289.47618)
			(xy 85.444833 -289.47618) (xy 85.448928 -289.425452) (xy 85.461107 -289.376038) (xy 85.481055 -289.329218)
			(xy 85.508256 -289.286204) (xy 85.542004 -289.24811) (xy 85.581426 -289.215923) (xy 85.6255 -289.190477)
			(xy 85.673086 -289.17243) (xy 85.72295 -289.16225) (xy 85.773802 -289.160201) (xy 85.824323 -289.166335)
			(xy 85.873207 -289.180495) (xy 85.919186 -289.202312) (xy 85.96107 -289.231222) (xy 85.997774 -289.266477)
			(xy 86.028347 -289.307163) (xy 86.051998 -289.352226) (xy 86.068114 -289.4005) (xy 86.076278 -289.450734)
			(xy 86.07679 -289.47618) (xy 86.076287 -289.501169) (xy 86.383604 -289.501169) (xy 86.383604 -289.451191)
			(xy 86.391423 -289.401828) (xy 86.406867 -289.354296) (xy 86.429557 -289.309764) (xy 86.458933 -289.269331)
			(xy 86.494273 -289.233991) (xy 86.534706 -289.204615) (xy 86.579238 -289.181925) (xy 86.62677 -289.166481)
			(xy 86.676133 -289.158662) (xy 86.726111 -289.158662) (xy 86.775474 -289.166481) (xy 86.823006 -289.181925)
			(xy 86.867538 -289.204615) (xy 86.907971 -289.233991) (xy 86.943311 -289.269331) (xy 86.972687 -289.309764)
			(xy 86.995377 -289.354296) (xy 87.010821 -289.401828) (xy 87.01864 -289.451191) (xy 87.01913 -289.47618)
			(xy 87.324687 -289.47618) (xy 87.328782 -289.425452) (xy 87.340961 -289.376038) (xy 87.360909 -289.329218)
			(xy 87.38811 -289.286204) (xy 87.421858 -289.24811) (xy 87.46128 -289.215923) (xy 87.505354 -289.190477)
			(xy 87.55294 -289.17243) (xy 87.602804 -289.16225) (xy 87.653656 -289.160201) (xy 87.704177 -289.166335)
			(xy 87.753061 -289.180495) (xy 87.79904 -289.202312) (xy 87.840924 -289.231222) (xy 87.877628 -289.266477)
			(xy 87.908201 -289.307163) (xy 87.931852 -289.352226) (xy 87.947968 -289.4005) (xy 87.956132 -289.450734)
			(xy 87.956644 -289.47618) (xy 87.956141 -289.501169) (xy 88.263458 -289.501169) (xy 88.263458 -289.451191)
			(xy 88.271277 -289.401828) (xy 88.286721 -289.354296) (xy 88.309411 -289.309764) (xy 88.338787 -289.269331)
			(xy 88.374127 -289.233991) (xy 88.41456 -289.204615) (xy 88.459092 -289.181925) (xy 88.506624 -289.166481)
			(xy 88.555987 -289.158662) (xy 88.605965 -289.158662) (xy 88.655328 -289.166481) (xy 88.70286 -289.181925)
			(xy 88.747392 -289.204615) (xy 88.787825 -289.233991) (xy 88.823165 -289.269331) (xy 88.852541 -289.309764)
			(xy 88.875231 -289.354296) (xy 88.890675 -289.401828) (xy 88.898494 -289.451191) (xy 88.898984 -289.47618)
			(xy 88.898494 -289.501169) (xy 88.890675 -289.550532) (xy 88.875231 -289.598064) (xy 88.852541 -289.642596)
			(xy 88.823165 -289.683029) (xy 88.787825 -289.718369) (xy 88.747392 -289.747745) (xy 88.70286 -289.770435)
			(xy 88.655328 -289.785879) (xy 88.605965 -289.793698) (xy 88.555987 -289.793698) (xy 88.506624 -289.785879)
			(xy 88.459092 -289.770435) (xy 88.41456 -289.747745) (xy 88.374127 -289.718369) (xy 88.338787 -289.683029)
			(xy 88.309411 -289.642596) (xy 88.286721 -289.598064) (xy 88.271277 -289.550532) (xy 88.263458 -289.501169)
			(xy 87.956141 -289.501169) (xy 87.956132 -289.501626) (xy 87.947968 -289.55186) (xy 87.931852 -289.600134)
			(xy 87.908201 -289.645197) (xy 87.877628 -289.685883) (xy 87.840924 -289.721138) (xy 87.79904 -289.750048)
			(xy 87.753061 -289.771865) (xy 87.704177 -289.786025) (xy 87.653656 -289.792159) (xy 87.602804 -289.79011)
			(xy 87.55294 -289.77993) (xy 87.505354 -289.761883) (xy 87.46128 -289.736437) (xy 87.421858 -289.70425)
			(xy 87.38811 -289.666156) (xy 87.360909 -289.623142) (xy 87.340961 -289.576322) (xy 87.328782 -289.526908)
			(xy 87.324687 -289.47618) (xy 87.01913 -289.47618) (xy 87.01864 -289.501169) (xy 87.010821 -289.550532)
			(xy 86.995377 -289.598064) (xy 86.972687 -289.642596) (xy 86.943311 -289.683029) (xy 86.907971 -289.718369)
			(xy 86.867538 -289.747745) (xy 86.823006 -289.770435) (xy 86.775474 -289.785879) (xy 86.726111 -289.793698)
			(xy 86.676133 -289.793698) (xy 86.62677 -289.785879) (xy 86.579238 -289.770435) (xy 86.534706 -289.747745)
			(xy 86.494273 -289.718369) (xy 86.458933 -289.683029) (xy 86.429557 -289.642596) (xy 86.406867 -289.598064)
			(xy 86.391423 -289.550532) (xy 86.383604 -289.501169) (xy 86.076287 -289.501169) (xy 86.076278 -289.501626)
			(xy 86.068114 -289.55186) (xy 86.051998 -289.600134) (xy 86.028347 -289.645197) (xy 85.997774 -289.685883)
			(xy 85.96107 -289.721138) (xy 85.919186 -289.750048) (xy 85.873207 -289.771865) (xy 85.824323 -289.786025)
			(xy 85.773802 -289.792159) (xy 85.72295 -289.79011) (xy 85.673086 -289.77993) (xy 85.6255 -289.761883)
			(xy 85.581426 -289.736437) (xy 85.542004 -289.70425) (xy 85.508256 -289.666156) (xy 85.481055 -289.623142)
			(xy 85.461107 -289.576322) (xy 85.448928 -289.526908) (xy 85.444833 -289.47618) (xy 85.136736 -289.47618)
			(xy 85.136224 -289.501626) (xy 85.12806 -289.55186) (xy 85.111944 -289.600134) (xy 85.088293 -289.645197)
			(xy 85.05772 -289.685883) (xy 85.021016 -289.721138) (xy 84.979132 -289.750048) (xy 84.933153 -289.771865)
			(xy 84.884269 -289.786025) (xy 84.833748 -289.792159) (xy 84.782896 -289.79011) (xy 84.733032 -289.77993)
			(xy 84.685446 -289.761883) (xy 84.641372 -289.736437) (xy 84.60195 -289.70425) (xy 84.568202 -289.666156)
			(xy 84.541001 -289.623142) (xy 84.521053 -289.576322) (xy 84.508874 -289.526908) (xy 84.504779 -289.47618)
			(xy 84.198968 -289.47618) (xy 84.198478 -289.501169) (xy 84.190659 -289.550532) (xy 84.175215 -289.598064)
			(xy 84.152525 -289.642596) (xy 84.123149 -289.683029) (xy 84.087809 -289.718369) (xy 84.047376 -289.747745)
			(xy 84.002844 -289.770435) (xy 83.955312 -289.785879) (xy 83.905949 -289.793698) (xy 83.855971 -289.793698)
			(xy 83.806608 -289.785879) (xy 83.759076 -289.770435) (xy 83.714544 -289.747745) (xy 83.674111 -289.718369)
			(xy 83.638771 -289.683029) (xy 83.609395 -289.642596) (xy 83.586705 -289.598064) (xy 83.571261 -289.550532)
			(xy 83.563442 -289.501169) (xy 83.256125 -289.501169) (xy 83.256116 -289.501626) (xy 83.247952 -289.55186)
			(xy 83.231836 -289.600134) (xy 83.208185 -289.645197) (xy 83.177612 -289.685883) (xy 83.140908 -289.721138)
			(xy 83.099024 -289.750048) (xy 83.053045 -289.771865) (xy 83.004161 -289.786025) (xy 82.95364 -289.792159)
			(xy 82.902788 -289.79011) (xy 82.852924 -289.77993) (xy 82.805338 -289.761883) (xy 82.761264 -289.736437)
			(xy 82.721842 -289.70425) (xy 82.688094 -289.666156) (xy 82.660893 -289.623142) (xy 82.640945 -289.576322)
			(xy 82.628766 -289.526908) (xy 82.624671 -289.47618) (xy 82.319114 -289.47618) (xy 82.318624 -289.501169)
			(xy 82.310805 -289.550532) (xy 82.295361 -289.598064) (xy 82.272671 -289.642596) (xy 82.243295 -289.683029)
			(xy 82.207955 -289.718369) (xy 82.167522 -289.747745) (xy 82.12299 -289.770435) (xy 82.075458 -289.785879)
			(xy 82.026095 -289.793698) (xy 81.976117 -289.793698) (xy 81.926754 -289.785879) (xy 81.879222 -289.770435)
			(xy 81.83469 -289.747745) (xy 81.794257 -289.718369) (xy 81.758917 -289.683029) (xy 81.729541 -289.642596)
			(xy 81.706851 -289.598064) (xy 81.691407 -289.550532) (xy 81.683588 -289.501169) (xy 81.376271 -289.501169)
			(xy 81.376262 -289.501626) (xy 81.368098 -289.55186) (xy 81.351982 -289.600134) (xy 81.328331 -289.645197)
			(xy 81.297758 -289.685883) (xy 81.261054 -289.721138) (xy 81.21917 -289.750048) (xy 81.173191 -289.771865)
			(xy 81.124307 -289.786025) (xy 81.073786 -289.792159) (xy 81.022934 -289.79011) (xy 80.97307 -289.77993)
			(xy 80.925484 -289.761883) (xy 80.88141 -289.736437) (xy 80.841988 -289.70425) (xy 80.80824 -289.666156)
			(xy 80.781039 -289.623142) (xy 80.761091 -289.576322) (xy 80.748912 -289.526908) (xy 80.744817 -289.47618)
			(xy 80.439006 -289.47618) (xy 80.438516 -289.501169) (xy 80.430697 -289.550532) (xy 80.415253 -289.598064)
			(xy 80.392563 -289.642596) (xy 80.363187 -289.683029) (xy 80.327847 -289.718369) (xy 80.287414 -289.747745)
			(xy 80.242882 -289.770435) (xy 80.19535 -289.785879) (xy 80.145987 -289.793698) (xy 80.096009 -289.793698)
			(xy 80.046646 -289.785879) (xy 79.999114 -289.770435) (xy 79.954582 -289.747745) (xy 79.914149 -289.718369)
			(xy 79.878809 -289.683029) (xy 79.849433 -289.642596) (xy 79.826743 -289.598064) (xy 79.811299 -289.550532)
			(xy 79.80348 -289.501169) (xy 79.53248 -289.501169) (xy 79.53248 -290.286186) (xy 81.214717 -290.286186)
			(xy 81.218812 -290.235458) (xy 81.230991 -290.186044) (xy 81.250939 -290.139224) (xy 81.27814 -290.09621)
			(xy 81.311888 -290.058116) (xy 81.35131 -290.025929) (xy 81.395384 -290.000483) (xy 81.44297 -289.982436)
			(xy 81.492834 -289.972256) (xy 81.543686 -289.970207) (xy 81.594207 -289.976341) (xy 81.643091 -289.990501)
			(xy 81.68907 -290.012318) (xy 81.730954 -290.041228) (xy 81.767658 -290.076483) (xy 81.798231 -290.117169)
			(xy 81.821882 -290.162232) (xy 81.837998 -290.210506) (xy 81.846162 -290.26074) (xy 81.846674 -290.286186)
			(xy 82.154771 -290.286186) (xy 82.158866 -290.235458) (xy 82.171045 -290.186044) (xy 82.190993 -290.139224)
			(xy 82.218194 -290.09621) (xy 82.251942 -290.058116) (xy 82.291364 -290.025929) (xy 82.335438 -290.000483)
			(xy 82.383024 -289.982436) (xy 82.432888 -289.972256) (xy 82.48374 -289.970207) (xy 82.534261 -289.976341)
			(xy 82.583145 -289.990501) (xy 82.629124 -290.012318) (xy 82.671008 -290.041228) (xy 82.707712 -290.076483)
			(xy 82.738285 -290.117169) (xy 82.761936 -290.162232) (xy 82.778052 -290.210506) (xy 82.786216 -290.26074)
			(xy 82.786728 -290.286186) (xy 82.786225 -290.311175) (xy 83.093542 -290.311175) (xy 83.093542 -290.261197)
			(xy 83.101361 -290.211834) (xy 83.116805 -290.164302) (xy 83.139495 -290.11977) (xy 83.168871 -290.079337)
			(xy 83.204211 -290.043997) (xy 83.244644 -290.014621) (xy 83.289176 -289.991931) (xy 83.336708 -289.976487)
			(xy 83.386071 -289.968668) (xy 83.436049 -289.968668) (xy 83.485412 -289.976487) (xy 83.532944 -289.991931)
			(xy 83.577476 -290.014621) (xy 83.617909 -290.043997) (xy 83.653249 -290.079337) (xy 83.682625 -290.11977)
			(xy 83.705315 -290.164302) (xy 83.720759 -290.211834) (xy 83.728578 -290.261197) (xy 83.729068 -290.286186)
			(xy 84.034879 -290.286186) (xy 84.038974 -290.235458) (xy 84.051153 -290.186044) (xy 84.071101 -290.139224)
			(xy 84.098302 -290.09621) (xy 84.13205 -290.058116) (xy 84.171472 -290.025929) (xy 84.215546 -290.000483)
			(xy 84.263132 -289.982436) (xy 84.312996 -289.972256) (xy 84.363848 -289.970207) (xy 84.414369 -289.976341)
			(xy 84.463253 -289.990501) (xy 84.509232 -290.012318) (xy 84.551116 -290.041228) (xy 84.58782 -290.076483)
			(xy 84.618393 -290.117169) (xy 84.642044 -290.162232) (xy 84.65816 -290.210506) (xy 84.666324 -290.26074)
			(xy 84.666836 -290.286186) (xy 84.666333 -290.311175) (xy 84.973396 -290.311175) (xy 84.973396 -290.261197)
			(xy 84.981215 -290.211834) (xy 84.996659 -290.164302) (xy 85.019349 -290.11977) (xy 85.048725 -290.079337)
			(xy 85.084065 -290.043997) (xy 85.124498 -290.014621) (xy 85.16903 -289.991931) (xy 85.216562 -289.976487)
			(xy 85.265925 -289.968668) (xy 85.315903 -289.968668) (xy 85.365266 -289.976487) (xy 85.412798 -289.991931)
			(xy 85.45733 -290.014621) (xy 85.497763 -290.043997) (xy 85.533103 -290.079337) (xy 85.562479 -290.11977)
			(xy 85.585169 -290.164302) (xy 85.600613 -290.211834) (xy 85.608432 -290.261197) (xy 85.608922 -290.286186)
			(xy 85.914733 -290.286186) (xy 85.918828 -290.235458) (xy 85.931007 -290.186044) (xy 85.950955 -290.139224)
			(xy 85.978156 -290.09621) (xy 86.011904 -290.058116) (xy 86.051326 -290.025929) (xy 86.0954 -290.000483)
			(xy 86.142986 -289.982436) (xy 86.19285 -289.972256) (xy 86.243702 -289.970207) (xy 86.294223 -289.976341)
			(xy 86.343107 -289.990501) (xy 86.389086 -290.012318) (xy 86.43097 -290.041228) (xy 86.467674 -290.076483)
			(xy 86.498247 -290.117169) (xy 86.521898 -290.162232) (xy 86.538014 -290.210506) (xy 86.546178 -290.26074)
			(xy 86.54669 -290.286186) (xy 87.794841 -290.286186) (xy 87.798936 -290.235458) (xy 87.811115 -290.186044)
			(xy 87.831063 -290.139224) (xy 87.858264 -290.09621) (xy 87.892012 -290.058116) (xy 87.931434 -290.025929)
			(xy 87.975508 -290.000483) (xy 88.023094 -289.982436) (xy 88.072958 -289.972256) (xy 88.12381 -289.970207)
			(xy 88.174331 -289.976341) (xy 88.223215 -289.990501) (xy 88.269194 -290.012318) (xy 88.311078 -290.041228)
			(xy 88.347782 -290.076483) (xy 88.378355 -290.117169) (xy 88.402006 -290.162232) (xy 88.418122 -290.210506)
			(xy 88.426286 -290.26074) (xy 88.426798 -290.286186) (xy 88.734895 -290.286186) (xy 88.73899 -290.235458)
			(xy 88.751169 -290.186044) (xy 88.771117 -290.139224) (xy 88.798318 -290.09621) (xy 88.832066 -290.058116)
			(xy 88.871488 -290.025929) (xy 88.915562 -290.000483) (xy 88.963148 -289.982436) (xy 89.013012 -289.972256)
			(xy 89.063864 -289.970207) (xy 89.114385 -289.976341) (xy 89.163269 -289.990501) (xy 89.209248 -290.012318)
			(xy 89.251132 -290.041228) (xy 89.287836 -290.076483) (xy 89.318409 -290.117169) (xy 89.34206 -290.162232)
			(xy 89.358176 -290.210506) (xy 89.36634 -290.26074) (xy 89.366852 -290.286186) (xy 89.36634 -290.311632)
			(xy 89.358176 -290.361866) (xy 89.34206 -290.41014) (xy 89.318409 -290.455203) (xy 89.287836 -290.495889)
			(xy 89.251132 -290.531144) (xy 89.209248 -290.560054) (xy 89.163269 -290.581871) (xy 89.114385 -290.596031)
			(xy 89.063864 -290.602165) (xy 89.013012 -290.600116) (xy 88.963148 -290.589936) (xy 88.915562 -290.571889)
			(xy 88.871488 -290.546443) (xy 88.832066 -290.514256) (xy 88.798318 -290.476162) (xy 88.771117 -290.433148)
			(xy 88.751169 -290.386328) (xy 88.73899 -290.336914) (xy 88.734895 -290.286186) (xy 88.426798 -290.286186)
			(xy 88.426286 -290.311632) (xy 88.418122 -290.361866) (xy 88.402006 -290.41014) (xy 88.378355 -290.455203)
			(xy 88.347782 -290.495889) (xy 88.311078 -290.531144) (xy 88.269194 -290.560054) (xy 88.223215 -290.581871)
			(xy 88.174331 -290.596031) (xy 88.12381 -290.602165) (xy 88.072958 -290.600116) (xy 88.023094 -290.589936)
			(xy 87.975508 -290.571889) (xy 87.931434 -290.546443) (xy 87.892012 -290.514256) (xy 87.858264 -290.476162)
			(xy 87.831063 -290.433148) (xy 87.811115 -290.386328) (xy 87.798936 -290.336914) (xy 87.794841 -290.286186)
			(xy 86.54669 -290.286186) (xy 86.546178 -290.311632) (xy 86.538014 -290.361866) (xy 86.521898 -290.41014)
			(xy 86.498247 -290.455203) (xy 86.467674 -290.495889) (xy 86.43097 -290.531144) (xy 86.389086 -290.560054)
			(xy 86.343107 -290.581871) (xy 86.294223 -290.596031) (xy 86.243702 -290.602165) (xy 86.19285 -290.600116)
			(xy 86.142986 -290.589936) (xy 86.0954 -290.571889) (xy 86.051326 -290.546443) (xy 86.011904 -290.514256)
			(xy 85.978156 -290.476162) (xy 85.950955 -290.433148) (xy 85.931007 -290.386328) (xy 85.918828 -290.336914)
			(xy 85.914733 -290.286186) (xy 85.608922 -290.286186) (xy 85.608432 -290.311175) (xy 85.600613 -290.360538)
			(xy 85.585169 -290.40807) (xy 85.562479 -290.452602) (xy 85.533103 -290.493035) (xy 85.497763 -290.528375)
			(xy 85.45733 -290.557751) (xy 85.412798 -290.580441) (xy 85.365266 -290.595885) (xy 85.315903 -290.603704)
			(xy 85.265925 -290.603704) (xy 85.216562 -290.595885) (xy 85.16903 -290.580441) (xy 85.124498 -290.557751)
			(xy 85.084065 -290.528375) (xy 85.048725 -290.493035) (xy 85.019349 -290.452602) (xy 84.996659 -290.40807)
			(xy 84.981215 -290.360538) (xy 84.973396 -290.311175) (xy 84.666333 -290.311175) (xy 84.666324 -290.311632)
			(xy 84.65816 -290.361866) (xy 84.642044 -290.41014) (xy 84.618393 -290.455203) (xy 84.58782 -290.495889)
			(xy 84.551116 -290.531144) (xy 84.509232 -290.560054) (xy 84.463253 -290.581871) (xy 84.414369 -290.596031)
			(xy 84.363848 -290.602165) (xy 84.312996 -290.600116) (xy 84.263132 -290.589936) (xy 84.215546 -290.571889)
			(xy 84.171472 -290.546443) (xy 84.13205 -290.514256) (xy 84.098302 -290.476162) (xy 84.071101 -290.433148)
			(xy 84.051153 -290.386328) (xy 84.038974 -290.336914) (xy 84.034879 -290.286186) (xy 83.729068 -290.286186)
			(xy 83.728578 -290.311175) (xy 83.720759 -290.360538) (xy 83.705315 -290.40807) (xy 83.682625 -290.452602)
			(xy 83.653249 -290.493035) (xy 83.617909 -290.528375) (xy 83.577476 -290.557751) (xy 83.532944 -290.580441)
			(xy 83.485412 -290.595885) (xy 83.436049 -290.603704) (xy 83.386071 -290.603704) (xy 83.336708 -290.595885)
			(xy 83.289176 -290.580441) (xy 83.244644 -290.557751) (xy 83.204211 -290.528375) (xy 83.168871 -290.493035)
			(xy 83.139495 -290.452602) (xy 83.116805 -290.40807) (xy 83.101361 -290.360538) (xy 83.093542 -290.311175)
			(xy 82.786225 -290.311175) (xy 82.786216 -290.311632) (xy 82.778052 -290.361866) (xy 82.761936 -290.41014)
			(xy 82.738285 -290.455203) (xy 82.707712 -290.495889) (xy 82.671008 -290.531144) (xy 82.629124 -290.560054)
			(xy 82.583145 -290.581871) (xy 82.534261 -290.596031) (xy 82.48374 -290.602165) (xy 82.432888 -290.600116)
			(xy 82.383024 -290.589936) (xy 82.335438 -290.571889) (xy 82.291364 -290.546443) (xy 82.251942 -290.514256)
			(xy 82.218194 -290.476162) (xy 82.190993 -290.433148) (xy 82.171045 -290.386328) (xy 82.158866 -290.336914)
			(xy 82.154771 -290.286186) (xy 81.846674 -290.286186) (xy 81.846162 -290.311632) (xy 81.837998 -290.361866)
			(xy 81.821882 -290.41014) (xy 81.798231 -290.455203) (xy 81.767658 -290.495889) (xy 81.730954 -290.531144)
			(xy 81.68907 -290.560054) (xy 81.643091 -290.581871) (xy 81.594207 -290.596031) (xy 81.543686 -290.602165)
			(xy 81.492834 -290.600116) (xy 81.44297 -290.589936) (xy 81.395384 -290.571889) (xy 81.35131 -290.546443)
			(xy 81.311888 -290.514256) (xy 81.27814 -290.476162) (xy 81.250939 -290.433148) (xy 81.230991 -290.386328)
			(xy 81.218812 -290.336914) (xy 81.214717 -290.286186) (xy 79.53248 -290.286186) (xy 79.53248 -291.121181)
			(xy 79.80348 -291.121181) (xy 79.80348 -291.071203) (xy 79.811299 -291.02184) (xy 79.826743 -290.974308)
			(xy 79.849433 -290.929776) (xy 79.878809 -290.889343) (xy 79.914149 -290.854003) (xy 79.954582 -290.824627)
			(xy 79.999114 -290.801937) (xy 80.046646 -290.786493) (xy 80.096009 -290.778674) (xy 80.145987 -290.778674)
			(xy 80.19535 -290.786493) (xy 80.242882 -290.801937) (xy 80.287414 -290.824627) (xy 80.327847 -290.854003)
			(xy 80.363187 -290.889343) (xy 80.392563 -290.929776) (xy 80.415253 -290.974308) (xy 80.430697 -291.02184)
			(xy 80.438516 -291.071203) (xy 80.439006 -291.096192) (xy 80.744817 -291.096192) (xy 80.748912 -291.045464)
			(xy 80.761091 -290.99605) (xy 80.781039 -290.94923) (xy 80.80824 -290.906216) (xy 80.841988 -290.868122)
			(xy 80.88141 -290.835935) (xy 80.925484 -290.810489) (xy 80.97307 -290.792442) (xy 81.022934 -290.782262)
			(xy 81.073786 -290.780213) (xy 81.124307 -290.786347) (xy 81.173191 -290.800507) (xy 81.21917 -290.822324)
			(xy 81.261054 -290.851234) (xy 81.297758 -290.886489) (xy 81.328331 -290.927175) (xy 81.351982 -290.972238)
			(xy 81.368098 -291.020512) (xy 81.376262 -291.070746) (xy 81.376774 -291.096192) (xy 81.376271 -291.121181)
			(xy 81.683588 -291.121181) (xy 81.683588 -291.071203) (xy 81.691407 -291.02184) (xy 81.706851 -290.974308)
			(xy 81.729541 -290.929776) (xy 81.758917 -290.889343) (xy 81.794257 -290.854003) (xy 81.83469 -290.824627)
			(xy 81.879222 -290.801937) (xy 81.926754 -290.786493) (xy 81.976117 -290.778674) (xy 82.026095 -290.778674)
			(xy 82.075458 -290.786493) (xy 82.12299 -290.801937) (xy 82.167522 -290.824627) (xy 82.207955 -290.854003)
			(xy 82.243295 -290.889343) (xy 82.272671 -290.929776) (xy 82.295361 -290.974308) (xy 82.310805 -291.02184)
			(xy 82.318624 -291.071203) (xy 82.319114 -291.096192) (xy 82.624671 -291.096192) (xy 82.628766 -291.045464)
			(xy 82.640945 -290.99605) (xy 82.660893 -290.94923) (xy 82.688094 -290.906216) (xy 82.721842 -290.868122)
			(xy 82.761264 -290.835935) (xy 82.805338 -290.810489) (xy 82.852924 -290.792442) (xy 82.902788 -290.782262)
			(xy 82.95364 -290.780213) (xy 83.004161 -290.786347) (xy 83.053045 -290.800507) (xy 83.099024 -290.822324)
			(xy 83.140908 -290.851234) (xy 83.177612 -290.886489) (xy 83.208185 -290.927175) (xy 83.231836 -290.972238)
			(xy 83.247952 -291.020512) (xy 83.256116 -291.070746) (xy 83.256628 -291.096192) (xy 83.256125 -291.121181)
			(xy 83.563442 -291.121181) (xy 83.563442 -291.071203) (xy 83.571261 -291.02184) (xy 83.586705 -290.974308)
			(xy 83.609395 -290.929776) (xy 83.638771 -290.889343) (xy 83.674111 -290.854003) (xy 83.714544 -290.824627)
			(xy 83.759076 -290.801937) (xy 83.806608 -290.786493) (xy 83.855971 -290.778674) (xy 83.905949 -290.778674)
			(xy 83.955312 -290.786493) (xy 84.002844 -290.801937) (xy 84.047376 -290.824627) (xy 84.087809 -290.854003)
			(xy 84.123149 -290.889343) (xy 84.152525 -290.929776) (xy 84.175215 -290.974308) (xy 84.190659 -291.02184)
			(xy 84.198478 -291.071203) (xy 84.198968 -291.096192) (xy 84.504779 -291.096192) (xy 84.508874 -291.045464)
			(xy 84.521053 -290.99605) (xy 84.541001 -290.94923) (xy 84.568202 -290.906216) (xy 84.60195 -290.868122)
			(xy 84.641372 -290.835935) (xy 84.685446 -290.810489) (xy 84.733032 -290.792442) (xy 84.782896 -290.782262)
			(xy 84.833748 -290.780213) (xy 84.884269 -290.786347) (xy 84.933153 -290.800507) (xy 84.979132 -290.822324)
			(xy 85.021016 -290.851234) (xy 85.05772 -290.886489) (xy 85.088293 -290.927175) (xy 85.111944 -290.972238)
			(xy 85.12806 -291.020512) (xy 85.136224 -291.070746) (xy 85.136736 -291.096192) (xy 85.444833 -291.096192)
			(xy 85.448928 -291.045464) (xy 85.461107 -290.99605) (xy 85.481055 -290.94923) (xy 85.508256 -290.906216)
			(xy 85.542004 -290.868122) (xy 85.581426 -290.835935) (xy 85.6255 -290.810489) (xy 85.673086 -290.792442)
			(xy 85.72295 -290.782262) (xy 85.773802 -290.780213) (xy 85.824323 -290.786347) (xy 85.873207 -290.800507)
			(xy 85.919186 -290.822324) (xy 85.96107 -290.851234) (xy 85.997774 -290.886489) (xy 86.028347 -290.927175)
			(xy 86.051998 -290.972238) (xy 86.068114 -291.020512) (xy 86.076278 -291.070746) (xy 86.07679 -291.096192)
			(xy 86.076287 -291.121181) (xy 86.383604 -291.121181) (xy 86.383604 -291.071203) (xy 86.391423 -291.02184)
			(xy 86.406867 -290.974308) (xy 86.429557 -290.929776) (xy 86.458933 -290.889343) (xy 86.494273 -290.854003)
			(xy 86.534706 -290.824627) (xy 86.579238 -290.801937) (xy 86.62677 -290.786493) (xy 86.676133 -290.778674)
			(xy 86.726111 -290.778674) (xy 86.775474 -290.786493) (xy 86.823006 -290.801937) (xy 86.867538 -290.824627)
			(xy 86.907971 -290.854003) (xy 86.943311 -290.889343) (xy 86.972687 -290.929776) (xy 86.995377 -290.974308)
			(xy 87.010821 -291.02184) (xy 87.01864 -291.071203) (xy 87.01913 -291.096192) (xy 87.324687 -291.096192)
			(xy 87.328782 -291.045464) (xy 87.340961 -290.99605) (xy 87.360909 -290.94923) (xy 87.38811 -290.906216)
			(xy 87.421858 -290.868122) (xy 87.46128 -290.835935) (xy 87.505354 -290.810489) (xy 87.55294 -290.792442)
			(xy 87.602804 -290.782262) (xy 87.653656 -290.780213) (xy 87.704177 -290.786347) (xy 87.753061 -290.800507)
			(xy 87.79904 -290.822324) (xy 87.840924 -290.851234) (xy 87.877628 -290.886489) (xy 87.908201 -290.927175)
			(xy 87.931852 -290.972238) (xy 87.947968 -291.020512) (xy 87.956132 -291.070746) (xy 87.956644 -291.096192)
			(xy 87.956141 -291.121181) (xy 88.263458 -291.121181) (xy 88.263458 -291.071203) (xy 88.271277 -291.02184)
			(xy 88.286721 -290.974308) (xy 88.309411 -290.929776) (xy 88.338787 -290.889343) (xy 88.374127 -290.854003)
			(xy 88.41456 -290.824627) (xy 88.459092 -290.801937) (xy 88.506624 -290.786493) (xy 88.555987 -290.778674)
			(xy 88.605965 -290.778674) (xy 88.655328 -290.786493) (xy 88.70286 -290.801937) (xy 88.747392 -290.824627)
			(xy 88.787825 -290.854003) (xy 88.823165 -290.889343) (xy 88.852541 -290.929776) (xy 88.875231 -290.974308)
			(xy 88.890675 -291.02184) (xy 88.898494 -291.071203) (xy 88.898984 -291.096192) (xy 88.898494 -291.121181)
			(xy 88.890675 -291.170544) (xy 88.875231 -291.218076) (xy 88.852541 -291.262608) (xy 88.823165 -291.303041)
			(xy 88.787825 -291.338381) (xy 88.747392 -291.367757) (xy 88.70286 -291.390447) (xy 88.655328 -291.405891)
			(xy 88.605965 -291.41371) (xy 88.555987 -291.41371) (xy 88.506624 -291.405891) (xy 88.459092 -291.390447)
			(xy 88.41456 -291.367757) (xy 88.374127 -291.338381) (xy 88.338787 -291.303041) (xy 88.309411 -291.262608)
			(xy 88.286721 -291.218076) (xy 88.271277 -291.170544) (xy 88.263458 -291.121181) (xy 87.956141 -291.121181)
			(xy 87.956132 -291.121638) (xy 87.947968 -291.171872) (xy 87.931852 -291.220146) (xy 87.908201 -291.265209)
			(xy 87.877628 -291.305895) (xy 87.840924 -291.34115) (xy 87.79904 -291.37006) (xy 87.753061 -291.391877)
			(xy 87.704177 -291.406037) (xy 87.653656 -291.412171) (xy 87.602804 -291.410122) (xy 87.55294 -291.399942)
			(xy 87.505354 -291.381895) (xy 87.46128 -291.356449) (xy 87.421858 -291.324262) (xy 87.38811 -291.286168)
			(xy 87.360909 -291.243154) (xy 87.340961 -291.196334) (xy 87.328782 -291.14692) (xy 87.324687 -291.096192)
			(xy 87.01913 -291.096192) (xy 87.01864 -291.121181) (xy 87.010821 -291.170544) (xy 86.995377 -291.218076)
			(xy 86.972687 -291.262608) (xy 86.943311 -291.303041) (xy 86.907971 -291.338381) (xy 86.867538 -291.367757)
			(xy 86.823006 -291.390447) (xy 86.775474 -291.405891) (xy 86.726111 -291.41371) (xy 86.676133 -291.41371)
			(xy 86.62677 -291.405891) (xy 86.579238 -291.390447) (xy 86.534706 -291.367757) (xy 86.494273 -291.338381)
			(xy 86.458933 -291.303041) (xy 86.429557 -291.262608) (xy 86.406867 -291.218076) (xy 86.391423 -291.170544)
			(xy 86.383604 -291.121181) (xy 86.076287 -291.121181) (xy 86.076278 -291.121638) (xy 86.068114 -291.171872)
			(xy 86.051998 -291.220146) (xy 86.028347 -291.265209) (xy 85.997774 -291.305895) (xy 85.96107 -291.34115)
			(xy 85.919186 -291.37006) (xy 85.873207 -291.391877) (xy 85.824323 -291.406037) (xy 85.773802 -291.412171)
			(xy 85.72295 -291.410122) (xy 85.673086 -291.399942) (xy 85.6255 -291.381895) (xy 85.581426 -291.356449)
			(xy 85.542004 -291.324262) (xy 85.508256 -291.286168) (xy 85.481055 -291.243154) (xy 85.461107 -291.196334)
			(xy 85.448928 -291.14692) (xy 85.444833 -291.096192) (xy 85.136736 -291.096192) (xy 85.136224 -291.121638)
			(xy 85.12806 -291.171872) (xy 85.111944 -291.220146) (xy 85.088293 -291.265209) (xy 85.05772 -291.305895)
			(xy 85.021016 -291.34115) (xy 84.979132 -291.37006) (xy 84.933153 -291.391877) (xy 84.884269 -291.406037)
			(xy 84.833748 -291.412171) (xy 84.782896 -291.410122) (xy 84.733032 -291.399942) (xy 84.685446 -291.381895)
			(xy 84.641372 -291.356449) (xy 84.60195 -291.324262) (xy 84.568202 -291.286168) (xy 84.541001 -291.243154)
			(xy 84.521053 -291.196334) (xy 84.508874 -291.14692) (xy 84.504779 -291.096192) (xy 84.198968 -291.096192)
			(xy 84.198478 -291.121181) (xy 84.190659 -291.170544) (xy 84.175215 -291.218076) (xy 84.152525 -291.262608)
			(xy 84.123149 -291.303041) (xy 84.087809 -291.338381) (xy 84.047376 -291.367757) (xy 84.002844 -291.390447)
			(xy 83.955312 -291.405891) (xy 83.905949 -291.41371) (xy 83.855971 -291.41371) (xy 83.806608 -291.405891)
			(xy 83.759076 -291.390447) (xy 83.714544 -291.367757) (xy 83.674111 -291.338381) (xy 83.638771 -291.303041)
			(xy 83.609395 -291.262608) (xy 83.586705 -291.218076) (xy 83.571261 -291.170544) (xy 83.563442 -291.121181)
			(xy 83.256125 -291.121181) (xy 83.256116 -291.121638) (xy 83.247952 -291.171872) (xy 83.231836 -291.220146)
			(xy 83.208185 -291.265209) (xy 83.177612 -291.305895) (xy 83.140908 -291.34115) (xy 83.099024 -291.37006)
			(xy 83.053045 -291.391877) (xy 83.004161 -291.406037) (xy 82.95364 -291.412171) (xy 82.902788 -291.410122)
			(xy 82.852924 -291.399942) (xy 82.805338 -291.381895) (xy 82.761264 -291.356449) (xy 82.721842 -291.324262)
			(xy 82.688094 -291.286168) (xy 82.660893 -291.243154) (xy 82.640945 -291.196334) (xy 82.628766 -291.14692)
			(xy 82.624671 -291.096192) (xy 82.319114 -291.096192) (xy 82.318624 -291.121181) (xy 82.310805 -291.170544)
			(xy 82.295361 -291.218076) (xy 82.272671 -291.262608) (xy 82.243295 -291.303041) (xy 82.207955 -291.338381)
			(xy 82.167522 -291.367757) (xy 82.12299 -291.390447) (xy 82.075458 -291.405891) (xy 82.026095 -291.41371)
			(xy 81.976117 -291.41371) (xy 81.926754 -291.405891) (xy 81.879222 -291.390447) (xy 81.83469 -291.367757)
			(xy 81.794257 -291.338381) (xy 81.758917 -291.303041) (xy 81.729541 -291.262608) (xy 81.706851 -291.218076)
			(xy 81.691407 -291.170544) (xy 81.683588 -291.121181) (xy 81.376271 -291.121181) (xy 81.376262 -291.121638)
			(xy 81.368098 -291.171872) (xy 81.351982 -291.220146) (xy 81.328331 -291.265209) (xy 81.297758 -291.305895)
			(xy 81.261054 -291.34115) (xy 81.21917 -291.37006) (xy 81.173191 -291.391877) (xy 81.124307 -291.406037)
			(xy 81.073786 -291.412171) (xy 81.022934 -291.410122) (xy 80.97307 -291.399942) (xy 80.925484 -291.381895)
			(xy 80.88141 -291.356449) (xy 80.841988 -291.324262) (xy 80.80824 -291.286168) (xy 80.781039 -291.243154)
			(xy 80.761091 -291.196334) (xy 80.748912 -291.14692) (xy 80.744817 -291.096192) (xy 80.439006 -291.096192)
			(xy 80.438516 -291.121181) (xy 80.430697 -291.170544) (xy 80.415253 -291.218076) (xy 80.392563 -291.262608)
			(xy 80.363187 -291.303041) (xy 80.327847 -291.338381) (xy 80.287414 -291.367757) (xy 80.242882 -291.390447)
			(xy 80.19535 -291.405891) (xy 80.145987 -291.41371) (xy 80.096009 -291.41371) (xy 80.046646 -291.405891)
			(xy 79.999114 -291.390447) (xy 79.954582 -291.367757) (xy 79.914149 -291.338381) (xy 79.878809 -291.303041)
			(xy 79.849433 -291.262608) (xy 79.826743 -291.218076) (xy 79.811299 -291.170544) (xy 79.80348 -291.121181)
			(xy 79.53248 -291.121181) (xy 79.53248 -291.931187) (xy 80.273634 -291.931187) (xy 80.273634 -291.881209)
			(xy 80.281453 -291.831846) (xy 80.296897 -291.784314) (xy 80.319587 -291.739782) (xy 80.348963 -291.699349)
			(xy 80.384303 -291.664009) (xy 80.424736 -291.634633) (xy 80.469268 -291.611943) (xy 80.5168 -291.596499)
			(xy 80.566163 -291.58868) (xy 80.616141 -291.58868) (xy 80.665504 -291.596499) (xy 80.713036 -291.611943)
			(xy 80.757568 -291.634633) (xy 80.798001 -291.664009) (xy 80.833341 -291.699349) (xy 80.862717 -291.739782)
			(xy 80.885407 -291.784314) (xy 80.900851 -291.831846) (xy 80.90867 -291.881209) (xy 80.90916 -291.906198)
			(xy 81.214717 -291.906198) (xy 81.218812 -291.85547) (xy 81.230991 -291.806056) (xy 81.250939 -291.759236)
			(xy 81.27814 -291.716222) (xy 81.311888 -291.678128) (xy 81.35131 -291.645941) (xy 81.395384 -291.620495)
			(xy 81.44297 -291.602448) (xy 81.492834 -291.592268) (xy 81.543686 -291.590219) (xy 81.594207 -291.596353)
			(xy 81.643091 -291.610513) (xy 81.68907 -291.63233) (xy 81.730954 -291.66124) (xy 81.767658 -291.696495)
			(xy 81.798231 -291.737181) (xy 81.821882 -291.782244) (xy 81.837998 -291.830518) (xy 81.846162 -291.880752)
			(xy 81.846674 -291.906198) (xy 82.154771 -291.906198) (xy 82.158866 -291.85547) (xy 82.171045 -291.806056)
			(xy 82.190993 -291.759236) (xy 82.218194 -291.716222) (xy 82.251942 -291.678128) (xy 82.291364 -291.645941)
			(xy 82.335438 -291.620495) (xy 82.383024 -291.602448) (xy 82.432888 -291.592268) (xy 82.48374 -291.590219)
			(xy 82.534261 -291.596353) (xy 82.583145 -291.610513) (xy 82.629124 -291.63233) (xy 82.671008 -291.66124)
			(xy 82.707712 -291.696495) (xy 82.738285 -291.737181) (xy 82.761936 -291.782244) (xy 82.778052 -291.830518)
			(xy 82.786216 -291.880752) (xy 82.786728 -291.906198) (xy 82.786225 -291.931187) (xy 83.093542 -291.931187)
			(xy 83.093542 -291.881209) (xy 83.101361 -291.831846) (xy 83.116805 -291.784314) (xy 83.139495 -291.739782)
			(xy 83.168871 -291.699349) (xy 83.204211 -291.664009) (xy 83.244644 -291.634633) (xy 83.289176 -291.611943)
			(xy 83.336708 -291.596499) (xy 83.386071 -291.58868) (xy 83.436049 -291.58868) (xy 83.485412 -291.596499)
			(xy 83.532944 -291.611943) (xy 83.577476 -291.634633) (xy 83.617909 -291.664009) (xy 83.653249 -291.699349)
			(xy 83.682625 -291.739782) (xy 83.705315 -291.784314) (xy 83.720759 -291.831846) (xy 83.728578 -291.881209)
			(xy 83.729068 -291.906198) (xy 84.034879 -291.906198) (xy 84.038974 -291.85547) (xy 84.051153 -291.806056)
			(xy 84.071101 -291.759236) (xy 84.098302 -291.716222) (xy 84.13205 -291.678128) (xy 84.171472 -291.645941)
			(xy 84.215546 -291.620495) (xy 84.263132 -291.602448) (xy 84.312996 -291.592268) (xy 84.363848 -291.590219)
			(xy 84.414369 -291.596353) (xy 84.463253 -291.610513) (xy 84.509232 -291.63233) (xy 84.551116 -291.66124)
			(xy 84.58782 -291.696495) (xy 84.618393 -291.737181) (xy 84.642044 -291.782244) (xy 84.65816 -291.830518)
			(xy 84.666324 -291.880752) (xy 84.666836 -291.906198) (xy 84.666333 -291.931187) (xy 84.973396 -291.931187)
			(xy 84.973396 -291.881209) (xy 84.981215 -291.831846) (xy 84.996659 -291.784314) (xy 85.019349 -291.739782)
			(xy 85.048725 -291.699349) (xy 85.084065 -291.664009) (xy 85.124498 -291.634633) (xy 85.16903 -291.611943)
			(xy 85.216562 -291.596499) (xy 85.265925 -291.58868) (xy 85.315903 -291.58868) (xy 85.365266 -291.596499)
			(xy 85.412798 -291.611943) (xy 85.45733 -291.634633) (xy 85.497763 -291.664009) (xy 85.533103 -291.699349)
			(xy 85.562479 -291.739782) (xy 85.585169 -291.784314) (xy 85.600613 -291.831846) (xy 85.608432 -291.881209)
			(xy 85.608922 -291.906198) (xy 85.914733 -291.906198) (xy 85.918828 -291.85547) (xy 85.931007 -291.806056)
			(xy 85.950955 -291.759236) (xy 85.978156 -291.716222) (xy 86.011904 -291.678128) (xy 86.051326 -291.645941)
			(xy 86.0954 -291.620495) (xy 86.142986 -291.602448) (xy 86.19285 -291.592268) (xy 86.243702 -291.590219)
			(xy 86.294223 -291.596353) (xy 86.343107 -291.610513) (xy 86.389086 -291.63233) (xy 86.43097 -291.66124)
			(xy 86.467674 -291.696495) (xy 86.498247 -291.737181) (xy 86.521898 -291.782244) (xy 86.538014 -291.830518)
			(xy 86.546178 -291.880752) (xy 86.54669 -291.906198) (xy 86.546187 -291.931187) (xy 86.853504 -291.931187)
			(xy 86.853504 -291.881209) (xy 86.861323 -291.831846) (xy 86.876767 -291.784314) (xy 86.899457 -291.739782)
			(xy 86.928833 -291.699349) (xy 86.964173 -291.664009) (xy 87.004606 -291.634633) (xy 87.049138 -291.611943)
			(xy 87.09667 -291.596499) (xy 87.146033 -291.58868) (xy 87.196011 -291.58868) (xy 87.245374 -291.596499)
			(xy 87.292906 -291.611943) (xy 87.337438 -291.634633) (xy 87.377871 -291.664009) (xy 87.413211 -291.699349)
			(xy 87.442587 -291.739782) (xy 87.465277 -291.784314) (xy 87.480721 -291.831846) (xy 87.48854 -291.881209)
			(xy 87.48903 -291.906198) (xy 87.794841 -291.906198) (xy 87.798936 -291.85547) (xy 87.811115 -291.806056)
			(xy 87.831063 -291.759236) (xy 87.858264 -291.716222) (xy 87.892012 -291.678128) (xy 87.931434 -291.645941)
			(xy 87.975508 -291.620495) (xy 88.023094 -291.602448) (xy 88.072958 -291.592268) (xy 88.12381 -291.590219)
			(xy 88.174331 -291.596353) (xy 88.223215 -291.610513) (xy 88.269194 -291.63233) (xy 88.311078 -291.66124)
			(xy 88.347782 -291.696495) (xy 88.378355 -291.737181) (xy 88.402006 -291.782244) (xy 88.418122 -291.830518)
			(xy 88.426286 -291.880752) (xy 88.426798 -291.906198) (xy 88.734895 -291.906198) (xy 88.73899 -291.85547)
			(xy 88.751169 -291.806056) (xy 88.771117 -291.759236) (xy 88.798318 -291.716222) (xy 88.832066 -291.678128)
			(xy 88.871488 -291.645941) (xy 88.915562 -291.620495) (xy 88.963148 -291.602448) (xy 89.013012 -291.592268)
			(xy 89.063864 -291.590219) (xy 89.114385 -291.596353) (xy 89.163269 -291.610513) (xy 89.209248 -291.63233)
			(xy 89.251132 -291.66124) (xy 89.287836 -291.696495) (xy 89.318409 -291.737181) (xy 89.34206 -291.782244)
			(xy 89.358176 -291.830518) (xy 89.36634 -291.880752) (xy 89.366852 -291.906198) (xy 89.36634 -291.931644)
			(xy 89.358176 -291.981878) (xy 89.34206 -292.030152) (xy 89.318409 -292.075215) (xy 89.287836 -292.115901)
			(xy 89.251132 -292.151156) (xy 89.209248 -292.180066) (xy 89.163269 -292.201883) (xy 89.114385 -292.216043)
			(xy 89.063864 -292.222177) (xy 89.013012 -292.220128) (xy 88.963148 -292.209948) (xy 88.915562 -292.191901)
			(xy 88.871488 -292.166455) (xy 88.832066 -292.134268) (xy 88.798318 -292.096174) (xy 88.771117 -292.05316)
			(xy 88.751169 -292.00634) (xy 88.73899 -291.956926) (xy 88.734895 -291.906198) (xy 88.426798 -291.906198)
			(xy 88.426286 -291.931644) (xy 88.418122 -291.981878) (xy 88.402006 -292.030152) (xy 88.378355 -292.075215)
			(xy 88.347782 -292.115901) (xy 88.311078 -292.151156) (xy 88.269194 -292.180066) (xy 88.223215 -292.201883)
			(xy 88.174331 -292.216043) (xy 88.12381 -292.222177) (xy 88.072958 -292.220128) (xy 88.023094 -292.209948)
			(xy 87.975508 -292.191901) (xy 87.931434 -292.166455) (xy 87.892012 -292.134268) (xy 87.858264 -292.096174)
			(xy 87.831063 -292.05316) (xy 87.811115 -292.00634) (xy 87.798936 -291.956926) (xy 87.794841 -291.906198)
			(xy 87.48903 -291.906198) (xy 87.48854 -291.931187) (xy 87.480721 -291.98055) (xy 87.465277 -292.028082)
			(xy 87.442587 -292.072614) (xy 87.413211 -292.113047) (xy 87.377871 -292.148387) (xy 87.337438 -292.177763)
			(xy 87.292906 -292.200453) (xy 87.245374 -292.215897) (xy 87.196011 -292.223716) (xy 87.146033 -292.223716)
			(xy 87.09667 -292.215897) (xy 87.049138 -292.200453) (xy 87.004606 -292.177763) (xy 86.964173 -292.148387)
			(xy 86.928833 -292.113047) (xy 86.899457 -292.072614) (xy 86.876767 -292.028082) (xy 86.861323 -291.98055)
			(xy 86.853504 -291.931187) (xy 86.546187 -291.931187) (xy 86.546178 -291.931644) (xy 86.538014 -291.981878)
			(xy 86.521898 -292.030152) (xy 86.498247 -292.075215) (xy 86.467674 -292.115901) (xy 86.43097 -292.151156)
			(xy 86.389086 -292.180066) (xy 86.343107 -292.201883) (xy 86.294223 -292.216043) (xy 86.243702 -292.222177)
			(xy 86.19285 -292.220128) (xy 86.142986 -292.209948) (xy 86.0954 -292.191901) (xy 86.051326 -292.166455)
			(xy 86.011904 -292.134268) (xy 85.978156 -292.096174) (xy 85.950955 -292.05316) (xy 85.931007 -292.00634)
			(xy 85.918828 -291.956926) (xy 85.914733 -291.906198) (xy 85.608922 -291.906198) (xy 85.608432 -291.931187)
			(xy 85.600613 -291.98055) (xy 85.585169 -292.028082) (xy 85.562479 -292.072614) (xy 85.533103 -292.113047)
			(xy 85.497763 -292.148387) (xy 85.45733 -292.177763) (xy 85.412798 -292.200453) (xy 85.365266 -292.215897)
			(xy 85.315903 -292.223716) (xy 85.265925 -292.223716) (xy 85.216562 -292.215897) (xy 85.16903 -292.200453)
			(xy 85.124498 -292.177763) (xy 85.084065 -292.148387) (xy 85.048725 -292.113047) (xy 85.019349 -292.072614)
			(xy 84.996659 -292.028082) (xy 84.981215 -291.98055) (xy 84.973396 -291.931187) (xy 84.666333 -291.931187)
			(xy 84.666324 -291.931644) (xy 84.65816 -291.981878) (xy 84.642044 -292.030152) (xy 84.618393 -292.075215)
			(xy 84.58782 -292.115901) (xy 84.551116 -292.151156) (xy 84.509232 -292.180066) (xy 84.463253 -292.201883)
			(xy 84.414369 -292.216043) (xy 84.363848 -292.222177) (xy 84.312996 -292.220128) (xy 84.263132 -292.209948)
			(xy 84.215546 -292.191901) (xy 84.171472 -292.166455) (xy 84.13205 -292.134268) (xy 84.098302 -292.096174)
			(xy 84.071101 -292.05316) (xy 84.051153 -292.00634) (xy 84.038974 -291.956926) (xy 84.034879 -291.906198)
			(xy 83.729068 -291.906198) (xy 83.728578 -291.931187) (xy 83.720759 -291.98055) (xy 83.705315 -292.028082)
			(xy 83.682625 -292.072614) (xy 83.653249 -292.113047) (xy 83.617909 -292.148387) (xy 83.577476 -292.177763)
			(xy 83.532944 -292.200453) (xy 83.485412 -292.215897) (xy 83.436049 -292.223716) (xy 83.386071 -292.223716)
			(xy 83.336708 -292.215897) (xy 83.289176 -292.200453) (xy 83.244644 -292.177763) (xy 83.204211 -292.148387)
			(xy 83.168871 -292.113047) (xy 83.139495 -292.072614) (xy 83.116805 -292.028082) (xy 83.101361 -291.98055)
			(xy 83.093542 -291.931187) (xy 82.786225 -291.931187) (xy 82.786216 -291.931644) (xy 82.778052 -291.981878)
			(xy 82.761936 -292.030152) (xy 82.738285 -292.075215) (xy 82.707712 -292.115901) (xy 82.671008 -292.151156)
			(xy 82.629124 -292.180066) (xy 82.583145 -292.201883) (xy 82.534261 -292.216043) (xy 82.48374 -292.222177)
			(xy 82.432888 -292.220128) (xy 82.383024 -292.209948) (xy 82.335438 -292.191901) (xy 82.291364 -292.166455)
			(xy 82.251942 -292.134268) (xy 82.218194 -292.096174) (xy 82.190993 -292.05316) (xy 82.171045 -292.00634)
			(xy 82.158866 -291.956926) (xy 82.154771 -291.906198) (xy 81.846674 -291.906198) (xy 81.846162 -291.931644)
			(xy 81.837998 -291.981878) (xy 81.821882 -292.030152) (xy 81.798231 -292.075215) (xy 81.767658 -292.115901)
			(xy 81.730954 -292.151156) (xy 81.68907 -292.180066) (xy 81.643091 -292.201883) (xy 81.594207 -292.216043)
			(xy 81.543686 -292.222177) (xy 81.492834 -292.220128) (xy 81.44297 -292.209948) (xy 81.395384 -292.191901)
			(xy 81.35131 -292.166455) (xy 81.311888 -292.134268) (xy 81.27814 -292.096174) (xy 81.250939 -292.05316)
			(xy 81.230991 -292.00634) (xy 81.218812 -291.956926) (xy 81.214717 -291.906198) (xy 80.90916 -291.906198)
			(xy 80.90867 -291.931187) (xy 80.900851 -291.98055) (xy 80.885407 -292.028082) (xy 80.862717 -292.072614)
			(xy 80.833341 -292.113047) (xy 80.798001 -292.148387) (xy 80.757568 -292.177763) (xy 80.713036 -292.200453)
			(xy 80.665504 -292.215897) (xy 80.616141 -292.223716) (xy 80.566163 -292.223716) (xy 80.5168 -292.215897)
			(xy 80.469268 -292.200453) (xy 80.424736 -292.177763) (xy 80.384303 -292.148387) (xy 80.348963 -292.113047)
			(xy 80.319587 -292.072614) (xy 80.296897 -292.028082) (xy 80.281453 -291.98055) (xy 80.273634 -291.931187)
			(xy 79.53248 -291.931187) (xy 79.53248 -292.716204) (xy 80.744817 -292.716204) (xy 80.748912 -292.665476)
			(xy 80.761091 -292.616062) (xy 80.781039 -292.569242) (xy 80.80824 -292.526228) (xy 80.841988 -292.488134)
			(xy 80.88141 -292.455947) (xy 80.925484 -292.430501) (xy 80.97307 -292.412454) (xy 81.022934 -292.402274)
			(xy 81.073786 -292.400225) (xy 81.124307 -292.406359) (xy 81.173191 -292.420519) (xy 81.21917 -292.442336)
			(xy 81.261054 -292.471246) (xy 81.297758 -292.506501) (xy 81.328331 -292.547187) (xy 81.351982 -292.59225)
			(xy 81.368098 -292.640524) (xy 81.376262 -292.690758) (xy 81.376774 -292.716204) (xy 81.376271 -292.741193)
			(xy 81.683588 -292.741193) (xy 81.683588 -292.691215) (xy 81.691407 -292.641852) (xy 81.706851 -292.59432)
			(xy 81.729541 -292.549788) (xy 81.758917 -292.509355) (xy 81.794257 -292.474015) (xy 81.83469 -292.444639)
			(xy 81.879222 -292.421949) (xy 81.926754 -292.406505) (xy 81.976117 -292.398686) (xy 82.026095 -292.398686)
			(xy 82.075458 -292.406505) (xy 82.12299 -292.421949) (xy 82.167522 -292.444639) (xy 82.207955 -292.474015)
			(xy 82.243295 -292.509355) (xy 82.272671 -292.549788) (xy 82.295361 -292.59432) (xy 82.310805 -292.641852)
			(xy 82.318624 -292.691215) (xy 82.319114 -292.716204) (xy 82.624671 -292.716204) (xy 82.628766 -292.665476)
			(xy 82.640945 -292.616062) (xy 82.660893 -292.569242) (xy 82.688094 -292.526228) (xy 82.721842 -292.488134)
			(xy 82.761264 -292.455947) (xy 82.805338 -292.430501) (xy 82.852924 -292.412454) (xy 82.902788 -292.402274)
			(xy 82.95364 -292.400225) (xy 83.004161 -292.406359) (xy 83.053045 -292.420519) (xy 83.099024 -292.442336)
			(xy 83.140908 -292.471246) (xy 83.177612 -292.506501) (xy 83.208185 -292.547187) (xy 83.231836 -292.59225)
			(xy 83.247952 -292.640524) (xy 83.256116 -292.690758) (xy 83.256628 -292.716204) (xy 83.256125 -292.741193)
			(xy 83.563442 -292.741193) (xy 83.563442 -292.691215) (xy 83.571261 -292.641852) (xy 83.586705 -292.59432)
			(xy 83.609395 -292.549788) (xy 83.638771 -292.509355) (xy 83.674111 -292.474015) (xy 83.714544 -292.444639)
			(xy 83.759076 -292.421949) (xy 83.806608 -292.406505) (xy 83.855971 -292.398686) (xy 83.905949 -292.398686)
			(xy 83.955312 -292.406505) (xy 84.002844 -292.421949) (xy 84.047376 -292.444639) (xy 84.087809 -292.474015)
			(xy 84.123149 -292.509355) (xy 84.152525 -292.549788) (xy 84.175215 -292.59432) (xy 84.190659 -292.641852)
			(xy 84.198478 -292.691215) (xy 84.198968 -292.716204) (xy 84.504779 -292.716204) (xy 84.508874 -292.665476)
			(xy 84.521053 -292.616062) (xy 84.541001 -292.569242) (xy 84.568202 -292.526228) (xy 84.60195 -292.488134)
			(xy 84.641372 -292.455947) (xy 84.685446 -292.430501) (xy 84.733032 -292.412454) (xy 84.782896 -292.402274)
			(xy 84.833748 -292.400225) (xy 84.884269 -292.406359) (xy 84.933153 -292.420519) (xy 84.979132 -292.442336)
			(xy 85.021016 -292.471246) (xy 85.05772 -292.506501) (xy 85.088293 -292.547187) (xy 85.111944 -292.59225)
			(xy 85.12806 -292.640524) (xy 85.136224 -292.690758) (xy 85.136736 -292.716204) (xy 85.444833 -292.716204)
			(xy 85.448928 -292.665476) (xy 85.461107 -292.616062) (xy 85.481055 -292.569242) (xy 85.508256 -292.526228)
			(xy 85.542004 -292.488134) (xy 85.581426 -292.455947) (xy 85.6255 -292.430501) (xy 85.673086 -292.412454)
			(xy 85.72295 -292.402274) (xy 85.773802 -292.400225) (xy 85.824323 -292.406359) (xy 85.873207 -292.420519)
			(xy 85.919186 -292.442336) (xy 85.96107 -292.471246) (xy 85.997774 -292.506501) (xy 86.028347 -292.547187)
			(xy 86.051998 -292.59225) (xy 86.068114 -292.640524) (xy 86.076278 -292.690758) (xy 86.07679 -292.716204)
			(xy 87.324687 -292.716204) (xy 87.328782 -292.665476) (xy 87.340961 -292.616062) (xy 87.360909 -292.569242)
			(xy 87.38811 -292.526228) (xy 87.421858 -292.488134) (xy 87.46128 -292.455947) (xy 87.505354 -292.430501)
			(xy 87.55294 -292.412454) (xy 87.602804 -292.402274) (xy 87.653656 -292.400225) (xy 87.704177 -292.406359)
			(xy 87.753061 -292.420519) (xy 87.79904 -292.442336) (xy 87.840924 -292.471246) (xy 87.877628 -292.506501)
			(xy 87.908201 -292.547187) (xy 87.931852 -292.59225) (xy 87.947968 -292.640524) (xy 87.956132 -292.690758)
			(xy 87.956644 -292.716204) (xy 87.956141 -292.741193) (xy 88.263458 -292.741193) (xy 88.263458 -292.691215)
			(xy 88.271277 -292.641852) (xy 88.286721 -292.59432) (xy 88.309411 -292.549788) (xy 88.338787 -292.509355)
			(xy 88.374127 -292.474015) (xy 88.41456 -292.444639) (xy 88.459092 -292.421949) (xy 88.506624 -292.406505)
			(xy 88.555987 -292.398686) (xy 88.605965 -292.398686) (xy 88.655328 -292.406505) (xy 88.70286 -292.421949)
			(xy 88.747392 -292.444639) (xy 88.787825 -292.474015) (xy 88.823165 -292.509355) (xy 88.852541 -292.549788)
			(xy 88.875231 -292.59432) (xy 88.890675 -292.641852) (xy 88.898494 -292.691215) (xy 88.898984 -292.716204)
			(xy 88.898494 -292.741193) (xy 88.890675 -292.790556) (xy 88.875231 -292.838088) (xy 88.852541 -292.88262)
			(xy 88.823165 -292.923053) (xy 88.787825 -292.958393) (xy 88.747392 -292.987769) (xy 88.70286 -293.010459)
			(xy 88.655328 -293.025903) (xy 88.605965 -293.033722) (xy 88.555987 -293.033722) (xy 88.506624 -293.025903)
			(xy 88.459092 -293.010459) (xy 88.41456 -292.987769) (xy 88.374127 -292.958393) (xy 88.338787 -292.923053)
			(xy 88.309411 -292.88262) (xy 88.286721 -292.838088) (xy 88.271277 -292.790556) (xy 88.263458 -292.741193)
			(xy 87.956141 -292.741193) (xy 87.956132 -292.74165) (xy 87.947968 -292.791884) (xy 87.931852 -292.840158)
			(xy 87.908201 -292.885221) (xy 87.877628 -292.925907) (xy 87.840924 -292.961162) (xy 87.79904 -292.990072)
			(xy 87.753061 -293.011889) (xy 87.704177 -293.026049) (xy 87.653656 -293.032183) (xy 87.602804 -293.030134)
			(xy 87.55294 -293.019954) (xy 87.505354 -293.001907) (xy 87.46128 -292.976461) (xy 87.421858 -292.944274)
			(xy 87.38811 -292.90618) (xy 87.360909 -292.863166) (xy 87.340961 -292.816346) (xy 87.328782 -292.766932)
			(xy 87.324687 -292.716204) (xy 86.07679 -292.716204) (xy 86.076278 -292.74165) (xy 86.068114 -292.791884)
			(xy 86.051998 -292.840158) (xy 86.028347 -292.885221) (xy 85.997774 -292.925907) (xy 85.96107 -292.961162)
			(xy 85.919186 -292.990072) (xy 85.873207 -293.011889) (xy 85.824323 -293.026049) (xy 85.773802 -293.032183)
			(xy 85.72295 -293.030134) (xy 85.673086 -293.019954) (xy 85.6255 -293.001907) (xy 85.581426 -292.976461)
			(xy 85.542004 -292.944274) (xy 85.508256 -292.90618) (xy 85.481055 -292.863166) (xy 85.461107 -292.816346)
			(xy 85.448928 -292.766932) (xy 85.444833 -292.716204) (xy 85.136736 -292.716204) (xy 85.136224 -292.74165)
			(xy 85.12806 -292.791884) (xy 85.111944 -292.840158) (xy 85.088293 -292.885221) (xy 85.05772 -292.925907)
			(xy 85.021016 -292.961162) (xy 84.979132 -292.990072) (xy 84.933153 -293.011889) (xy 84.884269 -293.026049)
			(xy 84.833748 -293.032183) (xy 84.782896 -293.030134) (xy 84.733032 -293.019954) (xy 84.685446 -293.001907)
			(xy 84.641372 -292.976461) (xy 84.60195 -292.944274) (xy 84.568202 -292.90618) (xy 84.541001 -292.863166)
			(xy 84.521053 -292.816346) (xy 84.508874 -292.766932) (xy 84.504779 -292.716204) (xy 84.198968 -292.716204)
			(xy 84.198478 -292.741193) (xy 84.190659 -292.790556) (xy 84.175215 -292.838088) (xy 84.152525 -292.88262)
			(xy 84.123149 -292.923053) (xy 84.087809 -292.958393) (xy 84.047376 -292.987769) (xy 84.002844 -293.010459)
			(xy 83.955312 -293.025903) (xy 83.905949 -293.033722) (xy 83.855971 -293.033722) (xy 83.806608 -293.025903)
			(xy 83.759076 -293.010459) (xy 83.714544 -292.987769) (xy 83.674111 -292.958393) (xy 83.638771 -292.923053)
			(xy 83.609395 -292.88262) (xy 83.586705 -292.838088) (xy 83.571261 -292.790556) (xy 83.563442 -292.741193)
			(xy 83.256125 -292.741193) (xy 83.256116 -292.74165) (xy 83.247952 -292.791884) (xy 83.231836 -292.840158)
			(xy 83.208185 -292.885221) (xy 83.177612 -292.925907) (xy 83.140908 -292.961162) (xy 83.099024 -292.990072)
			(xy 83.053045 -293.011889) (xy 83.004161 -293.026049) (xy 82.95364 -293.032183) (xy 82.902788 -293.030134)
			(xy 82.852924 -293.019954) (xy 82.805338 -293.001907) (xy 82.761264 -292.976461) (xy 82.721842 -292.944274)
			(xy 82.688094 -292.90618) (xy 82.660893 -292.863166) (xy 82.640945 -292.816346) (xy 82.628766 -292.766932)
			(xy 82.624671 -292.716204) (xy 82.319114 -292.716204) (xy 82.318624 -292.741193) (xy 82.310805 -292.790556)
			(xy 82.295361 -292.838088) (xy 82.272671 -292.88262) (xy 82.243295 -292.923053) (xy 82.207955 -292.958393)
			(xy 82.167522 -292.987769) (xy 82.12299 -293.010459) (xy 82.075458 -293.025903) (xy 82.026095 -293.033722)
			(xy 81.976117 -293.033722) (xy 81.926754 -293.025903) (xy 81.879222 -293.010459) (xy 81.83469 -292.987769)
			(xy 81.794257 -292.958393) (xy 81.758917 -292.923053) (xy 81.729541 -292.88262) (xy 81.706851 -292.838088)
			(xy 81.691407 -292.790556) (xy 81.683588 -292.741193) (xy 81.376271 -292.741193) (xy 81.376262 -292.74165)
			(xy 81.368098 -292.791884) (xy 81.351982 -292.840158) (xy 81.328331 -292.885221) (xy 81.297758 -292.925907)
			(xy 81.261054 -292.961162) (xy 81.21917 -292.990072) (xy 81.173191 -293.011889) (xy 81.124307 -293.026049)
			(xy 81.073786 -293.032183) (xy 81.022934 -293.030134) (xy 80.97307 -293.019954) (xy 80.925484 -293.001907)
			(xy 80.88141 -292.976461) (xy 80.841988 -292.944274) (xy 80.80824 -292.90618) (xy 80.781039 -292.863166)
			(xy 80.761091 -292.816346) (xy 80.748912 -292.766932) (xy 80.744817 -292.716204) (xy 79.53248 -292.716204)
			(xy 79.53248 -293.106856) (xy 79.532964 -293.120492) (xy 79.54027 -293.146769) (xy 79.554266 -293.170179)
			(xy 79.573955 -293.189053) (xy 79.597935 -293.202048) (xy 79.624498 -293.208237) (xy 79.638144 -293.208202)
			(xy 79.651098 -293.207948) (xy 79.676109 -293.208413) (xy 79.725515 -293.216238) (xy 79.773089 -293.231696)
			(xy 79.817658 -293.254405) (xy 79.858127 -293.283808) (xy 79.893497 -293.319179) (xy 79.922899 -293.359648)
			(xy 79.945607 -293.404219) (xy 79.961064 -293.451793) (xy 79.968888 -293.501199) (xy 79.96936 -293.52621)
			(xy 79.968875 -293.551199) (xy 80.273634 -293.551199) (xy 80.273634 -293.501221) (xy 80.281453 -293.451858)
			(xy 80.296897 -293.404326) (xy 80.319587 -293.359794) (xy 80.348963 -293.319361) (xy 80.384303 -293.284021)
			(xy 80.424736 -293.254645) (xy 80.469268 -293.231955) (xy 80.5168 -293.216511) (xy 80.566163 -293.208692)
			(xy 80.616141 -293.208692) (xy 80.665504 -293.216511) (xy 80.713036 -293.231955) (xy 80.757568 -293.254645)
			(xy 80.798001 -293.284021) (xy 80.833341 -293.319361) (xy 80.862717 -293.359794) (xy 80.885407 -293.404326)
			(xy 80.900851 -293.451858) (xy 80.90867 -293.501221) (xy 80.90916 -293.52621) (xy 80.90867 -293.551199)
			(xy 81.213434 -293.551199) (xy 81.213434 -293.501221) (xy 81.221253 -293.451858) (xy 81.236697 -293.404326)
			(xy 81.259387 -293.359794) (xy 81.288763 -293.319361) (xy 81.324103 -293.284021) (xy 81.364536 -293.254645)
			(xy 81.409068 -293.231955) (xy 81.4566 -293.216511) (xy 81.505963 -293.208692) (xy 81.555941 -293.208692)
			(xy 81.605304 -293.216511) (xy 81.652836 -293.231955) (xy 81.697368 -293.254645) (xy 81.737801 -293.284021)
			(xy 81.773141 -293.319361) (xy 81.802517 -293.359794) (xy 81.825207 -293.404326) (xy 81.840651 -293.451858)
			(xy 81.84847 -293.501221) (xy 81.84896 -293.52621) (xy 82.154771 -293.52621) (xy 82.158866 -293.475482)
			(xy 82.171045 -293.426068) (xy 82.190993 -293.379248) (xy 82.218194 -293.336234) (xy 82.251942 -293.29814)
			(xy 82.291364 -293.265953) (xy 82.335438 -293.240507) (xy 82.383024 -293.22246) (xy 82.432888 -293.21228)
			(xy 82.48374 -293.210231) (xy 82.534261 -293.216365) (xy 82.583145 -293.230525) (xy 82.629124 -293.252342)
			(xy 82.671008 -293.281252) (xy 82.707712 -293.316507) (xy 82.738285 -293.357193) (xy 82.761936 -293.402256)
			(xy 82.778052 -293.45053) (xy 82.786216 -293.500764) (xy 82.786728 -293.52621) (xy 82.786225 -293.551199)
			(xy 83.093542 -293.551199) (xy 83.093542 -293.501221) (xy 83.101361 -293.451858) (xy 83.116805 -293.404326)
			(xy 83.139495 -293.359794) (xy 83.168871 -293.319361) (xy 83.204211 -293.284021) (xy 83.244644 -293.254645)
			(xy 83.289176 -293.231955) (xy 83.336708 -293.216511) (xy 83.386071 -293.208692) (xy 83.436049 -293.208692)
			(xy 83.485412 -293.216511) (xy 83.532944 -293.231955) (xy 83.577476 -293.254645) (xy 83.617909 -293.284021)
			(xy 83.653249 -293.319361) (xy 83.682625 -293.359794) (xy 83.705315 -293.404326) (xy 83.720759 -293.451858)
			(xy 83.728578 -293.501221) (xy 83.729068 -293.52621) (xy 84.034879 -293.52621) (xy 84.038974 -293.475482)
			(xy 84.051153 -293.426068) (xy 84.071101 -293.379248) (xy 84.098302 -293.336234) (xy 84.13205 -293.29814)
			(xy 84.171472 -293.265953) (xy 84.215546 -293.240507) (xy 84.263132 -293.22246) (xy 84.312996 -293.21228)
			(xy 84.363848 -293.210231) (xy 84.414369 -293.216365) (xy 84.463253 -293.230525) (xy 84.509232 -293.252342)
			(xy 84.551116 -293.281252) (xy 84.58782 -293.316507) (xy 84.618393 -293.357193) (xy 84.642044 -293.402256)
			(xy 84.65816 -293.45053) (xy 84.666324 -293.500764) (xy 84.666836 -293.52621) (xy 84.666333 -293.551199)
			(xy 84.973396 -293.551199) (xy 84.973396 -293.501221) (xy 84.981215 -293.451858) (xy 84.996659 -293.404326)
			(xy 85.019349 -293.359794) (xy 85.048725 -293.319361) (xy 85.084065 -293.284021) (xy 85.124498 -293.254645)
			(xy 85.16903 -293.231955) (xy 85.216562 -293.216511) (xy 85.265925 -293.208692) (xy 85.315903 -293.208692)
			(xy 85.365266 -293.216511) (xy 85.412798 -293.231955) (xy 85.45733 -293.254645) (xy 85.497763 -293.284021)
			(xy 85.533103 -293.319361) (xy 85.562479 -293.359794) (xy 85.585169 -293.404326) (xy 85.600613 -293.451858)
			(xy 85.608432 -293.501221) (xy 85.608922 -293.52621) (xy 85.608432 -293.551199) (xy 85.91345 -293.551199)
			(xy 85.91345 -293.501221) (xy 85.921269 -293.451858) (xy 85.936713 -293.404326) (xy 85.959403 -293.359794)
			(xy 85.988779 -293.319361) (xy 86.024119 -293.284021) (xy 86.064552 -293.254645) (xy 86.109084 -293.231955)
			(xy 86.156616 -293.216511) (xy 86.205979 -293.208692) (xy 86.255957 -293.208692) (xy 86.30532 -293.216511)
			(xy 86.352852 -293.231955) (xy 86.397384 -293.254645) (xy 86.437817 -293.284021) (xy 86.473157 -293.319361)
			(xy 86.502533 -293.359794) (xy 86.525223 -293.404326) (xy 86.540667 -293.451858) (xy 86.548486 -293.501221)
			(xy 86.548976 -293.52621) (xy 86.548486 -293.551199) (xy 86.853504 -293.551199) (xy 86.853504 -293.501221)
			(xy 86.861323 -293.451858) (xy 86.876767 -293.404326) (xy 86.899457 -293.359794) (xy 86.928833 -293.319361)
			(xy 86.964173 -293.284021) (xy 87.004606 -293.254645) (xy 87.049138 -293.231955) (xy 87.09667 -293.216511)
			(xy 87.146033 -293.208692) (xy 87.196011 -293.208692) (xy 87.245374 -293.216511) (xy 87.292906 -293.231955)
			(xy 87.337438 -293.254645) (xy 87.377871 -293.284021) (xy 87.413211 -293.319361) (xy 87.442587 -293.359794)
			(xy 87.465277 -293.404326) (xy 87.480721 -293.451858) (xy 87.48854 -293.501221) (xy 87.48903 -293.52621)
			(xy 87.48854 -293.551199) (xy 87.793558 -293.551199) (xy 87.793558 -293.501221) (xy 87.801377 -293.451858)
			(xy 87.816821 -293.404326) (xy 87.839511 -293.359794) (xy 87.868887 -293.319361) (xy 87.904227 -293.284021)
			(xy 87.94466 -293.254645) (xy 87.989192 -293.231955) (xy 88.036724 -293.216511) (xy 88.086087 -293.208692)
			(xy 88.136065 -293.208692) (xy 88.185428 -293.216511) (xy 88.23296 -293.231955) (xy 88.277492 -293.254645)
			(xy 88.317925 -293.284021) (xy 88.353265 -293.319361) (xy 88.382641 -293.359794) (xy 88.405331 -293.404326)
			(xy 88.420775 -293.451858) (xy 88.428594 -293.501221) (xy 88.429084 -293.52621) (xy 88.734895 -293.52621)
			(xy 88.73899 -293.475482) (xy 88.751169 -293.426068) (xy 88.771117 -293.379248) (xy 88.798318 -293.336234)
			(xy 88.832066 -293.29814) (xy 88.871488 -293.265953) (xy 88.915562 -293.240507) (xy 88.963148 -293.22246)
			(xy 89.013012 -293.21228) (xy 89.063864 -293.210231) (xy 89.114385 -293.216365) (xy 89.163269 -293.230525)
			(xy 89.209248 -293.252342) (xy 89.251132 -293.281252) (xy 89.287836 -293.316507) (xy 89.318409 -293.357193)
			(xy 89.34206 -293.402256) (xy 89.358176 -293.45053) (xy 89.36634 -293.500764) (xy 89.366852 -293.52621)
			(xy 89.36634 -293.551656) (xy 89.358176 -293.60189) (xy 89.34206 -293.650164) (xy 89.318409 -293.695227)
			(xy 89.287836 -293.735913) (xy 89.251132 -293.771168) (xy 89.209248 -293.800078) (xy 89.163269 -293.821895)
			(xy 89.114385 -293.836055) (xy 89.063864 -293.842189) (xy 89.013012 -293.84014) (xy 88.963148 -293.82996)
			(xy 88.915562 -293.811913) (xy 88.871488 -293.786467) (xy 88.832066 -293.75428) (xy 88.798318 -293.716186)
			(xy 88.771117 -293.673172) (xy 88.751169 -293.626352) (xy 88.73899 -293.576938) (xy 88.734895 -293.52621)
			(xy 88.429084 -293.52621) (xy 88.428594 -293.551199) (xy 88.420775 -293.600562) (xy 88.405331 -293.648094)
			(xy 88.382641 -293.692626) (xy 88.353265 -293.733059) (xy 88.317925 -293.768399) (xy 88.277492 -293.797775)
			(xy 88.23296 -293.820465) (xy 88.185428 -293.835909) (xy 88.136065 -293.843728) (xy 88.086087 -293.843728)
			(xy 88.036724 -293.835909) (xy 87.989192 -293.820465) (xy 87.94466 -293.797775) (xy 87.904227 -293.768399)
			(xy 87.868887 -293.733059) (xy 87.839511 -293.692626) (xy 87.816821 -293.648094) (xy 87.801377 -293.600562)
			(xy 87.793558 -293.551199) (xy 87.48854 -293.551199) (xy 87.480721 -293.600562) (xy 87.465277 -293.648094)
			(xy 87.442587 -293.692626) (xy 87.413211 -293.733059) (xy 87.377871 -293.768399) (xy 87.337438 -293.797775)
			(xy 87.292906 -293.820465) (xy 87.245374 -293.835909) (xy 87.196011 -293.843728) (xy 87.146033 -293.843728)
			(xy 87.09667 -293.835909) (xy 87.049138 -293.820465) (xy 87.004606 -293.797775) (xy 86.964173 -293.768399)
			(xy 86.928833 -293.733059) (xy 86.899457 -293.692626) (xy 86.876767 -293.648094) (xy 86.861323 -293.600562)
			(xy 86.853504 -293.551199) (xy 86.548486 -293.551199) (xy 86.540667 -293.600562) (xy 86.525223 -293.648094)
			(xy 86.502533 -293.692626) (xy 86.473157 -293.733059) (xy 86.437817 -293.768399) (xy 86.397384 -293.797775)
			(xy 86.352852 -293.820465) (xy 86.30532 -293.835909) (xy 86.255957 -293.843728) (xy 86.205979 -293.843728)
			(xy 86.156616 -293.835909) (xy 86.109084 -293.820465) (xy 86.064552 -293.797775) (xy 86.024119 -293.768399)
			(xy 85.988779 -293.733059) (xy 85.959403 -293.692626) (xy 85.936713 -293.648094) (xy 85.921269 -293.600562)
			(xy 85.91345 -293.551199) (xy 85.608432 -293.551199) (xy 85.600613 -293.600562) (xy 85.585169 -293.648094)
			(xy 85.562479 -293.692626) (xy 85.533103 -293.733059) (xy 85.497763 -293.768399) (xy 85.45733 -293.797775)
			(xy 85.412798 -293.820465) (xy 85.365266 -293.835909) (xy 85.315903 -293.843728) (xy 85.265925 -293.843728)
			(xy 85.216562 -293.835909) (xy 85.16903 -293.820465) (xy 85.124498 -293.797775) (xy 85.084065 -293.768399)
			(xy 85.048725 -293.733059) (xy 85.019349 -293.692626) (xy 84.996659 -293.648094) (xy 84.981215 -293.600562)
			(xy 84.973396 -293.551199) (xy 84.666333 -293.551199) (xy 84.666324 -293.551656) (xy 84.65816 -293.60189)
			(xy 84.642044 -293.650164) (xy 84.618393 -293.695227) (xy 84.58782 -293.735913) (xy 84.551116 -293.771168)
			(xy 84.509232 -293.800078) (xy 84.463253 -293.821895) (xy 84.414369 -293.836055) (xy 84.363848 -293.842189)
			(xy 84.312996 -293.84014) (xy 84.263132 -293.82996) (xy 84.215546 -293.811913) (xy 84.171472 -293.786467)
			(xy 84.13205 -293.75428) (xy 84.098302 -293.716186) (xy 84.071101 -293.673172) (xy 84.051153 -293.626352)
			(xy 84.038974 -293.576938) (xy 84.034879 -293.52621) (xy 83.729068 -293.52621) (xy 83.728578 -293.551199)
			(xy 83.720759 -293.600562) (xy 83.705315 -293.648094) (xy 83.682625 -293.692626) (xy 83.653249 -293.733059)
			(xy 83.617909 -293.768399) (xy 83.577476 -293.797775) (xy 83.532944 -293.820465) (xy 83.485412 -293.835909)
			(xy 83.436049 -293.843728) (xy 83.386071 -293.843728) (xy 83.336708 -293.835909) (xy 83.289176 -293.820465)
			(xy 83.244644 -293.797775) (xy 83.204211 -293.768399) (xy 83.168871 -293.733059) (xy 83.139495 -293.692626)
			(xy 83.116805 -293.648094) (xy 83.101361 -293.600562) (xy 83.093542 -293.551199) (xy 82.786225 -293.551199)
			(xy 82.786216 -293.551656) (xy 82.778052 -293.60189) (xy 82.761936 -293.650164) (xy 82.738285 -293.695227)
			(xy 82.707712 -293.735913) (xy 82.671008 -293.771168) (xy 82.629124 -293.800078) (xy 82.583145 -293.821895)
			(xy 82.534261 -293.836055) (xy 82.48374 -293.842189) (xy 82.432888 -293.84014) (xy 82.383024 -293.82996)
			(xy 82.335438 -293.811913) (xy 82.291364 -293.786467) (xy 82.251942 -293.75428) (xy 82.218194 -293.716186)
			(xy 82.190993 -293.673172) (xy 82.171045 -293.626352) (xy 82.158866 -293.576938) (xy 82.154771 -293.52621)
			(xy 81.84896 -293.52621) (xy 81.84847 -293.551199) (xy 81.840651 -293.600562) (xy 81.825207 -293.648094)
			(xy 81.802517 -293.692626) (xy 81.773141 -293.733059) (xy 81.737801 -293.768399) (xy 81.697368 -293.797775)
			(xy 81.652836 -293.820465) (xy 81.605304 -293.835909) (xy 81.555941 -293.843728) (xy 81.505963 -293.843728)
			(xy 81.4566 -293.835909) (xy 81.409068 -293.820465) (xy 81.364536 -293.797775) (xy 81.324103 -293.768399)
			(xy 81.288763 -293.733059) (xy 81.259387 -293.692626) (xy 81.236697 -293.648094) (xy 81.221253 -293.600562)
			(xy 81.213434 -293.551199) (xy 80.90867 -293.551199) (xy 80.900851 -293.600562) (xy 80.885407 -293.648094)
			(xy 80.862717 -293.692626) (xy 80.833341 -293.733059) (xy 80.798001 -293.768399) (xy 80.757568 -293.797775)
			(xy 80.713036 -293.820465) (xy 80.665504 -293.835909) (xy 80.616141 -293.843728) (xy 80.566163 -293.843728)
			(xy 80.5168 -293.835909) (xy 80.469268 -293.820465) (xy 80.424736 -293.797775) (xy 80.384303 -293.768399)
			(xy 80.348963 -293.733059) (xy 80.319587 -293.692626) (xy 80.296897 -293.648094) (xy 80.281453 -293.600562)
			(xy 80.273634 -293.551199) (xy 79.968875 -293.551199) (xy 79.968867 -293.551612) (xy 79.960787 -293.60177)
			(xy 79.94482 -293.649999) (xy 79.933546 -293.672768) (xy 79.929736 -293.680134) (xy 79.927196 -293.695882)
			(xy 79.928466 -293.703756) (xy 79.929945 -293.711678) (xy 79.937187 -293.726064) (xy 79.94269 -293.73195)
			(xy 80.260952 -294.050212) (xy 80.268064 -294.054022) (xy 80.268318 -294.054022) (xy 80.289584 -294.065636)
			(xy 80.328641 -294.09431) (xy 80.362902 -294.128573) (xy 80.391574 -294.167632) (xy 80.403192 -294.188896)
			(xy 80.403192 -294.18915) (xy 80.407002 -294.196262) (xy 80.571945 -294.361205) (xy 81.683588 -294.361205)
			(xy 81.683588 -294.311227) (xy 81.691407 -294.261864) (xy 81.706851 -294.214332) (xy 81.729541 -294.1698)
			(xy 81.758917 -294.129367) (xy 81.794257 -294.094027) (xy 81.83469 -294.064651) (xy 81.879222 -294.041961)
			(xy 81.926754 -294.026517) (xy 81.976117 -294.018698) (xy 82.026095 -294.018698) (xy 82.075458 -294.026517)
			(xy 82.12299 -294.041961) (xy 82.167522 -294.064651) (xy 82.207955 -294.094027) (xy 82.243295 -294.129367)
			(xy 82.272671 -294.1698) (xy 82.295361 -294.214332) (xy 82.310805 -294.261864) (xy 82.318624 -294.311227)
			(xy 82.319114 -294.336216) (xy 82.318624 -294.361205) (xy 82.623388 -294.361205) (xy 82.623388 -294.311227)
			(xy 82.631207 -294.261864) (xy 82.646651 -294.214332) (xy 82.669341 -294.1698) (xy 82.698717 -294.129367)
			(xy 82.734057 -294.094027) (xy 82.77449 -294.064651) (xy 82.819022 -294.041961) (xy 82.866554 -294.026517)
			(xy 82.915917 -294.018698) (xy 82.965895 -294.018698) (xy 83.015258 -294.026517) (xy 83.06279 -294.041961)
			(xy 83.107322 -294.064651) (xy 83.147755 -294.094027) (xy 83.183095 -294.129367) (xy 83.212471 -294.1698)
			(xy 83.235161 -294.214332) (xy 83.250605 -294.261864) (xy 83.258424 -294.311227) (xy 83.258914 -294.336216)
			(xy 83.258424 -294.361205) (xy 83.563442 -294.361205) (xy 83.563442 -294.311227) (xy 83.571261 -294.261864)
			(xy 83.586705 -294.214332) (xy 83.609395 -294.1698) (xy 83.638771 -294.129367) (xy 83.674111 -294.094027)
			(xy 83.714544 -294.064651) (xy 83.759076 -294.041961) (xy 83.806608 -294.026517) (xy 83.855971 -294.018698)
			(xy 83.905949 -294.018698) (xy 83.955312 -294.026517) (xy 84.002844 -294.041961) (xy 84.047376 -294.064651)
			(xy 84.087809 -294.094027) (xy 84.123149 -294.129367) (xy 84.152525 -294.1698) (xy 84.175215 -294.214332)
			(xy 84.190659 -294.261864) (xy 84.198478 -294.311227) (xy 84.198968 -294.336216) (xy 84.198478 -294.361205)
			(xy 84.503496 -294.361205) (xy 84.503496 -294.311227) (xy 84.511315 -294.261864) (xy 84.526759 -294.214332)
			(xy 84.549449 -294.1698) (xy 84.578825 -294.129367) (xy 84.614165 -294.094027) (xy 84.654598 -294.064651)
			(xy 84.69913 -294.041961) (xy 84.746662 -294.026517) (xy 84.796025 -294.018698) (xy 84.846003 -294.018698)
			(xy 84.895366 -294.026517) (xy 84.942898 -294.041961) (xy 84.98743 -294.064651) (xy 85.027863 -294.094027)
			(xy 85.063203 -294.129367) (xy 85.092579 -294.1698) (xy 85.115269 -294.214332) (xy 85.130713 -294.261864)
			(xy 85.138532 -294.311227) (xy 85.139022 -294.336216) (xy 85.138532 -294.361205) (xy 85.44355 -294.361205)
			(xy 85.44355 -294.311227) (xy 85.451369 -294.261864) (xy 85.466813 -294.214332) (xy 85.489503 -294.1698)
			(xy 85.518879 -294.129367) (xy 85.554219 -294.094027) (xy 85.594652 -294.064651) (xy 85.639184 -294.041961)
			(xy 85.686716 -294.026517) (xy 85.736079 -294.018698) (xy 85.786057 -294.018698) (xy 85.83542 -294.026517)
			(xy 85.882952 -294.041961) (xy 85.927484 -294.064651) (xy 85.967917 -294.094027) (xy 86.003257 -294.129367)
			(xy 86.032633 -294.1698) (xy 86.055323 -294.214332) (xy 86.070767 -294.261864) (xy 86.078586 -294.311227)
			(xy 86.079076 -294.336216) (xy 86.078586 -294.361205) (xy 86.383604 -294.361205) (xy 86.383604 -294.311227)
			(xy 86.391423 -294.261864) (xy 86.406867 -294.214332) (xy 86.429557 -294.1698) (xy 86.458933 -294.129367)
			(xy 86.494273 -294.094027) (xy 86.534706 -294.064651) (xy 86.579238 -294.041961) (xy 86.62677 -294.026517)
			(xy 86.676133 -294.018698) (xy 86.726111 -294.018698) (xy 86.775474 -294.026517) (xy 86.823006 -294.041961)
			(xy 86.867538 -294.064651) (xy 86.907971 -294.094027) (xy 86.943311 -294.129367) (xy 86.972687 -294.1698)
			(xy 86.995377 -294.214332) (xy 87.010821 -294.261864) (xy 87.01864 -294.311227) (xy 87.01913 -294.336216)
			(xy 87.01864 -294.361205) (xy 87.010821 -294.410568) (xy 86.995377 -294.4581) (xy 86.972687 -294.502632)
			(xy 86.943311 -294.543065) (xy 86.907971 -294.578405) (xy 86.867538 -294.607781) (xy 86.823006 -294.630471)
			(xy 86.775474 -294.645915) (xy 86.726111 -294.653734) (xy 86.676133 -294.653734) (xy 86.62677 -294.645915)
			(xy 86.579238 -294.630471) (xy 86.534706 -294.607781) (xy 86.494273 -294.578405) (xy 86.458933 -294.543065)
			(xy 86.429557 -294.502632) (xy 86.406867 -294.4581) (xy 86.391423 -294.410568) (xy 86.383604 -294.361205)
			(xy 86.078586 -294.361205) (xy 86.070767 -294.410568) (xy 86.055323 -294.4581) (xy 86.032633 -294.502632)
			(xy 86.003257 -294.543065) (xy 85.967917 -294.578405) (xy 85.927484 -294.607781) (xy 85.882952 -294.630471)
			(xy 85.83542 -294.645915) (xy 85.786057 -294.653734) (xy 85.736079 -294.653734) (xy 85.686716 -294.645915)
			(xy 85.639184 -294.630471) (xy 85.594652 -294.607781) (xy 85.554219 -294.578405) (xy 85.518879 -294.543065)
			(xy 85.489503 -294.502632) (xy 85.466813 -294.4581) (xy 85.451369 -294.410568) (xy 85.44355 -294.361205)
			(xy 85.138532 -294.361205) (xy 85.130713 -294.410568) (xy 85.115269 -294.4581) (xy 85.092579 -294.502632)
			(xy 85.063203 -294.543065) (xy 85.027863 -294.578405) (xy 84.98743 -294.607781) (xy 84.942898 -294.630471)
			(xy 84.895366 -294.645915) (xy 84.846003 -294.653734) (xy 84.796025 -294.653734) (xy 84.746662 -294.645915)
			(xy 84.69913 -294.630471) (xy 84.654598 -294.607781) (xy 84.614165 -294.578405) (xy 84.578825 -294.543065)
			(xy 84.549449 -294.502632) (xy 84.526759 -294.4581) (xy 84.511315 -294.410568) (xy 84.503496 -294.361205)
			(xy 84.198478 -294.361205) (xy 84.190659 -294.410568) (xy 84.175215 -294.4581) (xy 84.152525 -294.502632)
			(xy 84.123149 -294.543065) (xy 84.087809 -294.578405) (xy 84.047376 -294.607781) (xy 84.002844 -294.630471)
			(xy 83.955312 -294.645915) (xy 83.905949 -294.653734) (xy 83.855971 -294.653734) (xy 83.806608 -294.645915)
			(xy 83.759076 -294.630471) (xy 83.714544 -294.607781) (xy 83.674111 -294.578405) (xy 83.638771 -294.543065)
			(xy 83.609395 -294.502632) (xy 83.586705 -294.4581) (xy 83.571261 -294.410568) (xy 83.563442 -294.361205)
			(xy 83.258424 -294.361205) (xy 83.250605 -294.410568) (xy 83.235161 -294.4581) (xy 83.212471 -294.502632)
			(xy 83.183095 -294.543065) (xy 83.147755 -294.578405) (xy 83.107322 -294.607781) (xy 83.06279 -294.630471)
			(xy 83.015258 -294.645915) (xy 82.965895 -294.653734) (xy 82.915917 -294.653734) (xy 82.866554 -294.645915)
			(xy 82.819022 -294.630471) (xy 82.77449 -294.607781) (xy 82.734057 -294.578405) (xy 82.698717 -294.543065)
			(xy 82.669341 -294.502632) (xy 82.646651 -294.4581) (xy 82.631207 -294.410568) (xy 82.623388 -294.361205)
			(xy 82.318624 -294.361205) (xy 82.310805 -294.410568) (xy 82.295361 -294.4581) (xy 82.272671 -294.502632)
			(xy 82.243295 -294.543065) (xy 82.207955 -294.578405) (xy 82.167522 -294.607781) (xy 82.12299 -294.630471)
			(xy 82.075458 -294.645915) (xy 82.026095 -294.653734) (xy 81.976117 -294.653734) (xy 81.926754 -294.645915)
			(xy 81.879222 -294.630471) (xy 81.83469 -294.607781) (xy 81.794257 -294.578405) (xy 81.758917 -294.543065)
			(xy 81.729541 -294.502632) (xy 81.706851 -294.4581) (xy 81.691407 -294.410568) (xy 81.683588 -294.361205)
			(xy 80.571945 -294.361205) (xy 80.963262 -294.752522) (xy 80.968764 -294.757504) (xy 80.981932 -294.764336)
			(xy 80.98917 -294.765984) (xy 80.998822 -294.767) (xy 88.617298 -294.767)
		)
		(stroke
			(width 0)
			(type solid)
		)
		(fill yes)
		(layer "B.Cu")
		(net "PVDDIO_P1")
	)
	(gr_line
		(start 9.958832 -110.020608)
		(end 10.490708 -110.552738)
		(stroke
			(width 0.06477)
			(type default)
		)
		(layer "B.Cu")
	)
	(gr_line
		(start 10.188448 -109.792516)
		(end 10.449306 -109.792516)
		(stroke
			(width 0.06477)
			(type default)
		)
		(layer "B.Cu")
	)
	(gr_line
		(start 10.33526 -106.00309)
		(end 10.51941 -106.18724)
		(stroke
			(width 0.06477)
			(type default)
		)
		(layer "B.Cu")
	)
	(gr_line
		(start 10.449306 -109.792516)
		(end 10.188448 -109.792516)
		(stroke
			(width 0.06477)
			(type default)
		)
		(layer "B.Cu")
	)
	(gr_line
		(start 10.449306 -109.792516)
		(end 10.7188 -110.06201)
		(stroke
			(width 0.06477)
			(type default)
		)
		(layer "B.Cu")
	)
	(gr_line
		(start 10.51941 -106.18724)
		(end 10.33526 -106.00309)
		(stroke
			(width 0.06477)
			(type default)
		)
		(layer "B.Cu")
	)
	(gr_line
		(start 10.51941 -106.18724)
		(end 10.90041 -106.18724)
		(stroke
			(width 0.06477)
			(type default)
		)
		(layer "B.Cu")
	)
	(gr_line
		(start 10.7188 -110.322868)
		(end 10.7188 -110.06201)
		(stroke
			(width 0.06477)
			(type default)
		)
		(layer "B.Cu")
	)
	(gr_line
		(start 10.7188 -110.06201)
		(end 10.449306 -109.792516)
		(stroke
			(width 0.06477)
			(type default)
		)
		(layer "B.Cu")
	)
	(gr_line
		(start 10.7188 -110.06201)
		(end 10.7188 -110.322868)
		(stroke
			(width 0.06477)
			(type default)
		)
		(layer "B.Cu")
	)
	(gr_line
		(start 10.90041 -106.18724)
		(end 10.51941 -106.18724)
		(stroke
			(width 0.06477)
			(type default)
		)
		(layer "B.Cu")
	)
	(gr_line
		(start 10.90041 -106.18724)
		(end 11.08456 -106.00309)
		(stroke
			(width 0.06477)
			(type default)
		)
		(layer "B.Cu")
	)
	(gr_line
		(start 11.08456 -106.00309)
		(end 10.90041 -106.18724)
		(stroke
			(width 0.06477)
			(type default)
		)
		(layer "B.Cu")
	)
	(gr_line
		(start 11.08583 -105.67924)
		(end 10.33399 -105.67924)
		(stroke
			(width 0.06477)
			(type default)
		)
		(layer "B.Cu")
	)
	(gr_line
		(start 11.876786 -113.360962)
		(end 11.906758 -113.390934)
		(stroke
			(width 0.06477)
			(type default)
		)
		(layer "B.Cu")
	)
	(gr_line
		(start 11.876786 -113.019332)
		(end 11.876786 -113.360962)
		(stroke
			(width 0.06477)
			(type default)
		)
		(layer "B.Cu")
	)
	(gr_line
		(start 11.876786 -111.619284)
		(end 11.876786 -113.019332)
		(stroke
			(width 0.06477)
			(type default)
		)
		(layer "B.Cu")
	)
	(gr_line
		(start 11.876786 -111.294926)
		(end 11.876786 -111.619284)
		(stroke
			(width 0.06477)
			(type default)
		)
		(layer "B.Cu")
	)
	(gr_line
		(start 11.906758 -114.436398)
		(end 11.636248 -114.706908)
		(stroke
			(width 0.06477)
			(type default)
		)
		(layer "B.Cu")
	)
	(gr_line
		(start 11.920474 -105.84053)
		(end 13.493496 -103.315516)
		(stroke
			(width 0.19304)
			(type default)
		)
		(layer "B.Cu")
	)
	(gr_line
		(start 11.921744 -106.00309)
		(end 12.095226 -106.176572)
		(stroke
			(width 0.06477)
			(type default)
		)
		(layer "B.Cu")
	)
	(gr_line
		(start 11.92403 -111.247682)
		(end 11.876786 -111.294926)
		(stroke
			(width 0.06477)
			(type default)
		)
		(layer "B.Cu")
	)
	(gr_line
		(start 11.981434 -105.67924)
		(end 11.920474 -105.67924)
		(stroke
			(width 0.06477)
			(type default)
		)
		(layer "B.Cu")
	)
	(gr_line
		(start 12.094972 -105.565702)
		(end 11.981434 -105.67924)
		(stroke
			(width 0.06477)
			(type default)
		)
		(layer "B.Cu")
	)
	(gr_line
		(start 12.094972 -105.456736)
		(end 12.094972 -105.565702)
		(stroke
			(width 0.06477)
			(type default)
		)
		(layer "B.Cu")
	)
	(gr_line
		(start 12.095226 -106.447336)
		(end 12.095226 -106.176572)
		(stroke
			(width 0.06477)
			(type default)
		)
		(layer "B.Cu")
	)
	(gr_line
		(start 12.095226 -106.176572)
		(end 11.921744 -106.00309)
		(stroke
			(width 0.06477)
			(type default)
		)
		(layer "B.Cu")
	)
	(gr_line
		(start 12.095226 -106.176572)
		(end 12.095226 -106.447336)
		(stroke
			(width 0.06477)
			(type default)
		)
		(layer "B.Cu")
	)
	(gr_line
		(start 12.229338 -114.436398)
		(end 12.499848 -114.706908)
		(stroke
			(width 0.06477)
			(type default)
		)
		(layer "B.Cu")
	)
	(gr_line
		(start 12.229338 -113.390934)
		(end 12.276582 -113.34369)
		(stroke
			(width 0.06477)
			(type default)
		)
		(layer "B.Cu")
	)
	(gr_line
		(start 12.24661 -111.247682)
		(end 12.276582 -111.277654)
		(stroke
			(width 0.06477)
			(type default)
		)
		(layer "B.Cu")
	)
	(gr_line
		(start 12.276582 -113.34369)
		(end 12.229338 -113.390934)
		(stroke
			(width 0.06477)
			(type default)
		)
		(layer "B.Cu")
	)
	(gr_line
		(start 12.276582 -113.34369)
		(end 12.276582 -113.019332)
		(stroke
			(width 0.06477)
			(type default)
		)
		(layer "B.Cu")
	)
	(gr_line
		(start 12.276582 -113.019332)
		(end 12.276582 -113.34369)
		(stroke
			(width 0.06477)
			(type default)
		)
		(layer "B.Cu")
	)
	(gr_line
		(start 12.276582 -113.019332)
		(end 12.276582 -111.619284)
		(stroke
			(width 0.06477)
			(type default)
		)
		(layer "B.Cu")
	)
	(gr_line
		(start 12.276582 -111.619284)
		(end 12.276582 -113.019332)
		(stroke
			(width 0.06477)
			(type default)
		)
		(layer "B.Cu")
	)
	(gr_line
		(start 12.276582 -111.619284)
		(end 12.276582 -111.277654)
		(stroke
			(width 0.06477)
			(type default)
		)
		(layer "B.Cu")
	)
	(gr_line
		(start 12.276582 -111.277654)
		(end 12.24661 -111.247682)
		(stroke
			(width 0.06477)
			(type default)
		)
		(layer "B.Cu")
	)
	(gr_line
		(start 12.276582 -111.277654)
		(end 12.276582 -111.619284)
		(stroke
			(width 0.06477)
			(type default)
		)
		(layer "B.Cu")
	)
	(gr_line
		(start 12.499848 -114.706908)
		(end 12.229338 -114.436398)
		(stroke
			(width 0.06477)
			(type default)
		)
		(layer "B.Cu")
	)
	(gr_line
		(start 21.802344 -421.269922)
		(end 21.531834 -420.999412)
		(stroke
			(width 0.06477)
			(type default)
		)
		(layer "B.Cu")
	)
	(gr_line
		(start 21.802344 -420.406322)
		(end 21.531834 -420.676832)
		(stroke
			(width 0.06477)
			(type default)
		)
		(layer "B.Cu")
	)
	(gr_line
		(start 21.814028 -418.555424)
		(end 22.583648 -418.555424)
		(stroke
			(width 0.06477)
			(type default)
		)
		(layer "B.Cu")
	)
	(gr_line
		(start 21.815298 -418.879274)
		(end 22.004528 -419.068504)
		(stroke
			(width 0.06477)
			(type default)
		)
		(layer "B.Cu")
	)
	(gr_line
		(start 22.004528 -419.068504)
		(end 22.393148 -419.068504)
		(stroke
			(width 0.06477)
			(type default)
		)
		(layer "B.Cu")
	)
	(gr_line
		(start 22.393148 -419.068504)
		(end 22.582378 -418.879274)
		(stroke
			(width 0.06477)
			(type default)
		)
		(layer "B.Cu")
	)
	(gr_line
		(start 22.594824 -425.057824)
		(end 22.324314 -425.328334)
		(stroke
			(width 0.06477)
			(type default)
		)
		(layer "B.Cu")
	)
	(gr_line
		(start 22.594824 -424.735244)
		(end 22.324314 -424.464734)
		(stroke
			(width 0.06477)
			(type default)
		)
		(layer "B.Cu")
	)
	(gr_line
		(start 22.972268 -418.555424)
		(end 23.741888 -418.555424)
		(stroke
			(width 0.06477)
			(type default)
		)
		(layer "B.Cu")
	)
	(gr_line
		(start 22.973538 -418.879274)
		(end 23.162768 -419.068504)
		(stroke
			(width 0.06477)
			(type default)
		)
		(layer "B.Cu")
	)
	(gr_line
		(start 23.162768 -419.068504)
		(end 23.551388 -419.068504)
		(stroke
			(width 0.06477)
			(type default)
		)
		(layer "B.Cu")
	)
	(gr_line
		(start 23.379176 -423.572432)
		(end 23.379176 -424.342052)
		(stroke
			(width 0.06477)
			(type default)
		)
		(layer "B.Cu")
	)
	(gr_line
		(start 23.379176 -422.414192)
		(end 23.379176 -423.183812)
		(stroke
			(width 0.06477)
			(type default)
		)
		(layer "B.Cu")
	)
	(gr_line
		(start 23.551388 -419.068504)
		(end 23.740618 -418.879274)
		(stroke
			(width 0.06477)
			(type default)
		)
		(layer "B.Cu")
	)
	(gr_line
		(start 23.703026 -423.573702)
		(end 23.892256 -423.762932)
		(stroke
			(width 0.06477)
			(type default)
		)
		(layer "B.Cu")
	)
	(gr_line
		(start 23.703026 -422.415462)
		(end 23.892256 -422.604692)
		(stroke
			(width 0.06477)
			(type default)
		)
		(layer "B.Cu")
	)
	(gr_line
		(start 23.892256 -424.151552)
		(end 23.703026 -424.340782)
		(stroke
			(width 0.06477)
			(type default)
		)
		(layer "B.Cu")
	)
	(gr_line
		(start 23.892256 -423.762932)
		(end 23.892256 -424.151552)
		(stroke
			(width 0.06477)
			(type default)
		)
		(layer "B.Cu")
	)
	(gr_line
		(start 23.892256 -422.993312)
		(end 23.703026 -423.182542)
		(stroke
			(width 0.06477)
			(type default)
		)
		(layer "B.Cu")
	)
	(gr_line
		(start 23.892256 -422.604692)
		(end 23.892256 -422.993312)
		(stroke
			(width 0.06477)
			(type default)
		)
		(layer "B.Cu")
	)
	(gr_line
		(start 24.130508 -418.555424)
		(end 24.900128 -418.555424)
		(stroke
			(width 0.06477)
			(type default)
		)
		(layer "B.Cu")
	)
	(gr_line
		(start 24.131778 -418.879274)
		(end 24.321008 -419.068504)
		(stroke
			(width 0.06477)
			(type default)
		)
		(layer "B.Cu")
	)
	(gr_line
		(start 24.321008 -419.068504)
		(end 24.709628 -419.068504)
		(stroke
			(width 0.06477)
			(type default)
		)
		(layer "B.Cu")
	)
	(gr_line
		(start 24.709628 -419.068504)
		(end 24.898858 -418.879274)
		(stroke
			(width 0.06477)
			(type default)
		)
		(layer "B.Cu")
	)
	(gr_line
		(start 25.288748 -418.555424)
		(end 26.058368 -418.555424)
		(stroke
			(width 0.06477)
			(type default)
		)
		(layer "B.Cu")
	)
	(gr_line
		(start 25.290018 -418.879274)
		(end 25.479248 -419.068504)
		(stroke
			(width 0.06477)
			(type default)
		)
		(layer "B.Cu")
	)
	(gr_line
		(start 25.479248 -419.068504)
		(end 25.867868 -419.068504)
		(stroke
			(width 0.06477)
			(type default)
		)
		(layer "B.Cu")
	)
	(gr_line
		(start 25.867868 -419.068504)
		(end 26.057098 -418.879274)
		(stroke
			(width 0.06477)
			(type default)
		)
		(layer "B.Cu")
	)
	(gr_line
		(start 26.446988 -418.555424)
		(end 27.216608 -418.555424)
		(stroke
			(width 0.06477)
			(type default)
		)
		(layer "B.Cu")
	)
	(gr_line
		(start 26.448258 -418.879274)
		(end 26.637488 -419.068504)
		(stroke
			(width 0.06477)
			(type default)
		)
		(layer "B.Cu")
	)
	(gr_line
		(start 26.637488 -419.068504)
		(end 27.026108 -419.068504)
		(stroke
			(width 0.06477)
			(type default)
		)
		(layer "B.Cu")
	)
	(gr_line
		(start 27.026108 -419.068504)
		(end 27.215338 -418.879274)
		(stroke
			(width 0.06477)
			(type default)
		)
		(layer "B.Cu")
	)
	(gr_line
		(start 29.375608 -419.069774)
		(end 30.076648 -419.069774)
		(stroke
			(width 0.06477)
			(type default)
		)
		(layer "B.Cu")
	)
	(gr_line
		(start 29.376878 -419.393624)
		(end 29.512768 -419.529514)
		(stroke
			(width 0.06477)
			(type default)
		)
		(layer "B.Cu")
	)
	(gr_line
		(start 29.512768 -419.529514)
		(end 29.939488 -419.529514)
		(stroke
			(width 0.06477)
			(type default)
		)
		(layer "B.Cu")
	)
	(gr_line
		(start 29.939488 -419.529514)
		(end 30.075378 -419.393624)
		(stroke
			(width 0.06477)
			(type default)
		)
		(layer "B.Cu")
	)
	(gr_line
		(start 30.503368 -419.069774)
		(end 31.204408 -419.069774)
		(stroke
			(width 0.06477)
			(type default)
		)
		(layer "B.Cu")
	)
	(gr_line
		(start 30.504638 -419.393624)
		(end 30.640528 -419.529514)
		(stroke
			(width 0.06477)
			(type default)
		)
		(layer "B.Cu")
	)
	(gr_line
		(start 30.640528 -419.529514)
		(end 31.067248 -419.529514)
		(stroke
			(width 0.06477)
			(type default)
		)
		(layer "B.Cu")
	)
	(gr_line
		(start 31.067248 -419.529514)
		(end 31.203138 -419.393624)
		(stroke
			(width 0.06477)
			(type default)
		)
		(layer "B.Cu")
	)
	(gr_line
		(start 31.631128 -419.069774)
		(end 32.332168 -419.069774)
		(stroke
			(width 0.06477)
			(type default)
		)
		(layer "B.Cu")
	)
	(gr_line
		(start 31.632398 -419.393624)
		(end 31.768288 -419.529514)
		(stroke
			(width 0.06477)
			(type default)
		)
		(layer "B.Cu")
	)
	(gr_line
		(start 31.768288 -419.529514)
		(end 32.195008 -419.529514)
		(stroke
			(width 0.06477)
			(type default)
		)
		(layer "B.Cu")
	)
	(gr_line
		(start 32.195008 -419.529514)
		(end 32.330898 -419.393624)
		(stroke
			(width 0.06477)
			(type default)
		)
		(layer "B.Cu")
	)
	(gr_line
		(start 32.758888 -419.069774)
		(end 33.459928 -419.069774)
		(stroke
			(width 0.06477)
			(type default)
		)
		(layer "B.Cu")
	)
	(gr_line
		(start 32.760158 -419.393624)
		(end 32.896048 -419.529514)
		(stroke
			(width 0.06477)
			(type default)
		)
		(layer "B.Cu")
	)
	(gr_line
		(start 32.896048 -419.529514)
		(end 33.322768 -419.529514)
		(stroke
			(width 0.06477)
			(type default)
		)
		(layer "B.Cu")
	)
	(gr_line
		(start 33.322768 -419.529514)
		(end 33.458658 -419.393624)
		(stroke
			(width 0.06477)
			(type default)
		)
		(layer "B.Cu")
	)
	(gr_line
		(start 33.895792 -419.069774)
		(end 34.596832 -419.069774)
		(stroke
			(width 0.06477)
			(type default)
		)
		(layer "B.Cu")
	)
	(gr_line
		(start 33.897062 -419.393624)
		(end 34.032952 -419.529514)
		(stroke
			(width 0.06477)
			(type default)
		)
		(layer "B.Cu")
	)
	(gr_line
		(start 34.032952 -419.529514)
		(end 34.459672 -419.529514)
		(stroke
			(width 0.06477)
			(type default)
		)
		(layer "B.Cu")
	)
	(gr_line
		(start 34.459672 -419.529514)
		(end 34.595562 -419.393624)
		(stroke
			(width 0.06477)
			(type default)
		)
		(layer "B.Cu")
	)
	(gr_line
		(start 35.023552 -419.069774)
		(end 35.724592 -419.069774)
		(stroke
			(width 0.06477)
			(type default)
		)
		(layer "B.Cu")
	)
	(gr_line
		(start 35.024822 -419.393624)
		(end 35.160712 -419.529514)
		(stroke
			(width 0.06477)
			(type default)
		)
		(layer "B.Cu")
	)
	(gr_line
		(start 35.160712 -419.529514)
		(end 35.587432 -419.529514)
		(stroke
			(width 0.06477)
			(type default)
		)
		(layer "B.Cu")
	)
	(gr_line
		(start 35.587432 -419.529514)
		(end 35.723322 -419.393624)
		(stroke
			(width 0.06477)
			(type default)
		)
		(layer "B.Cu")
	)
	(gr_line
		(start 36.151312 -419.069774)
		(end 36.852352 -419.069774)
		(stroke
			(width 0.06477)
			(type default)
		)
		(layer "B.Cu")
	)
	(gr_line
		(start 36.152582 -419.393624)
		(end 36.288472 -419.529514)
		(stroke
			(width 0.06477)
			(type default)
		)
		(layer "B.Cu")
	)
	(gr_line
		(start 36.214304 -417.465002)
		(end 36.484814 -417.194492)
		(stroke
			(width 0.06477)
			(type default)
		)
		(layer "B.Cu")
	)
	(gr_line
		(start 36.214304 -416.601402)
		(end 36.484814 -416.871912)
		(stroke
			(width 0.06477)
			(type default)
		)
		(layer "B.Cu")
	)
	(gr_line
		(start 36.288472 -419.529514)
		(end 36.715192 -419.529514)
		(stroke
			(width 0.06477)
			(type default)
		)
		(layer "B.Cu")
	)
	(gr_line
		(start 36.484814 -417.194492)
		(end 36.214304 -417.465002)
		(stroke
			(width 0.06477)
			(type default)
		)
		(layer "B.Cu")
	)
	(gr_line
		(start 36.715192 -419.529514)
		(end 36.851082 -419.393624)
		(stroke
			(width 0.06477)
			(type default)
		)
		(layer "B.Cu")
	)
	(gr_line
		(start 36.875974 -420.7637)
		(end 36.689284 -420.57701)
		(stroke
			(width 0.06477)
			(type default)
		)
		(layer "B.Cu")
	)
	(gr_line
		(start 37.264594 -420.7637)
		(end 36.875974 -420.7637)
		(stroke
			(width 0.06477)
			(type default)
		)
		(layer "B.Cu")
	)
	(gr_line
		(start 37.451284 -420.57701)
		(end 37.264594 -420.7637)
		(stroke
			(width 0.06477)
			(type default)
		)
		(layer "B.Cu")
	)
	(gr_line
		(start 37.452554 -420.25316)
		(end 36.688014 -420.25316)
		(stroke
			(width 0.06477)
			(type default)
		)
		(layer "B.Cu")
	)
	(gr_line
		(start 38.029134 -420.7637)
		(end 37.842444 -420.57701)
		(stroke
			(width 0.06477)
			(type default)
		)
		(layer "B.Cu")
	)
	(gr_line
		(start 38.417754 -420.7637)
		(end 38.029134 -420.7637)
		(stroke
			(width 0.06477)
			(type default)
		)
		(layer "B.Cu")
	)
	(gr_line
		(start 38.604444 -420.57701)
		(end 38.417754 -420.7637)
		(stroke
			(width 0.06477)
			(type default)
		)
		(layer "B.Cu")
	)
	(gr_line
		(start 38.605714 -420.25316)
		(end 37.841174 -420.25316)
		(stroke
			(width 0.06477)
			(type default)
		)
		(layer "B.Cu")
	)
	(gr_line
		(start 39.184834 -420.76624)
		(end 38.995604 -420.57701)
		(stroke
			(width 0.06477)
			(type default)
		)
		(layer "B.Cu")
	)
	(gr_line
		(start 39.35603 -413.4485)
		(end 39.62654 -413.17799)
		(stroke
			(width 0.06477)
			(type default)
		)
		(layer "B.Cu")
	)
	(gr_line
		(start 39.35603 -412.5849)
		(end 39.62654 -412.85541)
		(stroke
			(width 0.06477)
			(type default)
		)
		(layer "B.Cu")
	)
	(gr_line
		(start 39.573454 -420.76624)
		(end 39.184834 -420.76624)
		(stroke
			(width 0.06477)
			(type default)
		)
		(layer "B.Cu")
	)
	(gr_line
		(start 39.762684 -420.57701)
		(end 39.573454 -420.76624)
		(stroke
			(width 0.06477)
			(type default)
		)
		(layer "B.Cu")
	)
	(gr_line
		(start 39.763954 -420.25316)
		(end 38.994334 -420.25316)
		(stroke
			(width 0.06477)
			(type default)
		)
		(layer "B.Cu")
	)
	(gr_line
		(start 40.51046 -420.76624)
		(end 40.32123 -420.57701)
		(stroke
			(width 0.06477)
			(type default)
		)
		(layer "B.Cu")
	)
	(gr_line
		(start 40.89908 -420.76624)
		(end 40.51046 -420.76624)
		(stroke
			(width 0.06477)
			(type default)
		)
		(layer "B.Cu")
	)
	(gr_line
		(start 41.08831 -420.57701)
		(end 40.89908 -420.76624)
		(stroke
			(width 0.06477)
			(type default)
		)
		(layer "B.Cu")
	)
	(gr_line
		(start 41.08958 -420.25316)
		(end 40.31996 -420.25316)
		(stroke
			(width 0.06477)
			(type default)
		)
		(layer "B.Cu")
	)
	(gr_line
		(start 41.58869 -415.383726)
		(end 41.8592 -415.113216)
		(stroke
			(width 0.06477)
			(type default)
		)
		(layer "B.Cu")
	)
	(gr_line
		(start 41.58869 -414.520126)
		(end 41.8592 -414.790636)
		(stroke
			(width 0.06477)
			(type default)
		)
		(layer "B.Cu")
	)
	(gr_line
		(start 41.971468 -421.21201)
		(end 41.971468 -420.944294)
		(stroke
			(width 0.06477)
			(type default)
		)
		(layer "B.Cu")
	)
	(gr_line
		(start 42.034714 -423.057828)
		(end 42.305224 -422.787318)
		(stroke
			(width 0.06477)
			(type default)
		)
		(layer "B.Cu")
	)
	(gr_line
		(start 42.034714 -422.194228)
		(end 42.305224 -422.464738)
		(stroke
			(width 0.06477)
			(type default)
		)
		(layer "B.Cu")
	)
	(gr_line
		(start 42.24655 -421.487092)
		(end 41.971468 -421.21201)
		(stroke
			(width 0.06477)
			(type default)
		)
		(layer "B.Cu")
	)
	(gr_line
		(start 42.265854 -426.062648)
		(end 41.995344 -426.333158)
		(stroke
			(width 0.06477)
			(type default)
		)
		(layer "B.Cu")
	)
	(gr_line
		(start 42.265854 -425.740068)
		(end 41.995344 -425.469558)
		(stroke
			(width 0.06477)
			(type default)
		)
		(layer "B.Cu")
	)
	(gr_line
		(start 42.514266 -421.487092)
		(end 42.24655 -421.487092)
		(stroke
			(width 0.06477)
			(type default)
		)
		(layer "B.Cu")
	)
	(gr_line
		(start 42.744136 -421.259)
		(end 42.199814 -420.714424)
		(stroke
			(width 0.06477)
			(type default)
		)
		(layer "B.Cu")
	)
	(gr_line
		(start 42.979848 -425.196)
		(end 42.979848 -425.46397)
		(stroke
			(width 0.06477)
			(type default)
		)
		(layer "B.Cu")
	)
	(gr_line
		(start 43.209972 -420.44874)
		(end 43.485054 -420.723822)
		(stroke
			(width 0.06477)
			(type default)
		)
		(layer "B.Cu")
	)
	(gr_line
		(start 43.209972 -420.181024)
		(end 43.209972 -420.44874)
		(stroke
			(width 0.06477)
			(type default)
		)
		(layer "B.Cu")
	)
	(gr_line
		(start 43.25493 -424.920918)
		(end 42.979848 -425.196)
		(stroke
			(width 0.06477)
			(type default)
		)
		(layer "B.Cu")
	)
	(gr_line
		(start 43.438318 -419.951408)
		(end 43.98264 -420.495476)
		(stroke
			(width 0.06477)
			(type default)
		)
		(layer "B.Cu")
	)
	(gr_line
		(start 43.485054 -420.723822)
		(end 43.75277 -420.723822)
		(stroke
			(width 0.06477)
			(type default)
		)
		(layer "B.Cu")
	)
	(gr_line
		(start 43.5229 -424.920918)
		(end 43.25493 -424.920918)
		(stroke
			(width 0.06477)
			(type default)
		)
		(layer "B.Cu")
	)
	(gr_line
		(start 43.6245 -413.433768)
		(end 43.88231 -413.691578)
		(stroke
			(width 0.06477)
			(type default)
		)
		(layer "B.Cu")
	)
	(gr_line
		(start 43.6245 -413.111188)
		(end 43.88231 -412.853378)
		(stroke
			(width 0.06477)
			(type default)
		)
		(layer "B.Cu")
	)
	(gr_line
		(start 43.75277 -425.14901)
		(end 43.208194 -425.69384)
		(stroke
			(width 0.06477)
			(type default)
		)
		(layer "B.Cu")
	)
	(gr_line
		(start 43.90263 -423.773092)
		(end 44.09186 -423.962322)
		(stroke
			(width 0.06477)
			(type default)
		)
		(layer "B.Cu")
	)
	(gr_line
		(start 43.90263 -423.384472)
		(end 43.90263 -423.773092)
		(stroke
			(width 0.06477)
			(type default)
		)
		(layer "B.Cu")
	)
	(gr_line
		(start 44.09186 -423.195242)
		(end 43.90263 -423.384472)
		(stroke
			(width 0.06477)
			(type default)
		)
		(layer "B.Cu")
	)
	(gr_line
		(start 44.41571 -423.193972)
		(end 44.41571 -423.963592)
		(stroke
			(width 0.06477)
			(type default)
		)
		(layer "B.Cu")
	)
	(gr_line
		(start 44.41571 -413.691578)
		(end 44.67352 -413.433768)
		(stroke
			(width 0.06477)
			(type default)
		)
		(layer "B.Cu")
	)
	(gr_line
		(start 44.41571 -412.853378)
		(end 44.67352 -413.111188)
		(stroke
			(width 0.06477)
			(type default)
		)
		(layer "B.Cu")
	)
	(gr_line
		(start 49.300384 -408.784044)
		(end 49.596294 -409.079954)
		(stroke
			(width 0.06477)
			(type default)
		)
		(layer "B.Cu")
	)
	(gr_line
		(start 49.325784 -407.00452)
		(end 49.596294 -407.27503)
		(stroke
			(width 0.06477)
			(type default)
		)
		(layer "B.Cu")
	)
	(gr_line
		(start 49.596294 -409.759658)
		(end 49.325784 -410.030168)
		(stroke
			(width 0.06477)
			(type default)
		)
		(layer "B.Cu")
	)
	(gr_line
		(start 49.596294 -407.954734)
		(end 49.300384 -408.250644)
		(stroke
			(width 0.06477)
			(type default)
		)
		(layer "B.Cu")
	)
	(gr_line
		(start 49.918874 -409.759658)
		(end 50.189384 -410.030168)
		(stroke
			(width 0.06477)
			(type default)
		)
		(layer "B.Cu")
	)
	(gr_line
		(start 49.918874 -407.954734)
		(end 50.214784 -408.250644)
		(stroke
			(width 0.06477)
			(type default)
		)
		(layer "B.Cu")
	)
	(gr_line
		(start 49.970944 -419.377876)
		(end 49.973484 -419.377876)
		(stroke
			(width 0.06477)
			(type default)
		)
		(layer "B.Cu")
	)
	(gr_line
		(start 49.972214 -419.054026)
		(end 50.318924 -418.707316)
		(stroke
			(width 0.06477)
			(type default)
		)
		(layer "B.Cu")
	)
	(gr_line
		(start 49.973484 -419.377876)
		(end 49.970944 -419.377876)
		(stroke
			(width 0.06477)
			(type default)
		)
		(layer "B.Cu")
	)
	(gr_line
		(start 49.973484 -419.377876)
		(end 50.318924 -419.723316)
		(stroke
			(width 0.06477)
			(type default)
		)
		(layer "B.Cu")
	)
	(gr_line
		(start 50.189384 -407.00452)
		(end 49.918874 -407.27503)
		(stroke
			(width 0.06477)
			(type default)
		)
		(layer "B.Cu")
	)
	(gr_line
		(start 50.214784 -408.784044)
		(end 49.918874 -409.079954)
		(stroke
			(width 0.06477)
			(type default)
		)
		(layer "B.Cu")
	)
	(gr_line
		(start 50.318924 -419.723316)
		(end 49.973484 -419.377876)
		(stroke
			(width 0.06477)
			(type default)
		)
		(layer "B.Cu")
	)
	(gr_line
		(start 51.119024 -419.723316)
		(end 51.465734 -419.376606)
		(stroke
			(width 0.06477)
			(type default)
		)
		(layer "B.Cu")
	)
	(gr_line
		(start 51.119024 -418.707316)
		(end 51.465734 -419.054026)
		(stroke
			(width 0.06477)
			(type default)
		)
		(layer "B.Cu")
	)
	(gr_line
		(start 51.210464 -416.671506)
		(end 51.468274 -416.929316)
		(stroke
			(width 0.06477)
			(type default)
		)
		(layer "B.Cu")
	)
	(gr_line
		(start 51.210464 -416.348926)
		(end 51.468274 -416.091116)
		(stroke
			(width 0.06477)
			(type default)
		)
		(layer "B.Cu")
	)
	(gr_line
		(start 51.465734 -419.376606)
		(end 51.119024 -419.723316)
		(stroke
			(width 0.06477)
			(type default)
		)
		(layer "B.Cu")
	)
	(gr_line
		(start 51.91506 -419.376606)
		(end 51.927252 -419.376606)
		(stroke
			(width 0.06477)
			(type default)
		)
		(layer "B.Cu")
	)
	(gr_line
		(start 51.91633 -419.052756)
		(end 52.191666 -418.77742)
		(stroke
			(width 0.06477)
			(type default)
		)
		(layer "B.Cu")
	)
	(gr_line
		(start 51.927252 -419.376606)
		(end 51.91506 -419.376606)
		(stroke
			(width 0.06477)
			(type default)
		)
		(layer "B.Cu")
	)
	(gr_line
		(start 51.927252 -419.376606)
		(end 52.191666 -419.64102)
		(stroke
			(width 0.06477)
			(type default)
		)
		(layer "B.Cu")
	)
	(gr_line
		(start 52.001674 -416.929316)
		(end 52.259484 -416.671506)
		(stroke
			(width 0.06477)
			(type default)
		)
		(layer "B.Cu")
	)
	(gr_line
		(start 52.001674 -416.091116)
		(end 52.259484 -416.348926)
		(stroke
			(width 0.06477)
			(type default)
		)
		(layer "B.Cu")
	)
	(gr_line
		(start 52.191666 -419.64102)
		(end 51.927252 -419.376606)
		(stroke
			(width 0.06477)
			(type default)
		)
		(layer "B.Cu")
	)
	(gr_line
		(start 52.363624 -408.784044)
		(end 52.659534 -409.079954)
		(stroke
			(width 0.06477)
			(type default)
		)
		(layer "B.Cu")
	)
	(gr_line
		(start 52.374546 -181.374796)
		(end 52.692046 -181.057296)
		(stroke
			(width 0.127)
			(type default)
		)
		(layer "B.Cu")
	)
	(gr_line
		(start 52.389024 -407.00452)
		(end 52.659534 -407.27503)
		(stroke
			(width 0.06477)
			(type default)
		)
		(layer "B.Cu")
	)
	(gr_line
		(start 52.659534 -409.759658)
		(end 52.389024 -410.030168)
		(stroke
			(width 0.06477)
			(type default)
		)
		(layer "B.Cu")
	)
	(gr_line
		(start 52.659534 -407.954734)
		(end 52.363624 -408.250644)
		(stroke
			(width 0.06477)
			(type default)
		)
		(layer "B.Cu")
	)
	(gr_line
		(start 52.982114 -409.759658)
		(end 53.252624 -410.030168)
		(stroke
			(width 0.06477)
			(type default)
		)
		(layer "B.Cu")
	)
	(gr_line
		(start 52.982114 -407.954734)
		(end 53.278024 -408.250644)
		(stroke
			(width 0.06477)
			(type default)
		)
		(layer "B.Cu")
	)
	(gr_line
		(start 53.252624 -407.00452)
		(end 52.982114 -407.27503)
		(stroke
			(width 0.06477)
			(type default)
		)
		(layer "B.Cu")
	)
	(gr_line
		(start 53.278024 -408.784044)
		(end 52.982114 -409.079954)
		(stroke
			(width 0.06477)
			(type default)
		)
		(layer "B.Cu")
	)
	(gr_line
		(start 53.390546 -181.374796)
		(end 53.073046 -181.057296)
		(stroke
			(width 0.127)
			(type default)
		)
		(layer "B.Cu")
	)
	(gr_line
		(start 55.426864 -408.784044)
		(end 55.722774 -409.079954)
		(stroke
			(width 0.06477)
			(type default)
		)
		(layer "B.Cu")
	)
	(gr_line
		(start 55.452264 -407.00452)
		(end 55.722774 -407.27503)
		(stroke
			(width 0.06477)
			(type default)
		)
		(layer "B.Cu")
	)
	(gr_line
		(start 55.722774 -409.759658)
		(end 55.452264 -410.030168)
		(stroke
			(width 0.06477)
			(type default)
		)
		(layer "B.Cu")
	)
	(gr_line
		(start 55.722774 -407.954734)
		(end 55.426864 -408.250644)
		(stroke
			(width 0.06477)
			(type default)
		)
		(layer "B.Cu")
	)
	(gr_line
		(start 56.045354 -409.759658)
		(end 56.315864 -410.030168)
		(stroke
			(width 0.06477)
			(type default)
		)
		(layer "B.Cu")
	)
	(gr_line
		(start 56.045354 -407.954734)
		(end 56.341264 -408.250644)
		(stroke
			(width 0.06477)
			(type default)
		)
		(layer "B.Cu")
	)
	(gr_line
		(start 56.315864 -407.00452)
		(end 56.045354 -407.27503)
		(stroke
			(width 0.06477)
			(type default)
		)
		(layer "B.Cu")
	)
	(gr_line
		(start 56.341264 -408.784044)
		(end 56.045354 -409.079954)
		(stroke
			(width 0.06477)
			(type default)
		)
		(layer "B.Cu")
	)
	(gr_line
		(start 58.490104 -408.784044)
		(end 58.786014 -409.079954)
		(stroke
			(width 0.06477)
			(type default)
		)
		(layer "B.Cu")
	)
	(gr_line
		(start 58.515504 -407.00452)
		(end 58.786014 -407.27503)
		(stroke
			(width 0.06477)
			(type default)
		)
		(layer "B.Cu")
	)
	(gr_line
		(start 58.786014 -409.759658)
		(end 58.515504 -410.030168)
		(stroke
			(width 0.06477)
			(type default)
		)
		(layer "B.Cu")
	)
	(gr_line
		(start 58.786014 -407.954734)
		(end 58.490104 -408.250644)
		(stroke
			(width 0.06477)
			(type default)
		)
		(layer "B.Cu")
	)
	(gr_line
		(start 59.108594 -409.759658)
		(end 59.379104 -410.030168)
		(stroke
			(width 0.06477)
			(type default)
		)
		(layer "B.Cu")
	)
	(gr_line
		(start 59.108594 -407.954734)
		(end 59.404504 -408.250644)
		(stroke
			(width 0.06477)
			(type default)
		)
		(layer "B.Cu")
	)
	(gr_line
		(start 59.379104 -407.00452)
		(end 59.108594 -407.27503)
		(stroke
			(width 0.06477)
			(type default)
		)
		(layer "B.Cu")
	)
	(gr_line
		(start 59.404504 -408.784044)
		(end 59.108594 -409.079954)
		(stroke
			(width 0.06477)
			(type default)
		)
		(layer "B.Cu")
	)
	(gr_line
		(start 61.553344 -408.784044)
		(end 61.849254 -409.079954)
		(stroke
			(width 0.06477)
			(type default)
		)
		(layer "B.Cu")
	)
	(gr_line
		(start 61.578744 -407.00452)
		(end 61.849254 -407.27503)
		(stroke
			(width 0.06477)
			(type default)
		)
		(layer "B.Cu")
	)
	(gr_line
		(start 61.849254 -409.759658)
		(end 61.578744 -410.030168)
		(stroke
			(width 0.06477)
			(type default)
		)
		(layer "B.Cu")
	)
	(gr_line
		(start 61.849254 -407.954734)
		(end 61.553344 -408.250644)
		(stroke
			(width 0.06477)
			(type default)
		)
		(layer "B.Cu")
	)
	(gr_line
		(start 62.171834 -409.759658)
		(end 62.442344 -410.030168)
		(stroke
			(width 0.06477)
			(type default)
		)
		(layer "B.Cu")
	)
	(gr_line
		(start 62.171834 -407.954734)
		(end 62.467744 -408.250644)
		(stroke
			(width 0.06477)
			(type default)
		)
		(layer "B.Cu")
	)
	(gr_line
		(start 62.442344 -407.00452)
		(end 62.171834 -407.27503)
		(stroke
			(width 0.06477)
			(type default)
		)
		(layer "B.Cu")
	)
	(gr_line
		(start 62.467744 -408.784044)
		(end 62.171834 -409.079954)
		(stroke
			(width 0.06477)
			(type default)
		)
		(layer "B.Cu")
	)
	(gr_line
		(start 64.616584 -408.784044)
		(end 64.912494 -409.079954)
		(stroke
			(width 0.06477)
			(type default)
		)
		(layer "B.Cu")
	)
	(gr_line
		(start 64.641984 -407.00452)
		(end 64.912494 -407.27503)
		(stroke
			(width 0.06477)
			(type default)
		)
		(layer "B.Cu")
	)
	(gr_line
		(start 64.912494 -409.759658)
		(end 64.641984 -410.030168)
		(stroke
			(width 0.06477)
			(type default)
		)
		(layer "B.Cu")
	)
	(gr_line
		(start 64.912494 -407.954734)
		(end 64.616584 -408.250644)
		(stroke
			(width 0.06477)
			(type default)
		)
		(layer "B.Cu")
	)
	(gr_line
		(start 65.235074 -409.759658)
		(end 65.505584 -410.030168)
		(stroke
			(width 0.06477)
			(type default)
		)
		(layer "B.Cu")
	)
	(gr_line
		(start 65.235074 -407.954734)
		(end 65.530984 -408.250644)
		(stroke
			(width 0.06477)
			(type default)
		)
		(layer "B.Cu")
	)
	(gr_line
		(start 65.505584 -407.00452)
		(end 65.235074 -407.27503)
		(stroke
			(width 0.06477)
			(type default)
		)
		(layer "B.Cu")
	)
	(gr_line
		(start 65.530984 -408.784044)
		(end 65.235074 -409.079954)
		(stroke
			(width 0.06477)
			(type default)
		)
		(layer "B.Cu")
	)
	(gr_line
		(start 67.679824 -408.784044)
		(end 67.975734 -409.079954)
		(stroke
			(width 0.06477)
			(type default)
		)
		(layer "B.Cu")
	)
	(gr_line
		(start 67.705224 -407.00452)
		(end 67.975734 -407.27503)
		(stroke
			(width 0.06477)
			(type default)
		)
		(layer "B.Cu")
	)
	(gr_line
		(start 67.975734 -409.759658)
		(end 67.705224 -410.030168)
		(stroke
			(width 0.06477)
			(type default)
		)
		(layer "B.Cu")
	)
	(gr_line
		(start 67.975734 -407.954734)
		(end 67.679824 -408.250644)
		(stroke
			(width 0.06477)
			(type default)
		)
		(layer "B.Cu")
	)
	(gr_line
		(start 68.298314 -409.759658)
		(end 68.568824 -410.030168)
		(stroke
			(width 0.06477)
			(type default)
		)
		(layer "B.Cu")
	)
	(gr_line
		(start 68.298314 -407.954734)
		(end 68.594224 -408.250644)
		(stroke
			(width 0.06477)
			(type default)
		)
		(layer "B.Cu")
	)
	(gr_line
		(start 68.568824 -407.00452)
		(end 68.298314 -407.27503)
		(stroke
			(width 0.06477)
			(type default)
		)
		(layer "B.Cu")
	)
	(gr_line
		(start 68.594224 -408.784044)
		(end 68.298314 -409.079954)
		(stroke
			(width 0.06477)
			(type default)
		)
		(layer "B.Cu")
	)
	(gr_line
		(start 70.743064 -408.784044)
		(end 71.038974 -409.079954)
		(stroke
			(width 0.06477)
			(type default)
		)
		(layer "B.Cu")
	)
	(gr_line
		(start 70.768464 -407.00452)
		(end 71.038974 -407.27503)
		(stroke
			(width 0.06477)
			(type default)
		)
		(layer "B.Cu")
	)
	(gr_line
		(start 71.038974 -409.759658)
		(end 70.768464 -410.030168)
		(stroke
			(width 0.06477)
			(type default)
		)
		(layer "B.Cu")
	)
	(gr_line
		(start 71.038974 -407.954734)
		(end 70.743064 -408.250644)
		(stroke
			(width 0.06477)
			(type default)
		)
		(layer "B.Cu")
	)
	(gr_line
		(start 71.102982 -145.973292)
		(end 69.620384 -145.973292)
		(stroke
			(width 0.127)
			(type default)
		)
		(layer "B.Cu")
	)
	(gr_line
		(start 71.355712 -145.720562)
		(end 71.102982 -145.973292)
		(stroke
			(width 0.127)
			(type default)
		)
		(layer "B.Cu")
	)
	(gr_line
		(start 71.361554 -409.759658)
		(end 71.632064 -410.030168)
		(stroke
			(width 0.06477)
			(type default)
		)
		(layer "B.Cu")
	)
	(gr_line
		(start 71.361554 -407.954734)
		(end 71.657464 -408.250644)
		(stroke
			(width 0.06477)
			(type default)
		)
		(layer "B.Cu")
	)
	(gr_line
		(start 71.632064 -407.00452)
		(end 71.361554 -407.27503)
		(stroke
			(width 0.06477)
			(type default)
		)
		(layer "B.Cu")
	)
	(gr_line
		(start 71.657464 -408.784044)
		(end 71.361554 -409.079954)
		(stroke
			(width 0.06477)
			(type default)
		)
		(layer "B.Cu")
	)
	(gr_line
		(start 71.737982 -145.725134)
		(end 72.08774 -146.074892)
		(stroke
			(width 0.127)
			(type default)
		)
		(layer "B.Cu")
	)
	(gr_line
		(start 71.737982 -145.719292)
		(end 71.737982 -145.725134)
		(stroke
			(width 0.127)
			(type default)
		)
		(layer "B.Cu")
	)
	(gr_line
		(start 72.08774 -146.074892)
		(end 73.512934 -146.074892)
		(stroke
			(width 0.127)
			(type default)
		)
		(layer "B.Cu")
	)
	(gr_line
		(start 73.806304 -408.784044)
		(end 74.102214 -409.079954)
		(stroke
			(width 0.06477)
			(type default)
		)
		(layer "B.Cu")
	)
	(gr_line
		(start 73.831704 -407.00452)
		(end 74.102214 -407.27503)
		(stroke
			(width 0.06477)
			(type default)
		)
		(layer "B.Cu")
	)
	(gr_line
		(start 74.102214 -409.759658)
		(end 73.831704 -410.030168)
		(stroke
			(width 0.06477)
			(type default)
		)
		(layer "B.Cu")
	)
	(gr_line
		(start 74.102214 -407.954734)
		(end 73.806304 -408.250644)
		(stroke
			(width 0.06477)
			(type default)
		)
		(layer "B.Cu")
	)
	(gr_line
		(start 74.424794 -409.759658)
		(end 74.695304 -410.030168)
		(stroke
			(width 0.06477)
			(type default)
		)
		(layer "B.Cu")
	)
	(gr_line
		(start 74.424794 -407.954734)
		(end 74.720704 -408.250644)
		(stroke
			(width 0.06477)
			(type default)
		)
		(layer "B.Cu")
	)
	(gr_line
		(start 74.695304 -407.00452)
		(end 74.424794 -407.27503)
		(stroke
			(width 0.06477)
			(type default)
		)
		(layer "B.Cu")
	)
	(gr_line
		(start 74.720704 -408.784044)
		(end 74.424794 -409.079954)
		(stroke
			(width 0.06477)
			(type default)
		)
		(layer "B.Cu")
	)
	(gr_line
		(start 75.249532 -420.651178)
		(end 75.520042 -420.921688)
		(stroke
			(width 0.06477)
			(type default)
		)
		(layer "B.Cu")
	)
	(gr_line
		(start 75.249532 -420.328598)
		(end 75.520042 -420.058088)
		(stroke
			(width 0.06477)
			(type default)
		)
		(layer "B.Cu")
	)
	(gr_line
		(start 76.869544 -408.784044)
		(end 77.165454 -409.079954)
		(stroke
			(width 0.06477)
			(type default)
		)
		(layer "B.Cu")
	)
	(gr_line
		(start 76.894944 -407.00452)
		(end 77.165454 -407.27503)
		(stroke
			(width 0.06477)
			(type default)
		)
		(layer "B.Cu")
	)
	(gr_line
		(start 77.165454 -409.759658)
		(end 76.894944 -410.030168)
		(stroke
			(width 0.06477)
			(type default)
		)
		(layer "B.Cu")
	)
	(gr_line
		(start 77.165454 -407.954734)
		(end 76.869544 -408.250644)
		(stroke
			(width 0.06477)
			(type default)
		)
		(layer "B.Cu")
	)
	(gr_line
		(start 77.488034 -409.759658)
		(end 77.758544 -410.030168)
		(stroke
			(width 0.06477)
			(type default)
		)
		(layer "B.Cu")
	)
	(gr_line
		(start 77.488034 -407.954734)
		(end 77.783944 -408.250644)
		(stroke
			(width 0.06477)
			(type default)
		)
		(layer "B.Cu")
	)
	(gr_line
		(start 77.758544 -407.00452)
		(end 77.488034 -407.27503)
		(stroke
			(width 0.06477)
			(type default)
		)
		(layer "B.Cu")
	)
	(gr_line
		(start 77.77226 -418.10559)
		(end 78.04277 -418.3761)
		(stroke
			(width 0.06477)
			(type default)
		)
		(layer "B.Cu")
	)
	(gr_line
		(start 77.77226 -417.78301)
		(end 78.04277 -417.5125)
		(stroke
			(width 0.06477)
			(type default)
		)
		(layer "B.Cu")
	)
	(gr_line
		(start 77.783944 -408.784044)
		(end 77.488034 -409.079954)
		(stroke
			(width 0.06477)
			(type default)
		)
		(layer "B.Cu")
	)
	(gr_line
		(start 79.932784 -408.784044)
		(end 80.228694 -409.079954)
		(stroke
			(width 0.06477)
			(type default)
		)
		(layer "B.Cu")
	)
	(gr_line
		(start 79.958184 -407.00452)
		(end 80.228694 -407.27503)
		(stroke
			(width 0.06477)
			(type default)
		)
		(layer "B.Cu")
	)
	(gr_line
		(start 80.228694 -409.759658)
		(end 79.958184 -410.030168)
		(stroke
			(width 0.06477)
			(type default)
		)
		(layer "B.Cu")
	)
	(gr_line
		(start 80.228694 -407.954734)
		(end 79.932784 -408.250644)
		(stroke
			(width 0.06477)
			(type default)
		)
		(layer "B.Cu")
	)
	(gr_line
		(start 80.551274 -409.759658)
		(end 80.821784 -410.030168)
		(stroke
			(width 0.06477)
			(type default)
		)
		(layer "B.Cu")
	)
	(gr_line
		(start 80.551274 -407.954734)
		(end 80.847184 -408.250644)
		(stroke
			(width 0.06477)
			(type default)
		)
		(layer "B.Cu")
	)
	(gr_line
		(start 80.821784 -407.00452)
		(end 80.551274 -407.27503)
		(stroke
			(width 0.06477)
			(type default)
		)
		(layer "B.Cu")
	)
	(gr_line
		(start 80.847184 -408.784044)
		(end 80.551274 -409.079954)
		(stroke
			(width 0.06477)
			(type default)
		)
		(layer "B.Cu")
	)
	(gr_line
		(start 82.996024 -408.784044)
		(end 83.291934 -409.079954)
		(stroke
			(width 0.06477)
			(type default)
		)
		(layer "B.Cu")
	)
	(gr_line
		(start 83.021424 -407.00452)
		(end 83.291934 -407.27503)
		(stroke
			(width 0.06477)
			(type default)
		)
		(layer "B.Cu")
	)
	(gr_line
		(start 83.291934 -409.759658)
		(end 83.021424 -410.030168)
		(stroke
			(width 0.06477)
			(type default)
		)
		(layer "B.Cu")
	)
	(gr_line
		(start 83.291934 -407.954734)
		(end 82.996024 -408.250644)
		(stroke
			(width 0.06477)
			(type default)
		)
		(layer "B.Cu")
	)
	(gr_line
		(start 83.614514 -409.759658)
		(end 83.885024 -410.030168)
		(stroke
			(width 0.06477)
			(type default)
		)
		(layer "B.Cu")
	)
	(gr_line
		(start 83.614514 -407.954734)
		(end 83.910424 -408.250644)
		(stroke
			(width 0.06477)
			(type default)
		)
		(layer "B.Cu")
	)
	(gr_line
		(start 83.885024 -407.00452)
		(end 83.614514 -407.27503)
		(stroke
			(width 0.06477)
			(type default)
		)
		(layer "B.Cu")
	)
	(gr_line
		(start 83.910424 -408.784044)
		(end 83.614514 -409.079954)
		(stroke
			(width 0.06477)
			(type default)
		)
		(layer "B.Cu")
	)
	(gr_line
		(start 86.059264 -408.784044)
		(end 86.355174 -409.079954)
		(stroke
			(width 0.06477)
			(type default)
		)
		(layer "B.Cu")
	)
	(gr_line
		(start 86.084664 -407.00452)
		(end 86.355174 -407.27503)
		(stroke
			(width 0.06477)
			(type default)
		)
		(layer "B.Cu")
	)
	(gr_line
		(start 86.355174 -409.759658)
		(end 86.084664 -410.030168)
		(stroke
			(width 0.06477)
			(type default)
		)
		(layer "B.Cu")
	)
	(gr_line
		(start 86.355174 -407.954734)
		(end 86.059264 -408.250644)
		(stroke
			(width 0.06477)
			(type default)
		)
		(layer "B.Cu")
	)
	(gr_line
		(start 86.677754 -409.759658)
		(end 86.948264 -410.030168)
		(stroke
			(width 0.06477)
			(type default)
		)
		(layer "B.Cu")
	)
	(gr_line
		(start 86.677754 -407.954734)
		(end 86.973664 -408.250644)
		(stroke
			(width 0.06477)
			(type default)
		)
		(layer "B.Cu")
	)
	(gr_line
		(start 86.948264 -407.00452)
		(end 86.677754 -407.27503)
		(stroke
			(width 0.06477)
			(type default)
		)
		(layer "B.Cu")
	)
	(gr_line
		(start 86.973664 -408.784044)
		(end 86.677754 -409.079954)
		(stroke
			(width 0.06477)
			(type default)
		)
		(layer "B.Cu")
	)
	(gr_line
		(start 89.122504 -408.784044)
		(end 89.418414 -409.079954)
		(stroke
			(width 0.06477)
			(type default)
		)
		(layer "B.Cu")
	)
	(gr_line
		(start 89.147904 -407.00452)
		(end 89.418414 -407.27503)
		(stroke
			(width 0.06477)
			(type default)
		)
		(layer "B.Cu")
	)
	(gr_line
		(start 89.418414 -409.759658)
		(end 89.147904 -410.030168)
		(stroke
			(width 0.06477)
			(type default)
		)
		(layer "B.Cu")
	)
	(gr_line
		(start 89.418414 -407.954734)
		(end 89.122504 -408.250644)
		(stroke
			(width 0.06477)
			(type default)
		)
		(layer "B.Cu")
	)
	(gr_line
		(start 89.740994 -409.759658)
		(end 90.011504 -410.030168)
		(stroke
			(width 0.06477)
			(type default)
		)
		(layer "B.Cu")
	)
	(gr_line
		(start 89.740994 -407.954734)
		(end 90.036904 -408.250644)
		(stroke
			(width 0.06477)
			(type default)
		)
		(layer "B.Cu")
	)
	(gr_line
		(start 90.011504 -407.00452)
		(end 89.740994 -407.27503)
		(stroke
			(width 0.06477)
			(type default)
		)
		(layer "B.Cu")
	)
	(gr_line
		(start 90.036904 -408.784044)
		(end 89.740994 -409.079954)
		(stroke
			(width 0.06477)
			(type default)
		)
		(layer "B.Cu")
	)
	(gr_line
		(start 92.185744 -408.784044)
		(end 92.481654 -409.079954)
		(stroke
			(width 0.06477)
			(type default)
		)
		(layer "B.Cu")
	)
	(gr_line
		(start 92.211144 -407.00452)
		(end 92.481654 -407.27503)
		(stroke
			(width 0.06477)
			(type default)
		)
		(layer "B.Cu")
	)
	(gr_line
		(start 92.481654 -409.759658)
		(end 92.211144 -410.030168)
		(stroke
			(width 0.06477)
			(type default)
		)
		(layer "B.Cu")
	)
	(gr_line
		(start 92.481654 -407.954734)
		(end 92.185744 -408.250644)
		(stroke
			(width 0.06477)
			(type default)
		)
		(layer "B.Cu")
	)
	(gr_line
		(start 92.804234 -409.759658)
		(end 93.074744 -410.030168)
		(stroke
			(width 0.06477)
			(type default)
		)
		(layer "B.Cu")
	)
	(gr_line
		(start 92.804234 -407.954734)
		(end 93.100144 -408.250644)
		(stroke
			(width 0.06477)
			(type default)
		)
		(layer "B.Cu")
	)
	(gr_line
		(start 93.074744 -407.00452)
		(end 92.804234 -407.27503)
		(stroke
			(width 0.06477)
			(type default)
		)
		(layer "B.Cu")
	)
	(gr_line
		(start 93.100144 -408.784044)
		(end 92.804234 -409.079954)
		(stroke
			(width 0.06477)
			(type default)
		)
		(layer "B.Cu")
	)
	(gr_line
		(start 95.248984 -408.784044)
		(end 95.544894 -409.079954)
		(stroke
			(width 0.06477)
			(type default)
		)
		(layer "B.Cu")
	)
	(gr_line
		(start 95.274384 -407.00452)
		(end 95.544894 -407.27503)
		(stroke
			(width 0.06477)
			(type default)
		)
		(layer "B.Cu")
	)
	(gr_line
		(start 95.544894 -409.759658)
		(end 95.274384 -410.030168)
		(stroke
			(width 0.06477)
			(type default)
		)
		(layer "B.Cu")
	)
	(gr_line
		(start 95.544894 -407.954734)
		(end 95.248984 -408.250644)
		(stroke
			(width 0.06477)
			(type default)
		)
		(layer "B.Cu")
	)
	(gr_line
		(start 95.867474 -409.759658)
		(end 96.137984 -410.030168)
		(stroke
			(width 0.06477)
			(type default)
		)
		(layer "B.Cu")
	)
	(gr_line
		(start 95.867474 -407.954734)
		(end 96.163384 -408.250644)
		(stroke
			(width 0.06477)
			(type default)
		)
		(layer "B.Cu")
	)
	(gr_line
		(start 96.137984 -407.00452)
		(end 95.867474 -407.27503)
		(stroke
			(width 0.06477)
			(type default)
		)
		(layer "B.Cu")
	)
	(gr_line
		(start 96.163384 -408.784044)
		(end 95.867474 -409.079954)
		(stroke
			(width 0.06477)
			(type default)
		)
		(layer "B.Cu")
	)
	(gr_line
		(start 99.273614 3.091434)
		(end 98.621342 3.273298)
		(stroke
			(width 0.06477)
			(type default)
		)
		(layer "B.Cu")
	)
	(gr_line
		(start 99.273614 3.955034)
		(end 98.621342 3.77317)
		(stroke
			(width 0.06477)
			(type default)
		)
		(layer "B.Cu")
	)
	(gr_line
		(start 102.38105 -223.424496)
		(end 102.69474 -223.424496)
		(stroke
			(width 0.0381)
			(type default)
		)
		(layer "B.Cu")
	)
	(gr_line
		(start 102.68966 -221.193614)
		(end 102.68966 -221.174564)
		(stroke
			(width 0.0381)
			(type default)
		)
		(layer "B.Cu")
	)
	(gr_line
		(start 102.69474 -223.424496)
		(end 102.759256 -223.35998)
		(stroke
			(width 0.0381)
			(type default)
		)
		(layer "B.Cu")
	)
	(gr_line
		(start 102.7557 -221.804992)
		(end 102.7557 -221.804484)
		(stroke
			(width 0.0381)
			(type default)
		)
		(layer "B.Cu")
	)
	(gr_line
		(start 102.7557 -221.259654)
		(end 102.68966 -221.193614)
		(stroke
			(width 0.0381)
			(type default)
		)
		(layer "B.Cu")
	)
	(gr_arc
		(start 102.76205 -223.338898)
		(mid 102.760554 -223.349426)
		(end 102.759256 -223.35998)
		(stroke
			(width 0.0381)
			(type default)
		)
		(layer "B.Cu")
	)
	(gr_line
		(start 102.9462 -221.259654)
		(end 103.01224 -221.193614)
		(stroke
			(width 0.0381)
			(type default)
		)
		(layer "B.Cu")
	)
	(gr_line
		(start 103.007414 -223.424496)
		(end 102.951534 -223.368616)
		(stroke
			(width 0.0381)
			(type default)
		)
		(layer "B.Cu")
	)
	(gr_line
		(start 103.01224 -221.193614)
		(end 103.01224 -221.174564)
		(stroke
			(width 0.0381)
			(type default)
		)
		(layer "B.Cu")
	)
	(gr_line
		(start 103.321104 -223.424496)
		(end 103.007414 -223.424496)
		(stroke
			(width 0.0381)
			(type default)
		)
		(layer "B.Cu")
	)
	(gr_line
		(start 103.398574 -220.119702)
		(end 103.933752 -219.58427)
		(stroke
			(width 0.06477)
			(type default)
		)
		(layer "B.Cu")
	)
	(gr_line
		(start 103.62819 -220.348048)
		(end 103.89235 -220.348048)
		(stroke
			(width 0.06477)
			(type default)
		)
		(layer "B.Cu")
	)
	(gr_line
		(start 103.634794 -225.044508)
		(end 103.321104 -225.044508)
		(stroke
			(width 0.0381)
			(type default)
		)
		(layer "B.Cu")
	)
	(gr_line
		(start 103.69931 -224.979992)
		(end 103.634794 -225.044508)
		(stroke
			(width 0.0381)
			(type default)
		)
		(layer "B.Cu")
	)
	(gr_arc
		(start 103.702104 -224.95891)
		(mid 103.700608 -224.969438)
		(end 103.69931 -224.979992)
		(stroke
			(width 0.0381)
			(type default)
		)
		(layer "B.Cu")
	)
	(gr_line
		(start 103.891588 -224.988628)
		(end 103.947468 -225.044508)
		(stroke
			(width 0.0381)
			(type default)
		)
		(layer "B.Cu")
	)
	(gr_line
		(start 103.89235 -220.348048)
		(end 104.162098 -220.0783)
		(stroke
			(width 0.06477)
			(type default)
		)
		(layer "B.Cu")
	)
	(gr_line
		(start 103.947468 -225.044508)
		(end 104.261158 -225.044508)
		(stroke
			(width 0.0381)
			(type default)
		)
		(layer "B.Cu")
	)
	(gr_line
		(start 104.162098 -220.0783)
		(end 104.162098 -219.81414)
		(stroke
			(width 0.06477)
			(type default)
		)
		(layer "B.Cu")
	)
	(gr_line
		(start 104.203246 -219.315284)
		(end 104.738424 -218.779852)
		(stroke
			(width 0.06477)
			(type default)
		)
		(layer "B.Cu")
	)
	(gr_line
		(start 104.432862 -219.543376)
		(end 104.697276 -219.543376)
		(stroke
			(width 0.06477)
			(type default)
		)
		(layer "B.Cu")
	)
	(gr_line
		(start 104.450134 -223.745806)
		(end 104.448864 -223.746568)
		(stroke
			(width 0.0381)
			(type default)
		)
		(layer "B.Cu")
	)
	(gr_line
		(start 104.544114 -223.911922)
		(end 104.543606 -223.912176)
		(stroke
			(width 0.0381)
			(type default)
		)
		(layer "B.Cu")
	)
	(gr_line
		(start 104.54513 -223.911414)
		(end 104.544114 -223.911922)
		(stroke
			(width 0.0381)
			(type default)
		)
		(layer "B.Cu")
	)
	(gr_line
		(start 104.569768 -221.193614)
		(end 104.635808 -221.259654)
		(stroke
			(width 0.0381)
			(type default)
		)
		(layer "B.Cu")
	)
	(gr_line
		(start 104.569768 -221.174564)
		(end 104.569768 -221.193614)
		(stroke
			(width 0.0381)
			(type default)
		)
		(layer "B.Cu")
	)
	(gr_line
		(start 104.697276 -219.543376)
		(end 104.96677 -219.273628)
		(stroke
			(width 0.06477)
			(type default)
		)
		(layer "B.Cu")
	)
	(gr_line
		(start 104.892348 -221.193614)
		(end 104.826308 -221.259654)
		(stroke
			(width 0.0381)
			(type default)
		)
		(layer "B.Cu")
	)
	(gr_line
		(start 104.892348 -221.174564)
		(end 104.892348 -221.193614)
		(stroke
			(width 0.0381)
			(type default)
		)
		(layer "B.Cu")
	)
	(gr_arc
		(start 104.905556 -222.284544)
		(mid 104.909231 -222.286717)
		(end 104.912922 -222.288862)
		(stroke
			(width 0.0381)
			(type default)
		)
		(layer "B.Cu")
	)
	(gr_line
		(start 104.91978 -222.292926)
		(end 104.920034 -222.292926)
		(stroke
			(width 0.0381)
			(type default)
		)
		(layer "B.Cu")
	)
	(gr_line
		(start 104.96677 -219.273628)
		(end 104.96677 -219.009468)
		(stroke
			(width 0.06477)
			(type default)
		)
		(layer "B.Cu")
	)
	(gr_arc
		(start 105.015284 -222.127826)
		(mid 105.014269 -222.12719)
		(end 105.013252 -222.126556)
		(stroke
			(width 0.0381)
			(type default)
		)
		(layer "B.Cu")
	)
	(gr_line
		(start 105.935018 -217.67927)
		(end 106.551984 -217.240612)
		(stroke
			(width 0.06477)
			(type default)
		)
		(layer "B.Cu")
	)
	(gr_line
		(start 106.123486 -217.942668)
		(end 106.38409 -217.98661)
		(stroke
			(width 0.06477)
			(type default)
		)
		(layer "B.Cu")
	)
	(gr_line
		(start 106.38409 -217.98661)
		(end 106.694732 -217.765884)
		(stroke
			(width 0.06477)
			(type default)
		)
		(layer "B.Cu")
	)
	(gr_line
		(start 106.694732 -217.765884)
		(end 106.738674 -217.50528)
		(stroke
			(width 0.06477)
			(type default)
		)
		(layer "B.Cu")
	)
	(gr_line
		(start 107.114086 -219.20073)
		(end 106.849926 -219.15628)
		(stroke
			(width 0.06477)
			(type default)
		)
		(layer "B.Cu")
	)
	(gr_line
		(start 107.15371 -216.812622)
		(end 107.77093 -216.37371)
		(stroke
			(width 0.06477)
			(type default)
		)
		(layer "B.Cu")
	)
	(gr_line
		(start 107.28706 -218.447874)
		(end 106.661712 -218.892882)
		(stroke
			(width 0.06477)
			(type default)
		)
		(layer "B.Cu")
	)
	(gr_line
		(start 107.342432 -217.075766)
		(end 107.602782 -217.119962)
		(stroke
			(width 0.06477)
			(type default)
		)
		(layer "B.Cu")
	)
	(gr_line
		(start 107.429046 -218.976956)
		(end 107.114086 -219.20073)
		(stroke
			(width 0.06477)
			(type default)
		)
		(layer "B.Cu")
	)
	(gr_line
		(start 107.47375 -218.712542)
		(end 107.429046 -218.976956)
		(stroke
			(width 0.06477)
			(type default)
		)
		(layer "B.Cu")
	)
	(gr_line
		(start 107.602782 -217.119962)
		(end 107.913424 -216.898982)
		(stroke
			(width 0.06477)
			(type default)
		)
		(layer "B.Cu")
	)
	(gr_line
		(start 107.913424 -216.898982)
		(end 107.95762 -216.638378)
		(stroke
			(width 0.06477)
			(type default)
		)
		(layer "B.Cu")
	)
	(gr_line
		(start 108.05414 -218.532202)
		(end 107.78998 -218.487752)
		(stroke
			(width 0.06477)
			(type default)
		)
		(layer "B.Cu")
	)
	(gr_line
		(start 108.22686 -217.7796)
		(end 107.601512 -218.224354)
		(stroke
			(width 0.06477)
			(type default)
		)
		(layer "B.Cu")
	)
	(gr_line
		(start 108.3691 -218.308428)
		(end 108.05414 -218.532202)
		(stroke
			(width 0.06477)
			(type default)
		)
		(layer "B.Cu")
	)
	(gr_line
		(start 108.41355 -218.044268)
		(end 108.3691 -218.308428)
		(stroke
			(width 0.06477)
			(type default)
		)
		(layer "B.Cu")
	)
	(gr_line
		(start 108.413804 -218.042744)
		(end 108.413804 -218.04249)
		(stroke
			(width 0.06477)
			(type default)
		)
		(layer "B.Cu")
	)
	(gr_line
		(start 116.400326 -408.784044)
		(end 116.696236 -409.079954)
		(stroke
			(width 0.06477)
			(type default)
		)
		(layer "B.Cu")
	)
	(gr_line
		(start 116.425726 -407.00452)
		(end 116.696236 -407.27503)
		(stroke
			(width 0.06477)
			(type default)
		)
		(layer "B.Cu")
	)
	(gr_line
		(start 116.696236 -409.759658)
		(end 116.425726 -410.030168)
		(stroke
			(width 0.06477)
			(type default)
		)
		(layer "B.Cu")
	)
	(gr_line
		(start 116.696236 -407.954734)
		(end 116.400326 -408.250644)
		(stroke
			(width 0.06477)
			(type default)
		)
		(layer "B.Cu")
	)
	(gr_line
		(start 117.018816 -409.759658)
		(end 117.289326 -410.030168)
		(stroke
			(width 0.06477)
			(type default)
		)
		(layer "B.Cu")
	)
	(gr_line
		(start 117.018816 -407.954734)
		(end 117.314726 -408.250644)
		(stroke
			(width 0.06477)
			(type default)
		)
		(layer "B.Cu")
	)
	(gr_line
		(start 117.289326 -407.00452)
		(end 117.018816 -407.27503)
		(stroke
			(width 0.06477)
			(type default)
		)
		(layer "B.Cu")
	)
	(gr_line
		(start 117.314726 -408.784044)
		(end 117.018816 -409.079954)
		(stroke
			(width 0.06477)
			(type default)
		)
		(layer "B.Cu")
	)
	(gr_line
		(start 119.463566 -408.784044)
		(end 119.759476 -409.079954)
		(stroke
			(width 0.06477)
			(type default)
		)
		(layer "B.Cu")
	)
	(gr_line
		(start 119.488966 -407.00452)
		(end 119.759476 -407.27503)
		(stroke
			(width 0.06477)
			(type default)
		)
		(layer "B.Cu")
	)
	(gr_line
		(start 119.759476 -409.759658)
		(end 119.488966 -410.030168)
		(stroke
			(width 0.06477)
			(type default)
		)
		(layer "B.Cu")
	)
	(gr_line
		(start 119.759476 -407.954734)
		(end 119.463566 -408.250644)
		(stroke
			(width 0.06477)
			(type default)
		)
		(layer "B.Cu")
	)
	(gr_line
		(start 120.082056 -409.759658)
		(end 120.352566 -410.030168)
		(stroke
			(width 0.06477)
			(type default)
		)
		(layer "B.Cu")
	)
	(gr_line
		(start 120.082056 -407.954734)
		(end 120.377966 -408.250644)
		(stroke
			(width 0.06477)
			(type default)
		)
		(layer "B.Cu")
	)
	(gr_line
		(start 120.352566 -407.00452)
		(end 120.082056 -407.27503)
		(stroke
			(width 0.06477)
			(type default)
		)
		(layer "B.Cu")
	)
	(gr_line
		(start 120.377966 -408.784044)
		(end 120.082056 -409.079954)
		(stroke
			(width 0.06477)
			(type default)
		)
		(layer "B.Cu")
	)
	(gr_line
		(start 122.526806 -408.784044)
		(end 122.822716 -409.079954)
		(stroke
			(width 0.06477)
			(type default)
		)
		(layer "B.Cu")
	)
	(gr_line
		(start 122.552206 -407.00452)
		(end 122.822716 -407.27503)
		(stroke
			(width 0.06477)
			(type default)
		)
		(layer "B.Cu")
	)
	(gr_line
		(start 122.822716 -409.759658)
		(end 122.552206 -410.030168)
		(stroke
			(width 0.06477)
			(type default)
		)
		(layer "B.Cu")
	)
	(gr_line
		(start 122.822716 -407.954734)
		(end 122.526806 -408.250644)
		(stroke
			(width 0.06477)
			(type default)
		)
		(layer "B.Cu")
	)
	(gr_line
		(start 123.145296 -409.759658)
		(end 123.415806 -410.030168)
		(stroke
			(width 0.06477)
			(type default)
		)
		(layer "B.Cu")
	)
	(gr_line
		(start 123.145296 -407.954734)
		(end 123.441206 -408.250644)
		(stroke
			(width 0.06477)
			(type default)
		)
		(layer "B.Cu")
	)
	(gr_line
		(start 123.415806 -407.00452)
		(end 123.145296 -407.27503)
		(stroke
			(width 0.06477)
			(type default)
		)
		(layer "B.Cu")
	)
	(gr_line
		(start 123.441206 -408.784044)
		(end 123.145296 -409.079954)
		(stroke
			(width 0.06477)
			(type default)
		)
		(layer "B.Cu")
	)
	(gr_line
		(start 125.590046 -408.784044)
		(end 125.885956 -409.079954)
		(stroke
			(width 0.06477)
			(type default)
		)
		(layer "B.Cu")
	)
	(gr_line
		(start 125.615446 -407.00452)
		(end 125.885956 -407.27503)
		(stroke
			(width 0.06477)
			(type default)
		)
		(layer "B.Cu")
	)
	(gr_line
		(start 125.885956 -409.759658)
		(end 125.615446 -410.030168)
		(stroke
			(width 0.06477)
			(type default)
		)
		(layer "B.Cu")
	)
	(gr_line
		(start 125.885956 -407.954734)
		(end 125.590046 -408.250644)
		(stroke
			(width 0.06477)
			(type default)
		)
		(layer "B.Cu")
	)
	(gr_line
		(start 126.208536 -409.759658)
		(end 126.479046 -410.030168)
		(stroke
			(width 0.06477)
			(type default)
		)
		(layer "B.Cu")
	)
	(gr_line
		(start 126.208536 -407.954734)
		(end 126.504446 -408.250644)
		(stroke
			(width 0.06477)
			(type default)
		)
		(layer "B.Cu")
	)
	(gr_line
		(start 126.479046 -407.00452)
		(end 126.208536 -407.27503)
		(stroke
			(width 0.06477)
			(type default)
		)
		(layer "B.Cu")
	)
	(gr_line
		(start 126.504446 -408.784044)
		(end 126.208536 -409.079954)
		(stroke
			(width 0.06477)
			(type default)
		)
		(layer "B.Cu")
	)
	(gr_line
		(start 127.61976 -218.600528)
		(end 127.61976 -217.833448)
		(stroke
			(width 0.06477)
			(type default)
		)
		(layer "B.Cu")
	)
	(gr_line
		(start 127.61976 -217.447368)
		(end 127.61976 -216.680288)
		(stroke
			(width 0.06477)
			(type default)
		)
		(layer "B.Cu")
	)
	(gr_line
		(start 127.61976 -216.294208)
		(end 127.61976 -215.527128)
		(stroke
			(width 0.06477)
			(type default)
		)
		(layer "B.Cu")
	)
	(gr_line
		(start 127.61976 -215.134698)
		(end 127.61976 -214.367618)
		(stroke
			(width 0.06477)
			(type default)
		)
		(layer "B.Cu")
	)
	(gr_line
		(start 127.61976 -213.861904)
		(end 127.61976 -213.094824)
		(stroke
			(width 0.06477)
			(type default)
		)
		(layer "B.Cu")
	)
	(gr_line
		(start 127.94361 -217.834718)
		(end 128.13284 -218.023948)
		(stroke
			(width 0.06477)
			(type default)
		)
		(layer "B.Cu")
	)
	(gr_line
		(start 127.94361 -216.681558)
		(end 128.13284 -216.870788)
		(stroke
			(width 0.06477)
			(type default)
		)
		(layer "B.Cu")
	)
	(gr_line
		(start 127.94361 -215.528398)
		(end 128.13284 -215.717628)
		(stroke
			(width 0.06477)
			(type default)
		)
		(layer "B.Cu")
	)
	(gr_line
		(start 127.94361 -214.368888)
		(end 128.13284 -214.558118)
		(stroke
			(width 0.06477)
			(type default)
		)
		(layer "B.Cu")
	)
	(gr_line
		(start 127.94361 -213.096094)
		(end 128.13284 -213.285324)
		(stroke
			(width 0.06477)
			(type default)
		)
		(layer "B.Cu")
	)
	(gr_line
		(start 128.13284 -218.410028)
		(end 127.94361 -218.599258)
		(stroke
			(width 0.06477)
			(type default)
		)
		(layer "B.Cu")
	)
	(gr_line
		(start 128.13284 -218.023948)
		(end 128.13284 -218.410028)
		(stroke
			(width 0.06477)
			(type default)
		)
		(layer "B.Cu")
	)
	(gr_line
		(start 128.13284 -217.256868)
		(end 127.94361 -217.446098)
		(stroke
			(width 0.06477)
			(type default)
		)
		(layer "B.Cu")
	)
	(gr_line
		(start 128.13284 -216.870788)
		(end 128.13284 -217.256868)
		(stroke
			(width 0.06477)
			(type default)
		)
		(layer "B.Cu")
	)
	(gr_line
		(start 128.13284 -216.103708)
		(end 127.94361 -216.292938)
		(stroke
			(width 0.06477)
			(type default)
		)
		(layer "B.Cu")
	)
	(gr_line
		(start 128.13284 -215.717628)
		(end 128.13284 -216.103708)
		(stroke
			(width 0.06477)
			(type default)
		)
		(layer "B.Cu")
	)
	(gr_line
		(start 128.13284 -214.944198)
		(end 127.94361 -215.133428)
		(stroke
			(width 0.06477)
			(type default)
		)
		(layer "B.Cu")
	)
	(gr_line
		(start 128.13284 -214.558118)
		(end 128.13284 -214.944198)
		(stroke
			(width 0.06477)
			(type default)
		)
		(layer "B.Cu")
	)
	(gr_line
		(start 128.13284 -213.671404)
		(end 127.94361 -213.860634)
		(stroke
			(width 0.06477)
			(type default)
		)
		(layer "B.Cu")
	)
	(gr_line
		(start 128.13284 -213.285324)
		(end 128.13284 -213.671404)
		(stroke
			(width 0.06477)
			(type default)
		)
		(layer "B.Cu")
	)
	(gr_line
		(start 128.14554 -211.514944)
		(end 128.688084 -210.9724)
		(stroke
			(width 0.06477)
			(type default)
		)
		(layer "B.Cu")
	)
	(gr_line
		(start 128.643126 -211.74329)
		(end 128.37541 -211.74329)
		(stroke
			(width 0.06477)
			(type default)
		)
		(layer "B.Cu")
	)
	(gr_line
		(start 128.653286 -408.784044)
		(end 128.949196 -409.079954)
		(stroke
			(width 0.06477)
			(type default)
		)
		(layer "B.Cu")
	)
	(gr_line
		(start 128.678686 -407.00452)
		(end 128.949196 -407.27503)
		(stroke
			(width 0.06477)
			(type default)
		)
		(layer "B.Cu")
	)
	(gr_line
		(start 128.91643 -211.469986)
		(end 128.643126 -211.74329)
		(stroke
			(width 0.06477)
			(type default)
		)
		(layer "B.Cu")
	)
	(gr_line
		(start 128.91643 -211.20227)
		(end 128.91643 -211.469986)
		(stroke
			(width 0.06477)
			(type default)
		)
		(layer "B.Cu")
	)
	(gr_line
		(start 128.949196 -409.759658)
		(end 128.678686 -410.030168)
		(stroke
			(width 0.06477)
			(type default)
		)
		(layer "B.Cu")
	)
	(gr_line
		(start 128.949196 -407.954734)
		(end 128.653286 -408.250644)
		(stroke
			(width 0.06477)
			(type default)
		)
		(layer "B.Cu")
	)
	(gr_line
		(start 128.96088 -210.699604)
		(end 129.503678 -210.156806)
		(stroke
			(width 0.06477)
			(type default)
		)
		(layer "B.Cu")
	)
	(gr_line
		(start 129.271776 -409.759658)
		(end 129.542286 -410.030168)
		(stroke
			(width 0.06477)
			(type default)
		)
		(layer "B.Cu")
	)
	(gr_line
		(start 129.271776 -407.954734)
		(end 129.567686 -408.250644)
		(stroke
			(width 0.06477)
			(type default)
		)
		(layer "B.Cu")
	)
	(gr_line
		(start 129.45872 -210.92795)
		(end 129.19075 -210.92795)
		(stroke
			(width 0.06477)
			(type default)
		)
		(layer "B.Cu")
	)
	(gr_line
		(start 129.542286 -407.00452)
		(end 129.271776 -407.27503)
		(stroke
			(width 0.06477)
			(type default)
		)
		(layer "B.Cu")
	)
	(gr_line
		(start 129.567686 -408.784044)
		(end 129.271776 -409.079954)
		(stroke
			(width 0.06477)
			(type default)
		)
		(layer "B.Cu")
	)
	(gr_line
		(start 129.732024 -210.654646)
		(end 129.45872 -210.92795)
		(stroke
			(width 0.06477)
			(type default)
		)
		(layer "B.Cu")
	)
	(gr_line
		(start 129.732024 -210.386676)
		(end 129.732024 -210.654646)
		(stroke
			(width 0.06477)
			(type default)
		)
		(layer "B.Cu")
	)
	(gr_line
		(start 129.777998 -220.139768)
		(end 129.431288 -219.793058)
		(stroke
			(width 0.06477)
			(type default)
		)
		(layer "B.Cu")
	)
	(gr_line
		(start 130.447288 -219.793058)
		(end 130.100578 -220.139768)
		(stroke
			(width 0.06477)
			(type default)
		)
		(layer "B.Cu")
	)
	(gr_line
		(start 131.06908 -27.75458)
		(end 131.40309 -27.42057)
		(stroke
			(width 0.06477)
			(type default)
		)
		(layer "B.Cu")
	)
	(gr_line
		(start 131.06908 -26.76398)
		(end 131.40309 -27.09799)
		(stroke
			(width 0.06477)
			(type default)
		)
		(layer "B.Cu")
	)
	(gr_line
		(start 131.716526 -408.784044)
		(end 132.012436 -409.079954)
		(stroke
			(width 0.06477)
			(type default)
		)
		(layer "B.Cu")
	)
	(gr_line
		(start 131.741926 -407.00452)
		(end 132.012436 -407.27503)
		(stroke
			(width 0.06477)
			(type default)
		)
		(layer "B.Cu")
	)
	(gr_line
		(start 132.012436 -409.759658)
		(end 131.741926 -410.030168)
		(stroke
			(width 0.06477)
			(type default)
		)
		(layer "B.Cu")
	)
	(gr_line
		(start 132.012436 -407.954734)
		(end 131.716526 -408.250644)
		(stroke
			(width 0.06477)
			(type default)
		)
		(layer "B.Cu")
	)
	(gr_line
		(start 132.335016 -409.759658)
		(end 132.605526 -410.030168)
		(stroke
			(width 0.06477)
			(type default)
		)
		(layer "B.Cu")
	)
	(gr_line
		(start 132.335016 -407.954734)
		(end 132.630926 -408.250644)
		(stroke
			(width 0.06477)
			(type default)
		)
		(layer "B.Cu")
	)
	(gr_line
		(start 132.605526 -407.00452)
		(end 132.335016 -407.27503)
		(stroke
			(width 0.06477)
			(type default)
		)
		(layer "B.Cu")
	)
	(gr_line
		(start 132.630926 -408.784044)
		(end 132.335016 -409.079954)
		(stroke
			(width 0.06477)
			(type default)
		)
		(layer "B.Cu")
	)
	(gr_line
		(start 134.779766 -408.784044)
		(end 135.075676 -409.079954)
		(stroke
			(width 0.06477)
			(type default)
		)
		(layer "B.Cu")
	)
	(gr_line
		(start 134.805166 -407.00452)
		(end 135.075676 -407.27503)
		(stroke
			(width 0.06477)
			(type default)
		)
		(layer "B.Cu")
	)
	(gr_line
		(start 135.075676 -409.759658)
		(end 134.805166 -410.030168)
		(stroke
			(width 0.06477)
			(type default)
		)
		(layer "B.Cu")
	)
	(gr_line
		(start 135.075676 -407.954734)
		(end 134.779766 -408.250644)
		(stroke
			(width 0.06477)
			(type default)
		)
		(layer "B.Cu")
	)
	(gr_line
		(start 135.398256 -409.759658)
		(end 135.668766 -410.030168)
		(stroke
			(width 0.06477)
			(type default)
		)
		(layer "B.Cu")
	)
	(gr_line
		(start 135.398256 -407.954734)
		(end 135.694166 -408.250644)
		(stroke
			(width 0.06477)
			(type default)
		)
		(layer "B.Cu")
	)
	(gr_line
		(start 135.668766 -407.00452)
		(end 135.398256 -407.27503)
		(stroke
			(width 0.06477)
			(type default)
		)
		(layer "B.Cu")
	)
	(gr_line
		(start 135.694166 -408.784044)
		(end 135.398256 -409.079954)
		(stroke
			(width 0.06477)
			(type default)
		)
		(layer "B.Cu")
	)
	(gr_line
		(start 136.26719 -28.90901)
		(end 135.93318 -29.24302)
		(stroke
			(width 0.06477)
			(type default)
		)
		(layer "B.Cu")
	)
	(gr_line
		(start 136.26719 -28.58643)
		(end 135.93318 -28.25242)
		(stroke
			(width 0.06477)
			(type default)
		)
		(layer "B.Cu")
	)
	(gr_line
		(start 137.09015 -28.054808)
		(end 137.09015 -28.315666)
		(stroke
			(width 0.06477)
			(type default)
		)
		(layer "B.Cu")
	)
	(gr_line
		(start 137.359898 -27.785314)
		(end 137.09015 -28.054808)
		(stroke
			(width 0.06477)
			(type default)
		)
		(layer "B.Cu")
	)
	(gr_line
		(start 137.414762 -18.144744)
		(end 137.685272 -18.415254)
		(stroke
			(width 0.06477)
			(type default)
		)
		(layer "B.Cu")
	)
	(gr_line
		(start 137.620502 -27.785314)
		(end 137.359898 -27.785314)
		(stroke
			(width 0.06477)
			(type default)
		)
		(layer "B.Cu")
	)
	(gr_line
		(start 137.843006 -408.784044)
		(end 138.138916 -409.079954)
		(stroke
			(width 0.06477)
			(type default)
		)
		(layer "B.Cu")
	)
	(gr_line
		(start 137.850372 -28.01366)
		(end 137.318496 -28.545282)
		(stroke
			(width 0.06477)
			(type default)
		)
		(layer "B.Cu")
	)
	(gr_line
		(start 137.868406 -407.00452)
		(end 138.138916 -407.27503)
		(stroke
			(width 0.06477)
			(type default)
		)
		(layer "B.Cu")
	)
	(gr_line
		(start 137.891266 -27.253692)
		(end 137.891266 -27.51455)
		(stroke
			(width 0.06477)
			(type default)
		)
		(layer "B.Cu")
	)
	(gr_line
		(start 138.138916 -409.759658)
		(end 137.868406 -410.030168)
		(stroke
			(width 0.06477)
			(type default)
		)
		(layer "B.Cu")
	)
	(gr_line
		(start 138.138916 -407.954734)
		(end 137.843006 -408.250644)
		(stroke
			(width 0.06477)
			(type default)
		)
		(layer "B.Cu")
	)
	(gr_line
		(start 138.161014 -26.984198)
		(end 137.891266 -27.253692)
		(stroke
			(width 0.06477)
			(type default)
		)
		(layer "B.Cu")
	)
	(gr_line
		(start 138.278362 -18.144744)
		(end 138.007852 -18.415254)
		(stroke
			(width 0.06477)
			(type default)
		)
		(layer "B.Cu")
	)
	(gr_line
		(start 138.421618 -26.984198)
		(end 138.161014 -26.984198)
		(stroke
			(width 0.06477)
			(type default)
		)
		(layer "B.Cu")
	)
	(gr_line
		(start 138.461496 -409.759658)
		(end 138.732006 -410.030168)
		(stroke
			(width 0.06477)
			(type default)
		)
		(layer "B.Cu")
	)
	(gr_line
		(start 138.461496 -407.954734)
		(end 138.757406 -408.250644)
		(stroke
			(width 0.06477)
			(type default)
		)
		(layer "B.Cu")
	)
	(gr_line
		(start 138.57732 -26.07818)
		(end 138.76147 -26.26233)
		(stroke
			(width 0.06477)
			(type default)
		)
		(layer "B.Cu")
	)
	(gr_line
		(start 138.57732 -25.69718)
		(end 138.57732 -26.07818)
		(stroke
			(width 0.06477)
			(type default)
		)
		(layer "B.Cu")
	)
	(gr_line
		(start 138.61034 -23.594314)
		(end 138.76147 -23.745444)
		(stroke
			(width 0.06477)
			(type default)
		)
		(layer "B.Cu")
	)
	(gr_line
		(start 138.61034 -23.335234)
		(end 138.61034 -23.594314)
		(stroke
			(width 0.06477)
			(type default)
		)
		(layer "B.Cu")
	)
	(gr_line
		(start 138.651488 -27.212544)
		(end 138.119612 -27.74442)
		(stroke
			(width 0.06477)
			(type default)
		)
		(layer "B.Cu")
	)
	(gr_line
		(start 138.732006 -407.00452)
		(end 138.461496 -407.27503)
		(stroke
			(width 0.06477)
			(type default)
		)
		(layer "B.Cu")
	)
	(gr_line
		(start 138.757406 -408.784044)
		(end 138.461496 -409.079954)
		(stroke
			(width 0.06477)
			(type default)
		)
		(layer "B.Cu")
	)
	(gr_line
		(start 138.76147 -25.51303)
		(end 138.57732 -25.69718)
		(stroke
			(width 0.06477)
			(type default)
		)
		(layer "B.Cu")
	)
	(gr_line
		(start 138.76147 -23.184104)
		(end 138.61034 -23.335234)
		(stroke
			(width 0.06477)
			(type default)
		)
		(layer "B.Cu")
	)
	(gr_line
		(start 139.08532 -25.51176)
		(end 139.08532 -26.2636)
		(stroke
			(width 0.06477)
			(type default)
		)
		(layer "B.Cu")
	)
	(gr_line
		(start 139.08532 -23.182834)
		(end 139.08532 -23.746714)
		(stroke
			(width 0.06477)
			(type default)
		)
		(layer "B.Cu")
	)
	(gr_line
		(start 140.906246 -408.784044)
		(end 141.202156 -409.079954)
		(stroke
			(width 0.06477)
			(type default)
		)
		(layer "B.Cu")
	)
	(gr_line
		(start 140.931646 -407.00452)
		(end 141.202156 -407.27503)
		(stroke
			(width 0.06477)
			(type default)
		)
		(layer "B.Cu")
	)
	(gr_line
		(start 141.202156 -409.759658)
		(end 140.931646 -410.030168)
		(stroke
			(width 0.06477)
			(type default)
		)
		(layer "B.Cu")
	)
	(gr_line
		(start 141.202156 -407.954734)
		(end 140.906246 -408.250644)
		(stroke
			(width 0.06477)
			(type default)
		)
		(layer "B.Cu")
	)
	(gr_line
		(start 141.524736 -409.759658)
		(end 141.795246 -410.030168)
		(stroke
			(width 0.06477)
			(type default)
		)
		(layer "B.Cu")
	)
	(gr_line
		(start 141.524736 -407.954734)
		(end 141.820646 -408.250644)
		(stroke
			(width 0.06477)
			(type default)
		)
		(layer "B.Cu")
	)
	(gr_line
		(start 141.795246 -407.00452)
		(end 141.524736 -407.27503)
		(stroke
			(width 0.06477)
			(type default)
		)
		(layer "B.Cu")
	)
	(gr_line
		(start 141.820646 -408.784044)
		(end 141.524736 -409.079954)
		(stroke
			(width 0.06477)
			(type default)
		)
		(layer "B.Cu")
	)
	(gr_line
		(start 142.360396 -21.810218)
		(end 142.6337 -22.083522)
		(stroke
			(width 0.06477)
			(type default)
		)
		(layer "B.Cu")
	)
	(gr_line
		(start 142.360396 -21.542248)
		(end 142.360396 -21.810218)
		(stroke
			(width 0.06477)
			(type default)
		)
		(layer "B.Cu")
	)
	(gr_line
		(start 142.588488 -21.312378)
		(end 143.13154 -21.85543)
		(stroke
			(width 0.06477)
			(type default)
		)
		(layer "B.Cu")
	)
	(gr_line
		(start 142.6337 -22.083522)
		(end 142.90167 -22.083522)
		(stroke
			(width 0.06477)
			(type default)
		)
		(layer "B.Cu")
	)
	(gr_line
		(start 143.969486 -408.784044)
		(end 144.265396 -409.079954)
		(stroke
			(width 0.06477)
			(type default)
		)
		(layer "B.Cu")
	)
	(gr_line
		(start 143.994886 -407.00452)
		(end 144.265396 -407.27503)
		(stroke
			(width 0.06477)
			(type default)
		)
		(layer "B.Cu")
	)
	(gr_line
		(start 144.265396 -409.759658)
		(end 143.994886 -410.030168)
		(stroke
			(width 0.06477)
			(type default)
		)
		(layer "B.Cu")
	)
	(gr_line
		(start 144.265396 -407.954734)
		(end 143.969486 -408.250644)
		(stroke
			(width 0.06477)
			(type default)
		)
		(layer "B.Cu")
	)
	(gr_line
		(start 144.587976 -409.759658)
		(end 144.858486 -410.030168)
		(stroke
			(width 0.06477)
			(type default)
		)
		(layer "B.Cu")
	)
	(gr_line
		(start 144.587976 -407.954734)
		(end 144.883886 -408.250644)
		(stroke
			(width 0.06477)
			(type default)
		)
		(layer "B.Cu")
	)
	(gr_line
		(start 144.858486 -407.00452)
		(end 144.587976 -407.27503)
		(stroke
			(width 0.06477)
			(type default)
		)
		(layer "B.Cu")
	)
	(gr_line
		(start 144.883886 -408.784044)
		(end 144.587976 -409.079954)
		(stroke
			(width 0.06477)
			(type default)
		)
		(layer "B.Cu")
	)
	(gr_line
		(start 147.032726 -408.784044)
		(end 147.328636 -409.079954)
		(stroke
			(width 0.06477)
			(type default)
		)
		(layer "B.Cu")
	)
	(gr_line
		(start 147.058126 -407.00452)
		(end 147.328636 -407.27503)
		(stroke
			(width 0.06477)
			(type default)
		)
		(layer "B.Cu")
	)
	(gr_line
		(start 147.328636 -409.759658)
		(end 147.058126 -410.030168)
		(stroke
			(width 0.06477)
			(type default)
		)
		(layer "B.Cu")
	)
	(gr_line
		(start 147.328636 -407.954734)
		(end 147.032726 -408.250644)
		(stroke
			(width 0.06477)
			(type default)
		)
		(layer "B.Cu")
	)
	(gr_line
		(start 147.651216 -409.759658)
		(end 147.921726 -410.030168)
		(stroke
			(width 0.06477)
			(type default)
		)
		(layer "B.Cu")
	)
	(gr_line
		(start 147.651216 -407.954734)
		(end 147.947126 -408.250644)
		(stroke
			(width 0.06477)
			(type default)
		)
		(layer "B.Cu")
	)
	(gr_line
		(start 147.921726 -407.00452)
		(end 147.651216 -407.27503)
		(stroke
			(width 0.06477)
			(type default)
		)
		(layer "B.Cu")
	)
	(gr_line
		(start 147.947126 -408.784044)
		(end 147.651216 -409.079954)
		(stroke
			(width 0.06477)
			(type default)
		)
		(layer "B.Cu")
	)
	(gr_line
		(start 150.095966 -408.784044)
		(end 150.391876 -409.079954)
		(stroke
			(width 0.06477)
			(type default)
		)
		(layer "B.Cu")
	)
	(gr_line
		(start 150.121366 -407.00452)
		(end 150.391876 -407.27503)
		(stroke
			(width 0.06477)
			(type default)
		)
		(layer "B.Cu")
	)
	(gr_line
		(start 150.391876 -409.759658)
		(end 150.121366 -410.030168)
		(stroke
			(width 0.06477)
			(type default)
		)
		(layer "B.Cu")
	)
	(gr_line
		(start 150.391876 -407.954734)
		(end 150.095966 -408.250644)
		(stroke
			(width 0.06477)
			(type default)
		)
		(layer "B.Cu")
	)
	(gr_line
		(start 150.714456 -409.759658)
		(end 150.984966 -410.030168)
		(stroke
			(width 0.06477)
			(type default)
		)
		(layer "B.Cu")
	)
	(gr_line
		(start 150.714456 -407.954734)
		(end 151.010366 -408.250644)
		(stroke
			(width 0.06477)
			(type default)
		)
		(layer "B.Cu")
	)
	(gr_line
		(start 150.984966 -407.00452)
		(end 150.714456 -407.27503)
		(stroke
			(width 0.06477)
			(type default)
		)
		(layer "B.Cu")
	)
	(gr_line
		(start 151.010366 -408.784044)
		(end 150.714456 -409.079954)
		(stroke
			(width 0.06477)
			(type default)
		)
		(layer "B.Cu")
	)
	(gr_line
		(start 152.28443 -183.893714)
		(end 152.284176 -183.893714)
		(stroke
			(width 0.06477)
			(type default)
		)
		(layer "B.Cu")
	)
	(gr_line
		(start 153.159206 -408.784044)
		(end 153.455116 -409.079954)
		(stroke
			(width 0.06477)
			(type default)
		)
		(layer "B.Cu")
	)
	(gr_line
		(start 153.184606 -407.00452)
		(end 153.455116 -407.27503)
		(stroke
			(width 0.06477)
			(type default)
		)
		(layer "B.Cu")
	)
	(gr_line
		(start 153.455116 -409.759658)
		(end 153.184606 -410.030168)
		(stroke
			(width 0.06477)
			(type default)
		)
		(layer "B.Cu")
	)
	(gr_line
		(start 153.455116 -407.954734)
		(end 153.159206 -408.250644)
		(stroke
			(width 0.06477)
			(type default)
		)
		(layer "B.Cu")
	)
	(gr_line
		(start 153.777696 -409.759658)
		(end 154.048206 -410.030168)
		(stroke
			(width 0.06477)
			(type default)
		)
		(layer "B.Cu")
	)
	(gr_line
		(start 153.777696 -407.954734)
		(end 154.073606 -408.250644)
		(stroke
			(width 0.06477)
			(type default)
		)
		(layer "B.Cu")
	)
	(gr_line
		(start 154.048206 -407.00452)
		(end 153.777696 -407.27503)
		(stroke
			(width 0.06477)
			(type default)
		)
		(layer "B.Cu")
	)
	(gr_line
		(start 154.073606 -408.784044)
		(end 153.777696 -409.079954)
		(stroke
			(width 0.06477)
			(type default)
		)
		(layer "B.Cu")
	)
	(gr_line
		(start 154.544522 -183.84774)
		(end 154.276552 -183.853582)
		(stroke
			(width 0.06477)
			(type default)
		)
		(layer "B.Cu")
	)
	(gr_line
		(start 154.572716 -183.075834)
		(end 154.041856 -183.630316)
		(stroke
			(width 0.06477)
			(type default)
		)
		(layer "B.Cu")
	)
	(gr_line
		(start 154.805634 -183.300878)
		(end 154.807158 -183.36768)
		(stroke
			(width 0.06477)
			(type default)
		)
		(layer "B.Cu")
	)
	(gr_line
		(start 154.807158 -183.36768)
		(end 154.811476 -183.568594)
		(stroke
			(width 0.06477)
			(type default)
		)
		(layer "B.Cu")
	)
	(gr_line
		(start 154.811476 -183.568594)
		(end 154.544522 -183.84774)
		(stroke
			(width 0.06477)
			(type default)
		)
		(layer "B.Cu")
	)
	(gr_line
		(start 155.342082 -183.01462)
		(end 155.074112 -183.020462)
		(stroke
			(width 0.06477)
			(type default)
		)
		(layer "B.Cu")
	)
	(gr_line
		(start 155.370276 -182.242714)
		(end 154.839416 -182.797196)
		(stroke
			(width 0.06477)
			(type default)
		)
		(layer "B.Cu")
	)
	(gr_line
		(start 155.603194 -182.467758)
		(end 155.609036 -182.735474)
		(stroke
			(width 0.06477)
			(type default)
		)
		(layer "B.Cu")
	)
	(gr_line
		(start 155.607004 -182.46217)
		(end 155.603194 -182.46598)
		(stroke
			(width 0.06477)
			(type default)
		)
		(layer "B.Cu")
	)
	(gr_line
		(start 155.609036 -182.735474)
		(end 155.342082 -183.01462)
		(stroke
			(width 0.06477)
			(type default)
		)
		(layer "B.Cu")
	)
	(gr_line
		(start 156.139896 -182.181246)
		(end 155.871672 -182.187342)
		(stroke
			(width 0.06477)
			(type default)
		)
		(layer "B.Cu")
	)
	(gr_line
		(start 156.167836 -181.409594)
		(end 155.63723 -181.964076)
		(stroke
			(width 0.06477)
			(type default)
		)
		(layer "B.Cu")
	)
	(gr_line
		(start 156.222446 -408.784044)
		(end 156.518356 -409.079954)
		(stroke
			(width 0.06477)
			(type default)
		)
		(layer "B.Cu")
	)
	(gr_line
		(start 156.247846 -407.00452)
		(end 156.518356 -407.27503)
		(stroke
			(width 0.06477)
			(type default)
		)
		(layer "B.Cu")
	)
	(gr_line
		(start 156.401008 -181.634384)
		(end 156.40685 -181.9021)
		(stroke
			(width 0.06477)
			(type default)
		)
		(layer "B.Cu")
	)
	(gr_line
		(start 156.40685 -181.9021)
		(end 156.139896 -182.181246)
		(stroke
			(width 0.06477)
			(type default)
		)
		(layer "B.Cu")
	)
	(gr_line
		(start 156.518356 -409.759658)
		(end 156.247846 -410.030168)
		(stroke
			(width 0.06477)
			(type default)
		)
		(layer "B.Cu")
	)
	(gr_line
		(start 156.518356 -407.954734)
		(end 156.222446 -408.250644)
		(stroke
			(width 0.06477)
			(type default)
		)
		(layer "B.Cu")
	)
	(gr_line
		(start 156.840936 -409.759658)
		(end 157.111446 -410.030168)
		(stroke
			(width 0.06477)
			(type default)
		)
		(layer "B.Cu")
	)
	(gr_line
		(start 156.840936 -407.954734)
		(end 157.136846 -408.250644)
		(stroke
			(width 0.06477)
			(type default)
		)
		(layer "B.Cu")
	)
	(gr_line
		(start 157.111446 -407.00452)
		(end 156.840936 -407.27503)
		(stroke
			(width 0.06477)
			(type default)
		)
		(layer "B.Cu")
	)
	(gr_line
		(start 157.136846 -408.784044)
		(end 156.840936 -409.079954)
		(stroke
			(width 0.06477)
			(type default)
		)
		(layer "B.Cu")
	)
	(gr_line
		(start 159.285686 -408.784044)
		(end 159.581596 -409.079954)
		(stroke
			(width 0.06477)
			(type default)
		)
		(layer "B.Cu")
	)
	(gr_line
		(start 159.311086 -407.00452)
		(end 159.581596 -407.27503)
		(stroke
			(width 0.06477)
			(type default)
		)
		(layer "B.Cu")
	)
	(gr_line
		(start 159.581596 -409.759658)
		(end 159.311086 -410.030168)
		(stroke
			(width 0.06477)
			(type default)
		)
		(layer "B.Cu")
	)
	(gr_line
		(start 159.581596 -407.954734)
		(end 159.285686 -408.250644)
		(stroke
			(width 0.06477)
			(type default)
		)
		(layer "B.Cu")
	)
	(gr_line
		(start 159.904176 -409.759658)
		(end 160.174686 -410.030168)
		(stroke
			(width 0.06477)
			(type default)
		)
		(layer "B.Cu")
	)
	(gr_line
		(start 159.904176 -407.954734)
		(end 160.200086 -408.250644)
		(stroke
			(width 0.06477)
			(type default)
		)
		(layer "B.Cu")
	)
	(gr_line
		(start 160.174686 -407.00452)
		(end 159.904176 -407.27503)
		(stroke
			(width 0.06477)
			(type default)
		)
		(layer "B.Cu")
	)
	(gr_line
		(start 160.200086 -408.784044)
		(end 159.904176 -409.079954)
		(stroke
			(width 0.06477)
			(type default)
		)
		(layer "B.Cu")
	)
	(gr_line
		(start 161.432748 -179.990496)
		(end 161.432748 -179.99075)
		(stroke
			(width 0.06477)
			(type default)
		)
		(layer "B.Cu")
	)
	(gr_line
		(start 162.348926 -408.784044)
		(end 162.644836 -409.079954)
		(stroke
			(width 0.06477)
			(type default)
		)
		(layer "B.Cu")
	)
	(gr_line
		(start 162.374326 -407.00452)
		(end 162.644836 -407.27503)
		(stroke
			(width 0.06477)
			(type default)
		)
		(layer "B.Cu")
	)
	(gr_line
		(start 162.644836 -409.759658)
		(end 162.374326 -410.030168)
		(stroke
			(width 0.06477)
			(type default)
		)
		(layer "B.Cu")
	)
	(gr_line
		(start 162.644836 -407.954734)
		(end 162.348926 -408.250644)
		(stroke
			(width 0.06477)
			(type default)
		)
		(layer "B.Cu")
	)
	(gr_line
		(start 162.967416 -409.759658)
		(end 163.237926 -410.030168)
		(stroke
			(width 0.06477)
			(type default)
		)
		(layer "B.Cu")
	)
	(gr_line
		(start 162.967416 -407.954734)
		(end 163.263326 -408.250644)
		(stroke
			(width 0.06477)
			(type default)
		)
		(layer "B.Cu")
	)
	(gr_line
		(start 163.237926 -407.00452)
		(end 162.967416 -407.27503)
		(stroke
			(width 0.06477)
			(type default)
		)
		(layer "B.Cu")
	)
	(gr_line
		(start 163.263326 -408.784044)
		(end 162.967416 -409.079954)
		(stroke
			(width 0.06477)
			(type default)
		)
		(layer "B.Cu")
	)
	(gr_line
		(start 170.335702 -10.785856)
		(end 170.54703 -10.997184)
		(stroke
			(width 0.06477)
			(type default)
		)
		(layer "B.Cu")
	)
	(gr_line
		(start 170.54703 -10.997184)
		(end 170.54703 -11.115548)
		(stroke
			(width 0.06477)
			(type default)
		)
		(layer "B.Cu")
	)
	(gr_line
		(start 170.87088 -11.114278)
		(end 171.199302 -10.785856)
		(stroke
			(width 0.06477)
			(type default)
		)
		(layer "B.Cu")
	)
	(gr_line
		(start 185.037222 3.273298)
		(end 184.38495 3.091434)
		(stroke
			(width 0.06477)
			(type default)
		)
		(layer "B.Cu")
	)
	(gr_line
		(start 185.037222 3.77317)
		(end 184.38495 3.955034)
		(stroke
			(width 0.06477)
			(type default)
		)
		(layer "B.Cu")
	)
	(gr_line
		(start 188.167264 -180.691282)
		(end 188.167264 -180.691028)
		(stroke
			(width 0.06477)
			(type default)
		)
		(layer "B.Cu")
	)
	(gr_line
		(start 212.753702 -65.153032)
		(end 212.78469 -65.159128)
		(stroke
			(width 0.06477)
			(type default)
		)
		(layer "B.Cu")
	)
	(gr_line
		(start 212.78469 -65.159128)
		(end 212.816948 -65.159128)
		(stroke
			(width 0.06477)
			(type default)
		)
		(layer "B.Cu")
	)
	(gr_line
		(start 212.816948 -64.836548)
		(end 212.816694 -64.836294)
		(stroke
			(width 0.06477)
			(type default)
		)
		(layer "B.Cu")
	)
	(gr_line
		(start 213.43112 7.87273)
		(end 213.297008 7.87273)
		(stroke
			(width 0.06477)
			(type default)
		)
		(layer "B.Cu")
	)
	(gr_line
		(start 213.432136 7.372858)
		(end 213.297008 7.372858)
		(stroke
			(width 0.06477)
			(type default)
		)
		(layer "B.Cu")
	)
	(gr_line
		(start 213.519766 7.460488)
		(end 213.432136 7.372858)
		(stroke
			(width 0.06477)
			(type default)
		)
		(layer "B.Cu")
	)
	(gr_line
		(start 213.519766 7.784084)
		(end 213.43112 7.87273)
		(stroke
			(width 0.06477)
			(type default)
		)
		(layer "B.Cu")
	)
	(gr_line
		(start 213.520782 7.784084)
		(end 213.519766 7.784084)
		(stroke
			(width 0.06477)
			(type default)
		)
		(layer "B.Cu")
	)
	(gr_line
		(start 213.94928 -2.969006)
		(end 213.297008 -2.787142)
		(stroke
			(width 0.06477)
			(type default)
		)
		(layer "B.Cu")
	)
	(gr_line
		(start 213.94928 -2.105406)
		(end 213.297008 -2.28727)
		(stroke
			(width 0.06477)
			(type default)
		)
		(layer "B.Cu")
	)
	(gr_line
		(start 213.94928 2.110994)
		(end 213.297008 2.292858)
		(stroke
			(width 0.06477)
			(type default)
		)
		(layer "B.Cu")
	)
	(gr_line
		(start 213.94928 2.974594)
		(end 213.297008 2.79273)
		(stroke
			(width 0.06477)
			(type default)
		)
		(layer "B.Cu")
	)
	(gr_line
		(start 218.949778 -83.767422)
		(end 218.679268 -84.037932)
		(stroke
			(width 0.06477)
			(type default)
		)
		(layer "B.Cu")
	)
	(gr_line
		(start 219.272358 -83.767422)
		(end 219.542868 -84.037932)
		(stroke
			(width 0.06477)
			(type default)
		)
		(layer "B.Cu")
	)
	(gr_line
		(start 220.87078 -85.964268)
		(end 220.87078 -85.540088)
		(stroke
			(width 0.06477)
			(type default)
		)
		(layer "B.Cu")
	)
	(gr_line
		(start 220.87078 -85.540088)
		(end 221.00667 -85.404198)
		(stroke
			(width 0.06477)
			(type default)
		)
		(layer "B.Cu")
	)
	(gr_line
		(start 220.87078 -84.841588)
		(end 220.87078 -84.417408)
		(stroke
			(width 0.06477)
			(type default)
		)
		(layer "B.Cu")
	)
	(gr_line
		(start 220.87078 -84.417408)
		(end 221.00667 -84.281518)
		(stroke
			(width 0.06477)
			(type default)
		)
		(layer "B.Cu")
	)
	(gr_line
		(start 221.00667 -86.100158)
		(end 220.87078 -85.964268)
		(stroke
			(width 0.06477)
			(type default)
		)
		(layer "B.Cu")
	)
	(gr_line
		(start 221.00667 -84.977478)
		(end 220.87078 -84.841588)
		(stroke
			(width 0.06477)
			(type default)
		)
		(layer "B.Cu")
	)
	(gr_line
		(start 221.12986 -89.36736)
		(end 221.232476 -89.119964)
		(stroke
			(width 0.06477)
			(type default)
		)
		(layer "B.Cu")
	)
	(gr_line
		(start 221.277688 -89.72423)
		(end 221.12986 -89.36736)
		(stroke
			(width 0.06477)
			(type default)
		)
		(layer "B.Cu")
	)
	(gr_line
		(start 221.33052 -86.101428)
		(end 221.33052 -85.402928)
		(stroke
			(width 0.06477)
			(type default)
		)
		(layer "B.Cu")
	)
	(gr_line
		(start 221.33052 -84.978748)
		(end 221.33052 -84.280248)
		(stroke
			(width 0.06477)
			(type default)
		)
		(layer "B.Cu")
	)
	(gr_line
		(start 221.525084 -89.826592)
		(end 221.277688 -89.72423)
		(stroke
			(width 0.06477)
			(type default)
		)
		(layer "B.Cu")
	)
	(gr_line
		(start 221.526862 -89.827354)
		(end 221.526608 -89.827608)
		(stroke
			(width 0.06477)
			(type default)
		)
		(layer "B.Cu")
	)
	(gr_line
		(start 221.571312 -90.43289)
		(end 221.673674 -90.185494)
		(stroke
			(width 0.06477)
			(type default)
		)
		(layer "B.Cu")
	)
	(gr_line
		(start 221.674182 -90.18397)
		(end 221.674436 -90.18397)
		(stroke
			(width 0.06477)
			(type default)
		)
		(layer "B.Cu")
	)
	(gr_line
		(start 221.674182 -90.183716)
		(end 221.674182 -90.18397)
		(stroke
			(width 0.06477)
			(type default)
		)
		(layer "B.Cu")
	)
	(gr_line
		(start 221.71914 -90.78976)
		(end 221.571312 -90.43289)
		(stroke
			(width 0.06477)
			(type default)
		)
		(layer "B.Cu")
	)
	(gr_line
		(start 221.824804 -89.70391)
		(end 221.53118 -88.994996)
		(stroke
			(width 0.06477)
			(type default)
		)
		(layer "B.Cu")
	)
	(gr_line
		(start 221.966536 -90.892122)
		(end 221.71914 -90.78976)
		(stroke
			(width 0.06477)
			(type default)
		)
		(layer "B.Cu")
	)
	(gr_line
		(start 221.968314 -90.892884)
		(end 221.96806 -90.893138)
		(stroke
			(width 0.06477)
			(type default)
		)
		(layer "B.Cu")
	)
	(gr_line
		(start 222.012764 -91.49842)
		(end 222.115126 -91.251278)
		(stroke
			(width 0.06477)
			(type default)
		)
		(layer "B.Cu")
	)
	(gr_line
		(start 222.115634 -91.2495)
		(end 222.115888 -91.2495)
		(stroke
			(width 0.06477)
			(type default)
		)
		(layer "B.Cu")
	)
	(gr_line
		(start 222.115634 -91.249246)
		(end 222.115634 -91.2495)
		(stroke
			(width 0.06477)
			(type default)
		)
		(layer "B.Cu")
	)
	(gr_line
		(start 222.160592 -91.85529)
		(end 222.012764 -91.49842)
		(stroke
			(width 0.06477)
			(type default)
		)
		(layer "B.Cu")
	)
	(gr_line
		(start 222.266256 -90.769694)
		(end 221.972378 -90.060272)
		(stroke
			(width 0.06477)
			(type default)
		)
		(layer "B.Cu")
	)
	(gr_line
		(start 222.407734 -91.957652)
		(end 222.160592 -91.85529)
		(stroke
			(width 0.06477)
			(type default)
		)
		(layer "B.Cu")
	)
	(gr_line
		(start 222.409258 -91.958668)
		(end 222.409766 -91.958414)
		(stroke
			(width 0.06477)
			(type default)
		)
		(layer "B.Cu")
	)
	(gr_line
		(start 222.454216 -92.56395)
		(end 222.556578 -92.316808)
		(stroke
			(width 0.06477)
			(type default)
		)
		(layer "B.Cu")
	)
	(gr_line
		(start 222.557086 -92.31503)
		(end 222.55734 -92.31503)
		(stroke
			(width 0.06477)
			(type default)
		)
		(layer "B.Cu")
	)
	(gr_line
		(start 222.602044 -92.92082)
		(end 222.454216 -92.56395)
		(stroke
			(width 0.06477)
			(type default)
		)
		(layer "B.Cu")
	)
	(gr_line
		(start 222.707454 -91.83497)
		(end 222.41383 -91.125802)
		(stroke
			(width 0.06477)
			(type default)
		)
		(layer "B.Cu")
	)
	(gr_line
		(start 222.849186 -93.023182)
		(end 222.602044 -92.92082)
		(stroke
			(width 0.06477)
			(type default)
		)
		(layer "B.Cu")
	)
	(gr_line
		(start 222.85071 -93.023944)
		(end 222.851218 -93.023944)
		(stroke
			(width 0.06477)
			(type default)
		)
		(layer "B.Cu")
	)
	(gr_line
		(start 222.895668 -93.62948)
		(end 222.99803 -93.382592)
		(stroke
			(width 0.06477)
			(type default)
		)
		(layer "B.Cu")
	)
	(gr_line
		(start 222.998792 -93.38056)
		(end 222.998284 -93.380814)
		(stroke
			(width 0.06477)
			(type default)
		)
		(layer "B.Cu")
	)
	(gr_line
		(start 223.043496 -93.98635)
		(end 222.895668 -93.62948)
		(stroke
			(width 0.06477)
			(type default)
		)
		(layer "B.Cu")
	)
	(gr_line
		(start 223.148906 -92.9005)
		(end 222.855028 -92.191332)
		(stroke
			(width 0.06477)
			(type default)
		)
		(layer "B.Cu")
	)
	(gr_line
		(start 223.290384 -94.088458)
		(end 223.043496 -93.98635)
		(stroke
			(width 0.06477)
			(type default)
		)
		(layer "B.Cu")
	)
	(gr_line
		(start 223.292162 -94.089728)
		(end 223.29267 -94.089474)
		(stroke
			(width 0.06477)
			(type default)
		)
		(layer "B.Cu")
	)
	(gr_line
		(start 223.29267 -94.089474)
		(end 223.292162 -94.08922)
		(stroke
			(width 0.06477)
			(type default)
		)
		(layer "B.Cu")
	)
	(gr_line
		(start 223.590358 -93.966284)
		(end 223.296734 -93.25737)
		(stroke
			(width 0.06477)
			(type default)
		)
		(layer "B.Cu")
	)
	(gr_line
		(start 235.737908 9.738614)
		(end 235.737908 9.738868)
		(stroke
			(width 0.06477)
			(type default)
		)
		(layer "B.Cu")
	)
	(gr_line
		(start 243.781326 9.754108)
		(end 243.781326 9.754362)
		(stroke
			(width 0.06477)
			(type default)
		)
		(layer "B.Cu")
	)
	(gr_line
		(start 247.803162 9.760712)
		(end 247.803162 9.760966)
		(stroke
			(width 0.06477)
			(type default)
		)
		(layer "B.Cu")
	)
	(gr_line
		(start 251.822458 9.756394)
		(end 251.822458 9.756648)
		(stroke
			(width 0.06477)
			(type default)
		)
		(layer "B.Cu")
	)
	(gr_line
		(start 255.838198 9.728962)
		(end 255.838198 9.729216)
		(stroke
			(width 0.06477)
			(type default)
		)
		(layer "B.Cu")
	)
	(gr_line
		(start 257.574034 -201.138282)
		(end 257.574034 -200.371202)
		(stroke
			(width 0.06477)
			(type default)
		)
		(layer "B.Cu")
	)
	(gr_line
		(start 257.574034 -199.985122)
		(end 257.574034 -199.218042)
		(stroke
			(width 0.06477)
			(type default)
		)
		(layer "B.Cu")
	)
	(gr_line
		(start 257.574034 -198.831962)
		(end 257.574034 -198.064882)
		(stroke
			(width 0.06477)
			(type default)
		)
		(layer "B.Cu")
	)
	(gr_line
		(start 257.574034 -197.678802)
		(end 257.574034 -196.911722)
		(stroke
			(width 0.06477)
			(type default)
		)
		(layer "B.Cu")
	)
	(gr_line
		(start 257.574034 -196.525642)
		(end 257.574034 -195.758562)
		(stroke
			(width 0.06477)
			(type default)
		)
		(layer "B.Cu")
	)
	(gr_line
		(start 257.897884 -201.137012)
		(end 258.087114 -200.947782)
		(stroke
			(width 0.06477)
			(type default)
		)
		(layer "B.Cu")
	)
	(gr_line
		(start 257.897884 -199.983852)
		(end 258.087114 -199.794622)
		(stroke
			(width 0.06477)
			(type default)
		)
		(layer "B.Cu")
	)
	(gr_line
		(start 257.897884 -198.830692)
		(end 258.087114 -198.641462)
		(stroke
			(width 0.06477)
			(type default)
		)
		(layer "B.Cu")
	)
	(gr_line
		(start 257.897884 -197.677532)
		(end 258.087114 -197.488302)
		(stroke
			(width 0.06477)
			(type default)
		)
		(layer "B.Cu")
	)
	(gr_line
		(start 257.897884 -196.524372)
		(end 258.087114 -196.335142)
		(stroke
			(width 0.06477)
			(type default)
		)
		(layer "B.Cu")
	)
	(gr_line
		(start 258.087114 -200.947782)
		(end 258.087114 -200.561702)
		(stroke
			(width 0.06477)
			(type default)
		)
		(layer "B.Cu")
	)
	(gr_line
		(start 258.087114 -200.561702)
		(end 257.897884 -200.372472)
		(stroke
			(width 0.06477)
			(type default)
		)
		(layer "B.Cu")
	)
	(gr_line
		(start 258.087114 -199.794622)
		(end 258.087114 -199.408542)
		(stroke
			(width 0.06477)
			(type default)
		)
		(layer "B.Cu")
	)
	(gr_line
		(start 258.087114 -199.408542)
		(end 257.897884 -199.219312)
		(stroke
			(width 0.06477)
			(type default)
		)
		(layer "B.Cu")
	)
	(gr_line
		(start 258.087114 -198.641462)
		(end 258.087114 -198.255382)
		(stroke
			(width 0.06477)
			(type default)
		)
		(layer "B.Cu")
	)
	(gr_line
		(start 258.087114 -198.255382)
		(end 257.897884 -198.066152)
		(stroke
			(width 0.06477)
			(type default)
		)
		(layer "B.Cu")
	)
	(gr_line
		(start 258.087114 -197.488302)
		(end 258.087114 -197.102222)
		(stroke
			(width 0.06477)
			(type default)
		)
		(layer "B.Cu")
	)
	(gr_line
		(start 258.087114 -197.102222)
		(end 257.897884 -196.912992)
		(stroke
			(width 0.06477)
			(type default)
		)
		(layer "B.Cu")
	)
	(gr_line
		(start 258.087114 -196.335142)
		(end 258.087114 -195.949062)
		(stroke
			(width 0.06477)
			(type default)
		)
		(layer "B.Cu")
	)
	(gr_line
		(start 258.087114 -195.949062)
		(end 257.897884 -195.759832)
		(stroke
			(width 0.06477)
			(type default)
		)
		(layer "B.Cu")
	)
	(gr_line
		(start 260.112256 -193.80708)
		(end 260.170168 -193.80708)
		(stroke
			(width 0.06477)
			(type default)
		)
		(layer "B.Cu")
	)
	(gr_line
		(start 260.113526 -194.13093)
		(end 260.475222 -194.492626)
		(stroke
			(width 0.06477)
			(type default)
		)
		(layer "B.Cu")
	)
	(gr_line
		(start 260.170168 -193.80708)
		(end 260.475222 -193.502026)
		(stroke
			(width 0.06477)
			(type default)
		)
		(layer "B.Cu")
	)
	(gr_line
		(start 299.466762 7.461504)
		(end 299.461682 7.461504)
		(stroke
			(width 0.06477)
			(type default)
		)
		(layer "B.Cu")
	)
	(gr_line
		(start 299.550328 7.87273)
		(end 299.462952 7.785354)
		(stroke
			(width 0.06477)
			(type default)
		)
		(layer "B.Cu")
	)
	(gr_line
		(start 299.555408 7.372858)
		(end 299.466762 7.461504)
		(stroke
			(width 0.06477)
			(type default)
		)
		(layer "B.Cu")
	)
	(gr_line
		(start 299.712888 -2.787142)
		(end 299.060616 -2.969006)
		(stroke
			(width 0.06477)
			(type default)
		)
		(layer "B.Cu")
	)
	(gr_line
		(start 299.712888 -2.28727)
		(end 299.060616 -2.105406)
		(stroke
			(width 0.06477)
			(type default)
		)
		(layer "B.Cu")
	)
	(gr_line
		(start 299.712888 2.292858)
		(end 299.060616 2.110994)
		(stroke
			(width 0.06477)
			(type default)
		)
		(layer "B.Cu")
	)
	(gr_line
		(start 299.712888 2.79273)
		(end 299.060616 2.974594)
		(stroke
			(width 0.06477)
			(type default)
		)
		(layer "B.Cu")
	)
	(gr_line
		(start 299.712888 7.372858)
		(end 299.555408 7.372858)
		(stroke
			(width 0.06477)
			(type default)
		)
		(layer "B.Cu")
	)
	(gr_line
		(start 299.712888 7.87273)
		(end 299.550328 7.87273)
		(stroke
			(width 0.06477)
			(type default)
		)
		(layer "B.Cu")
	)
	(gr_line
		(start 305.300126 -417.166044)
		(end 305.596036 -417.461954)
		(stroke
			(width 0.06477)
			(type default)
		)
		(layer "B.Cu")
	)
	(gr_line
		(start 305.325526 -415.38652)
		(end 305.596036 -415.65703)
		(stroke
			(width 0.06477)
			(type default)
		)
		(layer "B.Cu")
	)
	(gr_line
		(start 305.596036 -418.141658)
		(end 305.325526 -418.412168)
		(stroke
			(width 0.06477)
			(type default)
		)
		(layer "B.Cu")
	)
	(gr_line
		(start 305.596036 -416.336734)
		(end 305.300126 -416.632644)
		(stroke
			(width 0.06477)
			(type default)
		)
		(layer "B.Cu")
	)
	(gr_line
		(start 305.918616 -418.141658)
		(end 306.189126 -418.412168)
		(stroke
			(width 0.06477)
			(type default)
		)
		(layer "B.Cu")
	)
	(gr_line
		(start 305.918616 -416.336734)
		(end 306.214526 -416.632644)
		(stroke
			(width 0.06477)
			(type default)
		)
		(layer "B.Cu")
	)
	(gr_line
		(start 306.189126 -415.38652)
		(end 305.918616 -415.65703)
		(stroke
			(width 0.06477)
			(type default)
		)
		(layer "B.Cu")
	)
	(gr_line
		(start 306.214526 -417.166044)
		(end 305.918616 -417.461954)
		(stroke
			(width 0.06477)
			(type default)
		)
		(layer "B.Cu")
	)
	(gr_line
		(start 306.905914 -182.438548)
		(end 306.905914 -182.438294)
		(stroke
			(width 0.06477)
			(type default)
		)
		(layer "B.Cu")
	)
	(gr_line
		(start 306.90693 -182.440072)
		(end 307.040534 -182.66791)
		(stroke
			(width 0.06477)
			(type default)
		)
		(layer "B.Cu")
	)
	(gr_line
		(start 306.98694 -182.126128)
		(end 307.71973 -182.316374)
		(stroke
			(width 0.06477)
			(type default)
		)
		(layer "B.Cu")
	)
	(gr_line
		(start 307.040534 -182.66791)
		(end 307.409596 -182.763414)
		(stroke
			(width 0.06477)
			(type default)
		)
		(layer "B.Cu")
	)
	(gr_line
		(start 307.409596 -182.763414)
		(end 307.637434 -182.629556)
		(stroke
			(width 0.06477)
			(type default)
		)
		(layer "B.Cu")
	)
	(gr_line
		(start 308.008274 -182.725822)
		(end 308.142132 -182.95366)
		(stroke
			(width 0.06477)
			(type default)
		)
		(layer "B.Cu")
	)
	(gr_line
		(start 308.088284 -182.412132)
		(end 308.821328 -182.602378)
		(stroke
			(width 0.06477)
			(type default)
		)
		(layer "B.Cu")
	)
	(gr_line
		(start 308.142132 -182.95366)
		(end 308.511194 -183.049418)
		(stroke
			(width 0.06477)
			(type default)
		)
		(layer "B.Cu")
	)
	(gr_line
		(start 308.363366 -417.166044)
		(end 308.659276 -417.461954)
		(stroke
			(width 0.06477)
			(type default)
		)
		(layer "B.Cu")
	)
	(gr_line
		(start 308.388766 -415.38652)
		(end 308.659276 -415.65703)
		(stroke
			(width 0.06477)
			(type default)
		)
		(layer "B.Cu")
	)
	(gr_line
		(start 308.511194 -183.049418)
		(end 308.739032 -182.91556)
		(stroke
			(width 0.06477)
			(type default)
		)
		(layer "B.Cu")
	)
	(gr_line
		(start 308.659276 -418.141658)
		(end 308.388766 -418.412168)
		(stroke
			(width 0.06477)
			(type default)
		)
		(layer "B.Cu")
	)
	(gr_line
		(start 308.659276 -416.336734)
		(end 308.363366 -416.632644)
		(stroke
			(width 0.06477)
			(type default)
		)
		(layer "B.Cu")
	)
	(gr_line
		(start 308.981856 -418.141658)
		(end 309.252366 -418.412168)
		(stroke
			(width 0.06477)
			(type default)
		)
		(layer "B.Cu")
	)
	(gr_line
		(start 308.981856 -416.336734)
		(end 309.277766 -416.632644)
		(stroke
			(width 0.06477)
			(type default)
		)
		(layer "B.Cu")
	)
	(gr_line
		(start 309.252366 -415.38652)
		(end 308.981856 -415.65703)
		(stroke
			(width 0.06477)
			(type default)
		)
		(layer "B.Cu")
	)
	(gr_line
		(start 309.277766 -417.166044)
		(end 308.981856 -417.461954)
		(stroke
			(width 0.06477)
			(type default)
		)
		(layer "B.Cu")
	)
	(gr_line
		(start 310.045862 -311.383934)
		(end 310.045862 -311.651904)
		(stroke
			(width 0.06477)
			(type default)
		)
		(layer "B.Cu")
	)
	(gr_line
		(start 310.320944 -311.108852)
		(end 310.045862 -311.383934)
		(stroke
			(width 0.06477)
			(type default)
		)
		(layer "B.Cu")
	)
	(gr_line
		(start 310.588914 -311.108852)
		(end 310.320944 -311.108852)
		(stroke
			(width 0.06477)
			(type default)
		)
		(layer "B.Cu")
	)
	(gr_line
		(start 310.818784 -311.336944)
		(end 310.274208 -311.88152)
		(stroke
			(width 0.06477)
			(type default)
		)
		(layer "B.Cu")
	)
	(gr_line
		(start 311.426606 -417.166044)
		(end 311.722516 -417.461954)
		(stroke
			(width 0.06477)
			(type default)
		)
		(layer "B.Cu")
	)
	(gr_line
		(start 311.452006 -415.38652)
		(end 311.722516 -415.65703)
		(stroke
			(width 0.06477)
			(type default)
		)
		(layer "B.Cu")
	)
	(gr_line
		(start 311.722516 -418.141658)
		(end 311.452006 -418.412168)
		(stroke
			(width 0.06477)
			(type default)
		)
		(layer "B.Cu")
	)
	(gr_line
		(start 311.722516 -416.336734)
		(end 311.426606 -416.632644)
		(stroke
			(width 0.06477)
			(type default)
		)
		(layer "B.Cu")
	)
	(gr_line
		(start 312.045096 -418.141658)
		(end 312.315606 -418.412168)
		(stroke
			(width 0.06477)
			(type default)
		)
		(layer "B.Cu")
	)
	(gr_line
		(start 312.045096 -416.336734)
		(end 312.341006 -416.632644)
		(stroke
			(width 0.06477)
			(type default)
		)
		(layer "B.Cu")
	)
	(gr_line
		(start 312.315606 -415.38652)
		(end 312.045096 -415.65703)
		(stroke
			(width 0.06477)
			(type default)
		)
		(layer "B.Cu")
	)
	(gr_line
		(start 312.341006 -417.166044)
		(end 312.045096 -417.461954)
		(stroke
			(width 0.06477)
			(type default)
		)
		(layer "B.Cu")
	)
	(gr_line
		(start 312.486548 -154.982418)
		(end 312.486548 -155.749498)
		(stroke
			(width 0.06477)
			(type default)
		)
		(layer "B.Cu")
	)
	(gr_line
		(start 312.486548 -153.829258)
		(end 312.486548 -154.596338)
		(stroke
			(width 0.06477)
			(type default)
		)
		(layer "B.Cu")
	)
	(gr_line
		(start 312.486548 -152.676098)
		(end 312.486548 -153.443178)
		(stroke
			(width 0.06477)
			(type default)
		)
		(layer "B.Cu")
	)
	(gr_line
		(start 312.486548 -151.522938)
		(end 312.486548 -152.290018)
		(stroke
			(width 0.06477)
			(type default)
		)
		(layer "B.Cu")
	)
	(gr_line
		(start 312.810398 -155.748228)
		(end 312.999628 -155.558998)
		(stroke
			(width 0.06477)
			(type default)
		)
		(layer "B.Cu")
	)
	(gr_line
		(start 312.810398 -154.595068)
		(end 312.999628 -154.405838)
		(stroke
			(width 0.06477)
			(type default)
		)
		(layer "B.Cu")
	)
	(gr_line
		(start 312.810398 -153.441908)
		(end 312.999628 -153.252678)
		(stroke
			(width 0.06477)
			(type default)
		)
		(layer "B.Cu")
	)
	(gr_line
		(start 312.810398 -152.288748)
		(end 312.999628 -152.099518)
		(stroke
			(width 0.06477)
			(type default)
		)
		(layer "B.Cu")
	)
	(gr_line
		(start 312.999628 -155.558998)
		(end 312.999628 -155.172918)
		(stroke
			(width 0.06477)
			(type default)
		)
		(layer "B.Cu")
	)
	(gr_line
		(start 312.999628 -155.172918)
		(end 312.810398 -154.983688)
		(stroke
			(width 0.06477)
			(type default)
		)
		(layer "B.Cu")
	)
	(gr_line
		(start 312.999628 -154.405838)
		(end 312.999628 -154.019758)
		(stroke
			(width 0.06477)
			(type default)
		)
		(layer "B.Cu")
	)
	(gr_line
		(start 312.999628 -154.019758)
		(end 312.810398 -153.830528)
		(stroke
			(width 0.06477)
			(type default)
		)
		(layer "B.Cu")
	)
	(gr_line
		(start 312.999628 -153.252678)
		(end 312.999628 -152.866598)
		(stroke
			(width 0.06477)
			(type default)
		)
		(layer "B.Cu")
	)
	(gr_line
		(start 312.999628 -152.866598)
		(end 312.810398 -152.677368)
		(stroke
			(width 0.06477)
			(type default)
		)
		(layer "B.Cu")
	)
	(gr_line
		(start 312.999628 -152.099518)
		(end 312.999628 -151.713438)
		(stroke
			(width 0.06477)
			(type default)
		)
		(layer "B.Cu")
	)
	(gr_line
		(start 312.999628 -151.713438)
		(end 312.810398 -151.524208)
		(stroke
			(width 0.06477)
			(type default)
		)
		(layer "B.Cu")
	)
	(gr_line
		(start 313.708288 -153.857452)
		(end 313.708288 -154.624532)
		(stroke
			(width 0.06477)
			(type default)
		)
		(layer "B.Cu")
	)
	(gr_line
		(start 313.708288 -152.704292)
		(end 313.708288 -153.471372)
		(stroke
			(width 0.06477)
			(type default)
		)
		(layer "B.Cu")
	)
	(gr_line
		(start 313.708288 -151.551132)
		(end 313.708288 -152.318212)
		(stroke
			(width 0.06477)
			(type default)
		)
		(layer "B.Cu")
	)
	(gr_line
		(start 314.032138 -154.623262)
		(end 314.221368 -154.434032)
		(stroke
			(width 0.06477)
			(type default)
		)
		(layer "B.Cu")
	)
	(gr_line
		(start 314.032138 -153.470102)
		(end 314.221368 -153.280872)
		(stroke
			(width 0.06477)
			(type default)
		)
		(layer "B.Cu")
	)
	(gr_line
		(start 314.032138 -152.316942)
		(end 314.221368 -152.127712)
		(stroke
			(width 0.06477)
			(type default)
		)
		(layer "B.Cu")
	)
	(gr_line
		(start 314.221368 -154.434032)
		(end 314.221368 -154.047952)
		(stroke
			(width 0.06477)
			(type default)
		)
		(layer "B.Cu")
	)
	(gr_line
		(start 314.221368 -154.047952)
		(end 314.032138 -153.858722)
		(stroke
			(width 0.06477)
			(type default)
		)
		(layer "B.Cu")
	)
	(gr_line
		(start 314.221368 -153.280872)
		(end 314.221368 -152.894792)
		(stroke
			(width 0.06477)
			(type default)
		)
		(layer "B.Cu")
	)
	(gr_line
		(start 314.221368 -152.894792)
		(end 314.032138 -152.705562)
		(stroke
			(width 0.06477)
			(type default)
		)
		(layer "B.Cu")
	)
	(gr_line
		(start 314.221368 -152.127712)
		(end 314.221368 -151.741632)
		(stroke
			(width 0.06477)
			(type default)
		)
		(layer "B.Cu")
	)
	(gr_line
		(start 314.221368 -151.741632)
		(end 314.032138 -151.552402)
		(stroke
			(width 0.06477)
			(type default)
		)
		(layer "B.Cu")
	)
	(gr_line
		(start 314.489846 -417.166044)
		(end 314.785756 -417.461954)
		(stroke
			(width 0.06477)
			(type default)
		)
		(layer "B.Cu")
	)
	(gr_line
		(start 314.515246 -415.38652)
		(end 314.785756 -415.65703)
		(stroke
			(width 0.06477)
			(type default)
		)
		(layer "B.Cu")
	)
	(gr_line
		(start 314.785756 -418.141658)
		(end 314.515246 -418.412168)
		(stroke
			(width 0.06477)
			(type default)
		)
		(layer "B.Cu")
	)
	(gr_line
		(start 314.785756 -416.336734)
		(end 314.489846 -416.632644)
		(stroke
			(width 0.06477)
			(type default)
		)
		(layer "B.Cu")
	)
	(gr_line
		(start 314.894722 -154.862276)
		(end 314.894722 -155.629356)
		(stroke
			(width 0.06477)
			(type default)
		)
		(layer "B.Cu")
	)
	(gr_line
		(start 314.894722 -153.709116)
		(end 314.894722 -154.476196)
		(stroke
			(width 0.06477)
			(type default)
		)
		(layer "B.Cu")
	)
	(gr_line
		(start 314.894722 -152.555956)
		(end 314.894722 -153.323036)
		(stroke
			(width 0.06477)
			(type default)
		)
		(layer "B.Cu")
	)
	(gr_line
		(start 314.894722 -151.402796)
		(end 314.894722 -152.169876)
		(stroke
			(width 0.06477)
			(type default)
		)
		(layer "B.Cu")
	)
	(gr_line
		(start 315.108336 -418.141658)
		(end 315.378846 -418.412168)
		(stroke
			(width 0.06477)
			(type default)
		)
		(layer "B.Cu")
	)
	(gr_line
		(start 315.108336 -416.336734)
		(end 315.404246 -416.632644)
		(stroke
			(width 0.06477)
			(type default)
		)
		(layer "B.Cu")
	)
	(gr_line
		(start 315.218572 -155.628086)
		(end 315.407802 -155.438856)
		(stroke
			(width 0.06477)
			(type default)
		)
		(layer "B.Cu")
	)
	(gr_line
		(start 315.218572 -154.474926)
		(end 315.407802 -154.285696)
		(stroke
			(width 0.06477)
			(type default)
		)
		(layer "B.Cu")
	)
	(gr_line
		(start 315.218572 -153.321766)
		(end 315.407802 -153.132536)
		(stroke
			(width 0.06477)
			(type default)
		)
		(layer "B.Cu")
	)
	(gr_line
		(start 315.218572 -152.168606)
		(end 315.407802 -151.979376)
		(stroke
			(width 0.06477)
			(type default)
		)
		(layer "B.Cu")
	)
	(gr_line
		(start 315.378846 -415.38652)
		(end 315.108336 -415.65703)
		(stroke
			(width 0.06477)
			(type default)
		)
		(layer "B.Cu")
	)
	(gr_line
		(start 315.404246 -417.166044)
		(end 315.108336 -417.461954)
		(stroke
			(width 0.06477)
			(type default)
		)
		(layer "B.Cu")
	)
	(gr_line
		(start 315.407802 -155.438856)
		(end 315.407802 -155.052776)
		(stroke
			(width 0.06477)
			(type default)
		)
		(layer "B.Cu")
	)
	(gr_line
		(start 315.407802 -155.052776)
		(end 315.218572 -154.863546)
		(stroke
			(width 0.06477)
			(type default)
		)
		(layer "B.Cu")
	)
	(gr_line
		(start 315.407802 -154.285696)
		(end 315.407802 -153.899616)
		(stroke
			(width 0.06477)
			(type default)
		)
		(layer "B.Cu")
	)
	(gr_line
		(start 315.407802 -153.899616)
		(end 315.218572 -153.710386)
		(stroke
			(width 0.06477)
			(type default)
		)
		(layer "B.Cu")
	)
	(gr_line
		(start 315.407802 -153.132536)
		(end 315.407802 -152.746456)
		(stroke
			(width 0.06477)
			(type default)
		)
		(layer "B.Cu")
	)
	(gr_line
		(start 315.407802 -152.746456)
		(end 315.218572 -152.557226)
		(stroke
			(width 0.06477)
			(type default)
		)
		(layer "B.Cu")
	)
	(gr_line
		(start 315.407802 -151.979376)
		(end 315.407802 -151.593296)
		(stroke
			(width 0.06477)
			(type default)
		)
		(layer "B.Cu")
	)
	(gr_line
		(start 315.407802 -151.593296)
		(end 315.218572 -151.404066)
		(stroke
			(width 0.06477)
			(type default)
		)
		(layer "B.Cu")
	)
	(gr_line
		(start 315.936884 2.292858)
		(end 315.791088 2.292858)
		(stroke
			(width 0.06477)
			(type default)
		)
		(layer "B.Cu")
	)
	(gr_line
		(start 315.957712 2.79273)
		(end 315.791088 2.79273)
		(stroke
			(width 0.06477)
			(type default)
		)
		(layer "B.Cu")
	)
	(gr_line
		(start 316.02553 2.381504)
		(end 315.936884 2.292858)
		(stroke
			(width 0.06477)
			(type default)
		)
		(layer "B.Cu")
	)
	(gr_line
		(start 316.045088 2.705354)
		(end 315.957712 2.79273)
		(stroke
			(width 0.06477)
			(type default)
		)
		(layer "B.Cu")
	)
	(gr_line
		(start 316.046358 2.381504)
		(end 316.02553 2.381504)
		(stroke
			(width 0.06477)
			(type default)
		)
		(layer "B.Cu")
	)
	(gr_line
		(start 316.07252 -155.509214)
		(end 316.07252 -154.742134)
		(stroke
			(width 0.06477)
			(type default)
		)
		(layer "B.Cu")
	)
	(gr_line
		(start 316.07252 -154.356054)
		(end 316.07252 -153.588974)
		(stroke
			(width 0.06477)
			(type default)
		)
		(layer "B.Cu")
	)
	(gr_line
		(start 316.07252 -153.202894)
		(end 316.07252 -152.435814)
		(stroke
			(width 0.06477)
			(type default)
		)
		(layer "B.Cu")
	)
	(gr_line
		(start 316.07252 -152.049734)
		(end 316.07252 -151.282654)
		(stroke
			(width 0.06477)
			(type default)
		)
		(layer "B.Cu")
	)
	(gr_line
		(start 316.39637 -155.507944)
		(end 316.5856 -155.318714)
		(stroke
			(width 0.06477)
			(type default)
		)
		(layer "B.Cu")
	)
	(gr_line
		(start 316.39637 -154.354784)
		(end 316.5856 -154.165554)
		(stroke
			(width 0.06477)
			(type default)
		)
		(layer "B.Cu")
	)
	(gr_line
		(start 316.39637 -153.201624)
		(end 316.5856 -153.012394)
		(stroke
			(width 0.06477)
			(type default)
		)
		(layer "B.Cu")
	)
	(gr_line
		(start 316.39637 -152.048464)
		(end 316.5856 -151.859234)
		(stroke
			(width 0.06477)
			(type default)
		)
		(layer "B.Cu")
	)
	(gr_line
		(start 316.44336 -2.969006)
		(end 315.791088 -2.787142)
		(stroke
			(width 0.06477)
			(type default)
		)
		(layer "B.Cu")
	)
	(gr_line
		(start 316.44336 -2.105406)
		(end 315.791088 -2.28727)
		(stroke
			(width 0.06477)
			(type default)
		)
		(layer "B.Cu")
	)
	(gr_line
		(start 316.44336 7.190994)
		(end 315.791088 7.372858)
		(stroke
			(width 0.06477)
			(type default)
		)
		(layer "B.Cu")
	)
	(gr_line
		(start 316.44336 8.054594)
		(end 315.791088 7.87273)
		(stroke
			(width 0.06477)
			(type default)
		)
		(layer "B.Cu")
	)
	(gr_line
		(start 316.5856 -155.318714)
		(end 316.5856 -154.932634)
		(stroke
			(width 0.06477)
			(type default)
		)
		(layer "B.Cu")
	)
	(gr_line
		(start 316.5856 -154.932634)
		(end 316.39637 -154.743404)
		(stroke
			(width 0.06477)
			(type default)
		)
		(layer "B.Cu")
	)
	(gr_line
		(start 316.5856 -154.165554)
		(end 316.5856 -153.779474)
		(stroke
			(width 0.06477)
			(type default)
		)
		(layer "B.Cu")
	)
	(gr_line
		(start 316.5856 -153.779474)
		(end 316.39637 -153.590244)
		(stroke
			(width 0.06477)
			(type default)
		)
		(layer "B.Cu")
	)
	(gr_line
		(start 316.5856 -153.012394)
		(end 316.5856 -152.626314)
		(stroke
			(width 0.06477)
			(type default)
		)
		(layer "B.Cu")
	)
	(gr_line
		(start 316.5856 -152.626314)
		(end 316.39637 -152.437084)
		(stroke
			(width 0.06477)
			(type default)
		)
		(layer "B.Cu")
	)
	(gr_line
		(start 316.5856 -151.859234)
		(end 316.5856 -151.473154)
		(stroke
			(width 0.06477)
			(type default)
		)
		(layer "B.Cu")
	)
	(gr_line
		(start 316.5856 -151.473154)
		(end 316.39637 -151.283924)
		(stroke
			(width 0.06477)
			(type default)
		)
		(layer "B.Cu")
	)
	(gr_line
		(start 317.553086 -417.166044)
		(end 317.848996 -417.461954)
		(stroke
			(width 0.06477)
			(type default)
		)
		(layer "B.Cu")
	)
	(gr_line
		(start 317.578486 -415.38652)
		(end 317.848996 -415.65703)
		(stroke
			(width 0.06477)
			(type default)
		)
		(layer "B.Cu")
	)
	(gr_line
		(start 317.848996 -418.141658)
		(end 317.578486 -418.412168)
		(stroke
			(width 0.06477)
			(type default)
		)
		(layer "B.Cu")
	)
	(gr_line
		(start 317.848996 -416.336734)
		(end 317.553086 -416.632644)
		(stroke
			(width 0.06477)
			(type default)
		)
		(layer "B.Cu")
	)
	(gr_line
		(start 317.92037 -189.749684)
		(end 318.195706 -189.873128)
		(stroke
			(width 0.06477)
			(type default)
		)
		(layer "B.Cu")
	)
	(gr_line
		(start 318.063626 -190.167514)
		(end 317.78829 -190.043816)
		(stroke
			(width 0.06477)
			(type default)
		)
		(layer "B.Cu")
	)
	(gr_line
		(start 318.159384 -190.419482)
		(end 318.064388 -190.169292)
		(stroke
			(width 0.06477)
			(type default)
		)
		(layer "B.Cu")
	)
	(gr_line
		(start 318.171576 -418.141658)
		(end 318.442086 -418.412168)
		(stroke
			(width 0.06477)
			(type default)
		)
		(layer "B.Cu")
	)
	(gr_line
		(start 318.171576 -416.336734)
		(end 318.467486 -416.632644)
		(stroke
			(width 0.06477)
			(type default)
		)
		(layer "B.Cu")
	)
	(gr_line
		(start 318.195706 -189.873128)
		(end 318.898016 -190.188596)
		(stroke
			(width 0.06477)
			(type default)
		)
		(layer "B.Cu")
	)
	(gr_line
		(start 318.442086 -415.38652)
		(end 318.171576 -415.65703)
		(stroke
			(width 0.06477)
			(type default)
		)
		(layer "B.Cu")
	)
	(gr_line
		(start 318.467486 -417.166044)
		(end 318.171576 -417.461954)
		(stroke
			(width 0.06477)
			(type default)
		)
		(layer "B.Cu")
	)
	(gr_line
		(start 318.514222 -190.57874)
		(end 318.159384 -190.419482)
		(stroke
			(width 0.06477)
			(type default)
		)
		(layer "B.Cu")
	)
	(gr_line
		(start 318.764412 -190.48349)
		(end 318.514222 -190.57874)
		(stroke
			(width 0.06477)
			(type default)
		)
		(layer "B.Cu")
	)
	(gr_line
		(start 319.216024 -190.894208)
		(end 319.120774 -190.643764)
		(stroke
			(width 0.06477)
			(type default)
		)
		(layer "B.Cu")
	)
	(gr_line
		(start 319.252346 -190.3476)
		(end 319.954656 -190.663068)
		(stroke
			(width 0.06477)
			(type default)
		)
		(layer "B.Cu")
	)
	(gr_line
		(start 319.570862 -191.053212)
		(end 319.216024 -190.894208)
		(stroke
			(width 0.06477)
			(type default)
		)
		(layer "B.Cu")
	)
	(gr_line
		(start 319.821052 -190.957962)
		(end 319.570862 -191.053212)
		(stroke
			(width 0.06477)
			(type default)
		)
		(layer "B.Cu")
	)
	(gr_line
		(start 320.616326 -417.166044)
		(end 320.912236 -417.461954)
		(stroke
			(width 0.06477)
			(type default)
		)
		(layer "B.Cu")
	)
	(gr_line
		(start 320.641726 -415.38652)
		(end 320.912236 -415.65703)
		(stroke
			(width 0.06477)
			(type default)
		)
		(layer "B.Cu")
	)
	(gr_line
		(start 320.912236 -418.141658)
		(end 320.641726 -418.412168)
		(stroke
			(width 0.06477)
			(type default)
		)
		(layer "B.Cu")
	)
	(gr_line
		(start 320.912236 -416.336734)
		(end 320.616326 -416.632644)
		(stroke
			(width 0.06477)
			(type default)
		)
		(layer "B.Cu")
	)
	(gr_line
		(start 321.234816 -418.141658)
		(end 321.505326 -418.412168)
		(stroke
			(width 0.06477)
			(type default)
		)
		(layer "B.Cu")
	)
	(gr_line
		(start 321.234816 -416.336734)
		(end 321.530726 -416.632644)
		(stroke
			(width 0.06477)
			(type default)
		)
		(layer "B.Cu")
	)
	(gr_line
		(start 321.505326 -415.38652)
		(end 321.234816 -415.65703)
		(stroke
			(width 0.06477)
			(type default)
		)
		(layer "B.Cu")
	)
	(gr_line
		(start 321.530726 -417.166044)
		(end 321.234816 -417.461954)
		(stroke
			(width 0.06477)
			(type default)
		)
		(layer "B.Cu")
	)
	(gr_line
		(start 323.679566 -417.166044)
		(end 323.975476 -417.461954)
		(stroke
			(width 0.06477)
			(type default)
		)
		(layer "B.Cu")
	)
	(gr_line
		(start 323.704966 -415.38652)
		(end 323.975476 -415.65703)
		(stroke
			(width 0.06477)
			(type default)
		)
		(layer "B.Cu")
	)
	(gr_line
		(start 323.975476 -418.141658)
		(end 323.704966 -418.412168)
		(stroke
			(width 0.06477)
			(type default)
		)
		(layer "B.Cu")
	)
	(gr_line
		(start 323.975476 -416.336734)
		(end 323.679566 -416.632644)
		(stroke
			(width 0.06477)
			(type default)
		)
		(layer "B.Cu")
	)
	(gr_line
		(start 324.298056 -418.141658)
		(end 324.568566 -418.412168)
		(stroke
			(width 0.06477)
			(type default)
		)
		(layer "B.Cu")
	)
	(gr_line
		(start 324.298056 -416.336734)
		(end 324.593966 -416.632644)
		(stroke
			(width 0.06477)
			(type default)
		)
		(layer "B.Cu")
	)
	(gr_line
		(start 324.568566 -415.38652)
		(end 324.298056 -415.65703)
		(stroke
			(width 0.06477)
			(type default)
		)
		(layer "B.Cu")
	)
	(gr_line
		(start 324.593966 -417.166044)
		(end 324.298056 -417.461954)
		(stroke
			(width 0.06477)
			(type default)
		)
		(layer "B.Cu")
	)
	(gr_line
		(start 326.742806 -417.166044)
		(end 327.038716 -417.461954)
		(stroke
			(width 0.06477)
			(type default)
		)
		(layer "B.Cu")
	)
	(gr_line
		(start 326.768206 -415.38652)
		(end 327.038716 -415.65703)
		(stroke
			(width 0.06477)
			(type default)
		)
		(layer "B.Cu")
	)
	(gr_line
		(start 327.038716 -416.336734)
		(end 326.742806 -416.632644)
		(stroke
			(width 0.06477)
			(type default)
		)
		(layer "B.Cu")
	)
	(gr_line
		(start 327.361296 -416.336734)
		(end 327.657206 -416.632644)
		(stroke
			(width 0.06477)
			(type default)
		)
		(layer "B.Cu")
	)
	(gr_line
		(start 327.631806 -415.38652)
		(end 327.361296 -415.65703)
		(stroke
			(width 0.06477)
			(type default)
		)
		(layer "B.Cu")
	)
	(gr_line
		(start 327.657206 -417.166044)
		(end 327.361296 -417.461954)
		(stroke
			(width 0.06477)
			(type default)
		)
		(layer "B.Cu")
	)
	(gr_line
		(start 329.806046 -417.166044)
		(end 330.101956 -417.461954)
		(stroke
			(width 0.06477)
			(type default)
		)
		(layer "B.Cu")
	)
	(gr_line
		(start 329.831446 -415.38652)
		(end 330.101956 -415.65703)
		(stroke
			(width 0.06477)
			(type default)
		)
		(layer "B.Cu")
	)
	(gr_line
		(start 330.101956 -418.141658)
		(end 329.831446 -418.412168)
		(stroke
			(width 0.06477)
			(type default)
		)
		(layer "B.Cu")
	)
	(gr_line
		(start 330.101956 -416.336734)
		(end 329.806046 -416.632644)
		(stroke
			(width 0.06477)
			(type default)
		)
		(layer "B.Cu")
	)
	(gr_line
		(start 330.424536 -418.141658)
		(end 330.695046 -418.412168)
		(stroke
			(width 0.06477)
			(type default)
		)
		(layer "B.Cu")
	)
	(gr_line
		(start 330.424536 -416.336734)
		(end 330.720446 -416.632644)
		(stroke
			(width 0.06477)
			(type default)
		)
		(layer "B.Cu")
	)
	(gr_line
		(start 330.695046 -415.38652)
		(end 330.424536 -415.65703)
		(stroke
			(width 0.06477)
			(type default)
		)
		(layer "B.Cu")
	)
	(gr_line
		(start 330.720446 -417.166044)
		(end 330.424536 -417.461954)
		(stroke
			(width 0.06477)
			(type default)
		)
		(layer "B.Cu")
	)
	(gr_line
		(start 332.869286 -417.166044)
		(end 333.165196 -417.461954)
		(stroke
			(width 0.06477)
			(type default)
		)
		(layer "B.Cu")
	)
	(gr_line
		(start 332.894686 -415.38652)
		(end 333.165196 -415.65703)
		(stroke
			(width 0.06477)
			(type default)
		)
		(layer "B.Cu")
	)
	(gr_line
		(start 333.165196 -416.336734)
		(end 332.869286 -416.632644)
		(stroke
			(width 0.06477)
			(type default)
		)
		(layer "B.Cu")
	)
	(gr_line
		(start 333.487776 -416.336734)
		(end 333.783686 -416.632644)
		(stroke
			(width 0.06477)
			(type default)
		)
		(layer "B.Cu")
	)
	(gr_line
		(start 333.758286 -415.38652)
		(end 333.487776 -415.65703)
		(stroke
			(width 0.06477)
			(type default)
		)
		(layer "B.Cu")
	)
	(gr_line
		(start 333.783686 -417.166044)
		(end 333.487776 -417.461954)
		(stroke
			(width 0.06477)
			(type default)
		)
		(layer "B.Cu")
	)
	(gr_line
		(start 335.932526 -417.166044)
		(end 336.228436 -417.461954)
		(stroke
			(width 0.06477)
			(type default)
		)
		(layer "B.Cu")
	)
	(gr_line
		(start 335.957926 -415.38652)
		(end 336.228436 -415.65703)
		(stroke
			(width 0.06477)
			(type default)
		)
		(layer "B.Cu")
	)
	(gr_line
		(start 336.228436 -418.141658)
		(end 335.957926 -418.412168)
		(stroke
			(width 0.06477)
			(type default)
		)
		(layer "B.Cu")
	)
	(gr_line
		(start 336.228436 -416.336734)
		(end 335.932526 -416.632644)
		(stroke
			(width 0.06477)
			(type default)
		)
		(layer "B.Cu")
	)
	(gr_line
		(start 336.551016 -418.141658)
		(end 336.821526 -418.412168)
		(stroke
			(width 0.06477)
			(type default)
		)
		(layer "B.Cu")
	)
	(gr_line
		(start 336.551016 -416.336734)
		(end 336.846926 -416.632644)
		(stroke
			(width 0.06477)
			(type default)
		)
		(layer "B.Cu")
	)
	(gr_line
		(start 336.821526 -415.38652)
		(end 336.551016 -415.65703)
		(stroke
			(width 0.06477)
			(type default)
		)
		(layer "B.Cu")
	)
	(gr_line
		(start 336.846926 -417.166044)
		(end 336.551016 -417.461954)
		(stroke
			(width 0.06477)
			(type default)
		)
		(layer "B.Cu")
	)
	(gr_line
		(start 337.80349 -302.733202)
		(end 337.61426 -302.922432)
		(stroke
			(width 0.06477)
			(type default)
		)
		(layer "B.Cu")
	)
	(gr_line
		(start 338.19211 -302.733202)
		(end 337.80349 -302.733202)
		(stroke
			(width 0.06477)
			(type default)
		)
		(layer "B.Cu")
	)
	(gr_line
		(start 338.38134 -302.922432)
		(end 338.19211 -302.733202)
		(stroke
			(width 0.06477)
			(type default)
		)
		(layer "B.Cu")
	)
	(gr_line
		(start 338.38261 -303.246282)
		(end 337.61299 -303.246282)
		(stroke
			(width 0.06477)
			(type default)
		)
		(layer "B.Cu")
	)
	(gr_line
		(start 338.706968 -212.492336)
		(end 338.706968 -212.106256)
		(stroke
			(width 0.06477)
			(type default)
		)
		(layer "B.Cu")
	)
	(gr_line
		(start 338.706968 -212.106256)
		(end 338.896198 -211.917026)
		(stroke
			(width 0.06477)
			(type default)
		)
		(layer "B.Cu")
	)
	(gr_line
		(start 338.706968 -211.339176)
		(end 338.706968 -210.953096)
		(stroke
			(width 0.06477)
			(type default)
		)
		(layer "B.Cu")
	)
	(gr_line
		(start 338.706968 -210.953096)
		(end 338.896198 -210.763866)
		(stroke
			(width 0.06477)
			(type default)
		)
		(layer "B.Cu")
	)
	(gr_line
		(start 338.706968 -210.186016)
		(end 338.706968 -209.799936)
		(stroke
			(width 0.06477)
			(type default)
		)
		(layer "B.Cu")
	)
	(gr_line
		(start 338.706968 -209.799936)
		(end 338.896198 -209.610706)
		(stroke
			(width 0.06477)
			(type default)
		)
		(layer "B.Cu")
	)
	(gr_line
		(start 338.706968 -209.032856)
		(end 338.706968 -208.646776)
		(stroke
			(width 0.06477)
			(type default)
		)
		(layer "B.Cu")
	)
	(gr_line
		(start 338.706968 -208.646776)
		(end 338.896198 -208.457546)
		(stroke
			(width 0.06477)
			(type default)
		)
		(layer "B.Cu")
	)
	(gr_line
		(start 338.710016 -296.469054)
		(end 338.710016 -296.450004)
		(stroke
			(width 0.0381)
			(type default)
		)
		(layer "B.Cu")
	)
	(gr_line
		(start 338.710016 -296.450004)
		(end 338.776056 -296.383964)
		(stroke
			(width 0.0381)
			(type default)
		)
		(layer "B.Cu")
	)
	(gr_line
		(start 338.776056 -295.956228)
		(end 338.775802 -295.955974)
		(stroke
			(width 0.0381)
			(type default)
		)
		(layer "B.Cu")
	)
	(gr_line
		(start 338.88553 -217.17)
		(end 338.896198 -217.159332)
		(stroke
			(width 0.06477)
			(type default)
		)
		(layer "B.Cu")
	)
	(gr_line
		(start 338.896198 -212.681566)
		(end 338.706968 -212.492336)
		(stroke
			(width 0.06477)
			(type default)
		)
		(layer "B.Cu")
	)
	(gr_line
		(start 338.896198 -211.528406)
		(end 338.706968 -211.339176)
		(stroke
			(width 0.06477)
			(type default)
		)
		(layer "B.Cu")
	)
	(gr_line
		(start 338.896198 -210.375246)
		(end 338.706968 -210.186016)
		(stroke
			(width 0.06477)
			(type default)
		)
		(layer "B.Cu")
	)
	(gr_line
		(start 338.896198 -209.222086)
		(end 338.706968 -209.032856)
		(stroke
			(width 0.06477)
			(type default)
		)
		(layer "B.Cu")
	)
	(gr_line
		(start 338.96173 -302.733202)
		(end 338.7725 -302.922432)
		(stroke
			(width 0.06477)
			(type default)
		)
		(layer "B.Cu")
	)
	(gr_line
		(start 338.966556 -296.383964)
		(end 339.032596 -296.450004)
		(stroke
			(width 0.0381)
			(type default)
		)
		(layer "B.Cu")
	)
	(gr_line
		(start 338.995766 -417.166044)
		(end 339.291676 -417.461954)
		(stroke
			(width 0.06477)
			(type default)
		)
		(layer "B.Cu")
	)
	(gr_arc
		(start 339.00491 -295.50106)
		(mid 338.994919 -295.50857)
		(end 338.985098 -295.5163)
		(stroke
			(width 0.0381)
			(type default)
		)
		(layer "B.Cu")
	)
	(gr_line
		(start 339.00491 -295.50106)
		(end 339.02777 -295.41597)
		(stroke
			(width 0.0381)
			(type default)
		)
		(layer "B.Cu")
	)
	(gr_line
		(start 339.021166 -415.38652)
		(end 339.291676 -415.65703)
		(stroke
			(width 0.06477)
			(type default)
		)
		(layer "B.Cu")
	)
	(gr_line
		(start 339.02777 -295.41597)
		(end 338.871052 -295.145968)
		(stroke
			(width 0.0381)
			(type default)
		)
		(layer "B.Cu")
	)
	(gr_line
		(start 339.032596 -296.450004)
		(end 339.032596 -296.469054)
		(stroke
			(width 0.0381)
			(type default)
		)
		(layer "B.Cu")
	)
	(gr_line
		(start 339.184488 -295.685972)
		(end 339.105494 -295.665144)
		(stroke
			(width 0.0381)
			(type default)
		)
		(layer "B.Cu")
	)
	(gr_line
		(start 339.220048 -217.158062)
		(end 339.220048 -217.191082)
		(stroke
			(width 0.06477)
			(type default)
		)
		(layer "B.Cu")
	)
	(gr_line
		(start 339.220048 -211.915756)
		(end 339.220048 -212.682836)
		(stroke
			(width 0.06477)
			(type default)
		)
		(layer "B.Cu")
	)
	(gr_line
		(start 339.220048 -210.762596)
		(end 339.220048 -211.529676)
		(stroke
			(width 0.06477)
			(type default)
		)
		(layer "B.Cu")
	)
	(gr_line
		(start 339.220048 -209.609436)
		(end 339.220048 -210.376516)
		(stroke
			(width 0.06477)
			(type default)
		)
		(layer "B.Cu")
	)
	(gr_line
		(start 339.220048 -208.456276)
		(end 339.220048 -209.223356)
		(stroke
			(width 0.06477)
			(type default)
		)
		(layer "B.Cu")
	)
	(gr_line
		(start 339.291676 -418.141658)
		(end 339.021166 -418.412168)
		(stroke
			(width 0.06477)
			(type default)
		)
		(layer "B.Cu")
	)
	(gr_line
		(start 339.291676 -416.336734)
		(end 338.995766 -416.632644)
		(stroke
			(width 0.06477)
			(type default)
		)
		(layer "B.Cu")
	)
	(gr_line
		(start 339.341206 -295.955974)
		(end 339.184488 -295.685972)
		(stroke
			(width 0.0381)
			(type default)
		)
		(layer "B.Cu")
	)
	(gr_line
		(start 339.35035 -302.733202)
		(end 338.96173 -302.733202)
		(stroke
			(width 0.06477)
			(type default)
		)
		(layer "B.Cu")
	)
	(gr_line
		(start 339.53958 -302.922432)
		(end 339.35035 -302.733202)
		(stroke
			(width 0.06477)
			(type default)
		)
		(layer "B.Cu")
	)
	(gr_line
		(start 339.54085 -303.246282)
		(end 338.77123 -303.246282)
		(stroke
			(width 0.06477)
			(type default)
		)
		(layer "B.Cu")
	)
	(gr_line
		(start 339.614256 -418.141658)
		(end 339.884766 -418.412168)
		(stroke
			(width 0.06477)
			(type default)
		)
		(layer "B.Cu")
	)
	(gr_line
		(start 339.614256 -416.336734)
		(end 339.910166 -416.632644)
		(stroke
			(width 0.06477)
			(type default)
		)
		(layer "B.Cu")
	)
	(gr_line
		(start 339.884766 -415.38652)
		(end 339.614256 -415.65703)
		(stroke
			(width 0.06477)
			(type default)
		)
		(layer "B.Cu")
	)
	(gr_line
		(start 339.910166 -417.166044)
		(end 339.614256 -417.461954)
		(stroke
			(width 0.06477)
			(type default)
		)
		(layer "B.Cu")
	)
	(gr_line
		(start 340.11997 -302.733202)
		(end 339.93074 -302.922432)
		(stroke
			(width 0.06477)
			(type default)
		)
		(layer "B.Cu")
	)
	(gr_line
		(start 340.50859 -302.733202)
		(end 340.11997 -302.733202)
		(stroke
			(width 0.06477)
			(type default)
		)
		(layer "B.Cu")
	)
	(gr_line
		(start 340.600792 -300.146974)
		(end 340.94801 -299.799756)
		(stroke
			(width 0.06477)
			(type default)
		)
		(layer "B.Cu")
	)
	(gr_line
		(start 340.600792 -299.130974)
		(end 340.945724 -299.475906)
		(stroke
			(width 0.06477)
			(type default)
		)
		(layer "B.Cu")
	)
	(gr_line
		(start 340.69782 -302.922432)
		(end 340.50859 -302.733202)
		(stroke
			(width 0.06477)
			(type default)
		)
		(layer "B.Cu")
	)
	(gr_line
		(start 340.69909 -303.246282)
		(end 339.92947 -303.246282)
		(stroke
			(width 0.06477)
			(type default)
		)
		(layer "B.Cu")
	)
	(gr_line
		(start 340.945724 -299.475906)
		(end 340.94928 -299.475906)
		(stroke
			(width 0.06477)
			(type default)
		)
		(layer "B.Cu")
	)
	(gr_line
		(start 341.396574 -302.733202)
		(end 341.207344 -302.922432)
		(stroke
			(width 0.06477)
			(type default)
		)
		(layer "B.Cu")
	)
	(gr_line
		(start 341.514938 -299.475906)
		(end 342.259158 -299.475906)
		(stroke
			(width 0.06477)
			(type default)
		)
		(layer "B.Cu")
	)
	(gr_line
		(start 341.516208 -299.799756)
		(end 341.692738 -299.976286)
		(stroke
			(width 0.06477)
			(type default)
		)
		(layer "B.Cu")
	)
	(gr_line
		(start 341.692738 -299.976286)
		(end 342.081358 -299.976286)
		(stroke
			(width 0.06477)
			(type default)
		)
		(layer "B.Cu")
	)
	(gr_line
		(start 341.785194 -302.733202)
		(end 341.396574 -302.733202)
		(stroke
			(width 0.06477)
			(type default)
		)
		(layer "B.Cu")
	)
	(gr_line
		(start 341.974424 -302.922432)
		(end 341.785194 -302.733202)
		(stroke
			(width 0.06477)
			(type default)
		)
		(layer "B.Cu")
	)
	(gr_line
		(start 341.975694 -303.246282)
		(end 341.206074 -303.246282)
		(stroke
			(width 0.06477)
			(type default)
		)
		(layer "B.Cu")
	)
	(gr_line
		(start 342.059006 -417.166044)
		(end 342.337644 -417.444682)
		(stroke
			(width 0.06477)
			(type default)
		)
		(layer "B.Cu")
	)
	(gr_line
		(start 342.081358 -299.976286)
		(end 342.257888 -299.799756)
		(stroke
			(width 0.06477)
			(type default)
		)
		(layer "B.Cu")
	)
	(gr_line
		(start 342.084406 -415.38652)
		(end 342.348058 -415.650172)
		(stroke
			(width 0.06477)
			(type default)
		)
		(layer "B.Cu")
	)
	(gr_line
		(start 342.337644 -418.15893)
		(end 342.084406 -418.412168)
		(stroke
			(width 0.06477)
			(type default)
		)
		(layer "B.Cu")
	)
	(gr_line
		(start 342.337644 -418.124386)
		(end 342.337644 -418.15893)
		(stroke
			(width 0.06477)
			(type default)
		)
		(layer "B.Cu")
	)
	(gr_line
		(start 342.337644 -417.444682)
		(end 342.337644 -417.479226)
		(stroke
			(width 0.06477)
			(type default)
		)
		(layer "B.Cu")
	)
	(gr_line
		(start 342.348058 -416.343592)
		(end 342.059006 -416.632644)
		(stroke
			(width 0.06477)
			(type default)
		)
		(layer "B.Cu")
	)
	(gr_line
		(start 342.348058 -416.329876)
		(end 342.348058 -416.343592)
		(stroke
			(width 0.06477)
			(type default)
		)
		(layer "B.Cu")
	)
	(gr_line
		(start 342.348058 -415.650172)
		(end 342.348058 -415.663888)
		(stroke
			(width 0.06477)
			(type default)
		)
		(layer "B.Cu")
	)
	(gr_line
		(start 342.661494 -418.125656)
		(end 342.948006 -418.412168)
		(stroke
			(width 0.06477)
			(type default)
		)
		(layer "B.Cu")
	)
	(gr_line
		(start 342.671908 -416.331146)
		(end 342.973406 -416.632644)
		(stroke
			(width 0.06477)
			(type default)
		)
		(layer "B.Cu")
	)
	(gr_line
		(start 342.948006 -415.38652)
		(end 342.671908 -415.662618)
		(stroke
			(width 0.06477)
			(type default)
		)
		(layer "B.Cu")
	)
	(gr_line
		(start 342.973406 -417.166044)
		(end 342.661494 -417.477956)
		(stroke
			(width 0.06477)
			(type default)
		)
		(layer "B.Cu")
	)
	(gr_line
		(start 343.5096 -301.505874)
		(end 343.514934 -301.511208)
		(stroke
			(width 0.06477)
			(type default)
		)
		(layer "B.Cu")
	)
	(gr_line
		(start 343.514934 -302.311308)
		(end 343.5096 -302.316642)
		(stroke
			(width 0.06477)
			(type default)
		)
		(layer "B.Cu")
	)
	(gr_line
		(start 344.803984 -297.222672)
		(end 344.993214 -297.033442)
		(stroke
			(width 0.06477)
			(type default)
		)
		(layer "B.Cu")
	)
	(gr_line
		(start 344.993214 -297.033442)
		(end 345.379294 -297.033442)
		(stroke
			(width 0.06477)
			(type default)
		)
		(layer "B.Cu")
	)
	(gr_line
		(start 345.122246 -417.166044)
		(end 345.418156 -417.461954)
		(stroke
			(width 0.06477)
			(type default)
		)
		(layer "B.Cu")
	)
	(gr_line
		(start 345.147646 -415.38652)
		(end 345.418156 -415.65703)
		(stroke
			(width 0.06477)
			(type default)
		)
		(layer "B.Cu")
	)
	(gr_line
		(start 345.379294 -297.033442)
		(end 345.568524 -297.222672)
		(stroke
			(width 0.06477)
			(type default)
		)
		(layer "B.Cu")
	)
	(gr_line
		(start 345.418156 -418.141658)
		(end 345.147646 -418.412168)
		(stroke
			(width 0.06477)
			(type default)
		)
		(layer "B.Cu")
	)
	(gr_line
		(start 345.418156 -416.336734)
		(end 345.122246 -416.632644)
		(stroke
			(width 0.06477)
			(type default)
		)
		(layer "B.Cu")
	)
	(gr_line
		(start 345.569794 -297.546522)
		(end 344.802714 -297.546522)
		(stroke
			(width 0.06477)
			(type default)
		)
		(layer "B.Cu")
	)
	(gr_line
		(start 345.740736 -418.141658)
		(end 346.011246 -418.412168)
		(stroke
			(width 0.06477)
			(type default)
		)
		(layer "B.Cu")
	)
	(gr_line
		(start 345.740736 -416.336734)
		(end 346.036646 -416.632644)
		(stroke
			(width 0.06477)
			(type default)
		)
		(layer "B.Cu")
	)
	(gr_line
		(start 346.011246 -415.38652)
		(end 345.740736 -415.65703)
		(stroke
			(width 0.06477)
			(type default)
		)
		(layer "B.Cu")
	)
	(gr_line
		(start 346.036646 -417.166044)
		(end 345.740736 -417.461954)
		(stroke
			(width 0.06477)
			(type default)
		)
		(layer "B.Cu")
	)
	(gr_line
		(start 346.226384 -297.222672)
		(end 346.415614 -297.033442)
		(stroke
			(width 0.06477)
			(type default)
		)
		(layer "B.Cu")
	)
	(gr_line
		(start 346.272358 -214.81796)
		(end 346.373704 -214.573358)
		(stroke
			(width 0.06477)
			(type default)
		)
		(layer "B.Cu")
	)
	(gr_line
		(start 346.415614 -297.033442)
		(end 346.801694 -297.033442)
		(stroke
			(width 0.06477)
			(type default)
		)
		(layer "B.Cu")
	)
	(gr_line
		(start 346.418154 -215.170258)
		(end 346.272358 -214.81796)
		(stroke
			(width 0.06477)
			(type default)
		)
		(layer "B.Cu")
	)
	(gr_line
		(start 346.66301 -215.271604)
		(end 346.418154 -215.170258)
		(stroke
			(width 0.06477)
			(type default)
		)
		(layer "B.Cu")
	)
	(gr_line
		(start 346.801694 -297.033442)
		(end 346.990924 -297.222672)
		(stroke
			(width 0.06477)
			(type default)
		)
		(layer "B.Cu")
	)
	(gr_line
		(start 346.905834 -216.34704)
		(end 347.006926 -216.102438)
		(stroke
			(width 0.06477)
			(type default)
		)
		(layer "B.Cu")
	)
	(gr_line
		(start 346.962476 -215.148414)
		(end 346.672662 -214.448644)
		(stroke
			(width 0.06477)
			(type default)
		)
		(layer "B.Cu")
	)
	(gr_line
		(start 346.992194 -297.546522)
		(end 346.225114 -297.546522)
		(stroke
			(width 0.06477)
			(type default)
		)
		(layer "B.Cu")
	)
	(gr_line
		(start 347.05163 -216.699338)
		(end 346.905834 -216.34704)
		(stroke
			(width 0.06477)
			(type default)
		)
		(layer "B.Cu")
	)
	(gr_line
		(start 347.296232 -216.800684)
		(end 347.05163 -216.699338)
		(stroke
			(width 0.06477)
			(type default)
		)
		(layer "B.Cu")
	)
	(gr_line
		(start 347.341444 -217.3986)
		(end 347.442536 -217.154252)
		(stroke
			(width 0.06477)
			(type default)
		)
		(layer "B.Cu")
	)
	(gr_line
		(start 347.48724 -217.750898)
		(end 347.341444 -217.3986)
		(stroke
			(width 0.06477)
			(type default)
		)
		(layer "B.Cu")
	)
	(gr_line
		(start 347.50121 -223.424242)
		(end 347.8149 -223.424242)
		(stroke
			(width 0.0381)
			(type default)
		)
		(layer "B.Cu")
	)
	(gr_line
		(start 347.595698 -216.677748)
		(end 347.305884 -215.977724)
		(stroke
			(width 0.06477)
			(type default)
		)
		(layer "B.Cu")
	)
	(gr_line
		(start 347.731588 -217.852244)
		(end 347.48724 -217.750898)
		(stroke
			(width 0.06477)
			(type default)
		)
		(layer "B.Cu")
	)
	(gr_line
		(start 347.777054 -218.45016)
		(end 347.878146 -218.205812)
		(stroke
			(width 0.06477)
			(type default)
		)
		(layer "B.Cu")
	)
	(gr_line
		(start 347.8149 -223.424242)
		(end 347.879416 -223.488758)
		(stroke
			(width 0.0381)
			(type default)
		)
		(layer "B.Cu")
	)
	(gr_arc
		(start 347.879416 -223.488758)
		(mid 347.880712 -223.499312)
		(end 347.88221 -223.50984)
		(stroke
			(width 0.0381)
			(type default)
		)
		(layer "B.Cu")
	)
	(gr_line
		(start 347.92285 -218.802458)
		(end 347.777054 -218.45016)
		(stroke
			(width 0.06477)
			(type default)
		)
		(layer "B.Cu")
	)
	(gr_line
		(start 348.031308 -217.729308)
		(end 347.741494 -217.029538)
		(stroke
			(width 0.06477)
			(type default)
		)
		(layer "B.Cu")
	)
	(gr_line
		(start 348.070678 -223.481138)
		(end 348.070678 -223.480884)
		(stroke
			(width 0.0381)
			(type default)
		)
		(layer "B.Cu")
	)
	(gr_line
		(start 348.12732 -223.424242)
		(end 348.071694 -223.479868)
		(stroke
			(width 0.0381)
			(type default)
		)
		(layer "B.Cu")
	)
	(gr_line
		(start 348.167198 -218.903804)
		(end 347.92285 -218.802458)
		(stroke
			(width 0.06477)
			(type default)
		)
		(layer "B.Cu")
	)
	(gr_line
		(start 348.185486 -417.166044)
		(end 348.481396 -417.461954)
		(stroke
			(width 0.06477)
			(type default)
		)
		(layer "B.Cu")
	)
	(gr_line
		(start 348.210886 -415.38652)
		(end 348.481396 -415.65703)
		(stroke
			(width 0.06477)
			(type default)
		)
		(layer "B.Cu")
	)
	(gr_line
		(start 348.212664 -219.501466)
		(end 348.313756 -219.257372)
		(stroke
			(width 0.06477)
			(type default)
		)
		(layer "B.Cu")
	)
	(gr_line
		(start 348.290134 -214.978234)
		(end 348.437962 -215.335104)
		(stroke
			(width 0.06477)
			(type default)
		)
		(layer "B.Cu")
	)
	(gr_line
		(start 348.35846 -219.853764)
		(end 348.212664 -219.501466)
		(stroke
			(width 0.06477)
			(type default)
		)
		(layer "B.Cu")
	)
	(gr_line
		(start 348.39275 -214.730838)
		(end 348.290134 -214.978234)
		(stroke
			(width 0.06477)
			(type default)
		)
		(layer "B.Cu")
	)
	(gr_line
		(start 348.437962 -215.335104)
		(end 348.685612 -215.43772)
		(stroke
			(width 0.06477)
			(type default)
		)
		(layer "B.Cu")
	)
	(gr_line
		(start 348.44101 -223.424242)
		(end 348.12732 -223.424242)
		(stroke
			(width 0.0381)
			(type default)
		)
		(layer "B.Cu")
	)
	(gr_line
		(start 348.466664 -218.780614)
		(end 348.177104 -218.081098)
		(stroke
			(width 0.06477)
			(type default)
		)
		(layer "B.Cu")
	)
	(gr_line
		(start 348.481396 -418.141658)
		(end 348.210886 -418.412168)
		(stroke
			(width 0.06477)
			(type default)
		)
		(layer "B.Cu")
	)
	(gr_line
		(start 348.481396 -416.336734)
		(end 348.185486 -416.632644)
		(stroke
			(width 0.06477)
			(type default)
		)
		(layer "B.Cu")
	)
	(gr_line
		(start 348.602554 -219.95511)
		(end 348.35846 -219.853764)
		(stroke
			(width 0.06477)
			(type default)
		)
		(layer "B.Cu")
	)
	(gr_line
		(start 348.658688 -223.729042)
		(end 348.658688 -223.728788)
		(stroke
			(width 0.0381)
			(type default)
		)
		(layer "B.Cu")
	)
	(gr_line
		(start 348.691454 -214.60587)
		(end 348.985332 -215.314784)
		(stroke
			(width 0.06477)
			(type default)
		)
		(layer "B.Cu")
	)
	(gr_line
		(start 348.73184 -216.043764)
		(end 348.879668 -216.400888)
		(stroke
			(width 0.06477)
			(type default)
		)
		(layer "B.Cu")
	)
	(gr_line
		(start 348.749874 -221.258384)
		(end 348.749874 -221.239334)
		(stroke
			(width 0.0381)
			(type default)
		)
		(layer "B.Cu")
	)
	(gr_line
		(start 348.7547 -225.044254)
		(end 348.44101 -225.044254)
		(stroke
			(width 0.0381)
			(type default)
		)
		(layer "B.Cu")
	)
	(gr_line
		(start 348.803976 -418.141658)
		(end 349.074486 -418.412168)
		(stroke
			(width 0.06477)
			(type default)
		)
		(layer "B.Cu")
	)
	(gr_line
		(start 348.803976 -416.336734)
		(end 349.099886 -416.632644)
		(stroke
			(width 0.06477)
			(type default)
		)
		(layer "B.Cu")
	)
	(gr_line
		(start 348.815914 -221.324424)
		(end 348.749874 -221.258384)
		(stroke
			(width 0.0381)
			(type default)
		)
		(layer "B.Cu")
	)
	(gr_line
		(start 348.819216 -225.10877)
		(end 348.7547 -225.044254)
		(stroke
			(width 0.0381)
			(type default)
		)
		(layer "B.Cu")
	)
	(gr_arc
		(start 348.819216 -225.10877)
		(mid 348.820515 -225.119324)
		(end 348.82201 -225.129852)
		(stroke
			(width 0.0381)
			(type default)
		)
		(layer "B.Cu")
	)
	(gr_line
		(start 348.834202 -215.796114)
		(end 348.73184 -216.043764)
		(stroke
			(width 0.06477)
			(type default)
		)
		(layer "B.Cu")
	)
	(gr_line
		(start 348.879668 -216.400888)
		(end 349.127318 -216.502996)
		(stroke
			(width 0.06477)
			(type default)
		)
		(layer "B.Cu")
	)
	(gr_line
		(start 348.902274 -219.832174)
		(end 348.61246 -219.132404)
		(stroke
			(width 0.06477)
			(type default)
		)
		(layer "B.Cu")
	)
	(gr_line
		(start 349.006414 -221.324424)
		(end 349.072454 -221.258384)
		(stroke
			(width 0.0381)
			(type default)
		)
		(layer "B.Cu")
	)
	(gr_line
		(start 349.011494 -225.100134)
		(end 349.067374 -225.044254)
		(stroke
			(width 0.0381)
			(type default)
		)
		(layer "B.Cu")
	)
	(gr_line
		(start 349.067374 -225.044254)
		(end 349.381064 -225.044254)
		(stroke
			(width 0.0381)
			(type default)
		)
		(layer "B.Cu")
	)
	(gr_line
		(start 349.072454 -221.258384)
		(end 349.072454 -221.239334)
		(stroke
			(width 0.0381)
			(type default)
		)
		(layer "B.Cu")
	)
	(gr_line
		(start 349.074486 -415.38652)
		(end 348.803976 -415.65703)
		(stroke
			(width 0.06477)
			(type default)
		)
		(layer "B.Cu")
	)
	(gr_line
		(start 349.098362 -222.936562)
		(end 349.09887 -222.936308)
		(stroke
			(width 0.0381)
			(type default)
		)
		(layer "B.Cu")
	)
	(gr_line
		(start 349.09887 -222.936308)
		(end 349.10014 -222.935546)
		(stroke
			(width 0.0381)
			(type default)
		)
		(layer "B.Cu")
	)
	(gr_line
		(start 349.099886 -417.166044)
		(end 348.803976 -417.461954)
		(stroke
			(width 0.06477)
			(type default)
		)
		(layer "B.Cu")
	)
	(gr_line
		(start 349.13316 -215.6714)
		(end 349.427038 -216.380314)
		(stroke
			(width 0.06477)
			(type default)
		)
		(layer "B.Cu")
	)
	(gr_line
		(start 349.173546 -217.109294)
		(end 349.321374 -217.466418)
		(stroke
			(width 0.06477)
			(type default)
		)
		(layer "B.Cu")
	)
	(gr_line
		(start 349.19412 -225.366834)
		(end 349.191326 -225.36531)
		(stroke
			(width 0.0381)
			(type default)
		)
		(layer "B.Cu")
	)
	(gr_line
		(start 349.194374 -223.101662)
		(end 349.195136 -223.101154)
		(stroke
			(width 0.0381)
			(type default)
		)
		(layer "B.Cu")
	)
	(gr_line
		(start 349.275908 -216.861644)
		(end 349.173546 -217.109294)
		(stroke
			(width 0.06477)
			(type default)
		)
		(layer "B.Cu")
	)
	(gr_line
		(start 349.321374 -217.466418)
		(end 349.56877 -217.568526)
		(stroke
			(width 0.06477)
			(type default)
		)
		(layer "B.Cu")
	)
	(gr_arc
		(start 349.57258 -225.36404)
		(mid 349.572199 -225.364294)
		(end 349.571818 -225.364548)
		(stroke
			(width 0.0381)
			(type default)
		)
		(layer "B.Cu")
	)
	(gr_line
		(start 349.574612 -216.73693)
		(end 349.86849 -217.446098)
		(stroke
			(width 0.06477)
			(type default)
		)
		(layer "B.Cu")
	)
	(gr_line
		(start 349.615252 -218.174824)
		(end 349.76308 -218.531948)
		(stroke
			(width 0.06477)
			(type default)
		)
		(layer "B.Cu")
	)
	(gr_line
		(start 349.717614 -217.927428)
		(end 349.615252 -218.174824)
		(stroke
			(width 0.06477)
			(type default)
		)
		(layer "B.Cu")
	)
	(gr_line
		(start 349.76308 -218.531948)
		(end 350.010476 -218.634056)
		(stroke
			(width 0.06477)
			(type default)
		)
		(layer "B.Cu")
	)
	(gr_line
		(start 349.86849 -217.446098)
		(end 349.928942 -217.591894)
		(stroke
			(width 0.06477)
			(type default)
		)
		(layer "B.Cu")
	)
	(gr_line
		(start 350.016318 -217.80246)
		(end 350.310196 -218.511628)
		(stroke
			(width 0.06477)
			(type default)
		)
		(layer "B.Cu")
	)
	(gr_line
		(start 350.033844 -224.559368)
		(end 350.033082 -224.559876)
		(stroke
			(width 0.0381)
			(type default)
		)
		(layer "B.Cu")
	)
	(gr_line
		(start 350.128332 -224.724976)
		(end 350.128586 -224.724976)
		(stroke
			(width 0.0381)
			(type default)
		)
		(layer "B.Cu")
	)
	(gr_line
		(start 350.130364 -224.72396)
		(end 350.128586 -224.724976)
		(stroke
			(width 0.0381)
			(type default)
		)
		(layer "B.Cu")
	)
	(gr_line
		(start 350.133666 -224.721928)
		(end 350.130364 -224.72396)
		(stroke
			(width 0.0381)
			(type default)
		)
		(layer "B.Cu")
	)
	(gr_line
		(start 350.159828 -221.277688)
		(end 350.225868 -221.343728)
		(stroke
			(width 0.0381)
			(type default)
		)
		(layer "B.Cu")
	)
	(gr_line
		(start 350.159828 -221.258638)
		(end 350.159828 -221.277688)
		(stroke
			(width 0.0381)
			(type default)
		)
		(layer "B.Cu")
	)
	(gr_line
		(start 350.171766 -224.69983)
		(end 350.165416 -224.703386)
		(stroke
			(width 0.0381)
			(type default)
		)
		(layer "B.Cu")
	)
	(gr_arc
		(start 350.171766 -224.69983)
		(mid 350.176482 -224.696552)
		(end 350.181164 -224.693226)
		(stroke
			(width 0.0381)
			(type default)
		)
		(layer "B.Cu")
	)
	(gr_line
		(start 350.310196 -218.511628)
		(end 350.440244 -218.825572)
		(stroke
			(width 0.06477)
			(type default)
		)
		(layer "B.Cu")
	)
	(gr_line
		(start 350.482408 -221.277688)
		(end 350.416368 -221.343728)
		(stroke
			(width 0.0381)
			(type default)
		)
		(layer "B.Cu")
	)
	(gr_line
		(start 350.482408 -221.258638)
		(end 350.482408 -221.277688)
		(stroke
			(width 0.0381)
			(type default)
		)
		(layer "B.Cu")
	)
	(gr_line
		(start 351.248726 -417.166044)
		(end 351.544636 -417.461954)
		(stroke
			(width 0.06477)
			(type default)
		)
		(layer "B.Cu")
	)
	(gr_line
		(start 351.274126 -415.38652)
		(end 351.544636 -415.65703)
		(stroke
			(width 0.06477)
			(type default)
		)
		(layer "B.Cu")
	)
	(gr_line
		(start 351.544636 -418.141658)
		(end 351.274126 -418.412168)
		(stroke
			(width 0.06477)
			(type default)
		)
		(layer "B.Cu")
	)
	(gr_line
		(start 351.544636 -416.336734)
		(end 351.248726 -416.632644)
		(stroke
			(width 0.06477)
			(type default)
		)
		(layer "B.Cu")
	)
	(gr_line
		(start 351.867216 -418.141658)
		(end 352.137726 -418.412168)
		(stroke
			(width 0.06477)
			(type default)
		)
		(layer "B.Cu")
	)
	(gr_line
		(start 351.867216 -416.336734)
		(end 352.163126 -416.632644)
		(stroke
			(width 0.06477)
			(type default)
		)
		(layer "B.Cu")
	)
	(gr_line
		(start 352.137726 -415.38652)
		(end 351.867216 -415.65703)
		(stroke
			(width 0.06477)
			(type default)
		)
		(layer "B.Cu")
	)
	(gr_line
		(start 352.163126 -417.166044)
		(end 351.867216 -417.461954)
		(stroke
			(width 0.06477)
			(type default)
		)
		(layer "B.Cu")
	)
	(gr_line
		(start 354.081334 -225.044254)
		(end 354.395024 -225.044254)
		(stroke
			(width 0.0381)
			(type default)
		)
		(layer "B.Cu")
	)
	(gr_line
		(start 354.38969 -221.222316)
		(end 354.38969 -221.203266)
		(stroke
			(width 0.0381)
			(type default)
		)
		(layer "B.Cu")
	)
	(gr_line
		(start 354.395024 -225.044254)
		(end 354.45954 -224.979738)
		(stroke
			(width 0.0381)
			(type default)
		)
		(layer "B.Cu")
	)
	(gr_line
		(start 354.45573 -221.288356)
		(end 354.38969 -221.222316)
		(stroke
			(width 0.0381)
			(type default)
		)
		(layer "B.Cu")
	)
	(gr_arc
		(start 354.462334 -224.958656)
		(mid 354.460838 -224.969184)
		(end 354.45954 -224.979738)
		(stroke
			(width 0.0381)
			(type default)
		)
		(layer "B.Cu")
	)
	(gr_line
		(start 354.64623 -221.288356)
		(end 354.71227 -221.222316)
		(stroke
			(width 0.0381)
			(type default)
		)
		(layer "B.Cu")
	)
	(gr_line
		(start 354.659946 -223.859344)
		(end 354.659438 -223.858836)
		(stroke
			(width 0.0381)
			(type default)
		)
		(layer "B.Cu")
	)
	(gr_arc
		(start 354.697792 -224.580704)
		(mid 354.695375 -224.582476)
		(end 354.692966 -224.58426)
		(stroke
			(width 0.0381)
			(type default)
		)
		(layer "B.Cu")
	)
	(gr_line
		(start 354.707698 -225.044254)
		(end 354.651818 -224.988374)
		(stroke
			(width 0.0381)
			(type default)
		)
		(layer "B.Cu")
	)
	(gr_line
		(start 354.71227 -221.222316)
		(end 354.71227 -221.203266)
		(stroke
			(width 0.0381)
			(type default)
		)
		(layer "B.Cu")
	)
	(gr_line
		(start 354.72497 -222.284036)
		(end 354.72243 -222.282512)
		(stroke
			(width 0.0381)
			(type default)
		)
		(layer "B.Cu")
	)
	(gr_line
		(start 354.73513 -222.289624)
		(end 354.734622 -222.28937)
		(stroke
			(width 0.0381)
			(type default)
		)
		(layer "B.Cu")
	)
	(gr_line
		(start 354.73767 -223.912938)
		(end 354.736908 -223.91243)
		(stroke
			(width 0.0381)
			(type default)
		)
		(layer "B.Cu")
	)
	(gr_line
		(start 354.738432 -222.942404)
		(end 354.738178 -222.942404)
		(stroke
			(width 0.0381)
			(type default)
		)
		(layer "B.Cu")
	)
	(gr_line
		(start 354.739448 -223.913954)
		(end 354.73767 -223.912938)
		(stroke
			(width 0.0381)
			(type default)
		)
		(layer "B.Cu")
	)
	(gr_line
		(start 354.831396 -223.746822)
		(end 354.83165 -223.747076)
		(stroke
			(width 0.0381)
			(type default)
		)
		(layer "B.Cu")
	)
	(gr_line
		(start 354.833682 -223.748092)
		(end 354.83165 -223.747076)
		(stroke
			(width 0.0381)
			(type default)
		)
		(layer "B.Cu")
	)
	(gr_arc
		(start 354.835206 -222.127572)
		(mid 354.834064 -222.126936)
		(end 354.83292 -222.126302)
		(stroke
			(width 0.0381)
			(type default)
		)
		(layer "B.Cu")
	)
	(gr_arc
		(start 354.83673 -223.74987)
		(mid 354.835207 -223.748979)
		(end 354.833682 -223.748092)
		(stroke
			(width 0.0381)
			(type default)
		)
		(layer "B.Cu")
	)
	(gr_line
		(start 355.021388 -225.044254)
		(end 354.707698 -225.044254)
		(stroke
			(width 0.0381)
			(type default)
		)
		(layer "B.Cu")
	)
	(gr_line
		(start 364.42904 -217.513408)
		(end 365.18088 -217.513408)
		(stroke
			(width 0.06477)
			(type default)
		)
		(layer "B.Cu")
	)
	(gr_line
		(start 364.43031 -217.837258)
		(end 364.61446 -218.021408)
		(stroke
			(width 0.06477)
			(type default)
		)
		(layer "B.Cu")
	)
	(gr_line
		(start 364.61446 -218.021408)
		(end 364.99546 -218.021408)
		(stroke
			(width 0.06477)
			(type default)
		)
		(layer "B.Cu")
	)
	(gr_line
		(start 364.99546 -218.021408)
		(end 365.17961 -217.837258)
		(stroke
			(width 0.06477)
			(type default)
		)
		(layer "B.Cu")
	)
	(gr_line
		(start 365.217964 2.381504)
		(end 365.2139 2.381504)
		(stroke
			(width 0.06477)
			(type default)
		)
		(layer "B.Cu")
	)
	(gr_line
		(start 365.302546 2.79273)
		(end 365.21517 2.705354)
		(stroke
			(width 0.06477)
			(type default)
		)
		(layer "B.Cu")
	)
	(gr_line
		(start 365.30661 2.292858)
		(end 365.217964 2.381504)
		(stroke
			(width 0.06477)
			(type default)
		)
		(layer "B.Cu")
	)
	(gr_line
		(start 365.463074 -2.787142)
		(end 364.810802 -2.969006)
		(stroke
			(width 0.06477)
			(type default)
		)
		(layer "B.Cu")
	)
	(gr_line
		(start 365.463074 -2.28727)
		(end 364.810802 -2.105406)
		(stroke
			(width 0.06477)
			(type default)
		)
		(layer "B.Cu")
	)
	(gr_line
		(start 365.463074 2.292858)
		(end 365.30661 2.292858)
		(stroke
			(width 0.06477)
			(type default)
		)
		(layer "B.Cu")
	)
	(gr_line
		(start 365.463074 2.79273)
		(end 365.302546 2.79273)
		(stroke
			(width 0.06477)
			(type default)
		)
		(layer "B.Cu")
	)
	(gr_line
		(start 365.463074 7.372858)
		(end 364.810802 7.190994)
		(stroke
			(width 0.06477)
			(type default)
		)
		(layer "B.Cu")
	)
	(gr_line
		(start 365.463074 7.87273)
		(end 364.810802 8.054594)
		(stroke
			(width 0.06477)
			(type default)
		)
		(layer "B.Cu")
	)
	(gr_line
		(start 365.56188 -217.513408)
		(end 366.31372 -217.513408)
		(stroke
			(width 0.06477)
			(type default)
		)
		(layer "B.Cu")
	)
	(gr_line
		(start 365.56315 -217.837258)
		(end 365.7473 -218.021408)
		(stroke
			(width 0.06477)
			(type default)
		)
		(layer "B.Cu")
	)
	(gr_line
		(start 365.7473 -218.021408)
		(end 366.1283 -218.021408)
		(stroke
			(width 0.06477)
			(type default)
		)
		(layer "B.Cu")
	)
	(gr_line
		(start 366.1283 -218.021408)
		(end 366.31245 -217.837258)
		(stroke
			(width 0.06477)
			(type default)
		)
		(layer "B.Cu")
	)
	(gr_line
		(start 366.69472 -217.513408)
		(end 367.44656 -217.513408)
		(stroke
			(width 0.06477)
			(type default)
		)
		(layer "B.Cu")
	)
	(gr_line
		(start 366.69599 -217.837258)
		(end 366.88014 -218.021408)
		(stroke
			(width 0.06477)
			(type default)
		)
		(layer "B.Cu")
	)
	(gr_line
		(start 366.88014 -218.021408)
		(end 367.26114 -218.021408)
		(stroke
			(width 0.06477)
			(type default)
		)
		(layer "B.Cu")
	)
	(gr_line
		(start 367.26114 -218.021408)
		(end 367.44529 -217.837258)
		(stroke
			(width 0.06477)
			(type default)
		)
		(layer "B.Cu")
	)
	(gr_line
		(start 371.134386 -214.923878)
		(end 371.246908 -215.0364)
		(stroke
			(width 0.06477)
			(type default)
		)
		(layer "B.Cu")
	)
	(gr_line
		(start 371.303296 -221.49562)
		(end 370.994686 -221.80423)
		(stroke
			(width 0.06477)
			(type default)
		)
		(layer "B.Cu")
	)
	(gr_line
		(start 371.62613 -221.49562)
		(end 371.93474 -221.80423)
		(stroke
			(width 0.06477)
			(type default)
		)
		(layer "B.Cu")
	)
	(gr_line
		(start 372.139464 -215.0364)
		(end 372.251986 -214.923878)
		(stroke
			(width 0.06477)
			(type default)
		)
		(layer "B.Cu")
	)
	(gr_line
		(start 372.232428 -216.514934)
		(end 372.77548 -217.057732)
		(stroke
			(width 0.06477)
			(type default)
		)
		(layer "B.Cu")
	)
	(gr_line
		(start 372.400322 -417.166044)
		(end 372.696232 -417.461954)
		(stroke
			(width 0.06477)
			(type default)
		)
		(layer "B.Cu")
	)
	(gr_line
		(start 372.425722 -415.38652)
		(end 372.696232 -415.65703)
		(stroke
			(width 0.06477)
			(type default)
		)
		(layer "B.Cu")
	)
	(gr_line
		(start 372.696232 -418.141658)
		(end 372.425722 -418.412168)
		(stroke
			(width 0.06477)
			(type default)
		)
		(layer "B.Cu")
	)
	(gr_line
		(start 372.696232 -416.336734)
		(end 372.400322 -416.632644)
		(stroke
			(width 0.06477)
			(type default)
		)
		(layer "B.Cu")
	)
	(gr_line
		(start 372.730268 -216.286588)
		(end 372.462298 -216.286588)
		(stroke
			(width 0.06477)
			(type default)
		)
		(layer "B.Cu")
	)
	(gr_line
		(start 373.003572 -216.827862)
		(end 373.003572 -216.559892)
		(stroke
			(width 0.06477)
			(type default)
		)
		(layer "B.Cu")
	)
	(gr_line
		(start 373.003572 -216.559892)
		(end 372.730268 -216.286588)
		(stroke
			(width 0.06477)
			(type default)
		)
		(layer "B.Cu")
	)
	(gr_line
		(start 373.018812 -418.141658)
		(end 373.289322 -418.412168)
		(stroke
			(width 0.06477)
			(type default)
		)
		(layer "B.Cu")
	)
	(gr_line
		(start 373.018812 -416.336734)
		(end 373.314722 -416.632644)
		(stroke
			(width 0.06477)
			(type default)
		)
		(layer "B.Cu")
	)
	(gr_line
		(start 373.048276 -217.330528)
		(end 373.294148 -217.5764)
		(stroke
			(width 0.06477)
			(type default)
		)
		(layer "B.Cu")
	)
	(gr_line
		(start 373.289322 -415.38652)
		(end 373.018812 -415.65703)
		(stroke
			(width 0.06477)
			(type default)
		)
		(layer "B.Cu")
	)
	(gr_line
		(start 373.314722 -417.166044)
		(end 373.018812 -417.461954)
		(stroke
			(width 0.06477)
			(type default)
		)
		(layer "B.Cu")
	)
	(gr_line
		(start 373.369586 -214.923878)
		(end 373.405908 -214.9602)
		(stroke
			(width 0.06477)
			(type default)
		)
		(layer "B.Cu")
	)
	(gr_line
		(start 373.545862 -217.102182)
		(end 373.277892 -217.102182)
		(stroke
			(width 0.06477)
			(type default)
		)
		(layer "B.Cu")
	)
	(gr_line
		(start 373.819166 -217.5764)
		(end 373.819166 -217.375486)
		(stroke
			(width 0.06477)
			(type default)
		)
		(layer "B.Cu")
	)
	(gr_line
		(start 373.819166 -217.375486)
		(end 373.545862 -217.102182)
		(stroke
			(width 0.06477)
			(type default)
		)
		(layer "B.Cu")
	)
	(gr_line
		(start 374.055894 -218.3384)
		(end 374.395746 -218.677998)
		(stroke
			(width 0.06477)
			(type default)
		)
		(layer "B.Cu")
	)
	(gr_line
		(start 374.450864 -214.9602)
		(end 374.487186 -214.923878)
		(stroke
			(width 0.06477)
			(type default)
		)
		(layer "B.Cu")
	)
	(gr_line
		(start 374.623838 -218.448128)
		(end 374.623838 -218.3384)
		(stroke
			(width 0.06477)
			(type default)
		)
		(layer "B.Cu")
	)
	(gr_line
		(start 374.664732 -218.946984)
		(end 375.200164 -219.482416)
		(stroke
			(width 0.06477)
			(type default)
		)
		(layer "B.Cu")
	)
	(gr_line
		(start 375.14022 -217.33002)
		(end 375.3866 -217.5764)
		(stroke
			(width 0.06477)
			(type default)
		)
		(layer "B.Cu")
	)
	(gr_line
		(start 375.159016 -218.718892)
		(end 374.894602 -218.718892)
		(stroke
			(width 0.06477)
			(type default)
		)
		(layer "B.Cu")
	)
	(gr_line
		(start 375.42851 -219.2528)
		(end 375.42851 -218.98864)
		(stroke
			(width 0.06477)
			(type default)
		)
		(layer "B.Cu")
	)
	(gr_line
		(start 375.42851 -218.98864)
		(end 375.159016 -218.718892)
		(stroke
			(width 0.06477)
			(type default)
		)
		(layer "B.Cu")
	)
	(gr_line
		(start 375.463562 -417.166044)
		(end 375.759472 -417.461954)
		(stroke
			(width 0.06477)
			(type default)
		)
		(layer "B.Cu")
	)
	(gr_line
		(start 375.469658 -219.751656)
		(end 376.004836 -220.287088)
		(stroke
			(width 0.06477)
			(type default)
		)
		(layer "B.Cu")
	)
	(gr_line
		(start 375.488962 -415.38652)
		(end 375.759472 -415.65703)
		(stroke
			(width 0.06477)
			(type default)
		)
		(layer "B.Cu")
	)
	(gr_line
		(start 375.6152 -214.113364)
		(end 375.604786 -214.123778)
		(stroke
			(width 0.06477)
			(type default)
		)
		(layer "B.Cu")
	)
	(gr_line
		(start 375.637806 -217.101674)
		(end 375.369836 -217.101674)
		(stroke
			(width 0.06477)
			(type default)
		)
		(layer "B.Cu")
	)
	(gr_line
		(start 375.759472 -418.141658)
		(end 375.488962 -418.412168)
		(stroke
			(width 0.06477)
			(type default)
		)
		(layer "B.Cu")
	)
	(gr_line
		(start 375.759472 -416.336734)
		(end 375.463562 -416.632644)
		(stroke
			(width 0.06477)
			(type default)
		)
		(layer "B.Cu")
	)
	(gr_line
		(start 375.91111 -217.5764)
		(end 375.91111 -217.374978)
		(stroke
			(width 0.06477)
			(type default)
		)
		(layer "B.Cu")
	)
	(gr_line
		(start 375.91111 -217.374978)
		(end 375.637806 -217.101674)
		(stroke
			(width 0.06477)
			(type default)
		)
		(layer "B.Cu")
	)
	(gr_line
		(start 375.963688 -219.523564)
		(end 375.699274 -219.523564)
		(stroke
			(width 0.06477)
			(type default)
		)
		(layer "B.Cu")
	)
	(gr_line
		(start 376.082052 -418.141658)
		(end 376.352562 -418.412168)
		(stroke
			(width 0.06477)
			(type default)
		)
		(layer "B.Cu")
	)
	(gr_line
		(start 376.082052 -416.336734)
		(end 376.377962 -416.632644)
		(stroke
			(width 0.06477)
			(type default)
		)
		(layer "B.Cu")
	)
	(gr_line
		(start 376.233182 -220.057472)
		(end 376.233182 -219.793312)
		(stroke
			(width 0.06477)
			(type default)
		)
		(layer "B.Cu")
	)
	(gr_line
		(start 376.233182 -219.793312)
		(end 375.963688 -219.523564)
		(stroke
			(width 0.06477)
			(type default)
		)
		(layer "B.Cu")
	)
	(gr_line
		(start 376.352562 -415.38652)
		(end 376.082052 -415.65703)
		(stroke
			(width 0.06477)
			(type default)
		)
		(layer "B.Cu")
	)
	(gr_line
		(start 376.377962 -417.166044)
		(end 376.082052 -417.461954)
		(stroke
			(width 0.06477)
			(type default)
		)
		(layer "B.Cu")
	)
	(gr_line
		(start 376.7074 -214.938864)
		(end 376.722386 -214.923878)
		(stroke
			(width 0.06477)
			(type default)
		)
		(layer "B.Cu")
	)
	(gr_line
		(start 377.839986 -214.923878)
		(end 378.213874 -215.297766)
		(stroke
			(width 0.06477)
			(type default)
		)
		(layer "B.Cu")
	)
	(gr_line
		(start 377.9266 -214.037164)
		(end 377.839986 -214.123778)
		(stroke
			(width 0.06477)
			(type default)
		)
		(layer "B.Cu")
	)
	(gr_line
		(start 378.213874 -215.297766)
		(end 378.213874 -215.34501)
		(stroke
			(width 0.06477)
			(type default)
		)
		(layer "B.Cu")
	)
	(gr_line
		(start 378.526802 -417.166044)
		(end 378.822712 -417.461954)
		(stroke
			(width 0.06477)
			(type default)
		)
		(layer "B.Cu")
	)
	(gr_line
		(start 378.552202 -415.38652)
		(end 378.822712 -415.65703)
		(stroke
			(width 0.06477)
			(type default)
		)
		(layer "B.Cu")
	)
	(gr_line
		(start 378.822712 -418.141658)
		(end 378.552202 -418.412168)
		(stroke
			(width 0.06477)
			(type default)
		)
		(layer "B.Cu")
	)
	(gr_line
		(start 378.822712 -416.336734)
		(end 378.526802 -416.632644)
		(stroke
			(width 0.06477)
			(type default)
		)
		(layer "B.Cu")
	)
	(gr_line
		(start 379.145292 -418.141658)
		(end 379.415802 -418.412168)
		(stroke
			(width 0.06477)
			(type default)
		)
		(layer "B.Cu")
	)
	(gr_line
		(start 379.145292 -416.336734)
		(end 379.441202 -416.632644)
		(stroke
			(width 0.06477)
			(type default)
		)
		(layer "B.Cu")
	)
	(gr_line
		(start 379.415802 -415.38652)
		(end 379.145292 -415.65703)
		(stroke
			(width 0.06477)
			(type default)
		)
		(layer "B.Cu")
	)
	(gr_line
		(start 379.441202 -417.166044)
		(end 379.145292 -417.461954)
		(stroke
			(width 0.06477)
			(type default)
		)
		(layer "B.Cu")
	)
	(gr_line
		(start 380.075186 -214.123778)
		(end 380.0856 -214.113364)
		(stroke
			(width 0.06477)
			(type default)
		)
		(layer "B.Cu")
	)
	(gr_line
		(start 380.111508 -214.9602)
		(end 380.075186 -214.923878)
		(stroke
			(width 0.06477)
			(type default)
		)
		(layer "B.Cu")
	)
	(gr_line
		(start 381.156464 -214.9602)
		(end 381.192786 -214.923878)
		(stroke
			(width 0.06477)
			(type default)
		)
		(layer "B.Cu")
	)
	(gr_line
		(start 381.590042 -417.166044)
		(end 381.885952 -417.461954)
		(stroke
			(width 0.06477)
			(type default)
		)
		(layer "B.Cu")
	)
	(gr_line
		(start 381.615442 -415.38652)
		(end 381.885952 -415.65703)
		(stroke
			(width 0.06477)
			(type default)
		)
		(layer "B.Cu")
	)
	(gr_line
		(start 381.885952 -418.141658)
		(end 381.615442 -418.412168)
		(stroke
			(width 0.06477)
			(type default)
		)
		(layer "B.Cu")
	)
	(gr_line
		(start 381.885952 -416.336734)
		(end 381.590042 -416.632644)
		(stroke
			(width 0.06477)
			(type default)
		)
		(layer "B.Cu")
	)
	(gr_line
		(start 382.025398 -223.117156)
		(end 382.044448 -223.117156)
		(stroke
			(width 0.0381)
			(type default)
		)
		(layer "B.Cu")
	)
	(gr_line
		(start 382.044448 -223.117156)
		(end 382.110488 -223.051116)
		(stroke
			(width 0.0381)
			(type default)
		)
		(layer "B.Cu")
	)
	(gr_line
		(start 382.044448 -222.794576)
		(end 382.025398 -222.794576)
		(stroke
			(width 0.0381)
			(type default)
		)
		(layer "B.Cu")
	)
	(gr_line
		(start 382.110488 -222.860616)
		(end 382.044448 -222.794576)
		(stroke
			(width 0.0381)
			(type default)
		)
		(layer "B.Cu")
	)
	(gr_line
		(start 382.208532 -418.141658)
		(end 382.479042 -418.412168)
		(stroke
			(width 0.06477)
			(type default)
		)
		(layer "B.Cu")
	)
	(gr_line
		(start 382.208532 -416.336734)
		(end 382.504442 -416.632644)
		(stroke
			(width 0.06477)
			(type default)
		)
		(layer "B.Cu")
	)
	(gr_line
		(start 382.479042 -415.38652)
		(end 382.208532 -415.65703)
		(stroke
			(width 0.06477)
			(type default)
		)
		(layer "B.Cu")
	)
	(gr_line
		(start 382.504442 -417.166044)
		(end 382.208532 -417.461954)
		(stroke
			(width 0.06477)
			(type default)
		)
		(layer "B.Cu")
	)
	(gr_line
		(start 383.405634 -223.104964)
		(end 383.408174 -223.107504)
		(stroke
			(width 0.0381)
			(type default)
		)
		(layer "B.Cu")
	)
	(gr_line
		(start 383.408174 -223.107504)
		(end 383.409952 -223.107504)
		(stroke
			(width 0.0381)
			(type default)
		)
		(layer "B.Cu")
	)
	(gr_line
		(start 383.412492 -223.107758)
		(end 383.412238 -223.107504)
		(stroke
			(width 0.0381)
			(type default)
		)
		(layer "B.Cu")
	)
	(gr_line
		(start 383.412492 -223.107758)
		(end 383.412492 -223.108012)
		(stroke
			(width 0.0381)
			(type default)
		)
		(layer "B.Cu")
	)
	(gr_line
		(start 383.50952 -222.943674)
		(end 383.498852 -222.937324)
		(stroke
			(width 0.0381)
			(type default)
		)
		(layer "B.Cu")
	)
	(gr_line
		(start 383.571242 -217.341958)
		(end 384.11404 -217.884756)
		(stroke
			(width 0.06477)
			(type default)
		)
		(layer "B.Cu")
	)
	(gr_line
		(start 383.990596 -222.131128)
		(end 384.056636 -222.197168)
		(stroke
			(width 0.0381)
			(type default)
		)
		(layer "B.Cu")
	)
	(gr_line
		(start 383.990596 -222.112078)
		(end 383.990596 -222.131128)
		(stroke
			(width 0.0381)
			(type default)
		)
		(layer "B.Cu")
	)
	(gr_line
		(start 384.068828 -217.113612)
		(end 383.800858 -217.113612)
		(stroke
			(width 0.06477)
			(type default)
		)
		(layer "B.Cu")
	)
	(gr_line
		(start 384.247136 -222.197168)
		(end 384.313176 -222.131128)
		(stroke
			(width 0.0381)
			(type default)
		)
		(layer "B.Cu")
	)
	(gr_line
		(start 384.276092 -223.063308)
		(end 384.304032 -223.167448)
		(stroke
			(width 0.0381)
			(type default)
		)
		(layer "B.Cu")
	)
	(gr_line
		(start 384.304032 -223.167448)
		(end 384.154934 -223.424242)
		(stroke
			(width 0.0381)
			(type default)
		)
		(layer "B.Cu")
	)
	(gr_line
		(start 384.313176 -222.131128)
		(end 384.313176 -222.112078)
		(stroke
			(width 0.0381)
			(type default)
		)
		(layer "B.Cu")
	)
	(gr_line
		(start 384.335528 -223.750632)
		(end 384.334766 -223.750886)
		(stroke
			(width 0.0381)
			(type default)
		)
		(layer "B.Cu")
	)
	(gr_line
		(start 384.342132 -217.654886)
		(end 384.342132 -217.386916)
		(stroke
			(width 0.06477)
			(type default)
		)
		(layer "B.Cu")
	)
	(gr_line
		(start 384.342132 -217.386916)
		(end 384.068828 -217.113612)
		(stroke
			(width 0.06477)
			(type default)
		)
		(layer "B.Cu")
	)
	(gr_arc
		(start 384.424682 -223.919034)
		(mid 384.425699 -223.918527)
		(end 384.426714 -223.918018)
		(stroke
			(width 0.0381)
			(type default)
		)
		(layer "B.Cu")
	)
	(gr_line
		(start 384.475736 -222.870776)
		(end 384.371596 -222.898208)
		(stroke
			(width 0.0381)
			(type default)
		)
		(layer "B.Cu")
	)
	(gr_line
		(start 384.624834 -222.614236)
		(end 384.475736 -222.870776)
		(stroke
			(width 0.0381)
			(type default)
		)
		(layer "B.Cu")
	)
	(gr_line
		(start 384.653282 -417.166044)
		(end 384.949192 -417.461954)
		(stroke
			(width 0.06477)
			(type default)
		)
		(layer "B.Cu")
	)
	(gr_line
		(start 384.678682 -415.38652)
		(end 384.949192 -415.65703)
		(stroke
			(width 0.06477)
			(type default)
		)
		(layer "B.Cu")
	)
	(gr_arc
		(start 384.8227 -223.917764)
		(mid 384.823842 -223.9184)
		(end 384.824986 -223.919034)
		(stroke
			(width 0.0381)
			(type default)
		)
		(layer "B.Cu")
	)
	(gr_line
		(start 384.870198 -216.100152)
		(end 384.602482 -216.100152)
		(stroke
			(width 0.06477)
			(type default)
		)
		(layer "B.Cu")
	)
	(gr_line
		(start 384.914648 -223.750886)
		(end 384.91414 -223.750632)
		(stroke
			(width 0.0381)
			(type default)
		)
		(layer "B.Cu")
	)
	(gr_line
		(start 384.915156 -216.870788)
		(end 384.372866 -216.328244)
		(stroke
			(width 0.06477)
			(type default)
		)
		(layer "B.Cu")
	)
	(gr_line
		(start 384.949192 -418.141658)
		(end 384.678682 -418.412168)
		(stroke
			(width 0.06477)
			(type default)
		)
		(layer "B.Cu")
	)
	(gr_line
		(start 384.949192 -416.336734)
		(end 384.653282 -416.632644)
		(stroke
			(width 0.06477)
			(type default)
		)
		(layer "B.Cu")
	)
	(gr_line
		(start 385.143502 -216.641172)
		(end 385.143502 -216.373456)
		(stroke
			(width 0.06477)
			(type default)
		)
		(layer "B.Cu")
	)
	(gr_line
		(start 385.143502 -216.373456)
		(end 384.870198 -216.100152)
		(stroke
			(width 0.06477)
			(type default)
		)
		(layer "B.Cu")
	)
	(gr_line
		(start 385.271772 -418.141658)
		(end 385.542282 -418.412168)
		(stroke
			(width 0.06477)
			(type default)
		)
		(layer "B.Cu")
	)
	(gr_line
		(start 385.271772 -416.336734)
		(end 385.567682 -416.632644)
		(stroke
			(width 0.06477)
			(type default)
		)
		(layer "B.Cu")
	)
	(gr_line
		(start 385.403344 -221.49562)
		(end 385.094734 -221.80423)
		(stroke
			(width 0.06477)
			(type default)
		)
		(layer "B.Cu")
	)
	(gr_line
		(start 385.542282 -415.38652)
		(end 385.271772 -415.65703)
		(stroke
			(width 0.06477)
			(type default)
		)
		(layer "B.Cu")
	)
	(gr_line
		(start 385.567682 -417.166044)
		(end 385.271772 -417.461954)
		(stroke
			(width 0.06477)
			(type default)
		)
		(layer "B.Cu")
	)
	(gr_line
		(start 386.034788 -221.80423)
		(end 385.726178 -221.49562)
		(stroke
			(width 0.06477)
			(type default)
		)
		(layer "B.Cu")
	)
	(gr_line
		(start 386.343652 -221.19336)
		(end 386.409692 -221.2594)
		(stroke
			(width 0.0381)
			(type default)
		)
		(layer "B.Cu")
	)
	(gr_line
		(start 386.343652 -221.17431)
		(end 386.343652 -221.19336)
		(stroke
			(width 0.0381)
			(type default)
		)
		(layer "B.Cu")
	)
	(gr_line
		(start 386.600192 -221.2594)
		(end 386.666232 -221.19336)
		(stroke
			(width 0.0381)
			(type default)
		)
		(layer "B.Cu")
	)
	(gr_line
		(start 386.666232 -221.19336)
		(end 386.666232 -221.17431)
		(stroke
			(width 0.0381)
			(type default)
		)
		(layer "B.Cu")
	)
	(gr_line
		(start 387.070092 -222.61449)
		(end 387.070346 -222.614236)
		(stroke
			(width 0.0381)
			(type default)
		)
		(layer "B.Cu")
	)
	(gr_arc
		(start 387.088888 -223.053402)
		(mid 387.098584 -223.061129)
		(end 387.108446 -223.068642)
		(stroke
			(width 0.0381)
			(type default)
		)
		(layer "B.Cu")
	)
	(gr_line
		(start 387.108446 -223.068642)
		(end 387.131306 -223.15424)
		(stroke
			(width 0.0381)
			(type default)
		)
		(layer "B.Cu")
	)
	(gr_line
		(start 387.131306 -223.15424)
		(end 386.974842 -223.424242)
		(stroke
			(width 0.0381)
			(type default)
		)
		(layer "B.Cu")
	)
	(gr_line
		(start 387.209792 -222.905066)
		(end 387.20903 -222.90532)
		(stroke
			(width 0.0381)
			(type default)
		)
		(layer "B.Cu")
	)
	(gr_line
		(start 387.288278 -222.884238)
		(end 387.2103 -222.905066)
		(stroke
			(width 0.0381)
			(type default)
		)
		(layer "B.Cu")
	)
	(gr_line
		(start 387.444742 -222.614236)
		(end 387.288278 -222.884238)
		(stroke
			(width 0.0381)
			(type default)
		)
		(layer "B.Cu")
	)
	(gr_line
		(start 387.63194 -222.936816)
		(end 387.630924 -222.937324)
		(stroke
			(width 0.0381)
			(type default)
		)
		(layer "B.Cu")
	)
	(gr_line
		(start 387.632448 -222.936562)
		(end 387.63194 -222.936816)
		(stroke
			(width 0.0381)
			(type default)
		)
		(layer "B.Cu")
	)
	(gr_line
		(start 387.716522 -417.166044)
		(end 388.012432 -417.461954)
		(stroke
			(width 0.06477)
			(type default)
		)
		(layer "B.Cu")
	)
	(gr_line
		(start 387.741922 -415.38652)
		(end 388.012432 -415.65703)
		(stroke
			(width 0.06477)
			(type default)
		)
		(layer "B.Cu")
	)
	(gr_line
		(start 387.914896 -221.80423)
		(end 388.228586 -221.80423)
		(stroke
			(width 0.0381)
			(type default)
		)
		(layer "B.Cu")
	)
	(gr_line
		(start 388.012432 -418.141658)
		(end 387.741922 -418.412168)
		(stroke
			(width 0.06477)
			(type default)
		)
		(layer "B.Cu")
	)
	(gr_line
		(start 388.012432 -416.336734)
		(end 387.716522 -416.632644)
		(stroke
			(width 0.06477)
			(type default)
		)
		(layer "B.Cu")
	)
	(gr_line
		(start 388.108698 -222.122746)
		(end 388.10692 -222.123762)
		(stroke
			(width 0.0381)
			(type default)
		)
		(layer "B.Cu")
	)
	(gr_line
		(start 388.10946 -222.122238)
		(end 388.108698 -222.122746)
		(stroke
			(width 0.0381)
			(type default)
		)
		(layer "B.Cu")
	)
	(gr_line
		(start 388.11073 -222.121476)
		(end 388.10946 -222.122238)
		(stroke
			(width 0.0381)
			(type default)
		)
		(layer "B.Cu")
	)
	(gr_line
		(start 388.112254 -222.120714)
		(end 388.11073 -222.121476)
		(stroke
			(width 0.0381)
			(type default)
		)
		(layer "B.Cu")
	)
	(gr_line
		(start 388.115556 -222.118936)
		(end 388.112254 -222.120714)
		(stroke
			(width 0.0381)
			(type default)
		)
		(layer "B.Cu")
	)
	(gr_line
		(start 388.200138 -222.290386)
		(end 388.202932 -222.288608)
		(stroke
			(width 0.0381)
			(type default)
		)
		(layer "B.Cu")
	)
	(gr_line
		(start 388.203186 -222.288608)
		(end 388.202932 -222.288608)
		(stroke
			(width 0.0381)
			(type default)
		)
		(layer "B.Cu")
	)
	(gr_line
		(start 388.206234 -222.287084)
		(end 388.206742 -222.28683)
		(stroke
			(width 0.0381)
			(type default)
		)
		(layer "B.Cu")
	)
	(gr_line
		(start 388.206742 -222.28683)
		(end 388.207758 -222.286068)
		(stroke
			(width 0.0381)
			(type default)
		)
		(layer "B.Cu")
	)
	(gr_line
		(start 388.209028 -222.285306)
		(end 388.210298 -222.284544)
		(stroke
			(width 0.0381)
			(type default)
		)
		(layer "B.Cu")
	)
	(gr_line
		(start 388.210298 -222.284544)
		(end 388.21106 -222.284036)
		(stroke
			(width 0.0381)
			(type default)
		)
		(layer "B.Cu")
	)
	(gr_line
		(start 388.228586 -221.80423)
		(end 388.284212 -221.859856)
		(stroke
			(width 0.0381)
			(type default)
		)
		(layer "B.Cu")
	)
	(gr_line
		(start 388.335012 -418.141658)
		(end 388.605522 -418.412168)
		(stroke
			(width 0.06477)
			(type default)
		)
		(layer "B.Cu")
	)
	(gr_line
		(start 388.335012 -416.336734)
		(end 388.630922 -416.632644)
		(stroke
			(width 0.06477)
			(type default)
		)
		(layer "B.Cu")
	)
	(gr_arc
		(start 388.473696 -221.889574)
		(mid 388.475189 -221.879173)
		(end 388.47649 -221.868746)
		(stroke
			(width 0.0381)
			(type default)
		)
		(layer "B.Cu")
	)
	(gr_line
		(start 388.47649 -221.868746)
		(end 388.541006 -221.80423)
		(stroke
			(width 0.0381)
			(type default)
		)
		(layer "B.Cu")
	)
	(gr_line
		(start 388.541006 -221.80423)
		(end 388.854696 -221.80423)
		(stroke
			(width 0.0381)
			(type default)
		)
		(layer "B.Cu")
	)
	(gr_line
		(start 388.605522 -415.38652)
		(end 388.335012 -415.65703)
		(stroke
			(width 0.06477)
			(type default)
		)
		(layer "B.Cu")
	)
	(gr_line
		(start 388.630922 -417.166044)
		(end 388.335012 -417.461954)
		(stroke
			(width 0.06477)
			(type default)
		)
		(layer "B.Cu")
	)
	(gr_line
		(start 388.852664 -336.38109)
		(end 389.041894 -336.19186)
		(stroke
			(width 0.06477)
			(type default)
		)
		(layer "B.Cu")
	)
	(gr_line
		(start 389.041894 -336.19186)
		(end 389.427974 -336.19186)
		(stroke
			(width 0.06477)
			(type default)
		)
		(layer "B.Cu")
	)
	(gr_line
		(start 389.427974 -336.19186)
		(end 389.617204 -336.38109)
		(stroke
			(width 0.06477)
			(type default)
		)
		(layer "B.Cu")
	)
	(gr_line
		(start 389.488172 -222.891858)
		(end 389.363712 -222.767398)
		(stroke
			(width 0.06477)
			(type default)
		)
		(layer "B.Cu")
	)
	(gr_line
		(start 389.524494 -222.91294)
		(end 389.488172 -222.891858)
		(stroke
			(width 0.06477)
			(type default)
		)
		(layer "B.Cu")
	)
	(gr_line
		(start 389.618474 -336.70494)
		(end 388.851394 -336.70494)
		(stroke
			(width 0.06477)
			(type default)
		)
		(layer "B.Cu")
	)
	(gr_line
		(start 389.683752 -223.005396)
		(end 389.68299 -223.004888)
		(stroke
			(width 0.06477)
			(type default)
		)
		(layer "B.Cu")
	)
	(gr_line
		(start 389.686546 -222.633794)
		(end 389.686292 -222.63354)
		(stroke
			(width 0.06477)
			(type default)
		)
		(layer "B.Cu")
	)
	(gr_line
		(start 389.79475 -223.424242)
		(end 389.683752 -223.005396)
		(stroke
			(width 0.06477)
			(type default)
		)
		(layer "B.Cu")
	)
	(gr_line
		(start 390.0424 -336.38109)
		(end 390.23163 -336.19186)
		(stroke
			(width 0.06477)
			(type default)
		)
		(layer "B.Cu")
	)
	(gr_line
		(start 390.23163 -336.19186)
		(end 390.61771 -336.19186)
		(stroke
			(width 0.06477)
			(type default)
		)
		(layer "B.Cu")
	)
	(gr_line
		(start 390.264904 -222.614236)
		(end 389.845042 -222.725742)
		(stroke
			(width 0.06477)
			(type default)
		)
		(layer "B.Cu")
	)
	(gr_line
		(start 390.61771 -336.19186)
		(end 390.80694 -336.38109)
		(stroke
			(width 0.06477)
			(type default)
		)
		(layer "B.Cu")
	)
	(gr_line
		(start 390.779762 -417.166044)
		(end 391.075672 -417.461954)
		(stroke
			(width 0.06477)
			(type default)
		)
		(layer "B.Cu")
	)
	(gr_line
		(start 390.805162 -415.38652)
		(end 391.075672 -415.65703)
		(stroke
			(width 0.06477)
			(type default)
		)
		(layer "B.Cu")
	)
	(gr_line
		(start 390.80821 -336.70494)
		(end 390.04113 -336.70494)
		(stroke
			(width 0.06477)
			(type default)
		)
		(layer "B.Cu")
	)
	(gr_line
		(start 390.940036 8.258048)
		(end 390.287764 8.439912)
		(stroke
			(width 0.06477)
			(type default)
		)
		(layer "B.Cu")
	)
	(gr_line
		(start 390.940036 9.121648)
		(end 390.287764 8.939784)
		(stroke
			(width 0.06477)
			(type default)
		)
		(layer "B.Cu")
	)
	(gr_line
		(start 391.075672 -418.141658)
		(end 390.805162 -418.412168)
		(stroke
			(width 0.06477)
			(type default)
		)
		(layer "B.Cu")
	)
	(gr_line
		(start 391.075672 -416.336734)
		(end 390.779762 -416.632644)
		(stroke
			(width 0.06477)
			(type default)
		)
		(layer "B.Cu")
	)
	(gr_line
		(start 391.398252 -418.141658)
		(end 391.668762 -418.412168)
		(stroke
			(width 0.06477)
			(type default)
		)
		(layer "B.Cu")
	)
	(gr_line
		(start 391.398252 -416.336734)
		(end 391.694162 -416.632644)
		(stroke
			(width 0.06477)
			(type default)
		)
		(layer "B.Cu")
	)
	(gr_line
		(start 391.580116 -336.38109)
		(end 391.769346 -336.19186)
		(stroke
			(width 0.06477)
			(type default)
		)
		(layer "B.Cu")
	)
	(gr_line
		(start 391.668762 -415.38652)
		(end 391.398252 -415.65703)
		(stroke
			(width 0.06477)
			(type default)
		)
		(layer "B.Cu")
	)
	(gr_line
		(start 391.694162 -417.166044)
		(end 391.398252 -417.461954)
		(stroke
			(width 0.06477)
			(type default)
		)
		(layer "B.Cu")
	)
	(gr_line
		(start 391.769346 -336.19186)
		(end 392.155426 -336.19186)
		(stroke
			(width 0.06477)
			(type default)
		)
		(layer "B.Cu")
	)
	(gr_line
		(start 392.155426 -336.19186)
		(end 392.344656 -336.38109)
		(stroke
			(width 0.06477)
			(type default)
		)
		(layer "B.Cu")
	)
	(gr_line
		(start 392.345926 -336.70494)
		(end 391.578846 -336.70494)
		(stroke
			(width 0.06477)
			(type default)
		)
		(layer "B.Cu")
	)
	(gr_line
		(start 392.733276 -336.38109)
		(end 392.922506 -336.19186)
		(stroke
			(width 0.06477)
			(type default)
		)
		(layer "B.Cu")
	)
	(gr_line
		(start 392.922506 -336.19186)
		(end 393.308586 -336.19186)
		(stroke
			(width 0.06477)
			(type default)
		)
		(layer "B.Cu")
	)
	(gr_line
		(start 393.308586 -336.19186)
		(end 393.497816 -336.38109)
		(stroke
			(width 0.06477)
			(type default)
		)
		(layer "B.Cu")
	)
	(gr_line
		(start 393.499086 -336.70494)
		(end 392.732006 -336.70494)
		(stroke
			(width 0.06477)
			(type default)
		)
		(layer "B.Cu")
	)
	(gr_line
		(start 393.843002 -417.166044)
		(end 394.138912 -417.461954)
		(stroke
			(width 0.06477)
			(type default)
		)
		(layer "B.Cu")
	)
	(gr_line
		(start 393.868402 -415.38652)
		(end 394.138912 -415.65703)
		(stroke
			(width 0.06477)
			(type default)
		)
		(layer "B.Cu")
	)
	(gr_line
		(start 393.886436 -336.38109)
		(end 394.075666 -336.19186)
		(stroke
			(width 0.06477)
			(type default)
		)
		(layer "B.Cu")
	)
	(gr_line
		(start 394.075666 -336.19186)
		(end 394.461746 -336.19186)
		(stroke
			(width 0.06477)
			(type default)
		)
		(layer "B.Cu")
	)
	(gr_line
		(start 394.138912 -416.336734)
		(end 393.843002 -416.632644)
		(stroke
			(width 0.06477)
			(type default)
		)
		(layer "B.Cu")
	)
	(gr_line
		(start 394.461492 -416.336734)
		(end 394.757402 -416.632644)
		(stroke
			(width 0.06477)
			(type default)
		)
		(layer "B.Cu")
	)
	(gr_line
		(start 394.461746 -336.19186)
		(end 394.650976 -336.38109)
		(stroke
			(width 0.06477)
			(type default)
		)
		(layer "B.Cu")
	)
	(gr_line
		(start 394.652246 -336.70494)
		(end 393.885166 -336.70494)
		(stroke
			(width 0.06477)
			(type default)
		)
		(layer "B.Cu")
	)
	(gr_line
		(start 394.732002 -415.38652)
		(end 394.461492 -415.65703)
		(stroke
			(width 0.06477)
			(type default)
		)
		(layer "B.Cu")
	)
	(gr_line
		(start 394.757402 -417.166044)
		(end 394.461492 -417.461954)
		(stroke
			(width 0.06477)
			(type default)
		)
		(layer "B.Cu")
	)
	(gr_line
		(start 396.906242 -417.166044)
		(end 397.186912 -417.446714)
		(stroke
			(width 0.06477)
			(type default)
		)
		(layer "B.Cu")
	)
	(gr_line
		(start 396.931642 -415.38652)
		(end 397.20266 -415.657538)
		(stroke
			(width 0.06477)
			(type default)
		)
		(layer "B.Cu")
	)
	(gr_line
		(start 397.186912 -418.126418)
		(end 397.186912 -418.156898)
		(stroke
			(width 0.06477)
			(type default)
		)
		(layer "B.Cu")
	)
	(gr_line
		(start 397.186912 -417.446714)
		(end 397.186912 -417.477194)
		(stroke
			(width 0.06477)
			(type default)
		)
		(layer "B.Cu")
	)
	(gr_line
		(start 397.20266 -416.336226)
		(end 396.906242 -416.632644)
		(stroke
			(width 0.06477)
			(type default)
		)
		(layer "B.Cu")
	)
	(gr_line
		(start 397.510762 -418.127688)
		(end 397.795242 -418.412168)
		(stroke
			(width 0.06477)
			(type default)
		)
		(layer "B.Cu")
	)
	(gr_line
		(start 397.52651 -416.338512)
		(end 397.820642 -416.632644)
		(stroke
			(width 0.06477)
			(type default)
		)
		(layer "B.Cu")
	)
	(gr_line
		(start 397.52651 -416.334956)
		(end 397.52651 -416.338512)
		(stroke
			(width 0.06477)
			(type default)
		)
		(layer "B.Cu")
	)
	(gr_line
		(start 397.52651 -415.655252)
		(end 397.52651 -415.658808)
		(stroke
			(width 0.06477)
			(type default)
		)
		(layer "B.Cu")
	)
	(gr_line
		(start 397.795242 -415.38652)
		(end 397.52651 -415.655252)
		(stroke
			(width 0.06477)
			(type default)
		)
		(layer "B.Cu")
	)
	(gr_line
		(start 397.820642 -417.166044)
		(end 397.510762 -417.475924)
		(stroke
			(width 0.06477)
			(type default)
		)
		(layer "B.Cu")
	)
	(gr_line
		(start 399.969482 -417.166044)
		(end 400.265392 -417.461954)
		(stroke
			(width 0.06477)
			(type default)
		)
		(layer "B.Cu")
	)
	(gr_line
		(start 399.994882 -415.38652)
		(end 400.265392 -415.65703)
		(stroke
			(width 0.06477)
			(type default)
		)
		(layer "B.Cu")
	)
	(gr_line
		(start 400.265392 -416.336734)
		(end 399.969482 -416.632644)
		(stroke
			(width 0.06477)
			(type default)
		)
		(layer "B.Cu")
	)
	(gr_line
		(start 400.587972 -416.336734)
		(end 400.883882 -416.632644)
		(stroke
			(width 0.06477)
			(type default)
		)
		(layer "B.Cu")
	)
	(gr_line
		(start 400.858482 -415.38652)
		(end 400.587972 -415.65703)
		(stroke
			(width 0.06477)
			(type default)
		)
		(layer "B.Cu")
	)
	(gr_line
		(start 400.883882 -417.166044)
		(end 400.587972 -417.461954)
		(stroke
			(width 0.06477)
			(type default)
		)
		(layer "B.Cu")
	)
	(gr_line
		(start 403.032722 -417.166044)
		(end 403.328632 -417.461954)
		(stroke
			(width 0.06477)
			(type default)
		)
		(layer "B.Cu")
	)
	(gr_line
		(start 403.058122 -415.38652)
		(end 403.328632 -415.65703)
		(stroke
			(width 0.06477)
			(type default)
		)
		(layer "B.Cu")
	)
	(gr_line
		(start 403.328632 -418.141658)
		(end 403.058122 -418.412168)
		(stroke
			(width 0.06477)
			(type default)
		)
		(layer "B.Cu")
	)
	(gr_line
		(start 403.328632 -416.336734)
		(end 403.032722 -416.632644)
		(stroke
			(width 0.06477)
			(type default)
		)
		(layer "B.Cu")
	)
	(gr_line
		(start 403.651212 -418.141658)
		(end 403.921722 -418.412168)
		(stroke
			(width 0.06477)
			(type default)
		)
		(layer "B.Cu")
	)
	(gr_line
		(start 403.651212 -416.336734)
		(end 403.947122 -416.632644)
		(stroke
			(width 0.06477)
			(type default)
		)
		(layer "B.Cu")
	)
	(gr_line
		(start 403.921722 -415.38652)
		(end 403.651212 -415.65703)
		(stroke
			(width 0.06477)
			(type default)
		)
		(layer "B.Cu")
	)
	(gr_line
		(start 403.947122 -417.166044)
		(end 403.651212 -417.461954)
		(stroke
			(width 0.06477)
			(type default)
		)
		(layer "B.Cu")
	)
	(gr_line
		(start 406.095962 -417.166044)
		(end 406.391872 -417.461954)
		(stroke
			(width 0.06477)
			(type default)
		)
		(layer "B.Cu")
	)
	(gr_line
		(start 406.121362 -415.38652)
		(end 406.391872 -415.65703)
		(stroke
			(width 0.06477)
			(type default)
		)
		(layer "B.Cu")
	)
	(gr_line
		(start 406.391872 -418.141658)
		(end 406.121362 -418.412168)
		(stroke
			(width 0.06477)
			(type default)
		)
		(layer "B.Cu")
	)
	(gr_line
		(start 406.391872 -416.336734)
		(end 406.095962 -416.632644)
		(stroke
			(width 0.06477)
			(type default)
		)
		(layer "B.Cu")
	)
	(gr_line
		(start 406.714452 -418.141658)
		(end 406.984962 -418.412168)
		(stroke
			(width 0.06477)
			(type default)
		)
		(layer "B.Cu")
	)
	(gr_line
		(start 406.714452 -416.336734)
		(end 407.010362 -416.632644)
		(stroke
			(width 0.06477)
			(type default)
		)
		(layer "B.Cu")
	)
	(gr_line
		(start 406.984962 -415.38652)
		(end 406.714452 -415.65703)
		(stroke
			(width 0.06477)
			(type default)
		)
		(layer "B.Cu")
	)
	(gr_line
		(start 407.010362 -417.166044)
		(end 406.714452 -417.461954)
		(stroke
			(width 0.06477)
			(type default)
		)
		(layer "B.Cu")
	)
	(gr_line
		(start 409.159202 -417.166044)
		(end 409.437332 -417.444174)
		(stroke
			(width 0.06477)
			(type default)
		)
		(layer "B.Cu")
	)
	(gr_line
		(start 409.184602 -415.38652)
		(end 409.455112 -415.65703)
		(stroke
			(width 0.06477)
			(type default)
		)
		(layer "B.Cu")
	)
	(gr_line
		(start 409.437332 -418.159438)
		(end 409.184602 -418.412168)
		(stroke
			(width 0.06477)
			(type default)
		)
		(layer "B.Cu")
	)
	(gr_line
		(start 409.437332 -418.123878)
		(end 409.437332 -418.159438)
		(stroke
			(width 0.06477)
			(type default)
		)
		(layer "B.Cu")
	)
	(gr_line
		(start 409.437332 -417.444174)
		(end 409.437332 -417.479734)
		(stroke
			(width 0.06477)
			(type default)
		)
		(layer "B.Cu")
	)
	(gr_line
		(start 409.455112 -416.336734)
		(end 409.159202 -416.632644)
		(stroke
			(width 0.06477)
			(type default)
		)
		(layer "B.Cu")
	)
	(gr_line
		(start 409.761182 -418.125148)
		(end 410.048202 -418.412168)
		(stroke
			(width 0.06477)
			(type default)
		)
		(layer "B.Cu")
	)
	(gr_line
		(start 409.777692 -416.336734)
		(end 410.073602 -416.632644)
		(stroke
			(width 0.06477)
			(type default)
		)
		(layer "B.Cu")
	)
	(gr_line
		(start 410.048202 -415.38652)
		(end 409.777692 -415.65703)
		(stroke
			(width 0.06477)
			(type default)
		)
		(layer "B.Cu")
	)
	(gr_line
		(start 410.073602 -417.166044)
		(end 409.761182 -417.478464)
		(stroke
			(width 0.06477)
			(type default)
		)
		(layer "B.Cu")
	)
	(gr_line
		(start 410.5021 -333.61884)
		(end 410.5021 -333.23276)
		(stroke
			(width 0.06477)
			(type default)
		)
		(layer "B.Cu")
	)
	(gr_line
		(start 410.5021 -333.23276)
		(end 410.69133 -333.04353)
		(stroke
			(width 0.06477)
			(type default)
		)
		(layer "B.Cu")
	)
	(gr_line
		(start 410.69133 -333.80807)
		(end 410.5021 -333.61884)
		(stroke
			(width 0.06477)
			(type default)
		)
		(layer "B.Cu")
	)
	(gr_line
		(start 411.01518 -333.04226)
		(end 411.01518 -333.80934)
		(stroke
			(width 0.06477)
			(type default)
		)
		(layer "B.Cu")
	)
	(gr_line
		(start 412.222442 -417.166044)
		(end 412.518352 -417.461954)
		(stroke
			(width 0.06477)
			(type default)
		)
		(layer "B.Cu")
	)
	(gr_line
		(start 412.247842 -415.38652)
		(end 412.518352 -415.65703)
		(stroke
			(width 0.06477)
			(type default)
		)
		(layer "B.Cu")
	)
	(gr_line
		(start 412.518352 -418.141658)
		(end 412.247842 -418.412168)
		(stroke
			(width 0.06477)
			(type default)
		)
		(layer "B.Cu")
	)
	(gr_line
		(start 412.518352 -416.336734)
		(end 412.222442 -416.632644)
		(stroke
			(width 0.06477)
			(type default)
		)
		(layer "B.Cu")
	)
	(gr_line
		(start 412.840932 -418.141658)
		(end 413.111442 -418.412168)
		(stroke
			(width 0.06477)
			(type default)
		)
		(layer "B.Cu")
	)
	(gr_line
		(start 412.840932 -416.336734)
		(end 413.136842 -416.632644)
		(stroke
			(width 0.06477)
			(type default)
		)
		(layer "B.Cu")
	)
	(gr_line
		(start 413.111442 -415.38652)
		(end 412.840932 -415.65703)
		(stroke
			(width 0.06477)
			(type default)
		)
		(layer "B.Cu")
	)
	(gr_line
		(start 413.136842 -417.166044)
		(end 412.840932 -417.461954)
		(stroke
			(width 0.06477)
			(type default)
		)
		(layer "B.Cu")
	)
	(gr_line
		(start 415.285682 -417.166044)
		(end 415.581592 -417.461954)
		(stroke
			(width 0.06477)
			(type default)
		)
		(layer "B.Cu")
	)
	(gr_line
		(start 415.311082 -415.38652)
		(end 415.581592 -415.65703)
		(stroke
			(width 0.06477)
			(type default)
		)
		(layer "B.Cu")
	)
	(gr_line
		(start 415.581592 -418.141658)
		(end 415.311082 -418.412168)
		(stroke
			(width 0.06477)
			(type default)
		)
		(layer "B.Cu")
	)
	(gr_line
		(start 415.581592 -416.336734)
		(end 415.285682 -416.632644)
		(stroke
			(width 0.06477)
			(type default)
		)
		(layer "B.Cu")
	)
	(gr_line
		(start 415.904172 -418.141658)
		(end 416.174682 -418.412168)
		(stroke
			(width 0.06477)
			(type default)
		)
		(layer "B.Cu")
	)
	(gr_line
		(start 415.904172 -416.336734)
		(end 416.200082 -416.632644)
		(stroke
			(width 0.06477)
			(type default)
		)
		(layer "B.Cu")
	)
	(gr_line
		(start 416.174682 -415.38652)
		(end 415.904172 -415.65703)
		(stroke
			(width 0.06477)
			(type default)
		)
		(layer "B.Cu")
	)
	(gr_line
		(start 416.200082 -417.166044)
		(end 415.904172 -417.461954)
		(stroke
			(width 0.06477)
			(type default)
		)
		(layer "B.Cu")
	)
	(gr_line
		(start 418.348922 -417.166044)
		(end 418.644832 -417.461954)
		(stroke
			(width 0.06477)
			(type default)
		)
		(layer "B.Cu")
	)
	(gr_line
		(start 418.374322 -415.38652)
		(end 418.644832 -415.65703)
		(stroke
			(width 0.06477)
			(type default)
		)
		(layer "B.Cu")
	)
	(gr_line
		(start 418.644832 -418.141658)
		(end 418.374322 -418.412168)
		(stroke
			(width 0.06477)
			(type default)
		)
		(layer "B.Cu")
	)
	(gr_line
		(start 418.644832 -416.336734)
		(end 418.348922 -416.632644)
		(stroke
			(width 0.06477)
			(type default)
		)
		(layer "B.Cu")
	)
	(gr_line
		(start 418.967412 -418.141658)
		(end 419.237922 -418.412168)
		(stroke
			(width 0.06477)
			(type default)
		)
		(layer "B.Cu")
	)
	(gr_line
		(start 418.967412 -416.336734)
		(end 419.263322 -416.632644)
		(stroke
			(width 0.06477)
			(type default)
		)
		(layer "B.Cu")
	)
	(gr_line
		(start 419.237922 -415.38652)
		(end 418.967412 -415.65703)
		(stroke
			(width 0.06477)
			(type default)
		)
		(layer "B.Cu")
	)
	(gr_line
		(start 419.263322 -417.166044)
		(end 418.967412 -417.461954)
		(stroke
			(width 0.06477)
			(type default)
		)
		(layer "B.Cu")
	)
	(gr_line
		(start 421.9321 -24.047958)
		(end 422.199816 -24.047958)
		(stroke
			(width 0.06477)
			(type default)
		)
		(layer "B.Cu")
	)
	(gr_line
		(start 422.199816 -24.047958)
		(end 422.474898 -23.772876)
		(stroke
			(width 0.06477)
			(type default)
		)
		(layer "B.Cu")
	)
	(gr_line
		(start 422.246552 -23.27529)
		(end 421.702484 -23.819612)
		(stroke
			(width 0.06477)
			(type default)
		)
		(layer "B.Cu")
	)
	(gr_line
		(start 422.474898 -23.772876)
		(end 422.474898 -23.50516)
		(stroke
			(width 0.06477)
			(type default)
		)
		(layer "B.Cu")
	)
	(gr_line
		(start 422.627806 -9.292844)
		(end 422.627806 -10.062464)
		(stroke
			(width 0.06477)
			(type default)
		)
		(layer "B.Cu")
	)
	(gr_line
		(start 422.627806 -7.771384)
		(end 422.627806 -8.538464)
		(stroke
			(width 0.06477)
			(type default)
		)
		(layer "B.Cu")
	)
	(gr_line
		(start 422.627806 -6.618224)
		(end 422.627806 -7.385304)
		(stroke
			(width 0.06477)
			(type default)
		)
		(layer "B.Cu")
	)
	(gr_line
		(start 422.951656 -10.061194)
		(end 423.140886 -9.871964)
		(stroke
			(width 0.06477)
			(type default)
		)
		(layer "B.Cu")
	)
	(gr_line
		(start 422.951656 -8.537194)
		(end 423.120312 -8.368538)
		(stroke
			(width 0.06477)
			(type default)
		)
		(layer "B.Cu")
	)
	(gr_line
		(start 422.951656 -7.384034)
		(end 423.140886 -7.194804)
		(stroke
			(width 0.06477)
			(type default)
		)
		(layer "B.Cu")
	)
	(gr_line
		(start 423.120312 -8.368538)
		(end 423.120312 -7.94131)
		(stroke
			(width 0.06477)
			(type default)
		)
		(layer "B.Cu")
	)
	(gr_line
		(start 423.120312 -7.94131)
		(end 422.951656 -7.772654)
		(stroke
			(width 0.06477)
			(type default)
		)
		(layer "B.Cu")
	)
	(gr_line
		(start 423.140886 -9.871964)
		(end 423.140886 -9.483344)
		(stroke
			(width 0.06477)
			(type default)
		)
		(layer "B.Cu")
	)
	(gr_line
		(start 423.140886 -9.483344)
		(end 422.951656 -9.294114)
		(stroke
			(width 0.06477)
			(type default)
		)
		(layer "B.Cu")
	)
	(gr_line
		(start 423.140886 -7.194804)
		(end 423.140886 -6.808724)
		(stroke
			(width 0.06477)
			(type default)
		)
		(layer "B.Cu")
	)
	(gr_line
		(start 423.140886 -6.808724)
		(end 422.951656 -6.619494)
		(stroke
			(width 0.06477)
			(type default)
		)
		(layer "B.Cu")
	)
	(gr_line
		(start 428.66564 -3.632708)
		(end 428.85487 -3.821938)
		(stroke
			(width 0.06477)
			(type default)
		)
		(layer "B.Cu")
	)
	(gr_line
		(start 428.85487 -3.821938)
		(end 429.24095 -3.821938)
		(stroke
			(width 0.06477)
			(type default)
		)
		(layer "B.Cu")
	)
	(gr_line
		(start 429.24095 -3.821938)
		(end 429.43018 -3.632708)
		(stroke
			(width 0.06477)
			(type default)
		)
		(layer "B.Cu")
	)
	(gr_line
		(start 429.43145 -3.308858)
		(end 428.66437 -3.308858)
		(stroke
			(width 0.06477)
			(type default)
		)
		(layer "B.Cu")
	)
	(gr_line
		(start 432.105054 -12.594336)
		(end 431.834544 -12.864846)
		(stroke
			(width 0.06477)
			(type default)
		)
		(layer "B.Cu")
	)
	(gr_line
		(start 432.116992 -6.46176)
		(end 431.846482 -6.73227)
		(stroke
			(width 0.06477)
			(type default)
		)
		(layer "B.Cu")
	)
	(gr_line
		(start 432.412394 -14.630146)
		(end 432.144424 -14.630146)
		(stroke
			(width 0.06477)
			(type default)
		)
		(layer "B.Cu")
	)
	(gr_line
		(start 432.427634 -12.594336)
		(end 432.698144 -12.864846)
		(stroke
			(width 0.06477)
			(type default)
		)
		(layer "B.Cu")
	)
	(gr_line
		(start 432.457352 -15.40129)
		(end 431.914808 -14.858492)
		(stroke
			(width 0.06477)
			(type default)
		)
		(layer "B.Cu")
	)
	(gr_line
		(start 432.555904 -164.050726)
		(end 432.221894 -163.716716)
		(stroke
			(width 0.06477)
			(type default)
		)
		(layer "B.Cu")
	)
	(gr_line
		(start 432.685698 -15.17142)
		(end 432.685698 -14.90345)
		(stroke
			(width 0.06477)
			(type default)
		)
		(layer "B.Cu")
	)
	(gr_line
		(start 432.685698 -14.90345)
		(end 432.412394 -14.630146)
		(stroke
			(width 0.06477)
			(type default)
		)
		(layer "B.Cu")
	)
	(gr_line
		(start 432.710082 -6.73227)
		(end 432.439572 -6.46176)
		(stroke
			(width 0.06477)
			(type default)
		)
		(layer "B.Cu")
	)
	(gr_line
		(start 433.212494 -163.716716)
		(end 432.878484 -164.050726)
		(stroke
			(width 0.06477)
			(type default)
		)
		(layer "B.Cu")
	)
	(gr_line
		(start 433.227988 -15.44574)
		(end 432.960018 -15.44574)
		(stroke
			(width 0.06477)
			(type default)
		)
		(layer "B.Cu")
	)
	(gr_line
		(start 433.2732 -16.216884)
		(end 432.730148 -15.674086)
		(stroke
			(width 0.06477)
			(type default)
		)
		(layer "B.Cu")
	)
	(gr_line
		(start 433.501292 -15.987014)
		(end 433.501292 -15.719044)
		(stroke
			(width 0.06477)
			(type default)
		)
		(layer "B.Cu")
	)
	(gr_line
		(start 433.501292 -15.719044)
		(end 433.227988 -15.44574)
		(stroke
			(width 0.06477)
			(type default)
		)
		(layer "B.Cu")
	)
	(gr_line
		(start 434.043582 -16.261334)
		(end 433.775612 -16.261334)
		(stroke
			(width 0.06477)
			(type default)
		)
		(layer "B.Cu")
	)
	(gr_line
		(start 434.088794 -17.032478)
		(end 433.545996 -16.489426)
		(stroke
			(width 0.06477)
			(type default)
		)
		(layer "B.Cu")
	)
	(gr_line
		(start 434.316886 -16.802608)
		(end 434.316886 -16.534638)
		(stroke
			(width 0.06477)
			(type default)
		)
		(layer "B.Cu")
	)
	(gr_line
		(start 434.316886 -16.534638)
		(end 434.043582 -16.261334)
		(stroke
			(width 0.06477)
			(type default)
		)
		(layer "B.Cu")
	)
	(gr_line
		(start 435.693312 -2.495296)
		(end 435.882542 -2.684526)
		(stroke
			(width 0.06477)
			(type default)
		)
		(layer "B.Cu")
	)
	(gr_line
		(start 435.882542 -2.684526)
		(end 436.268622 -2.684526)
		(stroke
			(width 0.06477)
			(type default)
		)
		(layer "B.Cu")
	)
	(gr_line
		(start 436.268622 -2.684526)
		(end 436.457852 -2.495296)
		(stroke
			(width 0.06477)
			(type default)
		)
		(layer "B.Cu")
	)
	(gr_line
		(start 436.459122 -2.171446)
		(end 435.692042 -2.171446)
		(stroke
			(width 0.06477)
			(type default)
		)
		(layer "B.Cu")
	)
	(gr_line
		(start 436.846472 -2.495296)
		(end 437.035702 -2.684526)
		(stroke
			(width 0.06477)
			(type default)
		)
		(layer "B.Cu")
	)
	(gr_line
		(start 437.035702 -2.684526)
		(end 437.421782 -2.684526)
		(stroke
			(width 0.06477)
			(type default)
		)
		(layer "B.Cu")
	)
	(gr_line
		(start 437.421782 -2.684526)
		(end 437.611012 -2.495296)
		(stroke
			(width 0.06477)
			(type default)
		)
		(layer "B.Cu")
	)
	(gr_line
		(start 437.612282 -2.171446)
		(end 436.845202 -2.171446)
		(stroke
			(width 0.06477)
			(type default)
		)
		(layer "B.Cu")
	)
	(gr_line
		(start 437.999632 -2.495296)
		(end 438.188862 -2.684526)
		(stroke
			(width 0.06477)
			(type default)
		)
		(layer "B.Cu")
	)
	(gr_line
		(start 438.188862 -2.684526)
		(end 438.574942 -2.684526)
		(stroke
			(width 0.06477)
			(type default)
		)
		(layer "B.Cu")
	)
	(gr_line
		(start 438.574942 -2.684526)
		(end 438.764172 -2.495296)
		(stroke
			(width 0.06477)
			(type default)
		)
		(layer "B.Cu")
	)
	(gr_line
		(start 438.765442 -2.171446)
		(end 437.998362 -2.171446)
		(stroke
			(width 0.06477)
			(type default)
		)
		(layer "B.Cu")
	)
	(gr_line
		(start 439.95975 8.439912)
		(end 439.307478 8.258048)
		(stroke
			(width 0.06477)
			(type default)
		)
		(layer "B.Cu")
	)
	(gr_line
		(start 439.95975 8.939784)
		(end 439.307478 9.121648)
		(stroke
			(width 0.06477)
			(type default)
		)
		(layer "B.Cu")
	)
	(gr_line
		(start 441.725812 -5.694934)
		(end 441.915042 -5.884164)
		(stroke
			(width 0.06477)
			(type default)
		)
		(layer "B.Cu")
	)
	(gr_line
		(start 441.915042 -5.884164)
		(end 442.301122 -5.884164)
		(stroke
			(width 0.06477)
			(type default)
		)
		(layer "B.Cu")
	)
	(gr_line
		(start 442.301122 -5.884164)
		(end 442.490352 -5.694934)
		(stroke
			(width 0.06477)
			(type default)
		)
		(layer "B.Cu")
	)
	(gr_line
		(start 442.491622 -5.371084)
		(end 441.724542 -5.371084)
		(stroke
			(width 0.06477)
			(type default)
		)
		(layer "B.Cu")
	)
	(gr_line
		(start 442.878972 -5.694934)
		(end 443.068202 -5.884164)
		(stroke
			(width 0.06477)
			(type default)
		)
		(layer "B.Cu")
	)
	(gr_line
		(start 443.068202 -5.884164)
		(end 443.454282 -5.884164)
		(stroke
			(width 0.06477)
			(type default)
		)
		(layer "B.Cu")
	)
	(gr_line
		(start 443.454282 -5.884164)
		(end 443.643512 -5.694934)
		(stroke
			(width 0.06477)
			(type default)
		)
		(layer "B.Cu")
	)
	(gr_line
		(start 443.644782 -5.371084)
		(end 442.877702 -5.371084)
		(stroke
			(width 0.06477)
			(type default)
		)
		(layer "B.Cu")
	)
	(gr_line
		(start 446.1002 -12.594336)
		(end 445.82969 -12.864846)
		(stroke
			(width 0.06477)
			(type default)
		)
		(layer "B.Cu")
	)
	(gr_line
		(start 446.100962 -6.454648)
		(end 445.830452 -6.725158)
		(stroke
			(width 0.06477)
			(type default)
		)
		(layer "B.Cu")
	)
	(gr_line
		(start 446.69329 -12.864846)
		(end 446.42278 -12.594336)
		(stroke
			(width 0.06477)
			(type default)
		)
		(layer "B.Cu")
	)
	(gr_line
		(start 446.694052 -6.725158)
		(end 446.423542 -6.454648)
		(stroke
			(width 0.06477)
			(type default)
		)
		(layer "B.Cu")
	)
	(gr_line
		(start 0 -77.671676)
		(end 0 -13.780008)
		(stroke
			(width 1.016)
			(type default)
		)
		(layer "In1.Cu")
	)
	(gr_arc
		(start 0 -77.671676)
		(mid 0.152237 -78.436936)
		(end 0.585724 -79.085694)
		(stroke
			(width 1.016)
			(type default)
		)
		(layer "In1.Cu")
	)
	(gr_poly
		(pts
			(arc
				(start 279.248108 -392.23696)
				(mid 279.284029 -392.222081)
				(end 279.298908 -392.18616)
			)
			(arc
				(start 279.298908 -383.93116)
				(mid 279.284029 -383.895239)
				(end 279.248108 -383.88036)
			)
			(arc
				(start 275.026374 -383.88036)
				(mid 275.006851 -383.884261)
				(end 274.990306 -383.895346)
			)
			(arc
				(start 274.766278 -384.119374)
				(mid 274.755167 -384.135908)
				(end 274.751292 -384.155442)
			)
			(arc
				(start 274.751292 -392.107928)
				(mid 274.755193 -392.127451)
				(end 274.766278 -392.143996)
			)
			(arc
				(start 274.844256 -392.221974)
				(mid 274.86079 -392.233085)
				(end 274.880324 -392.23696)
			)
		)
		(stroke
			(width 0)
			(type solid)
		)
		(fill yes)
		(layer "In1.Cu")
		(net "P12V_MAIN_R_0")
	)
	(gr_poly
		(pts
			(arc
				(start 273.15541 -393.27836)
				(mid 273.174933 -393.274459)
				(end 273.191478 -393.263374)
			)
			(xy 273.191732 -393.26312) (xy 273.669252 -392.7856)
			(arc
				(start 273.669506 -392.785346)
				(mid 273.680617 -392.768812)
				(end 273.684492 -392.749278)
			)
			(arc
				(start 273.684492 -384.155442)
				(mid 273.680591 -384.135919)
				(end 273.669506 -384.119374)
			)
			(xy 273.669252 -384.11912) (xy 273.447764 -383.897632) (xy 273.447256 -383.897124)
			(arc
				(start 273.445478 -383.895346)
				(mid 273.428944 -383.884235)
				(end 273.40941 -383.88036)
			)
			(arc
				(start 239.542574 -383.88036)
				(mid 239.523051 -383.884261)
				(end 239.506506 -383.895346)
			)
			(xy 239.506252 -383.8956) (xy 239.03051 -384.371342) (xy 239.030256 -384.371596)
			(arc
				(start 239.028478 -384.373374)
				(mid 239.017367 -384.389908)
				(end 239.013492 -384.409442)
			)
			(arc
				(start 239.013492 -393.003278)
				(mid 239.017393 -393.022801)
				(end 239.028478 -393.039346)
			)
			(xy 239.028732 -393.0396) (xy 239.252252 -393.26312)
			(arc
				(start 239.252506 -393.263374)
				(mid 239.26904 -393.274485)
				(end 239.288574 -393.27836)
			)
		)
		(stroke
			(width 0)
			(type solid)
		)
		(fill yes)
		(layer "In1.Cu")
		(net "P12V_MAIN_R")
	)
	(gr_poly
		(pts
			(arc
				(start 228.921818 -436.47868)
				(mid 228.941341 -436.474779)
				(end 228.957886 -436.463694)
			)
			(arc
				(start 229.664514 -435.757066)
				(mid 229.675625 -435.740532)
				(end 229.6795 -435.720998)
			)
			(arc
				(start 229.6795 -422.180766)
				(mid 229.703653 -422.05925)
				(end 229.772464 -421.95623)
			)
			(arc
				(start 234.67314 -417.055554)
				(mid 234.776172 -416.986773)
				(end 234.897676 -416.96259)
			)
			(arc
				(start 272.037556 -416.96259)
				(mid 272.057079 -416.958689)
				(end 272.073624 -416.947604)
			)
			(arc
				(start 280.035254 -408.985974)
				(mid 280.046365 -408.96944)
				(end 280.05024 -408.949906)
			)
			(arc
				(start 280.05024 -394.963396)
				(mid 280.046339 -394.943873)
				(end 280.035254 -394.927328)
			)
			(xy 280.035 -394.927074) (xy 279.65146 -394.543534)
			(arc
				(start 279.651206 -394.54328)
				(mid 279.634672 -394.532169)
				(end 279.615138 -394.528294)
			)
			(arc
				(start 278.051514 -394.528294)
				(mid 278.036928 -394.530433)
				(end 278.023574 -394.536676)
			)
			(arc
				(start 278.023574 -394.536676)
				(mid 277.823537 -394.629726)
				(end 277.605236 -394.661644)
			)
			(arc
				(start 277.605236 -394.661644)
				(mid 277.421236 -394.639047)
				(end 277.248112 -394.572744)
			)
			(arc
				(start 277.248112 -394.572744)
				(mid 277.224236 -394.566797)
				(end 277.20036 -394.572744)
			)
			(arc
				(start 277.20036 -394.572744)
				(mid 277.027244 -394.639078)
				(end 276.843236 -394.661644)
			)
			(arc
				(start 276.843236 -394.661644)
				(mid 276.624932 -394.629737)
				(end 276.424898 -394.536676)
			)
			(arc
				(start 276.424898 -394.536676)
				(mid 276.411542 -394.53044)
				(end 276.396958 -394.528294)
			)
			(arc
				(start 269.04569 -394.528294)
				(mid 269.030398 -394.53065)
				(end 269.01648 -394.537438)
			)
			(arc
				(start 269.01648 -394.537438)
				(mid 268.808203 -394.640414)
				(end 268.578584 -394.675868)
			)
			(arc
				(start 268.578584 -394.675868)
				(mid 268.394584 -394.653271)
				(end 268.22146 -394.586968)
			)
			(arc
				(start 268.22146 -394.586968)
				(mid 268.197584 -394.581021)
				(end 268.173708 -394.586968)
			)
			(arc
				(start 268.173708 -394.586968)
				(mid 268.000592 -394.653302)
				(end 267.816584 -394.675868)
			)
			(arc
				(start 267.816584 -394.675868)
				(mid 267.586971 -394.640395)
				(end 267.378688 -394.537438)
			)
			(arc
				(start 267.378688 -394.537438)
				(mid 267.364793 -394.530577)
				(end 267.349478 -394.528294)
			)
			(arc
				(start 261.01929 -394.528294)
				(mid 261.003998 -394.53065)
				(end 260.99008 -394.537438)
			)
			(arc
				(start 260.99008 -394.537438)
				(mid 260.781803 -394.640414)
				(end 260.552184 -394.675868)
			)
			(arc
				(start 260.552184 -394.675868)
				(mid 260.368184 -394.653271)
				(end 260.19506 -394.586968)
			)
			(arc
				(start 260.19506 -394.586968)
				(mid 260.171184 -394.581021)
				(end 260.147308 -394.586968)
			)
			(arc
				(start 260.147308 -394.586968)
				(mid 259.974192 -394.653302)
				(end 259.790184 -394.675868)
			)
			(arc
				(start 259.790184 -394.675868)
				(mid 259.560571 -394.640395)
				(end 259.352288 -394.537438)
			)
			(arc
				(start 259.352288 -394.537438)
				(mid 259.338393 -394.530577)
				(end 259.323078 -394.528294)
			)
			(arc
				(start 252.99289 -394.528294)
				(mid 252.977598 -394.53065)
				(end 252.96368 -394.537438)
			)
			(arc
				(start 252.96368 -394.537438)
				(mid 252.755403 -394.640414)
				(end 252.525784 -394.675868)
			)
			(arc
				(start 252.525784 -394.675868)
				(mid 252.341784 -394.653271)
				(end 252.16866 -394.586968)
			)
			(arc
				(start 252.16866 -394.586968)
				(mid 252.144784 -394.581021)
				(end 252.120908 -394.586968)
			)
			(arc
				(start 252.120908 -394.586968)
				(mid 251.947792 -394.653302)
				(end 251.763784 -394.675868)
			)
			(arc
				(start 251.763784 -394.675868)
				(mid 251.534171 -394.640395)
				(end 251.325888 -394.537438)
			)
			(arc
				(start 251.325888 -394.537438)
				(mid 251.311993 -394.530577)
				(end 251.296678 -394.528294)
			)
			(arc
				(start 244.9576 -394.528294)
				(mid 244.942576 -394.530567)
				(end 244.928898 -394.537184)
			)
			(arc
				(start 244.928898 -394.537184)
				(mid 244.722849 -394.637373)
				(end 244.496336 -394.671804)
			)
			(arc
				(start 244.496336 -394.671804)
				(mid 244.312336 -394.649207)
				(end 244.139212 -394.582904)
			)
			(arc
				(start 244.139212 -394.582904)
				(mid 244.115336 -394.576957)
				(end 244.09146 -394.582904)
			)
			(arc
				(start 244.09146 -394.582904)
				(mid 243.918344 -394.649238)
				(end 243.734336 -394.671804)
			)
			(arc
				(start 243.734336 -394.671804)
				(mid 243.507823 -394.637371)
				(end 243.301774 -394.537184)
			)
			(arc
				(start 243.301774 -394.537184)
				(mid 243.288095 -394.53057)
				(end 243.273072 -394.528294)
			)
			(arc
				(start 239.250982 -394.528294)
				(mid 239.215061 -394.543173)
				(end 239.200182 -394.579094)
			)
			(arc
				(start 239.200182 -405.390096)
				(mid 239.176029 -405.511612)
				(end 239.107218 -405.614632)
			)
			(arc
				(start 238.94034 -405.78151)
				(mid 238.837308 -405.850291)
				(end 238.715804 -405.874474)
			)
			(arc
				(start 234.522264 -405.874474)
				(mid 234.400748 -405.850321)
				(end 234.297728 -405.78151)
			)
			(arc
				(start 233.595926 -405.079708)
				(mid 233.527145 -404.976676)
				(end 233.502962 -404.855172)
			)
			(arc
				(start 233.502962 -404.072344)
				(mid 233.499061 -404.052821)
				(end 233.487976 -404.036276)
			)
			(arc
				(start 233.3498 -403.8981)
				(mid 233.281019 -403.795068)
				(end 233.256836 -403.673564)
			)
			(arc
				(start 233.256836 -400.256502)
				(mid 233.252935 -400.236979)
				(end 233.24185 -400.220434)
			)
			(arc
				(start 233.236008 -400.214592)
				(mid 233.219474 -400.203481)
				(end 233.19994 -400.199606)
			)
			(arc
				(start 229.898956 -400.199606)
				(mid 229.879433 -400.203507)
				(end 229.862888 -400.214592)
			)
			(arc
				(start 229.848664 -400.228816)
				(mid 229.837553 -400.24535)
				(end 229.833678 -400.264884)
			)
			(arc
				(start 229.833678 -403.583648)
				(mid 229.809525 -403.705164)
				(end 229.740714 -403.808184)
			)
			(arc
				(start 229.66426 -403.884638)
				(mid 229.653149 -403.901172)
				(end 229.649274 -403.920706)
			)
			(arc
				(start 229.649274 -406.19299)
				(mid 229.625121 -406.314506)
				(end 229.55631 -406.417526)
			)
			(arc
				(start 227.443284 -408.530552)
				(mid 227.340252 -408.599333)
				(end 227.218748 -408.623516)
			)
			(arc
				(start 225.642424 -408.623516)
				(mid 225.623565 -408.627146)
				(end 225.607372 -408.637486)
			)
			(arc
				(start 225.607372 -408.637486)
				(mid 225.364908 -408.792887)
				(end 225.0821 -408.84729)
			)
			(arc
				(start 225.0821 -408.84729)
				(mid 224.549885 -408.630828)
				(end 224.319846 -408.10434)
			)
			(xy 224.319592 -408.094434) (xy 224.311972 -408.076654)
			(arc
				(start 222.874586 -406.639268)
				(mid 222.805805 -406.536236)
				(end 222.781622 -406.414732)
			)
			(arc
				(start 222.781622 -403.953472)
				(mid 222.777721 -403.933949)
				(end 222.766636 -403.917404)
			)
			(arc
				(start 222.681546 -403.832314)
				(mid 222.612765 -403.729282)
				(end 222.588582 -403.607778)
			)
			(xy 222.588582 -400.229832) (xy 222.580962 -400.21129) (xy 222.57766 -400.207988)
			(arc
				(start 219.197936 -400.207988)
				(mid 219.178413 -400.211889)
				(end 219.161868 -400.222974)
			)
			(xy 219.157296 -400.227546)
			(arc
				(start 219.157296 -403.583394)
				(mid 219.133143 -403.70491)
				(end 219.064332 -403.80793)
			)
			(arc
				(start 219.00007 -403.872192)
				(mid 218.988959 -403.888726)
				(end 218.985084 -403.90826)
			)
			(arc
				(start 218.985084 -406.217374)
				(mid 218.960931 -406.33889)
				(end 218.89212 -406.44191)
			)
			(arc
				(start 216.76614 -408.56789)
				(mid 216.663108 -408.636671)
				(end 216.541604 -408.660854)
			)
			(arc
				(start 214.93226 -408.660854)
				(mid 214.915131 -408.66392)
				(end 214.900002 -408.672538)
			)
			(arc
				(start 214.900002 -408.672538)
				(mid 214.672289 -408.802264)
				(end 214.4141 -408.84729)
			)
			(arc
				(start 214.4141 -408.84729)
				(mid 213.886272 -408.635069)
				(end 213.652354 -408.116532)
			)
			(xy 213.651846 -408.10688) (xy 213.644226 -408.089608)
			(arc
				(start 212.189822 -406.635204)
				(mid 212.121041 -406.532172)
				(end 212.096858 -406.410668)
			)
			(arc
				(start 212.096858 -403.916642)
				(mid 212.092957 -403.897119)
				(end 212.081872 -403.880574)
			)
			(arc
				(start 212.058504 -403.857206)
				(mid 211.989723 -403.754174)
				(end 211.96554 -403.63267)
			)
			(arc
				(start 211.96554 -400.29765)
				(mid 211.961639 -400.278127)
				(end 211.950554 -400.261582)
			)
			(arc
				(start 211.854542 -400.16557)
				(mid 211.838008 -400.154459)
				(end 211.818474 -400.150584)
			)
			(arc
				(start 208.578704 -400.150584)
				(mid 208.559181 -400.154485)
				(end 208.542636 -400.16557)
			)
			(arc
				(start 208.512156 -400.19605)
				(mid 208.501045 -400.212584)
				(end 208.49717 -400.232118)
			)
			(arc
				(start 208.49717 -403.534118)
				(mid 208.473017 -403.655634)
				(end 208.404206 -403.758654)
			)
			(arc
				(start 208.323688 -403.839172)
				(mid 208.312577 -403.855706)
				(end 208.308702 -403.87524)
			)
			(arc
				(start 208.308702 -406.275032)
				(mid 208.284549 -406.396548)
				(end 208.215738 -406.499568)
			)
			(arc
				(start 206.172562 -408.542744)
				(mid 206.06953 -408.611525)
				(end 205.948026 -408.635708)
			)
			(arc
				(start 204.293216 -408.635708)
				(mid 204.274946 -408.639107)
				(end 204.25918 -408.648916)
			)
			(arc
				(start 204.25918 -408.648916)
				(mid 204.021144 -408.79596)
				(end 203.7461 -408.84729)
			)
			(arc
				(start 203.7461 -408.84729)
				(mid 203.306844 -408.708001)
				(end 203.028042 -408.341068)
			)
			(xy 203.023978 -408.330146)
			(arc
				(start 201.5871 -406.893268)
				(mid 201.518319 -406.790236)
				(end 201.494136 -406.668732)
			)
			(arc
				(start 201.494136 -403.941026)
				(mid 201.490235 -403.921503)
				(end 201.47915 -403.904958)
			)
			(arc
				(start 201.373994 -403.799802)
				(mid 201.305213 -403.69677)
				(end 201.28103 -403.575266)
			)
			(arc
				(start 201.28103 -400.264884)
				(mid 201.277129 -400.245361)
				(end 201.266044 -400.228816)
			)
			(arc
				(start 201.221594 -400.184366)
				(mid 201.20506 -400.173255)
				(end 201.185526 -400.16938)
			)
			(arc
				(start 197.9168 -400.16938)
				(mid 197.897277 -400.173281)
				(end 197.880732 -400.184366)
			)
			(arc
				(start 197.844156 -400.220942)
				(mid 197.833045 -400.237476)
				(end 197.82917 -400.25701)
			)
			(arc
				(start 197.82917 -403.58314)
				(mid 197.805017 -403.704656)
				(end 197.736206 -403.807676)
			)
			(arc
				(start 195.6435 -405.900382)
				(mid 195.540468 -405.969163)
				(end 195.418964 -405.993346)
			)
			(arc
				(start 191.073786 -405.993346)
				(mid 190.95227 -405.969193)
				(end 190.84925 -405.900382)
			)
			(arc
				(start 188.07938 -403.130512)
				(mid 188.010599 -403.02748)
				(end 187.986416 -402.905976)
			)
			(arc
				(start 187.986416 -400.258534)
				(mid 187.971537 -400.222613)
				(end 187.935616 -400.207734)
			)
			(arc
				(start 184.616598 -400.207734)
				(mid 184.597075 -400.211635)
				(end 184.58053 -400.22272)
			)
			(xy 184.575958 -400.227292) (xy 184.575958 -405.83104) (xy 184.598818 -405.85898)
			(arc
				(start 184.617106 -405.862536)
				(mid 184.925224 -406.236932)
				(end 184.617106 -406.611328)
			)
			(xy 184.598818 -406.614884) (xy 184.575958 -406.642824)
			(arc
				(start 184.575958 -410.555694)
				(mid 184.579859 -410.575217)
				(end 184.590944 -410.591762)
			)
			(arc
				(start 184.926986 -410.927804)
				(mid 184.94352 -410.938915)
				(end 184.963054 -410.94279)
			)
			(arc
				(start 187.965334 -410.94279)
				(mid 188.08685 -410.966943)
				(end 188.18987 -411.035754)
			)
			(arc
				(start 188.836808 -411.682692)
				(mid 188.853342 -411.693803)
				(end 188.872876 -411.697678)
			)
			(arc
				(start 195.270882 -411.697678)
				(mid 195.392398 -411.721831)
				(end 195.495418 -411.790642)
			)
			(arc
				(start 196.65696 -412.952184)
				(mid 196.725741 -413.055216)
				(end 196.749924 -413.17672)
			)
			(arc
				(start 196.749924 -421.558466)
				(mid 196.753825 -421.577989)
				(end 196.76491 -421.594534)
			)
			(arc
				(start 205.961996 -430.79162)
				(mid 206.030777 -430.894652)
				(end 206.05496 -431.016156)
			)
			(arc
				(start 206.05496 -435.078378)
				(mid 206.058861 -435.097901)
				(end 206.069946 -435.114446)
			)
			(arc
				(start 207.419194 -436.463694)
				(mid 207.435728 -436.474805)
				(end 207.455262 -436.47868)
			)
		)
		(stroke
			(width 0)
			(type solid)
		)
		(fill yes)
		(layer "In1.Cu")
		(net "P12V_PSU")
	)
	(gr_poly
		(pts
			(xy 531.7998 -462.519268) (xy 531.855569 -462.518759) (xy 531.966796 -462.510424) (xy 532.077089 -462.4938)
			(xy 532.185831 -462.46898) (xy 532.292414 -462.436103) (xy 532.396243 -462.395354) (xy 532.496736 -462.346959)
			(xy 532.593331 -462.291189) (xy 532.685488 -462.228357) (xy 532.772692 -462.158813) (xy 532.854456 -462.082947)
			(xy 532.930321 -462.001183) (xy 532.999864 -461.913979) (xy 533.062695 -461.821821) (xy 533.118464 -461.725225)
			(xy 533.166858 -461.624732) (xy 533.207607 -461.520903) (xy 533.240483 -461.41432) (xy 533.265302 -461.305577)
			(xy 533.281925 -461.195284) (xy 533.29026 -461.084057) (xy 533.29078 -461.028288) (xy 533.29078 -455.0283)
			(xy 533.290259 -454.972531) (xy 533.281923 -454.861305) (xy 533.265299 -454.751013) (xy 533.24048 -454.642271)
			(xy 533.207603 -454.535688) (xy 533.166854 -454.43186) (xy 533.118459 -454.331368) (xy 533.06269 -454.234773)
			(xy 532.999859 -454.142616) (xy 532.930316 -454.055412) (xy 532.854451 -453.973649) (xy 532.772688 -453.897784)
			(xy 532.685484 -453.828241) (xy 532.593327 -453.76541) (xy 532.496732 -453.709641) (xy 532.39624 -453.661246)
			(xy 532.292412 -453.620497) (xy 532.185829 -453.58762) (xy 532.077087 -453.562801) (xy 531.966795 -453.546177)
			(xy 531.855569 -453.537841) (xy 531.7998 -453.53732) (xy 516.019796 -453.53732) (xy 515.949414 -453.536826)
			(xy 515.808871 -453.528933) (xy 515.668991 -453.513172) (xy 515.530216 -453.489593) (xy 515.392981 -453.45827)
			(xy 515.257718 -453.419302) (xy 515.124852 -453.37281) (xy 514.994803 -453.318942) (xy 514.867978 -453.257866)
			(xy 514.744778 -453.189776) (xy 514.625589 -453.114884) (xy 514.510787 -453.033428) (xy 514.400733 -452.945663)
			(xy 514.295773 -452.851865) (xy 514.196238 -452.75233) (xy 514.10244 -452.64737) (xy 514.014674 -452.537316)
			(xy 513.933218 -452.422514) (xy 513.858326 -452.303325) (xy 513.790236 -452.180125) (xy 513.72916 -452.053301)
			(xy 513.675292 -451.923251) (xy 513.6288 -451.790386) (xy 513.589831 -451.655123) (xy 513.558507 -451.517888)
			(xy 513.534928 -451.379113) (xy 513.519167 -451.239233) (xy 513.511274 -451.09869) (xy 513.510784 -451.028308)
			(xy 513.510784 -312.408316) (xy 513.511268 -312.337933) (xy 513.51916 -312.197389) (xy 513.53492 -312.057508)
			(xy 513.558498 -311.918731) (xy 513.589821 -311.781495) (xy 513.628789 -311.646231) (xy 513.67528 -311.513364)
			(xy 513.729148 -311.383313) (xy 513.790224 -311.256488) (xy 513.858314 -311.133286) (xy 513.933205 -311.014096)
			(xy 514.014662 -310.899292) (xy 514.102427 -310.789237) (xy 514.196225 -310.684276) (xy 514.295761 -310.584739)
			(xy 514.400722 -310.49094) (xy 514.510776 -310.403174) (xy 514.625579 -310.321716) (xy 514.744769 -310.246824)
			(xy 514.86797 -310.178733) (xy 514.994795 -310.117656) (xy 515.124845 -310.063787) (xy 515.257712 -310.017295)
			(xy 515.392976 -309.978326) (xy 515.530212 -309.947002) (xy 515.668989 -309.923423) (xy 515.808869 -309.907662)
			(xy 515.949413 -309.899769) (xy 516.019796 -309.899304) (xy 531.7998 -309.899304) (xy 531.855569 -309.898783)
			(xy 531.966796 -309.890447) (xy 532.077089 -309.873823) (xy 532.185831 -309.849004) (xy 532.292415 -309.816128)
			(xy 532.396243 -309.775378) (xy 532.496737 -309.726984) (xy 532.593332 -309.671215) (xy 532.68549 -309.608384)
			(xy 532.772695 -309.538841) (xy 532.854459 -309.462976) (xy 532.930326 -309.381213) (xy 532.99987 -309.294009)
			(xy 533.062703 -309.201852) (xy 533.118473 -309.105258) (xy 533.166869 -309.004765) (xy 533.20762 -308.900937)
			(xy 533.240498 -308.794355) (xy 533.265319 -308.685613) (xy 533.281945 -308.57532) (xy 533.290282 -308.464093)
			(xy 533.29078 -308.408324) (xy 533.29078 10.40003) (xy 533.290257 10.455798) (xy 533.28192 10.567023)
			(xy 533.265294 10.677313) (xy 533.240473 10.786053) (xy 533.207596 10.892634) (xy 533.166845 10.99646)
			(xy 533.11845 11.09695) (xy 533.06268 11.193543) (xy 532.999848 11.285698) (xy 532.930305 11.3729)
			(xy 532.85444 11.454661) (xy 532.772677 11.530525) (xy 532.685474 11.600066) (xy 532.593318 11.662896)
			(xy 532.496724 11.718664) (xy 532.396232 11.767057) (xy 532.292406 11.807806) (xy 532.185824 11.840681)
			(xy 532.077084 11.8655) (xy 531.966793 11.882123) (xy 531.855568 11.890459) (xy 531.7998 11.89101)
			(xy 475.799912 11.89101) (xy 475.744142 11.890489) (xy 475.632915 11.882155) (xy 475.522621 11.865531)
			(xy 475.413878 11.840713) (xy 475.307293 11.807837) (xy 475.203464 11.767088) (xy 475.10297 11.718694)
			(xy 475.006373 11.662926) (xy 474.914214 11.600094) (xy 474.827008 11.530552) (xy 474.745243 11.454687)
			(xy 474.669376 11.372924) (xy 474.599831 11.28572) (xy 474.536997 11.193563) (xy 474.481225 11.096967)
			(xy 474.432829 10.996475) (xy 474.392077 10.892646) (xy 474.359198 10.786063) (xy 474.334376 10.67732)
			(xy 474.31775 10.567027) (xy 474.309413 10.4558) (xy 474.308932 10.40003) (xy 474.308932 7.335466)
			(xy 526.704041 7.335466) (xy 526.704041 7.464606) (xy 526.711991 7.593501) (xy 526.727861 7.721661)
			(xy 526.75159 7.848602) (xy 526.783089 7.973841) (xy 526.822238 8.096904) (xy 526.868889 8.217323)
			(xy 526.922864 8.334642) (xy 526.983959 8.448416) (xy 527.051942 8.558213) (xy 527.126556 8.663616)
			(xy 527.207517 8.764226) (xy 527.294517 8.859661) (xy 527.387228 8.94956) (xy 527.485298 9.033581)
			(xy 527.588353 9.111405) (xy 527.696004 9.182737) (xy 527.807843 9.247307) (xy 527.923444 9.304869)
			(xy 528.042369 9.355206) (xy 528.164168 9.398126) (xy 528.288378 9.433467) (xy 528.414527 9.461094)
			(xy 528.542139 9.480903) (xy 528.670728 9.492819) (xy 528.799806 9.496796) (xy 528.928884 9.492819)
			(xy 529.057473 9.480903) (xy 529.185085 9.461094) (xy 529.311234 9.433467) (xy 529.435444 9.398126)
			(xy 529.557243 9.355206) (xy 529.676168 9.304869) (xy 529.791769 9.247307) (xy 529.903608 9.182737)
			(xy 530.011259 9.111405) (xy 530.114314 9.033581) (xy 530.212384 8.94956) (xy 530.305095 8.859661)
			(xy 530.392095 8.764226) (xy 530.473056 8.663616) (xy 530.54767 8.558213) (xy 530.615653 8.448416)
			(xy 530.676748 8.334642) (xy 530.730723 8.217323) (xy 530.777374 8.096904) (xy 530.816523 7.973841)
			(xy 530.848022 7.848602) (xy 530.871751 7.721661) (xy 530.887621 7.593501) (xy 530.895571 7.464606)
			(xy 530.896068 7.400036) (xy 530.895571 7.335466) (xy 530.887621 7.206571) (xy 530.871751 7.078411)
			(xy 530.848022 6.95147) (xy 530.816523 6.826231) (xy 530.777374 6.703168) (xy 530.730723 6.582749)
			(xy 530.676748 6.46543) (xy 530.615653 6.351656) (xy 530.54767 6.241859) (xy 530.473056 6.136456)
			(xy 530.392095 6.035846) (xy 530.305095 5.940411) (xy 530.212384 5.850512) (xy 530.114314 5.766491)
			(xy 530.011259 5.688667) (xy 529.903608 5.617335) (xy 529.791769 5.552765) (xy 529.676168 5.495203)
			(xy 529.557243 5.444866) (xy 529.435444 5.401946) (xy 529.311234 5.366605) (xy 529.185085 5.338978)
			(xy 529.057473 5.319169) (xy 528.928884 5.307253) (xy 528.799806 5.303277) (xy 528.670728 5.307253)
			(xy 528.542139 5.319169) (xy 528.414527 5.338978) (xy 528.288378 5.366605) (xy 528.164168 5.401946)
			(xy 528.042369 5.444866) (xy 527.923444 5.495203) (xy 527.807843 5.552765) (xy 527.696004 5.617335)
			(xy 527.588353 5.688667) (xy 527.485298 5.766491) (xy 527.387228 5.850512) (xy 527.294517 5.940411)
			(xy 527.207517 6.035846) (xy 527.126556 6.136456) (xy 527.051942 6.241859) (xy 526.983959 6.351656)
			(xy 526.922864 6.46543) (xy 526.868889 6.582749) (xy 526.822238 6.703168) (xy 526.783089 6.826231)
			(xy 526.75159 6.95147) (xy 526.727861 7.078411) (xy 526.711991 7.206571) (xy 526.704041 7.335466)
			(xy 474.308932 7.335466) (xy 474.308932 -12.515904) (xy 476.704141 -12.515904) (xy 476.704141 -12.386764)
			(xy 476.712091 -12.257869) (xy 476.727961 -12.129709) (xy 476.75169 -12.002768) (xy 476.783189 -11.877529)
			(xy 476.822338 -11.754466) (xy 476.868989 -11.634047) (xy 476.922964 -11.516728) (xy 476.984059 -11.402954)
			(xy 477.052042 -11.293157) (xy 477.126656 -11.187754) (xy 477.207617 -11.087144) (xy 477.294617 -10.991709)
			(xy 477.387328 -10.90181) (xy 477.485398 -10.817789) (xy 477.588453 -10.739965) (xy 477.696104 -10.668633)
			(xy 477.807943 -10.604063) (xy 477.923544 -10.546501) (xy 478.042469 -10.496164) (xy 478.164268 -10.453244)
			(xy 478.288478 -10.417903) (xy 478.414627 -10.390276) (xy 478.542239 -10.370467) (xy 478.670828 -10.358551)
			(xy 478.799906 -10.354575) (xy 478.928984 -10.358551) (xy 479.057573 -10.370467) (xy 479.185185 -10.390276)
			(xy 479.311334 -10.417903) (xy 479.435544 -10.453244) (xy 479.557343 -10.496164) (xy 479.676268 -10.546501)
			(xy 479.791869 -10.604063) (xy 479.903708 -10.668633) (xy 480.011359 -10.739965) (xy 480.114414 -10.817789)
			(xy 480.212484 -10.90181) (xy 480.305195 -10.991709) (xy 480.392195 -11.087144) (xy 480.473156 -11.187754)
			(xy 480.54777 -11.293157) (xy 480.615753 -11.402954) (xy 480.676848 -11.516728) (xy 480.730823 -11.634047)
			(xy 480.777474 -11.754466) (xy 480.816623 -11.877529) (xy 480.848122 -12.002768) (xy 480.871851 -12.129709)
			(xy 480.887721 -12.257869) (xy 480.895671 -12.386764) (xy 480.896168 -12.451334) (xy 480.895671 -12.515904)
			(xy 480.887721 -12.644799) (xy 480.871851 -12.772959) (xy 480.848122 -12.8999) (xy 480.816623 -13.025139)
			(xy 480.777474 -13.148202) (xy 480.730823 -13.268621) (xy 480.676848 -13.38594) (xy 480.615753 -13.499714)
			(xy 480.54777 -13.609511) (xy 480.473156 -13.714914) (xy 480.392195 -13.815524) (xy 480.305195 -13.910959)
			(xy 480.212484 -14.000858) (xy 480.114414 -14.084879) (xy 480.011359 -14.162703) (xy 479.903708 -14.234035)
			(xy 479.791869 -14.298605) (xy 479.676268 -14.356167) (xy 479.557343 -14.406504) (xy 479.435544 -14.449424)
			(xy 479.311334 -14.484765) (xy 479.185185 -14.512392) (xy 479.057573 -14.532201) (xy 478.928984 -14.544117)
			(xy 478.799906 -14.548094) (xy 478.670828 -14.544117) (xy 478.542239 -14.532201) (xy 478.414627 -14.512392)
			(xy 478.288478 -14.484765) (xy 478.164268 -14.449424) (xy 478.042469 -14.406504) (xy 477.923544 -14.356167)
			(xy 477.807943 -14.298605) (xy 477.696104 -14.234035) (xy 477.588453 -14.162703) (xy 477.485398 -14.084879)
			(xy 477.387328 -14.000858) (xy 477.294617 -13.910959) (xy 477.207617 -13.815524) (xy 477.126656 -13.714914)
			(xy 477.052042 -13.609511) (xy 476.984059 -13.499714) (xy 476.922964 -13.38594) (xy 476.868989 -13.268621)
			(xy 476.822338 -13.148202) (xy 476.783189 -13.025139) (xy 476.75169 -12.8999) (xy 476.727961 -12.772959)
			(xy 476.712091 -12.644799) (xy 476.704141 -12.515904) (xy 474.308932 -12.515904) (xy 474.308932 -77.67193)
			(xy 474.308458 -77.765117) (xy 474.300759 -77.951331) (xy 474.28537 -78.137067) (xy 474.262318 -78.32201)
			(xy 474.231642 -78.505841) (xy 474.193396 -78.688247) (xy 474.147643 -78.868917) (xy 474.094463 -79.047542)
			(xy 474.033945 -79.223817) (xy 473.966195 -79.397439) (xy 473.891327 -79.568113) (xy 473.809469 -79.735548)
			(xy 473.720761 -79.899456) (xy 473.625355 -80.059558) (xy 473.523414 -80.21558) (xy 473.415112 -80.367256)
			(xy 473.300633 -80.514327) (xy 473.180175 -80.65654) (xy 473.053942 -80.793654) (xy 472.988386 -80.859884)
			(xy 471.245946 -82.602324) (xy 471.208633 -82.640304) (xy 471.138899 -82.72077) (xy 471.07508 -82.806006)
			(xy 471.017504 -82.895576) (xy 470.966464 -82.989025) (xy 470.922218 -83.085876) (xy 470.884993 -83.185636)
			(xy 470.854978 -83.287798) (xy 470.832326 -83.391839) (xy 470.817153 -83.497232) (xy 470.809535 -83.603438)
			(xy 470.809066 -83.656678) (xy 470.809066 -328.137828) (xy 473.204275 -328.137828) (xy 473.204275 -328.008688)
			(xy 473.212225 -327.879793) (xy 473.228095 -327.751633) (xy 473.251824 -327.624692) (xy 473.283323 -327.499453)
			(xy 473.322472 -327.37639) (xy 473.369123 -327.255971) (xy 473.423098 -327.138652) (xy 473.484193 -327.024878)
			(xy 473.552176 -326.915081) (xy 473.62679 -326.809678) (xy 473.707751 -326.709068) (xy 473.794751 -326.613633)
			(xy 473.887462 -326.523734) (xy 473.985532 -326.439713) (xy 474.088587 -326.361889) (xy 474.196238 -326.290557)
			(xy 474.308077 -326.225987) (xy 474.423678 -326.168425) (xy 474.542603 -326.118088) (xy 474.664402 -326.075168)
			(xy 474.788612 -326.039827) (xy 474.914761 -326.0122) (xy 475.042373 -325.992391) (xy 475.170962 -325.980475)
			(xy 475.30004 -325.976499) (xy 475.429118 -325.980475) (xy 475.557707 -325.992391) (xy 475.685319 -326.0122)
			(xy 475.811468 -326.039827) (xy 475.935678 -326.075168) (xy 476.057477 -326.118088) (xy 476.176402 -326.168425)
			(xy 476.292003 -326.225987) (xy 476.403842 -326.290557) (xy 476.511493 -326.361889) (xy 476.614548 -326.439713)
			(xy 476.712618 -326.523734) (xy 476.805329 -326.613633) (xy 476.892329 -326.709068) (xy 476.97329 -326.809678)
			(xy 477.047904 -326.915081) (xy 477.115887 -327.024878) (xy 477.176982 -327.138652) (xy 477.230957 -327.255971)
			(xy 477.277608 -327.37639) (xy 477.316757 -327.499453) (xy 477.348256 -327.624692) (xy 477.371985 -327.751633)
			(xy 477.387855 -327.879793) (xy 477.395805 -328.008688) (xy 477.396302 -328.073258) (xy 477.395805 -328.137828)
			(xy 477.387855 -328.266723) (xy 477.371985 -328.394883) (xy 477.348256 -328.521824) (xy 477.316757 -328.647063)
			(xy 477.277608 -328.770126) (xy 477.230957 -328.890545) (xy 477.176982 -329.007864) (xy 477.115887 -329.121638)
			(xy 477.047904 -329.231435) (xy 476.97329 -329.336838) (xy 476.892329 -329.437448) (xy 476.805329 -329.532883)
			(xy 476.712618 -329.622782) (xy 476.614548 -329.706803) (xy 476.511493 -329.784627) (xy 476.403842 -329.855959)
			(xy 476.292003 -329.920529) (xy 476.176402 -329.978091) (xy 476.057477 -330.028428) (xy 475.935678 -330.071348)
			(xy 475.811468 -330.106689) (xy 475.685319 -330.134316) (xy 475.557707 -330.154125) (xy 475.429118 -330.166041)
			(xy 475.30004 -330.170018) (xy 475.170962 -330.166041) (xy 475.042373 -330.154125) (xy 474.914761 -330.134316)
			(xy 474.788612 -330.106689) (xy 474.664402 -330.071348) (xy 474.542603 -330.028428) (xy 474.423678 -329.978091)
			(xy 474.308077 -329.920529) (xy 474.196238 -329.855959) (xy 474.088587 -329.784627) (xy 473.985532 -329.706803)
			(xy 473.887462 -329.622782) (xy 473.794751 -329.532883) (xy 473.707751 -329.437448) (xy 473.62679 -329.336838)
			(xy 473.552176 -329.231435) (xy 473.484193 -329.121638) (xy 473.423098 -329.007864) (xy 473.369123 -328.890545)
			(xy 473.322472 -328.770126) (xy 473.283323 -328.647063) (xy 473.251824 -328.521824) (xy 473.228095 -328.394883)
			(xy 473.212225 -328.266723) (xy 473.204275 -328.137828) (xy 470.809066 -328.137828) (xy 470.809066 -404.871936)
			(xy 470.808592 -404.965123) (xy 470.800892 -405.151337) (xy 470.785503 -405.337074) (xy 470.762451 -405.522016)
			(xy 470.731776 -405.705847) (xy 470.693529 -405.888254) (xy 470.647776 -406.068924) (xy 470.594596 -406.247549)
			(xy 470.534079 -406.423823) (xy 470.466329 -406.597446) (xy 470.391461 -406.76812) (xy 470.309603 -406.935555)
			(xy 470.220896 -407.099463) (xy 470.12549 -407.259566) (xy 470.02355 -407.415588) (xy 469.915248 -407.567265)
			(xy 469.80077 -407.714335) (xy 469.680312 -407.856549) (xy 469.554079 -407.993664) (xy 469.48852 -408.05989)
			(xy 468.245698 -409.302712) (xy 468.208406 -409.340689) (xy 468.138712 -409.421147) (xy 468.074932 -409.506369)
			(xy 468.017391 -409.595922) (xy 467.966382 -409.68935) (xy 467.922165 -409.786178) (xy 467.884964 -409.885911)
			(xy 467.85497 -409.988044) (xy 467.832334 -410.092055) (xy 467.817172 -410.197416) (xy 467.809562 -410.303589)
			(xy 467.809072 -410.356812) (xy 467.809072 -439.989976) (xy 467.809593 -440.045746) (xy 467.817926 -440.156975)
			(xy 467.834548 -440.26727) (xy 467.859367 -440.376014) (xy 467.892242 -440.4826) (xy 467.93299 -440.586431)
			(xy 467.981383 -440.686926) (xy 468.037152 -440.783525) (xy 468.099983 -440.875685) (xy 468.169525 -440.962893)
			(xy 468.24539 -441.044659) (xy 468.327153 -441.120528) (xy 468.414357 -441.190075) (xy 468.506514 -441.25291)
			(xy 468.60311 -441.308683) (xy 468.703603 -441.357081) (xy 468.807432 -441.397835) (xy 468.914016 -441.430715)
			(xy 469.022759 -441.455538) (xy 469.133053 -441.472166) (xy 469.244282 -441.480505) (xy 469.300052 -441.480956)
			(xy 471.79992 -441.480956) (xy 471.870302 -441.48145) (xy 472.010845 -441.489344) (xy 472.150724 -441.505105)
			(xy 472.2895 -441.528685) (xy 472.426735 -441.560009) (xy 472.561998 -441.598978) (xy 472.694863 -441.64547)
			(xy 472.824912 -441.699339) (xy 472.951736 -441.760414) (xy 473.074936 -441.828505) (xy 473.194125 -441.903396)
			(xy 473.308927 -441.984852) (xy 473.418981 -442.072617) (xy 473.523941 -442.166415) (xy 473.623477 -442.26595)
			(xy 473.717275 -442.37091) (xy 473.80504 -442.480964) (xy 473.886497 -442.595765) (xy 473.961389 -442.714953)
			(xy 474.02948 -442.838153) (xy 474.090556 -442.964977) (xy 474.144426 -443.095026) (xy 474.190918 -443.227891)
			(xy 474.229888 -443.363154) (xy 474.261212 -443.500389) (xy 474.284793 -443.639164) (xy 474.300555 -443.779043)
			(xy 474.308449 -443.919586) (xy 474.308932 -443.989968) (xy 474.308932 -458.092864) (xy 526.704041 -458.092864)
			(xy 526.704041 -457.963724) (xy 526.711991 -457.834829) (xy 526.727861 -457.706669) (xy 526.75159 -457.579728)
			(xy 526.783089 -457.454489) (xy 526.822238 -457.331426) (xy 526.868889 -457.211007) (xy 526.922864 -457.093688)
			(xy 526.983959 -456.979914) (xy 527.051942 -456.870117) (xy 527.126556 -456.764714) (xy 527.207517 -456.664104)
			(xy 527.294517 -456.568669) (xy 527.387228 -456.47877) (xy 527.485298 -456.394749) (xy 527.588353 -456.316925)
			(xy 527.696004 -456.245593) (xy 527.807843 -456.181023) (xy 527.923444 -456.123461) (xy 528.042369 -456.073124)
			(xy 528.164168 -456.030204) (xy 528.288378 -455.994863) (xy 528.414527 -455.967236) (xy 528.542139 -455.947427)
			(xy 528.670728 -455.935511) (xy 528.799806 -455.931535) (xy 528.928884 -455.935511) (xy 529.057473 -455.947427)
			(xy 529.185085 -455.967236) (xy 529.311234 -455.994863) (xy 529.435444 -456.030204) (xy 529.557243 -456.073124)
			(xy 529.676168 -456.123461) (xy 529.791769 -456.181023) (xy 529.903608 -456.245593) (xy 530.011259 -456.316925)
			(xy 530.114314 -456.394749) (xy 530.212384 -456.47877) (xy 530.305095 -456.568669) (xy 530.392095 -456.664104)
			(xy 530.473056 -456.764714) (xy 530.54767 -456.870117) (xy 530.615653 -456.979914) (xy 530.676748 -457.093688)
			(xy 530.730723 -457.211007) (xy 530.777374 -457.331426) (xy 530.816523 -457.454489) (xy 530.848022 -457.579728)
			(xy 530.871751 -457.706669) (xy 530.887621 -457.834829) (xy 530.895571 -457.963724) (xy 530.896068 -458.028294)
			(xy 530.895571 -458.092864) (xy 530.887621 -458.221759) (xy 530.871751 -458.349919) (xy 530.848022 -458.47686)
			(xy 530.816523 -458.602099) (xy 530.777374 -458.725162) (xy 530.730723 -458.845581) (xy 530.676748 -458.9629)
			(xy 530.615653 -459.076674) (xy 530.54767 -459.186471) (xy 530.473056 -459.291874) (xy 530.392095 -459.392484)
			(xy 530.305095 -459.487919) (xy 530.212384 -459.577818) (xy 530.114314 -459.661839) (xy 530.011259 -459.739663)
			(xy 529.903608 -459.810995) (xy 529.791769 -459.875565) (xy 529.676168 -459.933127) (xy 529.557243 -459.983464)
			(xy 529.435444 -460.026384) (xy 529.311234 -460.061725) (xy 529.185085 -460.089352) (xy 529.057473 -460.109161)
			(xy 528.928884 -460.121077) (xy 528.799806 -460.125054) (xy 528.670728 -460.121077) (xy 528.542139 -460.109161)
			(xy 528.414527 -460.089352) (xy 528.288378 -460.061725) (xy 528.164168 -460.026384) (xy 528.042369 -459.983464)
			(xy 527.923444 -459.933127) (xy 527.807843 -459.875565) (xy 527.696004 -459.810995) (xy 527.588353 -459.739663)
			(xy 527.485298 -459.661839) (xy 527.387228 -459.577818) (xy 527.294517 -459.487919) (xy 527.207517 -459.392484)
			(xy 527.126556 -459.291874) (xy 527.051942 -459.186471) (xy 526.983959 -459.076674) (xy 526.922864 -458.9629)
			(xy 526.868889 -458.845581) (xy 526.822238 -458.725162) (xy 526.783089 -458.602099) (xy 526.75159 -458.47686)
			(xy 526.727861 -458.349919) (xy 526.711991 -458.221759) (xy 526.704041 -458.092864) (xy 474.308932 -458.092864)
			(xy 474.308932 -461.028288) (xy 474.30944 -461.084058) (xy 474.317775 -461.195285) (xy 474.334398 -461.305579)
			(xy 474.359217 -461.414322) (xy 474.392093 -461.520906) (xy 474.432843 -461.624735) (xy 474.481238 -461.725228)
			(xy 474.537007 -461.821824) (xy 474.599839 -461.913982) (xy 474.669383 -462.001187) (xy 474.745248 -462.082952)
			(xy 474.827013 -462.158817) (xy 474.914218 -462.228361) (xy 475.006376 -462.291193) (xy 475.102972 -462.346962)
			(xy 475.203465 -462.395357) (xy 475.307294 -462.436107) (xy 475.413878 -462.468983) (xy 475.522621 -462.493802)
			(xy 475.632915 -462.510425) (xy 475.744142 -462.51876) (xy 475.799912 -462.519268)
		)
		(stroke
			(width 0)
			(type solid)
		)
		(fill yes)
		(layer "In1.Cu")
		(net "T1_GND")
	)
	(gr_poly
		(pts
			(xy 255.800098 -33.611058) (xy 255.832245 -33.610555) (xy 255.89599 -33.602163) (xy 255.958093 -33.585522)
			(xy 256.017493 -33.560917) (xy 256.073173 -33.528769) (xy 256.124181 -33.489628) (xy 256.169643 -33.444164)
			(xy 256.208781 -33.393155) (xy 256.240927 -33.337473) (xy 256.265529 -33.278072) (xy 256.282167 -33.215968)
			(xy 256.290557 -33.152223) (xy 256.29108 -33.120076) (xy 256.29108 -11.780012) (xy 256.291564 -11.709629)
			(xy 256.299456 -11.569085) (xy 256.315217 -11.429205) (xy 256.338795 -11.290428) (xy 256.370118 -11.153191)
			(xy 256.409086 -11.017927) (xy 256.455577 -10.885061) (xy 256.509445 -10.75501) (xy 256.570521 -10.628184)
			(xy 256.638611 -10.504983) (xy 256.713502 -10.385793) (xy 256.794959 -10.27099) (xy 256.882724 -10.160934)
			(xy 256.976523 -10.055973) (xy 257.076059 -9.956436) (xy 257.181019 -9.862637) (xy 257.291074 -9.774871)
			(xy 257.405876 -9.693414) (xy 257.525065 -9.618521) (xy 257.648266 -9.55043) (xy 257.775092 -9.489354)
			(xy 257.905142 -9.435484) (xy 258.038008 -9.388992) (xy 258.173272 -9.350023) (xy 258.310508 -9.318699)
			(xy 258.449285 -9.295119) (xy 258.589165 -9.279358) (xy 258.729709 -9.271465) (xy 258.800092 -9.271)
			(xy 383.601976 -9.271) (xy 383.657746 -9.270492) (xy 383.768975 -9.262159) (xy 383.87927 -9.245536)
			(xy 383.988015 -9.220718) (xy 384.094601 -9.187842) (xy 384.198432 -9.147093) (xy 384.298927 -9.098699)
			(xy 384.395525 -9.04293) (xy 384.487685 -8.980099) (xy 384.574892 -8.910555) (xy 384.656659 -8.83469)
			(xy 384.732527 -8.752926) (xy 384.802073 -8.665721) (xy 384.864907 -8.573562) (xy 384.920679 -8.476966)
			(xy 384.969076 -8.376472) (xy 385.009828 -8.272642) (xy 385.042706 -8.166058) (xy 385.067528 -8.057314)
			(xy 385.084154 -7.947019) (xy 385.092491 -7.83579) (xy 385.092956 -7.78002) (xy 385.092956 0.40005)
			(xy 385.093451 0.470432) (xy 385.101346 0.610973) (xy 385.117109 0.750851) (xy 385.14069 0.889625)
			(xy 385.172015 1.026859) (xy 385.210985 1.16212) (xy 385.257478 1.294984) (xy 385.311348 1.425032)
			(xy 385.372424 1.551855) (xy 385.440515 1.675053) (xy 385.515407 1.79424) (xy 385.596863 1.909041)
			(xy 385.684628 2.019094) (xy 385.778426 2.124052) (xy 385.877961 2.223587) (xy 385.98292 2.317383)
			(xy 386.092974 2.405148) (xy 386.207775 2.486603) (xy 386.326962 2.561494) (xy 386.450161 2.629584)
			(xy 386.576985 2.69066) (xy 386.707033 2.744528) (xy 386.839897 2.79102) (xy 386.975158 2.829989)
			(xy 387.112392 2.861313) (xy 387.251166 2.884893) (xy 387.391045 2.900655) (xy 387.531586 2.908549)
			(xy 387.601968 2.909062) (xy 456.202034 2.909062) (xy 456.272416 2.908567) (xy 456.412959 2.900673)
			(xy 456.552838 2.884911) (xy 456.691613 2.861331) (xy 456.828848 2.830006) (xy 456.96411 2.791037)
			(xy 457.096975 2.744544) (xy 457.227024 2.690676) (xy 457.353848 2.6296) (xy 457.477048 2.561509)
			(xy 457.596236 2.486618) (xy 457.711038 2.405161) (xy 457.821092 2.317396) (xy 457.926052 2.223599)
			(xy 458.025588 2.124064) (xy 458.119386 2.019104) (xy 458.207152 1.909051) (xy 458.288609 1.79425)
			(xy 458.363501 1.675062) (xy 458.431592 1.551862) (xy 458.492669 1.425039) (xy 458.546539 1.29499)
			(xy 458.593032 1.162126) (xy 458.632002 1.026863) (xy 458.663327 0.889629) (xy 458.686909 0.750854)
			(xy 458.702672 0.610975) (xy 458.710567 0.470432) (xy 458.711046 0.40005) (xy 458.711046 -4.844596)
			(xy 464.704165 -4.844596) (xy 464.704165 -4.715456) (xy 464.712115 -4.586561) (xy 464.727985 -4.458401)
			(xy 464.751714 -4.33146) (xy 464.783213 -4.206221) (xy 464.822362 -4.083158) (xy 464.869013 -3.962739)
			(xy 464.922988 -3.84542) (xy 464.984083 -3.731646) (xy 465.052066 -3.621849) (xy 465.12668 -3.516446)
			(xy 465.207641 -3.415836) (xy 465.294641 -3.320401) (xy 465.387352 -3.230502) (xy 465.485422 -3.146481)
			(xy 465.588477 -3.068657) (xy 465.696128 -2.997325) (xy 465.807967 -2.932755) (xy 465.923568 -2.875193)
			(xy 466.042493 -2.824856) (xy 466.164292 -2.781936) (xy 466.288502 -2.746595) (xy 466.414651 -2.718968)
			(xy 466.542263 -2.699159) (xy 466.670852 -2.687243) (xy 466.79993 -2.683267) (xy 466.929008 -2.687243)
			(xy 467.057597 -2.699159) (xy 467.185209 -2.718968) (xy 467.311358 -2.746595) (xy 467.435568 -2.781936)
			(xy 467.557367 -2.824856) (xy 467.676292 -2.875193) (xy 467.791893 -2.932755) (xy 467.903732 -2.997325)
			(xy 468.011383 -3.068657) (xy 468.114438 -3.146481) (xy 468.212508 -3.230502) (xy 468.305219 -3.320401)
			(xy 468.392219 -3.415836) (xy 468.47318 -3.516446) (xy 468.547794 -3.621849) (xy 468.615777 -3.731646)
			(xy 468.676872 -3.84542) (xy 468.730847 -3.962739) (xy 468.777498 -4.083158) (xy 468.816647 -4.206221)
			(xy 468.848146 -4.33146) (xy 468.871875 -4.458401) (xy 468.887745 -4.586561) (xy 468.895695 -4.715456)
			(xy 468.896192 -4.780026) (xy 468.895695 -4.844596) (xy 468.887745 -4.973491) (xy 468.871875 -5.101651)
			(xy 468.848146 -5.228592) (xy 468.816647 -5.353831) (xy 468.777498 -5.476894) (xy 468.730847 -5.597313)
			(xy 468.676872 -5.714632) (xy 468.615777 -5.828406) (xy 468.547794 -5.938203) (xy 468.47318 -6.043606)
			(xy 468.392219 -6.144216) (xy 468.305219 -6.239651) (xy 468.212508 -6.32955) (xy 468.114438 -6.413571)
			(xy 468.011383 -6.491395) (xy 467.903732 -6.562727) (xy 467.791893 -6.627297) (xy 467.676292 -6.684859)
			(xy 467.557367 -6.735196) (xy 467.435568 -6.778116) (xy 467.311358 -6.813457) (xy 467.185209 -6.841084)
			(xy 467.057597 -6.860893) (xy 466.929008 -6.872809) (xy 466.79993 -6.876786) (xy 466.670852 -6.872809)
			(xy 466.542263 -6.860893) (xy 466.414651 -6.841084) (xy 466.288502 -6.813457) (xy 466.164292 -6.778116)
			(xy 466.042493 -6.735196) (xy 465.923568 -6.684859) (xy 465.807967 -6.627297) (xy 465.696128 -6.562727)
			(xy 465.588477 -6.491395) (xy 465.485422 -6.413571) (xy 465.387352 -6.32955) (xy 465.294641 -6.239651)
			(xy 465.207641 -6.144216) (xy 465.12668 -6.043606) (xy 465.052066 -5.938203) (xy 464.984083 -5.828406)
			(xy 464.922988 -5.714632) (xy 464.869013 -5.597313) (xy 464.822362 -5.476894) (xy 464.783213 -5.353831)
			(xy 464.751714 -5.228592) (xy 464.727985 -5.101651) (xy 464.712115 -4.973491) (xy 464.704165 -4.844596)
			(xy 458.711046 -4.844596) (xy 458.711046 -7.78002) (xy 458.711555 -7.835789) (xy 458.719892 -7.947014)
			(xy 458.736517 -8.057305) (xy 458.761338 -8.166046) (xy 458.794216 -8.272628) (xy 458.834967 -8.376454)
			(xy 458.883362 -8.476945) (xy 458.939132 -8.573538) (xy 459.001965 -8.665694) (xy 459.071509 -8.752896)
			(xy 459.147375 -8.834658) (xy 459.229138 -8.910521) (xy 459.316343 -8.980062) (xy 459.4085 -9.042892)
			(xy 459.505096 -9.098659) (xy 459.605588 -9.147052) (xy 459.709416 -9.187799) (xy 459.815999 -9.220674)
			(xy 459.92474 -9.245491) (xy 460.035032 -9.262113) (xy 460.146257 -9.270446) (xy 460.202026 -9.271)
			(xy 469.799924 -9.271) (xy 469.855693 -9.270478) (xy 469.966918 -9.262141) (xy 470.07721 -9.245516)
			(xy 470.18595 -9.220695) (xy 470.292532 -9.187817) (xy 470.396359 -9.147067) (xy 470.49685 -9.098672)
			(xy 470.593444 -9.042903) (xy 470.685601 -8.980071) (xy 470.772804 -8.910528) (xy 470.854566 -8.834664)
			(xy 470.930431 -8.752901) (xy 470.999974 -8.665697) (xy 471.062805 -8.573541) (xy 471.118574 -8.476947)
			(xy 471.166969 -8.376455) (xy 471.207719 -8.272628) (xy 471.240596 -8.166046) (xy 471.265416 -8.057306)
			(xy 471.282041 -7.947014) (xy 471.290378 -7.835789) (xy 471.290904 -7.78002) (xy 471.290904 10.40003)
			(xy 471.290381 10.455799) (xy 471.282044 10.567024) (xy 471.265419 10.677315) (xy 471.240598 10.786055)
			(xy 471.20772 10.892637) (xy 471.16697 10.996464) (xy 471.118574 11.096955) (xy 471.062805 11.193548)
			(xy 470.999973 11.285705) (xy 470.930431 11.372908) (xy 470.854566 11.45467) (xy 470.772803 11.530534)
			(xy 470.6856 11.600077) (xy 470.593443 11.662908) (xy 470.49685 11.718677) (xy 470.396358 11.767072)
			(xy 470.292531 11.807822) (xy 470.18595 11.840699) (xy 470.077209 11.86552) (xy 469.966918 11.882145)
			(xy 469.855693 11.890482) (xy 469.799924 11.89101) (xy 1.999996 11.89101) (xy 1.944227 11.890488)
			(xy 1.833001 11.882153) (xy 1.722709 11.865529) (xy 1.613968 11.840709) (xy 1.507385 11.807832) (xy 1.403558 11.767083)
			(xy 1.303066 11.718688) (xy 1.206471 11.662919) (xy 1.114314 11.600087) (xy 1.027111 11.530545) (xy 0.945348 11.454679)
			(xy 0.869483 11.372916) (xy 0.79994 11.285712) (xy 0.737109 11.193555) (xy 0.68134 11.096961) (xy 0.632946 10.996469)
			(xy 0.592196 10.892641) (xy 0.55932 10.786058) (xy 0.534501 10.677317) (xy 0.517877 10.567025) (xy 0.509541 10.455799)
			(xy 0.509016 10.40003) (xy 0.509016 9.916973) (xy 385.651997 9.916973) (xy 385.651997 10.002723)
			(xy 385.659909 10.088106) (xy 385.675665 10.172396) (xy 385.699132 10.254872) (xy 385.730108 10.334831)
			(xy 385.76833 10.411591) (xy 385.813471 10.484497) (xy 385.865147 10.552926) (xy 385.922916 10.616296)
			(xy 385.986286 10.674065) (xy 386.054715 10.725741) (xy 386.127621 10.770882) (xy 386.204381 10.809104)
			(xy 386.28434 10.84008) (xy 386.366816 10.863547) (xy 386.451106 10.879303) (xy 386.536489 10.887215)
			(xy 386.622239 10.887215) (xy 386.707622 10.879303) (xy 386.791912 10.863547) (xy 386.874388 10.84008)
			(xy 386.954347 10.809104) (xy 387.031107 10.770882) (xy 387.104013 10.725741) (xy 387.172442 10.674065)
			(xy 387.235812 10.616296) (xy 387.293581 10.552926) (xy 387.345257 10.484497) (xy 387.390398 10.411591)
			(xy 387.42862 10.334831) (xy 387.459596 10.254872) (xy 387.483063 10.172396) (xy 387.498819 10.088106)
			(xy 387.506731 10.002723) (xy 387.507226 9.959848) (xy 387.506731 9.916973) (xy 392.001997 9.916973)
			(xy 392.001997 10.002723) (xy 392.009909 10.088106) (xy 392.025665 10.172396) (xy 392.049132 10.254872)
			(xy 392.080108 10.334831) (xy 392.11833 10.411591) (xy 392.163471 10.484497) (xy 392.215147 10.552926)
			(xy 392.272916 10.616296) (xy 392.336286 10.674065) (xy 392.404715 10.725741) (xy 392.477621 10.770882)
			(xy 392.554381 10.809104) (xy 392.63434 10.84008) (xy 392.716816 10.863547) (xy 392.801106 10.879303)
			(xy 392.886489 10.887215) (xy 392.972239 10.887215) (xy 393.057622 10.879303) (xy 393.141912 10.863547)
			(xy 393.224388 10.84008) (xy 393.304347 10.809104) (xy 393.381107 10.770882) (xy 393.454013 10.725741)
			(xy 393.522442 10.674065) (xy 393.585812 10.616296) (xy 393.643581 10.552926) (xy 393.695257 10.484497)
			(xy 393.740398 10.411591) (xy 393.77862 10.334831) (xy 393.809596 10.254872) (xy 393.833063 10.172396)
			(xy 393.848819 10.088106) (xy 393.856731 10.002723) (xy 393.857226 9.959848) (xy 393.856731 9.916973)
			(xy 436.390783 9.916973) (xy 436.390783 10.002723) (xy 436.398695 10.088106) (xy 436.414451 10.172396)
			(xy 436.437918 10.254872) (xy 436.468894 10.334831) (xy 436.507116 10.411591) (xy 436.552257 10.484497)
			(xy 436.603933 10.552926) (xy 436.661702 10.616296) (xy 436.725072 10.674065) (xy 436.793501 10.725741)
			(xy 436.866407 10.770882) (xy 436.943167 10.809104) (xy 437.023126 10.84008) (xy 437.105602 10.863547)
			(xy 437.189892 10.879303) (xy 437.275275 10.887215) (xy 437.361025 10.887215) (xy 437.446408 10.879303)
			(xy 437.530698 10.863547) (xy 437.613174 10.84008) (xy 437.693133 10.809104) (xy 437.769893 10.770882)
			(xy 437.842799 10.725741) (xy 437.911228 10.674065) (xy 437.974598 10.616296) (xy 438.032367 10.552926)
			(xy 438.084043 10.484497) (xy 438.129184 10.411591) (xy 438.167406 10.334831) (xy 438.198382 10.254872)
			(xy 438.221849 10.172396) (xy 438.237605 10.088106) (xy 438.245517 10.002723) (xy 438.246012 9.959848)
			(xy 438.245517 9.916973) (xy 442.740783 9.916973) (xy 442.740783 10.002723) (xy 442.748695 10.088106)
			(xy 442.764451 10.172396) (xy 442.787918 10.254872) (xy 442.818894 10.334831) (xy 442.857116 10.411591)
			(xy 442.902257 10.484497) (xy 442.953933 10.552926) (xy 443.011702 10.616296) (xy 443.075072 10.674065)
			(xy 443.143501 10.725741) (xy 443.216407 10.770882) (xy 443.293167 10.809104) (xy 443.373126 10.84008)
			(xy 443.455602 10.863547) (xy 443.539892 10.879303) (xy 443.625275 10.887215) (xy 443.711025 10.887215)
			(xy 443.796408 10.879303) (xy 443.880698 10.863547) (xy 443.963174 10.84008) (xy 444.043133 10.809104)
			(xy 444.119893 10.770882) (xy 444.192799 10.725741) (xy 444.261228 10.674065) (xy 444.324598 10.616296)
			(xy 444.382367 10.552926) (xy 444.434043 10.484497) (xy 444.479184 10.411591) (xy 444.517406 10.334831)
			(xy 444.548382 10.254872) (xy 444.571849 10.172396) (xy 444.587605 10.088106) (xy 444.595517 10.002723)
			(xy 444.596012 9.959848) (xy 444.595517 9.916973) (xy 444.587605 9.83159) (xy 444.571849 9.7473)
			(xy 444.548382 9.664824) (xy 444.517406 9.584865) (xy 444.479184 9.508105) (xy 444.434043 9.435199)
			(xy 444.382367 9.36677) (xy 444.324598 9.3034) (xy 444.261228 9.245631) (xy 444.192799 9.193955)
			(xy 444.119893 9.148814) (xy 444.043133 9.110592) (xy 443.963174 9.079616) (xy 443.880698 9.056149)
			(xy 443.796408 9.040393) (xy 443.711025 9.032481) (xy 443.625275 9.032481) (xy 443.539892 9.040393)
			(xy 443.455602 9.056149) (xy 443.373126 9.079616) (xy 443.293167 9.110592) (xy 443.216407 9.148814)
			(xy 443.143501 9.193955) (xy 443.075072 9.245631) (xy 443.011702 9.3034) (xy 442.953933 9.36677)
			(xy 442.902257 9.435199) (xy 442.857116 9.508105) (xy 442.818894 9.584865) (xy 442.787918 9.664824)
			(xy 442.764451 9.7473) (xy 442.748695 9.83159) (xy 442.740783 9.916973) (xy 438.245517 9.916973)
			(xy 438.237605 9.83159) (xy 438.221849 9.7473) (xy 438.198382 9.664824) (xy 438.167406 9.584865)
			(xy 438.129184 9.508105) (xy 438.084043 9.435199) (xy 438.032367 9.36677) (xy 437.974598 9.3034)
			(xy 437.911228 9.245631) (xy 437.842799 9.193955) (xy 437.769893 9.148814) (xy 437.693133 9.110592)
			(xy 437.613174 9.079616) (xy 437.530698 9.056149) (xy 437.446408 9.040393) (xy 437.361025 9.032481)
			(xy 437.275275 9.032481) (xy 437.189892 9.040393) (xy 437.105602 9.056149) (xy 437.023126 9.079616)
			(xy 436.943167 9.110592) (xy 436.866407 9.148814) (xy 436.793501 9.193955) (xy 436.725072 9.245631)
			(xy 436.661702 9.3034) (xy 436.603933 9.36677) (xy 436.552257 9.435199) (xy 436.507116 9.508105)
			(xy 436.468894 9.584865) (xy 436.437918 9.664824) (xy 436.414451 9.7473) (xy 436.398695 9.83159)
			(xy 436.390783 9.916973) (xy 393.856731 9.916973) (xy 393.848819 9.83159) (xy 393.833063 9.7473)
			(xy 393.809596 9.664824) (xy 393.77862 9.584865) (xy 393.740398 9.508105) (xy 393.695257 9.435199)
			(xy 393.643581 9.36677) (xy 393.585812 9.3034) (xy 393.522442 9.245631) (xy 393.454013 9.193955)
			(xy 393.381107 9.148814) (xy 393.304347 9.110592) (xy 393.224388 9.079616) (xy 393.141912 9.056149)
			(xy 393.057622 9.040393) (xy 392.972239 9.032481) (xy 392.886489 9.032481) (xy 392.801106 9.040393)
			(xy 392.716816 9.056149) (xy 392.63434 9.079616) (xy 392.554381 9.110592) (xy 392.477621 9.148814)
			(xy 392.404715 9.193955) (xy 392.336286 9.245631) (xy 392.272916 9.3034) (xy 392.215147 9.36677)
			(xy 392.163471 9.435199) (xy 392.11833 9.508105) (xy 392.080108 9.584865) (xy 392.049132 9.664824)
			(xy 392.025665 9.7473) (xy 392.009909 9.83159) (xy 392.001997 9.916973) (xy 387.506731 9.916973)
			(xy 387.498819 9.83159) (xy 387.483063 9.7473) (xy 387.459596 9.664824) (xy 387.42862 9.584865) (xy 387.390398 9.508105)
			(xy 387.345257 9.435199) (xy 387.293581 9.36677) (xy 387.235812 9.3034) (xy 387.172442 9.245631)
			(xy 387.104013 9.193955) (xy 387.031107 9.148814) (xy 386.954347 9.110592) (xy 386.874388 9.079616)
			(xy 386.791912 9.056149) (xy 386.707622 9.040393) (xy 386.622239 9.032481) (xy 386.536489 9.032481)
			(xy 386.451106 9.040393) (xy 386.366816 9.056149) (xy 386.28434 9.079616) (xy 386.204381 9.110592)
			(xy 386.127621 9.148814) (xy 386.054715 9.193955) (xy 385.986286 9.245631) (xy 385.922916 9.3034)
			(xy 385.865147 9.36677) (xy 385.813471 9.435199) (xy 385.76833 9.508105) (xy 385.730108 9.584865)
			(xy 385.699132 9.664824) (xy 385.675665 9.7473) (xy 385.659909 9.83159) (xy 385.651997 9.916973)
			(xy 0.509016 9.916973) (xy 0.509016 7.335466) (xy 2.904225 7.335466) (xy 2.904225 7.464606) (xy 2.912175 7.593501)
			(xy 2.928045 7.721661) (xy 2.951774 7.848602) (xy 2.983273 7.973841) (xy 3.022422 8.096904) (xy 3.069073 8.217323)
			(xy 3.123048 8.334642) (xy 3.184143 8.448416) (xy 3.252126 8.558213) (xy 3.32674 8.663616) (xy 3.407701 8.764226)
			(xy 3.494701 8.859661) (xy 3.587412 8.94956) (xy 3.685482 9.033581) (xy 3.788537 9.111405) (xy 3.896188 9.182737)
			(xy 4.008027 9.247307) (xy 4.123628 9.304869) (xy 4.242553 9.355206) (xy 4.364352 9.398126) (xy 4.488562 9.433467)
			(xy 4.614711 9.461094) (xy 4.742323 9.480903) (xy 4.870912 9.492819) (xy 4.99999 9.496796) (xy 5.129068 9.492819)
			(xy 5.257657 9.480903) (xy 5.385269 9.461094) (xy 5.511418 9.433467) (xy 5.635628 9.398126) (xy 5.757427 9.355206)
			(xy 5.876352 9.304869) (xy 5.991953 9.247307) (xy 6.103792 9.182737) (xy 6.211443 9.111405) (xy 6.314498 9.033581)
			(xy 6.412568 8.94956) (xy 6.505279 8.859661) (xy 6.51416 8.849919) (xy 208.661241 8.849919) (xy 208.661241 8.935669)
			(xy 208.669153 9.021052) (xy 208.684909 9.105342) (xy 208.708376 9.187818) (xy 208.739352 9.267777)
			(xy 208.777574 9.344537) (xy 208.822715 9.417443) (xy 208.874391 9.485872) (xy 208.93216 9.549242)
			(xy 208.99553 9.607011) (xy 209.063959 9.658687) (xy 209.136865 9.703828) (xy 209.213625 9.74205)
			(xy 209.293584 9.773026) (xy 209.37606 9.796493) (xy 209.46035 9.812249) (xy 209.545733 9.820161)
			(xy 209.631483 9.820161) (xy 209.716866 9.812249) (xy 209.801156 9.796493) (xy 209.883632 9.773026)
			(xy 209.963591 9.74205) (xy 210.040351 9.703828) (xy 210.113257 9.658687) (xy 210.181686 9.607011)
			(xy 210.245056 9.549242) (xy 210.302825 9.485872) (xy 210.354501 9.417443) (xy 210.399642 9.344537)
			(xy 210.437864 9.267777) (xy 210.46884 9.187818) (xy 210.492307 9.105342) (xy 210.508063 9.021052)
			(xy 210.515975 8.935669) (xy 210.51647 8.892794) (xy 210.515975 8.849919) (xy 215.011241 8.849919)
			(xy 215.011241 8.935669) (xy 215.019153 9.021052) (xy 215.034909 9.105342) (xy 215.058376 9.187818)
			(xy 215.089352 9.267777) (xy 215.127574 9.344537) (xy 215.172715 9.417443) (xy 215.224391 9.485872)
			(xy 215.28216 9.549242) (xy 215.34553 9.607011) (xy 215.413959 9.658687) (xy 215.486865 9.703828)
			(xy 215.563625 9.74205) (xy 215.643584 9.773026) (xy 215.72606 9.796493) (xy 215.81035 9.812249)
			(xy 215.895733 9.820161) (xy 215.981483 9.820161) (xy 216.066866 9.812249) (xy 216.151156 9.796493)
			(xy 216.233632 9.773026) (xy 216.313591 9.74205) (xy 216.390351 9.703828) (xy 216.463257 9.658687)
			(xy 216.531686 9.607011) (xy 216.595056 9.549242) (xy 216.652825 9.485872) (xy 216.704501 9.417443)
			(xy 216.749642 9.344537) (xy 216.787864 9.267777) (xy 216.81884 9.187818) (xy 216.842307 9.105342)
			(xy 216.858063 9.021052) (xy 216.865975 8.935669) (xy 216.86647 8.892794) (xy 216.865975 8.849919)
			(xy 296.143921 8.849919) (xy 296.143921 8.935669) (xy 296.151833 9.021052) (xy 296.167589 9.105342)
			(xy 296.191056 9.187818) (xy 296.222032 9.267777) (xy 296.260254 9.344537) (xy 296.305395 9.417443)
			(xy 296.357071 9.485872) (xy 296.41484 9.549242) (xy 296.47821 9.607011) (xy 296.546639 9.658687)
			(xy 296.619545 9.703828) (xy 296.696305 9.74205) (xy 296.776264 9.773026) (xy 296.85874 9.796493)
			(xy 296.94303 9.812249) (xy 297.028413 9.820161) (xy 297.114163 9.820161) (xy 297.199546 9.812249)
			(xy 297.283836 9.796493) (xy 297.366312 9.773026) (xy 297.446271 9.74205) (xy 297.523031 9.703828)
			(xy 297.595937 9.658687) (xy 297.664366 9.607011) (xy 297.727736 9.549242) (xy 297.785505 9.485872)
			(xy 297.837181 9.417443) (xy 297.882322 9.344537) (xy 297.920544 9.267777) (xy 297.95152 9.187818)
			(xy 297.974987 9.105342) (xy 297.990743 9.021052) (xy 297.998655 8.935669) (xy 297.99915 8.892794)
			(xy 297.998655 8.849919) (xy 302.493921 8.849919) (xy 302.493921 8.935669) (xy 302.501833 9.021052)
			(xy 302.517589 9.105342) (xy 302.541056 9.187818) (xy 302.572032 9.267777) (xy 302.610254 9.344537)
			(xy 302.655395 9.417443) (xy 302.707071 9.485872) (xy 302.76484 9.549242) (xy 302.82821 9.607011)
			(xy 302.896639 9.658687) (xy 302.969545 9.703828) (xy 303.046305 9.74205) (xy 303.126264 9.773026)
			(xy 303.20874 9.796493) (xy 303.29303 9.812249) (xy 303.378413 9.820161) (xy 303.464163 9.820161)
			(xy 303.549546 9.812249) (xy 303.633836 9.796493) (xy 303.716312 9.773026) (xy 303.796271 9.74205)
			(xy 303.873031 9.703828) (xy 303.945937 9.658687) (xy 304.014366 9.607011) (xy 304.077736 9.549242)
			(xy 304.135505 9.485872) (xy 304.187181 9.417443) (xy 304.232322 9.344537) (xy 304.270544 9.267777)
			(xy 304.30152 9.187818) (xy 304.324987 9.105342) (xy 304.340743 9.021052) (xy 304.348655 8.935669)
			(xy 304.34915 8.892794) (xy 304.348655 8.849919) (xy 311.155321 8.849919) (xy 311.155321 8.935669)
			(xy 311.163233 9.021052) (xy 311.178989 9.105342) (xy 311.202456 9.187818) (xy 311.233432 9.267777)
			(xy 311.271654 9.344537) (xy 311.316795 9.417443) (xy 311.368471 9.485872) (xy 311.42624 9.549242)
			(xy 311.48961 9.607011) (xy 311.558039 9.658687) (xy 311.630945 9.703828) (xy 311.707705 9.74205)
			(xy 311.787664 9.773026) (xy 311.87014 9.796493) (xy 311.95443 9.812249) (xy 312.039813 9.820161)
			(xy 312.125563 9.820161) (xy 312.210946 9.812249) (xy 312.295236 9.796493) (xy 312.377712 9.773026)
			(xy 312.457671 9.74205) (xy 312.534431 9.703828) (xy 312.607337 9.658687) (xy 312.675766 9.607011)
			(xy 312.739136 9.549242) (xy 312.796905 9.485872) (xy 312.848581 9.417443) (xy 312.893722 9.344537)
			(xy 312.931944 9.267777) (xy 312.96292 9.187818) (xy 312.986387 9.105342) (xy 313.002143 9.021052)
			(xy 313.010055 8.935669) (xy 313.01055 8.892794) (xy 313.010055 8.849919) (xy 317.505321 8.849919)
			(xy 317.505321 8.935669) (xy 317.513233 9.021052) (xy 317.528989 9.105342) (xy 317.552456 9.187818)
			(xy 317.583432 9.267777) (xy 317.621654 9.344537) (xy 317.666795 9.417443) (xy 317.718471 9.485872)
			(xy 317.77624 9.549242) (xy 317.83961 9.607011) (xy 317.908039 9.658687) (xy 317.980945 9.703828)
			(xy 318.057705 9.74205) (xy 318.137664 9.773026) (xy 318.22014 9.796493) (xy 318.30443 9.812249)
			(xy 318.389813 9.820161) (xy 318.475563 9.820161) (xy 318.560946 9.812249) (xy 318.645236 9.796493)
			(xy 318.727712 9.773026) (xy 318.807671 9.74205) (xy 318.884431 9.703828) (xy 318.957337 9.658687)
			(xy 319.025766 9.607011) (xy 319.089136 9.549242) (xy 319.146905 9.485872) (xy 319.198581 9.417443)
			(xy 319.243722 9.344537) (xy 319.281944 9.267777) (xy 319.31292 9.187818) (xy 319.336387 9.105342)
			(xy 319.352143 9.021052) (xy 319.360055 8.935669) (xy 319.36055 8.892794) (xy 319.360055 8.849919)
			(xy 361.894107 8.849919) (xy 361.894107 8.935669) (xy 361.902019 9.021052) (xy 361.917775 9.105342)
			(xy 361.941242 9.187818) (xy 361.972218 9.267777) (xy 362.01044 9.344537) (xy 362.055581 9.417443)
			(xy 362.107257 9.485872) (xy 362.165026 9.549242) (xy 362.228396 9.607011) (xy 362.296825 9.658687)
			(xy 362.369731 9.703828) (xy 362.446491 9.74205) (xy 362.52645 9.773026) (xy 362.608926 9.796493)
			(xy 362.693216 9.812249) (xy 362.778599 9.820161) (xy 362.864349 9.820161) (xy 362.949732 9.812249)
			(xy 363.034022 9.796493) (xy 363.116498 9.773026) (xy 363.196457 9.74205) (xy 363.273217 9.703828)
			(xy 363.346123 9.658687) (xy 363.414552 9.607011) (xy 363.477922 9.549242) (xy 363.535691 9.485872)
			(xy 363.587367 9.417443) (xy 363.632508 9.344537) (xy 363.67073 9.267777) (xy 363.701706 9.187818)
			(xy 363.725173 9.105342) (xy 363.740929 9.021052) (xy 363.748841 8.935669) (xy 363.749336 8.892794)
			(xy 363.748841 8.849919) (xy 368.244107 8.849919) (xy 368.244107 8.935669) (xy 368.252019 9.021052)
			(xy 368.267775 9.105342) (xy 368.291242 9.187818) (xy 368.322218 9.267777) (xy 368.36044 9.344537)
			(xy 368.405581 9.417443) (xy 368.457257 9.485872) (xy 368.515026 9.549242) (xy 368.578396 9.607011)
			(xy 368.646825 9.658687) (xy 368.719731 9.703828) (xy 368.796491 9.74205) (xy 368.87645 9.773026)
			(xy 368.958926 9.796493) (xy 369.043216 9.812249) (xy 369.128599 9.820161) (xy 369.214349 9.820161)
			(xy 369.299732 9.812249) (xy 369.384022 9.796493) (xy 369.466498 9.773026) (xy 369.546457 9.74205)
			(xy 369.623217 9.703828) (xy 369.696123 9.658687) (xy 369.764552 9.607011) (xy 369.827922 9.549242)
			(xy 369.885691 9.485872) (xy 369.937367 9.417443) (xy 369.982508 9.344537) (xy 370.02073 9.267777)
			(xy 370.051706 9.187818) (xy 370.075173 9.105342) (xy 370.090929 9.021052) (xy 370.098841 8.935669)
			(xy 370.099336 8.892794) (xy 370.098841 8.849919) (xy 370.090929 8.764536) (xy 370.075173 8.680246)
			(xy 370.051706 8.59777) (xy 370.02073 8.517811) (xy 369.982508 8.441051) (xy 369.937367 8.368145)
			(xy 369.885691 8.299716) (xy 369.827922 8.236346) (xy 369.764552 8.178577) (xy 369.696123 8.126901)
			(xy 369.623217 8.08176) (xy 369.546457 8.043538) (xy 369.466498 8.012562) (xy 369.384022 7.989095)
			(xy 369.299732 7.973339) (xy 369.214349 7.965427) (xy 369.128599 7.965427) (xy 369.043216 7.973339)
			(xy 368.958926 7.989095) (xy 368.87645 8.012562) (xy 368.796491 8.043538) (xy 368.719731 8.08176)
			(xy 368.646825 8.126901) (xy 368.578396 8.178577) (xy 368.515026 8.236346) (xy 368.457257 8.299716)
			(xy 368.405581 8.368145) (xy 368.36044 8.441051) (xy 368.322218 8.517811) (xy 368.291242 8.59777)
			(xy 368.267775 8.680246) (xy 368.252019 8.764536) (xy 368.244107 8.849919) (xy 363.748841 8.849919)
			(xy 363.740929 8.764536) (xy 363.725173 8.680246) (xy 363.701706 8.59777) (xy 363.67073 8.517811)
			(xy 363.632508 8.441051) (xy 363.587367 8.368145) (xy 363.535691 8.299716) (xy 363.477922 8.236346)
			(xy 363.414552 8.178577) (xy 363.346123 8.126901) (xy 363.273217 8.08176) (xy 363.196457 8.043538)
			(xy 363.116498 8.012562) (xy 363.034022 7.989095) (xy 362.949732 7.973339) (xy 362.864349 7.965427)
			(xy 362.778599 7.965427) (xy 362.693216 7.973339) (xy 362.608926 7.989095) (xy 362.52645 8.012562)
			(xy 362.446491 8.043538) (xy 362.369731 8.08176) (xy 362.296825 8.126901) (xy 362.228396 8.178577)
			(xy 362.165026 8.236346) (xy 362.107257 8.299716) (xy 362.055581 8.368145) (xy 362.01044 8.441051)
			(xy 361.972218 8.517811) (xy 361.941242 8.59777) (xy 361.917775 8.680246) (xy 361.902019 8.764536)
			(xy 361.894107 8.849919) (xy 319.360055 8.849919) (xy 319.352143 8.764536) (xy 319.336387 8.680246)
			(xy 319.31292 8.59777) (xy 319.281944 8.517811) (xy 319.243722 8.441051) (xy 319.198581 8.368145)
			(xy 319.146905 8.299716) (xy 319.089136 8.236346) (xy 319.025766 8.178577) (xy 318.957337 8.126901)
			(xy 318.884431 8.08176) (xy 318.807671 8.043538) (xy 318.727712 8.012562) (xy 318.645236 7.989095)
			(xy 318.560946 7.973339) (xy 318.475563 7.965427) (xy 318.389813 7.965427) (xy 318.30443 7.973339)
			(xy 318.22014 7.989095) (xy 318.137664 8.012562) (xy 318.057705 8.043538) (xy 317.980945 8.08176)
			(xy 317.908039 8.126901) (xy 317.83961 8.178577) (xy 317.77624 8.236346) (xy 317.718471 8.299716)
			(xy 317.666795 8.368145) (xy 317.621654 8.441051) (xy 317.583432 8.517811) (xy 317.552456 8.59777)
			(xy 317.528989 8.680246) (xy 317.513233 8.764536) (xy 317.505321 8.849919) (xy 313.010055 8.849919)
			(xy 313.002143 8.764536) (xy 312.986387 8.680246) (xy 312.96292 8.59777) (xy 312.931944 8.517811)
			(xy 312.893722 8.441051) (xy 312.848581 8.368145) (xy 312.796905 8.299716) (xy 312.739136 8.236346)
			(xy 312.675766 8.178577) (xy 312.607337 8.126901) (xy 312.534431 8.08176) (xy 312.457671 8.043538)
			(xy 312.377712 8.012562) (xy 312.295236 7.989095) (xy 312.210946 7.973339) (xy 312.125563 7.965427)
			(xy 312.039813 7.965427) (xy 311.95443 7.973339) (xy 311.87014 7.989095) (xy 311.787664 8.012562)
			(xy 311.707705 8.043538) (xy 311.630945 8.08176) (xy 311.558039 8.126901) (xy 311.48961 8.178577)
			(xy 311.42624 8.236346) (xy 311.368471 8.299716) (xy 311.316795 8.368145) (xy 311.271654 8.441051)
			(xy 311.233432 8.517811) (xy 311.202456 8.59777) (xy 311.178989 8.680246) (xy 311.163233 8.764536)
			(xy 311.155321 8.849919) (xy 304.348655 8.849919) (xy 304.340743 8.764536) (xy 304.324987 8.680246)
			(xy 304.30152 8.59777) (xy 304.270544 8.517811) (xy 304.232322 8.441051) (xy 304.187181 8.368145)
			(xy 304.135505 8.299716) (xy 304.077736 8.236346) (xy 304.014366 8.178577) (xy 303.945937 8.126901)
			(xy 303.873031 8.08176) (xy 303.796271 8.043538) (xy 303.716312 8.012562) (xy 303.633836 7.989095)
			(xy 303.549546 7.973339) (xy 303.464163 7.965427) (xy 303.378413 7.965427) (xy 303.29303 7.973339)
			(xy 303.20874 7.989095) (xy 303.126264 8.012562) (xy 303.046305 8.043538) (xy 302.969545 8.08176)
			(xy 302.896639 8.126901) (xy 302.82821 8.178577) (xy 302.76484 8.236346) (xy 302.707071 8.299716)
			(xy 302.655395 8.368145) (xy 302.610254 8.441051) (xy 302.572032 8.517811) (xy 302.541056 8.59777)
			(xy 302.517589 8.680246) (xy 302.501833 8.764536) (xy 302.493921 8.849919) (xy 297.998655 8.849919)
			(xy 297.990743 8.764536) (xy 297.974987 8.680246) (xy 297.95152 8.59777) (xy 297.920544 8.517811)
			(xy 297.882322 8.441051) (xy 297.837181 8.368145) (xy 297.785505 8.299716) (xy 297.727736 8.236346)
			(xy 297.664366 8.178577) (xy 297.595937 8.126901) (xy 297.523031 8.08176) (xy 297.446271 8.043538)
			(xy 297.366312 8.012562) (xy 297.283836 7.989095) (xy 297.199546 7.973339) (xy 297.114163 7.965427)
			(xy 297.028413 7.965427) (xy 296.94303 7.973339) (xy 296.85874 7.989095) (xy 296.776264 8.012562)
			(xy 296.696305 8.043538) (xy 296.619545 8.08176) (xy 296.546639 8.126901) (xy 296.47821 8.178577)
			(xy 296.41484 8.236346) (xy 296.357071 8.299716) (xy 296.305395 8.368145) (xy 296.260254 8.441051)
			(xy 296.222032 8.517811) (xy 296.191056 8.59777) (xy 296.167589 8.680246) (xy 296.151833 8.764536)
			(xy 296.143921 8.849919) (xy 216.865975 8.849919) (xy 216.858063 8.764536) (xy 216.842307 8.680246)
			(xy 216.81884 8.59777) (xy 216.787864 8.517811) (xy 216.749642 8.441051) (xy 216.704501 8.368145)
			(xy 216.652825 8.299716) (xy 216.595056 8.236346) (xy 216.531686 8.178577) (xy 216.463257 8.126901)
			(xy 216.390351 8.08176) (xy 216.313591 8.043538) (xy 216.233632 8.012562) (xy 216.151156 7.989095)
			(xy 216.066866 7.973339) (xy 215.981483 7.965427) (xy 215.895733 7.965427) (xy 215.81035 7.973339)
			(xy 215.72606 7.989095) (xy 215.643584 8.012562) (xy 215.563625 8.043538) (xy 215.486865 8.08176)
			(xy 215.413959 8.126901) (xy 215.34553 8.178577) (xy 215.28216 8.236346) (xy 215.224391 8.299716)
			(xy 215.172715 8.368145) (xy 215.127574 8.441051) (xy 215.089352 8.517811) (xy 215.058376 8.59777)
			(xy 215.034909 8.680246) (xy 215.019153 8.764536) (xy 215.011241 8.849919) (xy 210.515975 8.849919)
			(xy 210.508063 8.764536) (xy 210.492307 8.680246) (xy 210.46884 8.59777) (xy 210.437864 8.517811)
			(xy 210.399642 8.441051) (xy 210.354501 8.368145) (xy 210.302825 8.299716) (xy 210.245056 8.236346)
			(xy 210.181686 8.178577) (xy 210.113257 8.126901) (xy 210.040351 8.08176) (xy 209.963591 8.043538)
			(xy 209.883632 8.012562) (xy 209.801156 7.989095) (xy 209.716866 7.973339) (xy 209.631483 7.965427)
			(xy 209.545733 7.965427) (xy 209.46035 7.973339) (xy 209.37606 7.989095) (xy 209.293584 8.012562)
			(xy 209.213625 8.043538) (xy 209.136865 8.08176) (xy 209.063959 8.126901) (xy 208.99553 8.178577)
			(xy 208.93216 8.236346) (xy 208.874391 8.299716) (xy 208.822715 8.368145) (xy 208.777574 8.441051)
			(xy 208.739352 8.517811) (xy 208.708376 8.59777) (xy 208.684909 8.680246) (xy 208.669153 8.764536)
			(xy 208.661241 8.849919) (xy 6.51416 8.849919) (xy 6.592279 8.764226) (xy 6.67324 8.663616) (xy 6.747854 8.558213)
			(xy 6.815837 8.448416) (xy 6.876932 8.334642) (xy 6.930907 8.217323) (xy 6.977558 8.096904) (xy 7.016707 7.973841)
			(xy 7.048206 7.848602) (xy 7.071935 7.721661) (xy 7.087805 7.593501) (xy 7.095755 7.464606) (xy 7.096252 7.400036)
			(xy 7.095755 7.335466) (xy 7.092973 7.290359) (xy 93.985575 7.290359) (xy 93.985575 7.376109) (xy 93.993487 7.461492)
			(xy 94.009243 7.545782) (xy 94.03271 7.628258) (xy 94.063686 7.708217) (xy 94.101908 7.784977) (xy 94.147049 7.857883)
			(xy 94.198725 7.926312) (xy 94.256494 7.989682) (xy 94.319864 8.047451) (xy 94.388293 8.099127) (xy 94.461199 8.144268)
			(xy 94.537959 8.18249) (xy 94.617918 8.213466) (xy 94.700394 8.236933) (xy 94.784684 8.252689) (xy 94.870067 8.260601)
			(xy 94.955817 8.260601) (xy 95.0412 8.252689) (xy 95.12549 8.236933) (xy 95.207966 8.213466) (xy 95.287925 8.18249)
			(xy 95.364685 8.144268) (xy 95.437591 8.099127) (xy 95.50602 8.047451) (xy 95.56939 7.989682) (xy 95.627159 7.926312)
			(xy 95.678835 7.857883) (xy 95.723976 7.784977) (xy 95.762198 7.708217) (xy 95.793174 7.628258) (xy 95.816641 7.545782)
			(xy 95.832397 7.461492) (xy 95.840309 7.376109) (xy 95.840804 7.333234) (xy 95.840309 7.290359) (xy 100.335575 7.290359)
			(xy 100.335575 7.376109) (xy 100.343487 7.461492) (xy 100.359243 7.545782) (xy 100.38271 7.628258)
			(xy 100.413686 7.708217) (xy 100.451908 7.784977) (xy 100.497049 7.857883) (xy 100.548725 7.926312)
			(xy 100.606494 7.989682) (xy 100.669864 8.047451) (xy 100.738293 8.099127) (xy 100.811199 8.144268)
			(xy 100.887959 8.18249) (xy 100.967918 8.213466) (xy 101.050394 8.236933) (xy 101.134684 8.252689)
			(xy 101.220067 8.260601) (xy 101.305817 8.260601) (xy 101.3912 8.252689) (xy 101.47549 8.236933)
			(xy 101.557966 8.213466) (xy 101.637925 8.18249) (xy 101.714685 8.144268) (xy 101.787591 8.099127)
			(xy 101.85602 8.047451) (xy 101.91939 7.989682) (xy 101.977159 7.926312) (xy 102.028835 7.857883)
			(xy 102.073976 7.784977) (xy 102.112198 7.708217) (xy 102.143174 7.628258) (xy 102.166641 7.545782)
			(xy 102.182397 7.461492) (xy 102.190309 7.376109) (xy 102.190804 7.333234) (xy 102.190309 7.290359)
			(xy 181.468255 7.290359) (xy 181.468255 7.376109) (xy 181.476167 7.461492) (xy 181.491923 7.545782)
			(xy 181.51539 7.628258) (xy 181.546366 7.708217) (xy 181.584588 7.784977) (xy 181.629729 7.857883)
			(xy 181.681405 7.926312) (xy 181.739174 7.989682) (xy 181.802544 8.047451) (xy 181.870973 8.099127)
			(xy 181.943879 8.144268) (xy 182.020639 8.18249) (xy 182.100598 8.213466) (xy 182.183074 8.236933)
			(xy 182.267364 8.252689) (xy 182.352747 8.260601) (xy 182.438497 8.260601) (xy 182.52388 8.252689)
			(xy 182.60817 8.236933) (xy 182.690646 8.213466) (xy 182.770605 8.18249) (xy 182.847365 8.144268)
			(xy 182.920271 8.099127) (xy 182.9887 8.047451) (xy 183.05207 7.989682) (xy 183.109839 7.926312)
			(xy 183.161515 7.857883) (xy 183.206656 7.784977) (xy 183.244878 7.708217) (xy 183.275854 7.628258)
			(xy 183.299321 7.545782) (xy 183.315077 7.461492) (xy 183.322989 7.376109) (xy 183.323484 7.333234)
			(xy 183.322989 7.290359) (xy 187.818255 7.290359) (xy 187.818255 7.376109) (xy 187.826167 7.461492)
			(xy 187.841923 7.545782) (xy 187.86539 7.628258) (xy 187.896366 7.708217) (xy 187.934588 7.784977)
			(xy 187.979729 7.857883) (xy 188.031405 7.926312) (xy 188.089174 7.989682) (xy 188.152544 8.047451)
			(xy 188.220973 8.099127) (xy 188.293879 8.144268) (xy 188.370639 8.18249) (xy 188.450598 8.213466)
			(xy 188.533074 8.236933) (xy 188.617364 8.252689) (xy 188.702747 8.260601) (xy 188.788497 8.260601)
			(xy 188.87388 8.252689) (xy 188.95817 8.236933) (xy 189.040646 8.213466) (xy 189.120605 8.18249)
			(xy 189.197365 8.144268) (xy 189.270271 8.099127) (xy 189.3387 8.047451) (xy 189.40207 7.989682)
			(xy 189.459839 7.926312) (xy 189.511515 7.857883) (xy 189.556656 7.784977) (xy 189.594878 7.708217)
			(xy 189.625854 7.628258) (xy 189.649321 7.545782) (xy 189.665077 7.461492) (xy 189.672989 7.376109)
			(xy 189.673484 7.333234) (xy 189.672989 7.290359) (xy 189.665077 7.204976) (xy 189.649321 7.120686)
			(xy 189.625854 7.03821) (xy 189.594878 6.958251) (xy 189.556656 6.881491) (xy 189.511515 6.808585)
			(xy 189.459839 6.740156) (xy 189.40207 6.676786) (xy 189.3387 6.619017) (xy 189.270271 6.567341)
			(xy 189.197365 6.5222) (xy 189.120605 6.483978) (xy 189.040646 6.453002) (xy 188.95817 6.429535)
			(xy 188.87388 6.413779) (xy 188.788497 6.405867) (xy 188.702747 6.405867) (xy 188.617364 6.413779)
			(xy 188.533074 6.429535) (xy 188.450598 6.453002) (xy 188.370639 6.483978) (xy 188.293879 6.5222)
			(xy 188.220973 6.567341) (xy 188.152544 6.619017) (xy 188.089174 6.676786) (xy 188.031405 6.740156)
			(xy 187.979729 6.808585) (xy 187.934588 6.881491) (xy 187.896366 6.958251) (xy 187.86539 7.03821)
			(xy 187.841923 7.120686) (xy 187.826167 7.204976) (xy 187.818255 7.290359) (xy 183.322989 7.290359)
			(xy 183.315077 7.204976) (xy 183.299321 7.120686) (xy 183.275854 7.03821) (xy 183.244878 6.958251)
			(xy 183.206656 6.881491) (xy 183.161515 6.808585) (xy 183.109839 6.740156) (xy 183.05207 6.676786)
			(xy 182.9887 6.619017) (xy 182.920271 6.567341) (xy 182.847365 6.5222) (xy 182.770605 6.483978) (xy 182.690646 6.453002)
			(xy 182.60817 6.429535) (xy 182.52388 6.413779) (xy 182.438497 6.405867) (xy 182.352747 6.405867)
			(xy 182.267364 6.413779) (xy 182.183074 6.429535) (xy 182.100598 6.453002) (xy 182.020639 6.483978)
			(xy 181.943879 6.5222) (xy 181.870973 6.567341) (xy 181.802544 6.619017) (xy 181.739174 6.676786)
			(xy 181.681405 6.740156) (xy 181.629729 6.808585) (xy 181.584588 6.881491) (xy 181.546366 6.958251)
			(xy 181.51539 7.03821) (xy 181.491923 7.120686) (xy 181.476167 7.204976) (xy 181.468255 7.290359)
			(xy 102.190309 7.290359) (xy 102.182397 7.204976) (xy 102.166641 7.120686) (xy 102.143174 7.03821)
			(xy 102.112198 6.958251) (xy 102.073976 6.881491) (xy 102.028835 6.808585) (xy 101.977159 6.740156)
			(xy 101.91939 6.676786) (xy 101.85602 6.619017) (xy 101.787591 6.567341) (xy 101.714685 6.5222) (xy 101.637925 6.483978)
			(xy 101.557966 6.453002) (xy 101.47549 6.429535) (xy 101.3912 6.413779) (xy 101.305817 6.405867)
			(xy 101.220067 6.405867) (xy 101.134684 6.413779) (xy 101.050394 6.429535) (xy 100.967918 6.453002)
			(xy 100.887959 6.483978) (xy 100.811199 6.5222) (xy 100.738293 6.567341) (xy 100.669864 6.619017)
			(xy 100.606494 6.676786) (xy 100.548725 6.740156) (xy 100.497049 6.808585) (xy 100.451908 6.881491)
			(xy 100.413686 6.958251) (xy 100.38271 7.03821) (xy 100.359243 7.120686) (xy 100.343487 7.204976)
			(xy 100.335575 7.290359) (xy 95.840309 7.290359) (xy 95.832397 7.204976) (xy 95.816641 7.120686)
			(xy 95.793174 7.03821) (xy 95.762198 6.958251) (xy 95.723976 6.881491) (xy 95.678835 6.808585) (xy 95.627159 6.740156)
			(xy 95.56939 6.676786) (xy 95.50602 6.619017) (xy 95.437591 6.567341) (xy 95.364685 6.5222) (xy 95.287925 6.483978)
			(xy 95.207966 6.453002) (xy 95.12549 6.429535) (xy 95.0412 6.413779) (xy 94.955817 6.405867) (xy 94.870067 6.405867)
			(xy 94.784684 6.413779) (xy 94.700394 6.429535) (xy 94.617918 6.453002) (xy 94.537959 6.483978) (xy 94.461199 6.5222)
			(xy 94.388293 6.567341) (xy 94.319864 6.619017) (xy 94.256494 6.676786) (xy 94.198725 6.740156) (xy 94.147049 6.808585)
			(xy 94.101908 6.881491) (xy 94.063686 6.958251) (xy 94.03271 7.03821) (xy 94.009243 7.120686) (xy 93.993487 7.204976)
			(xy 93.985575 7.290359) (xy 7.092973 7.290359) (xy 7.087805 7.206571) (xy 7.071935 7.078411) (xy 7.048206 6.95147)
			(xy 7.016707 6.826231) (xy 6.977558 6.703168) (xy 6.930907 6.582749) (xy 6.876932 6.46543) (xy 6.815837 6.351656)
			(xy 6.747854 6.241859) (xy 6.67324 6.136456) (xy 6.592279 6.035846) (xy 6.505279 5.940411) (xy 6.412568 5.850512)
			(xy 6.314498 5.766491) (xy 6.211443 5.688667) (xy 6.103792 5.617335) (xy 5.991953 5.552765) (xy 5.876352 5.495203)
			(xy 5.757427 5.444866) (xy 5.635628 5.401946) (xy 5.511418 5.366605) (xy 5.385269 5.338978) (xy 5.257657 5.319169)
			(xy 5.129068 5.307253) (xy 4.99999 5.303277) (xy 4.870912 5.307253) (xy 4.742323 5.319169) (xy 4.614711 5.338978)
			(xy 4.488562 5.366605) (xy 4.364352 5.401946) (xy 4.242553 5.444866) (xy 4.123628 5.495203) (xy 4.008027 5.552765)
			(xy 3.896188 5.617335) (xy 3.788537 5.688667) (xy 3.685482 5.766491) (xy 3.587412 5.850512) (xy 3.494701 5.940411)
			(xy 3.407701 6.035846) (xy 3.32674 6.136456) (xy 3.252126 6.241859) (xy 3.184143 6.351656) (xy 3.123048 6.46543)
			(xy 3.069073 6.582749) (xy 3.022422 6.703168) (xy 2.983273 6.826231) (xy 2.951774 6.95147) (xy 2.928045 7.078411)
			(xy 2.912175 7.206571) (xy 2.904225 7.335466) (xy 0.509016 7.335466) (xy 0.509016 4.750359) (xy 93.985575 4.750359)
			(xy 93.985575 4.836109) (xy 93.993487 4.921492) (xy 94.009243 5.005782) (xy 94.03271 5.088258) (xy 94.063686 5.168217)
			(xy 94.101908 5.244977) (xy 94.147049 5.317883) (xy 94.198725 5.386312) (xy 94.256494 5.449682) (xy 94.319864 5.507451)
			(xy 94.388293 5.559127) (xy 94.461199 5.604268) (xy 94.537959 5.64249) (xy 94.617918 5.673466) (xy 94.700394 5.696933)
			(xy 94.784684 5.712689) (xy 94.870067 5.720601) (xy 94.955817 5.720601) (xy 95.0412 5.712689) (xy 95.12549 5.696933)
			(xy 95.207966 5.673466) (xy 95.287925 5.64249) (xy 95.364685 5.604268) (xy 95.437591 5.559127) (xy 95.493198 5.517134)
			(xy 98.144076 5.517134) (xy 98.144076 6.614414) (xy 98.144449 6.626541) (xy 98.15195 6.649607) (xy 98.166212 6.669225)
			(xy 98.18584 6.683474) (xy 98.20891 6.690959) (xy 98.221038 6.691376) (xy 98.833178 6.691376) (xy 98.837242 6.691122)
			(xy 98.843259 6.691051) (xy 98.855065 6.693357) (xy 98.86061 6.695694) (xy 98.88728 6.707632) (xy 98.893941 6.710896)
			(xy 98.905172 6.720573) (xy 98.909378 6.726682) (xy 98.926448 6.752712) (xy 98.966901 6.80002) (xy 99.01372 6.841039)
			(xy 99.065937 6.874921) (xy 99.122473 6.900965) (xy 99.182158 6.918634) (xy 99.243761 6.927561) (xy 99.274884 6.928104)
			(xy 99.30319 6.92765) (xy 99.359317 6.920263) (xy 99.414 6.905612) (xy 99.466303 6.883949) (xy 99.51533 6.855645)
			(xy 99.560244 6.821183) (xy 99.600275 6.781153) (xy 99.634738 6.73624) (xy 99.663044 6.687214) (xy 99.684709 6.634911)
			(xy 99.699361 6.580229) (xy 99.70675 6.524102) (xy 99.707192 6.495796) (xy 99.707192 5.632196) (xy 99.706769 5.603889)
			(xy 99.699379 5.54776) (xy 99.684725 5.493076) (xy 99.66306 5.440772) (xy 99.634752 5.391744) (xy 99.600287 5.346831)
			(xy 99.560254 5.3068) (xy 99.515339 5.272337) (xy 99.46631 5.244032) (xy 99.414005 5.222368) (xy 99.35932 5.207717)
			(xy 99.303191 5.20033) (xy 99.274884 5.199888) (xy 99.243508 5.200417) (xy 99.181414 5.209481) (xy 99.12128 5.227417)
			(xy 99.064366 5.253847) (xy 99.011866 5.28822) (xy 98.964879 5.329813) (xy 98.92439 5.377756) (xy 98.907346 5.404104)
			(xy 98.903286 5.410247) (xy 98.892314 5.420058) (xy 98.885756 5.423408) (xy 98.846894 5.441442) (xy 98.833178 5.440172)
			(xy 98.221038 5.440172) (xy 98.208914 5.440593) (xy 98.18585 5.448079) (xy 98.166232 5.462329) (xy 98.151981 5.481947)
			(xy 98.144493 5.50501) (xy 98.144076 5.517134) (xy 95.493198 5.517134) (xy 95.50602 5.507451) (xy 95.56939 5.449682)
			(xy 95.627159 5.386312) (xy 95.678835 5.317883) (xy 95.723976 5.244977) (xy 95.762198 5.168217) (xy 95.793174 5.088258)
			(xy 95.816641 5.005782) (xy 95.832397 4.921492) (xy 95.840309 4.836109) (xy 95.840804 4.793234) (xy 95.840309 4.750359)
			(xy 100.335575 4.750359) (xy 100.335575 4.836109) (xy 100.343487 4.921492) (xy 100.359243 5.005782)
			(xy 100.38271 5.088258) (xy 100.413686 5.168217) (xy 100.451908 5.244977) (xy 100.497049 5.317883)
			(xy 100.548725 5.386312) (xy 100.606494 5.449682) (xy 100.669864 5.507451) (xy 100.738293 5.559127)
			(xy 100.811199 5.604268) (xy 100.887959 5.64249) (xy 100.967918 5.673466) (xy 101.050394 5.696933)
			(xy 101.134684 5.712689) (xy 101.220067 5.720601) (xy 101.305817 5.720601) (xy 101.3912 5.712689)
			(xy 101.47549 5.696933) (xy 101.557966 5.673466) (xy 101.637925 5.64249) (xy 101.714685 5.604268)
			(xy 101.787591 5.559127) (xy 101.85602 5.507451) (xy 101.91939 5.449682) (xy 101.977159 5.386312)
			(xy 102.028835 5.317883) (xy 102.073976 5.244977) (xy 102.112198 5.168217) (xy 102.143174 5.088258)
			(xy 102.166641 5.005782) (xy 102.182397 4.921492) (xy 102.190309 4.836109) (xy 102.190804 4.793234)
			(xy 102.190309 4.750359) (xy 181.468255 4.750359) (xy 181.468255 4.836109) (xy 181.476167 4.921492)
			(xy 181.491923 5.005782) (xy 181.51539 5.088258) (xy 181.546366 5.168217) (xy 181.584588 5.244977)
			(xy 181.629729 5.317883) (xy 181.681405 5.386312) (xy 181.739174 5.449682) (xy 181.802544 5.507451)
			(xy 181.870973 5.559127) (xy 181.943879 5.604268) (xy 182.020639 5.64249) (xy 182.100598 5.673466)
			(xy 182.183074 5.696933) (xy 182.267364 5.712689) (xy 182.352747 5.720601) (xy 182.438497 5.720601)
			(xy 182.52388 5.712689) (xy 182.60817 5.696933) (xy 182.690646 5.673466) (xy 182.770605 5.64249)
			(xy 182.791278 5.632196) (xy 183.953912 5.632196) (xy 183.953912 6.495796) (xy 183.954338 6.524103)
			(xy 183.961728 6.580232) (xy 183.97638 6.634916) (xy 183.998046 6.68722) (xy 184.026353 6.736248)
			(xy 184.060817 6.781162) (xy 184.10085 6.821193) (xy 184.145765 6.855656) (xy 184.194794 6.883962)
			(xy 184.247099 6.905625) (xy 184.301784 6.920275) (xy 184.357913 6.927663) (xy 184.38622 6.928104)
			(xy 184.417684 6.927495) (xy 184.479947 6.918382) (xy 184.540231 6.900337) (xy 184.597262 6.873742)
			(xy 184.649834 6.839159) (xy 184.696835 6.797318) (xy 184.737273 6.749104) (xy 184.754266 6.722618)
			(xy 184.758313 6.716581) (xy 184.769143 6.706898) (xy 184.775602 6.703568) (xy 184.813702 6.68528)
			(xy 184.825386 6.686296) (xy 185.437526 6.686296) (xy 185.449639 6.685811) (xy 185.472677 6.678321)
			(xy 185.492275 6.664081) (xy 185.506517 6.644484) (xy 185.51401 6.621446) (xy 185.514488 6.609334)
			(xy 185.514488 6.309919) (xy 208.661241 6.309919) (xy 208.661241 6.395669) (xy 208.669153 6.481052)
			(xy 208.684909 6.565342) (xy 208.708376 6.647818) (xy 208.739352 6.727777) (xy 208.777574 6.804537)
			(xy 208.822715 6.877443) (xy 208.874391 6.945872) (xy 208.93216 7.009242) (xy 208.99553 7.067011)
			(xy 209.063959 7.118687) (xy 209.136865 7.163828) (xy 209.213625 7.20205) (xy 209.293584 7.233026)
			(xy 209.37606 7.256493) (xy 209.46035 7.272249) (xy 209.545733 7.280161) (xy 209.631483 7.280161)
			(xy 209.716866 7.272249) (xy 209.801156 7.256493) (xy 209.883632 7.233026) (xy 209.963591 7.20205)
			(xy 210.040351 7.163828) (xy 210.113257 7.118687) (xy 210.181686 7.067011) (xy 210.245056 7.009242)
			(xy 210.302825 6.945872) (xy 210.354501 6.877443) (xy 210.399642 6.804537) (xy 210.437864 6.727777)
			(xy 210.46884 6.647818) (xy 210.492307 6.565342) (xy 210.508063 6.481052) (xy 210.515975 6.395669)
			(xy 210.51647 6.352794) (xy 210.515975 6.309919) (xy 215.011241 6.309919) (xy 215.011241 6.395669)
			(xy 215.019153 6.481052) (xy 215.034909 6.565342) (xy 215.058376 6.647818) (xy 215.089352 6.727777)
			(xy 215.127574 6.804537) (xy 215.172715 6.877443) (xy 215.224391 6.945872) (xy 215.28216 7.009242)
			(xy 215.34553 7.067011) (xy 215.413959 7.118687) (xy 215.486865 7.163828) (xy 215.563625 7.20205)
			(xy 215.643584 7.233026) (xy 215.72606 7.256493) (xy 215.81035 7.272249) (xy 215.895733 7.280161)
			(xy 215.981483 7.280161) (xy 216.066866 7.272249) (xy 216.151156 7.256493) (xy 216.233632 7.233026)
			(xy 216.313591 7.20205) (xy 216.390351 7.163828) (xy 216.463257 7.118687) (xy 216.531686 7.067011)
			(xy 216.595056 7.009242) (xy 216.652825 6.945872) (xy 216.704501 6.877443) (xy 216.749642 6.804537)
			(xy 216.787864 6.727777) (xy 216.81884 6.647818) (xy 216.842307 6.565342) (xy 216.858063 6.481052)
			(xy 216.865975 6.395669) (xy 216.86647 6.352794) (xy 216.865975 6.309919) (xy 296.143921 6.309919)
			(xy 296.143921 6.395669) (xy 296.151833 6.481052) (xy 296.167589 6.565342) (xy 296.191056 6.647818)
			(xy 296.222032 6.727777) (xy 296.260254 6.804537) (xy 296.305395 6.877443) (xy 296.357071 6.945872)
			(xy 296.41484 7.009242) (xy 296.47821 7.067011) (xy 296.546639 7.118687) (xy 296.619545 7.163828)
			(xy 296.696305 7.20205) (xy 296.776264 7.233026) (xy 296.85874 7.256493) (xy 296.94303 7.272249)
			(xy 297.028413 7.280161) (xy 297.114163 7.280161) (xy 297.199546 7.272249) (xy 297.283836 7.256493)
			(xy 297.366312 7.233026) (xy 297.446271 7.20205) (xy 297.523031 7.163828) (xy 297.595937 7.118687)
			(xy 297.664366 7.067011) (xy 297.727736 7.009242) (xy 297.785505 6.945872) (xy 297.837181 6.877443)
			(xy 297.882322 6.804537) (xy 297.920544 6.727777) (xy 297.95152 6.647818) (xy 297.974987 6.565342)
			(xy 297.990743 6.481052) (xy 297.998655 6.395669) (xy 297.99915 6.352794) (xy 297.998655 6.309919)
			(xy 302.493921 6.309919) (xy 302.493921 6.395669) (xy 302.501833 6.481052) (xy 302.517589 6.565342)
			(xy 302.541056 6.647818) (xy 302.572032 6.727777) (xy 302.610254 6.804537) (xy 302.655395 6.877443)
			(xy 302.707071 6.945872) (xy 302.76484 7.009242) (xy 302.82821 7.067011) (xy 302.896639 7.118687)
			(xy 302.969545 7.163828) (xy 303.046305 7.20205) (xy 303.126264 7.233026) (xy 303.20874 7.256493)
			(xy 303.29303 7.272249) (xy 303.378413 7.280161) (xy 303.464163 7.280161) (xy 303.549546 7.272249)
			(xy 303.633836 7.256493) (xy 303.716312 7.233026) (xy 303.796271 7.20205) (xy 303.873031 7.163828)
			(xy 303.945937 7.118687) (xy 304.014366 7.067011) (xy 304.077736 7.009242) (xy 304.135505 6.945872)
			(xy 304.187181 6.877443) (xy 304.232322 6.804537) (xy 304.270544 6.727777) (xy 304.30152 6.647818)
			(xy 304.324987 6.565342) (xy 304.340743 6.481052) (xy 304.348655 6.395669) (xy 304.34915 6.352794)
			(xy 304.348655 6.309919) (xy 311.155321 6.309919) (xy 311.155321 6.395669) (xy 311.163233 6.481052)
			(xy 311.178989 6.565342) (xy 311.202456 6.647818) (xy 311.233432 6.727777) (xy 311.271654 6.804537)
			(xy 311.316795 6.877443) (xy 311.368471 6.945872) (xy 311.42624 7.009242) (xy 311.48961 7.067011)
			(xy 311.558039 7.118687) (xy 311.630945 7.163828) (xy 311.707705 7.20205) (xy 311.787664 7.233026)
			(xy 311.87014 7.256493) (xy 311.95443 7.272249) (xy 312.039813 7.280161) (xy 312.125563 7.280161)
			(xy 312.210946 7.272249) (xy 312.295236 7.256493) (xy 312.377712 7.233026) (xy 312.457671 7.20205)
			(xy 312.478344 7.191756) (xy 316.012068 7.191756) (xy 316.012068 8.055356) (xy 316.012572 8.08491)
			(xy 316.020621 8.143466) (xy 316.036567 8.200381) (xy 316.060116 8.254595) (xy 316.090827 8.305098)
			(xy 316.128129 8.350948) (xy 316.171326 8.391291) (xy 316.219615 8.425377) (xy 316.272095 8.45257)
			(xy 316.32779 8.472364) (xy 316.385661 8.48439) (xy 316.44463 8.488424) (xy 316.503599 8.48439) (xy 316.56147 8.472364)
			(xy 316.617165 8.45257) (xy 316.669645 8.425377) (xy 316.717934 8.391291) (xy 316.761131 8.350948)
			(xy 316.798433 8.305098) (xy 316.829144 8.254595) (xy 316.852693 8.200381) (xy 316.868639 8.143466)
			(xy 316.876688 8.08491) (xy 316.877192 8.055356) (xy 316.877192 7.191756) (xy 316.876688 7.162202)
			(xy 316.868639 7.103646) (xy 316.852693 7.046731) (xy 316.829144 6.992517) (xy 316.798433 6.942014)
			(xy 316.761131 6.896164) (xy 316.717934 6.855821) (xy 316.669645 6.821735) (xy 316.617165 6.794542)
			(xy 316.56147 6.774748) (xy 316.503599 6.762722) (xy 316.44463 6.758689) (xy 316.385661 6.762722)
			(xy 316.32779 6.774748) (xy 316.272095 6.794542) (xy 316.219615 6.821735) (xy 316.171326 6.855821)
			(xy 316.128129 6.896164) (xy 316.090827 6.942014) (xy 316.060116 6.992517) (xy 316.036567 7.046731)
			(xy 316.020621 7.103646) (xy 316.012572 7.162202) (xy 316.012068 7.191756) (xy 312.478344 7.191756)
			(xy 312.534431 7.163828) (xy 312.607337 7.118687) (xy 312.675766 7.067011) (xy 312.739136 7.009242)
			(xy 312.796905 6.945872) (xy 312.848581 6.877443) (xy 312.893722 6.804537) (xy 312.931944 6.727777)
			(xy 312.96292 6.647818) (xy 312.986387 6.565342) (xy 313.002143 6.481052) (xy 313.010055 6.395669)
			(xy 313.01055 6.352794) (xy 313.010055 6.309919) (xy 317.505321 6.309919) (xy 317.505321 6.395669)
			(xy 317.513233 6.481052) (xy 317.528989 6.565342) (xy 317.552456 6.647818) (xy 317.583432 6.727777)
			(xy 317.621654 6.804537) (xy 317.666795 6.877443) (xy 317.718471 6.945872) (xy 317.77624 7.009242)
			(xy 317.83961 7.067011) (xy 317.908039 7.118687) (xy 317.980945 7.163828) (xy 318.057705 7.20205)
			(xy 318.137664 7.233026) (xy 318.22014 7.256493) (xy 318.30443 7.272249) (xy 318.389813 7.280161)
			(xy 318.475563 7.280161) (xy 318.560946 7.272249) (xy 318.645236 7.256493) (xy 318.727712 7.233026)
			(xy 318.807671 7.20205) (xy 318.884431 7.163828) (xy 318.957337 7.118687) (xy 319.025766 7.067011)
			(xy 319.089136 7.009242) (xy 319.146905 6.945872) (xy 319.198581 6.877443) (xy 319.243722 6.804537)
			(xy 319.281944 6.727777) (xy 319.31292 6.647818) (xy 319.336387 6.565342) (xy 319.352143 6.481052)
			(xy 319.360055 6.395669) (xy 319.36055 6.352794) (xy 319.360055 6.309919) (xy 361.894107 6.309919)
			(xy 361.894107 6.395669) (xy 361.902019 6.481052) (xy 361.917775 6.565342) (xy 361.941242 6.647818)
			(xy 361.972218 6.727777) (xy 362.01044 6.804537) (xy 362.055581 6.877443) (xy 362.107257 6.945872)
			(xy 362.165026 7.009242) (xy 362.228396 7.067011) (xy 362.296825 7.118687) (xy 362.369731 7.163828)
			(xy 362.446491 7.20205) (xy 362.52645 7.233026) (xy 362.608926 7.256493) (xy 362.693216 7.272249)
			(xy 362.778599 7.280161) (xy 362.864349 7.280161) (xy 362.949732 7.272249) (xy 363.034022 7.256493)
			(xy 363.116498 7.233026) (xy 363.196457 7.20205) (xy 363.21713 7.191756) (xy 364.379764 7.191756)
			(xy 364.379764 8.055356) (xy 364.380268 8.084892) (xy 364.388312 8.143414) (xy 364.404249 8.200296)
			(xy 364.427784 8.254478) (xy 364.458477 8.304951) (xy 364.495757 8.350774) (xy 364.538929 8.391094)
			(xy 364.587189 8.42516) (xy 364.639639 8.452337) (xy 364.6953 8.472119) (xy 364.753137 8.484138)
			(xy 364.812072 8.488169) (xy 364.871007 8.484138) (xy 364.928844 8.472119) (xy 364.984505 8.452337)
			(xy 365.036955 8.42516) (xy 365.085215 8.391094) (xy 365.128387 8.350774) (xy 365.165667 8.304951)
			(xy 365.19636 8.254478) (xy 365.219895 8.200296) (xy 365.235832 8.143414) (xy 365.243876 8.084892)
			(xy 365.24438 8.055356) (xy 365.24438 7.376973) (xy 385.651997 7.376973) (xy 385.651997 7.462723)
			(xy 385.659909 7.548106) (xy 385.675665 7.632396) (xy 385.699132 7.714872) (xy 385.730108 7.794831)
			(xy 385.76833 7.871591) (xy 385.813471 7.944497) (xy 385.865147 8.012926) (xy 385.922916 8.076296)
			(xy 385.986286 8.134065) (xy 386.054715 8.185741) (xy 386.127621 8.230882) (xy 386.204381 8.269104)
			(xy 386.28434 8.30008) (xy 386.366816 8.323547) (xy 386.451106 8.339303) (xy 386.536489 8.347215)
			(xy 386.622239 8.347215) (xy 386.707622 8.339303) (xy 386.791912 8.323547) (xy 386.874388 8.30008)
			(xy 386.954347 8.269104) (xy 386.97502 8.25881) (xy 390.508744 8.25881) (xy 390.508744 9.12241) (xy 390.509248 9.151964)
			(xy 390.517297 9.21052) (xy 390.533243 9.267435) (xy 390.556792 9.321649) (xy 390.587503 9.372152)
			(xy 390.624805 9.418002) (xy 390.668002 9.458345) (xy 390.716291 9.492431) (xy 390.768771 9.519624)
			(xy 390.824466 9.539418) (xy 390.882337 9.551444) (xy 390.941306 9.555478) (xy 391.000275 9.551444)
			(xy 391.058146 9.539418) (xy 391.113841 9.519624) (xy 391.166321 9.492431) (xy 391.21461 9.458345)
			(xy 391.257807 9.418002) (xy 391.295109 9.372152) (xy 391.32582 9.321649) (xy 391.349369 9.267435)
			(xy 391.365315 9.21052) (xy 391.373364 9.151964) (xy 391.373868 9.12241) (xy 391.373868 8.25881)
			(xy 391.373364 8.229256) (xy 391.365315 8.1707) (xy 391.349369 8.113785) (xy 391.32582 8.059571)
			(xy 391.295109 8.009068) (xy 391.257807 7.963218) (xy 391.21461 7.922875) (xy 391.166321 7.888789)
			(xy 391.113841 7.861596) (xy 391.058146 7.841802) (xy 391.000275 7.829776) (xy 390.941306 7.825743)
			(xy 390.882337 7.829776) (xy 390.824466 7.841802) (xy 390.768771 7.861596) (xy 390.716291 7.888789)
			(xy 390.668002 7.922875) (xy 390.624805 7.963218) (xy 390.587503 8.009068) (xy 390.556792 8.059571)
			(xy 390.533243 8.113785) (xy 390.517297 8.1707) (xy 390.509248 8.229256) (xy 390.508744 8.25881)
			(xy 386.97502 8.25881) (xy 387.031107 8.230882) (xy 387.104013 8.185741) (xy 387.172442 8.134065)
			(xy 387.235812 8.076296) (xy 387.293581 8.012926) (xy 387.345257 7.944497) (xy 387.390398 7.871591)
			(xy 387.42862 7.794831) (xy 387.459596 7.714872) (xy 387.483063 7.632396) (xy 387.498819 7.548106)
			(xy 387.506731 7.462723) (xy 387.507226 7.419848) (xy 387.506731 7.376973) (xy 392.001997 7.376973)
			(xy 392.001997 7.462723) (xy 392.009909 7.548106) (xy 392.025665 7.632396) (xy 392.049132 7.714872)
			(xy 392.080108 7.794831) (xy 392.11833 7.871591) (xy 392.163471 7.944497) (xy 392.215147 8.012926)
			(xy 392.272916 8.076296) (xy 392.336286 8.134065) (xy 392.404715 8.185741) (xy 392.477621 8.230882)
			(xy 392.554381 8.269104) (xy 392.63434 8.30008) (xy 392.716816 8.323547) (xy 392.801106 8.339303)
			(xy 392.886489 8.347215) (xy 392.972239 8.347215) (xy 393.057622 8.339303) (xy 393.141912 8.323547)
			(xy 393.224388 8.30008) (xy 393.304347 8.269104) (xy 393.381107 8.230882) (xy 393.454013 8.185741)
			(xy 393.522442 8.134065) (xy 393.585812 8.076296) (xy 393.643581 8.012926) (xy 393.695257 7.944497)
			(xy 393.740398 7.871591) (xy 393.77862 7.794831) (xy 393.809596 7.714872) (xy 393.833063 7.632396)
			(xy 393.848819 7.548106) (xy 393.856731 7.462723) (xy 393.857226 7.419848) (xy 393.856731 7.376973)
			(xy 436.390783 7.376973) (xy 436.390783 7.462723) (xy 436.398695 7.548106) (xy 436.414451 7.632396)
			(xy 436.437918 7.714872) (xy 436.468894 7.794831) (xy 436.507116 7.871591) (xy 436.552257 7.944497)
			(xy 436.603933 8.012926) (xy 436.661702 8.076296) (xy 436.725072 8.134065) (xy 436.793501 8.185741)
			(xy 436.866407 8.230882) (xy 436.943167 8.269104) (xy 437.023126 8.30008) (xy 437.105602 8.323547)
			(xy 437.189892 8.339303) (xy 437.275275 8.347215) (xy 437.361025 8.347215) (xy 437.446408 8.339303)
			(xy 437.530698 8.323547) (xy 437.613174 8.30008) (xy 437.693133 8.269104) (xy 437.713806 8.25881)
			(xy 438.87644 8.25881) (xy 438.87644 9.12241) (xy 438.876944 9.151946) (xy 438.884988 9.210468) (xy 438.900925 9.26735)
			(xy 438.92446 9.321532) (xy 438.955153 9.372005) (xy 438.992433 9.417828) (xy 439.035605 9.458148)
			(xy 439.083865 9.492214) (xy 439.136315 9.519391) (xy 439.191976 9.539173) (xy 439.249813 9.551192)
			(xy 439.308748 9.555223) (xy 439.367683 9.551192) (xy 439.42552 9.539173) (xy 439.481181 9.519391)
			(xy 439.533631 9.492214) (xy 439.581891 9.458148) (xy 439.625063 9.417828) (xy 439.662343 9.372005)
			(xy 439.693036 9.321532) (xy 439.716571 9.26735) (xy 439.732508 9.210468) (xy 439.740552 9.151946)
			(xy 439.741056 9.12241) (xy 439.741056 8.25881) (xy 439.740552 8.229274) (xy 439.732508 8.170752)
			(xy 439.716571 8.11387) (xy 439.693036 8.059688) (xy 439.662343 8.009215) (xy 439.625063 7.963392)
			(xy 439.581891 7.923072) (xy 439.533631 7.889006) (xy 439.481181 7.861829) (xy 439.42552 7.842047)
			(xy 439.367683 7.830028) (xy 439.308748 7.825997) (xy 439.249813 7.830028) (xy 439.191976 7.842047)
			(xy 439.136315 7.861829) (xy 439.083865 7.889006) (xy 439.035605 7.923072) (xy 438.992433 7.963392)
			(xy 438.955153 8.009215) (xy 438.92446 8.059688) (xy 438.900925 8.11387) (xy 438.884988 8.170752)
			(xy 438.876944 8.229274) (xy 438.87644 8.25881) (xy 437.713806 8.25881) (xy 437.769893 8.230882)
			(xy 437.842799 8.185741) (xy 437.911228 8.134065) (xy 437.974598 8.076296) (xy 438.032367 8.012926)
			(xy 438.084043 7.944497) (xy 438.129184 7.871591) (xy 438.167406 7.794831) (xy 438.198382 7.714872)
			(xy 438.221849 7.632396) (xy 438.237605 7.548106) (xy 438.245517 7.462723) (xy 438.246012 7.419848)
			(xy 438.245517 7.376973) (xy 442.740783 7.376973) (xy 442.740783 7.462723) (xy 442.748695 7.548106)
			(xy 442.764451 7.632396) (xy 442.787918 7.714872) (xy 442.818894 7.794831) (xy 442.857116 7.871591)
			(xy 442.902257 7.944497) (xy 442.953933 8.012926) (xy 443.011702 8.076296) (xy 443.075072 8.134065)
			(xy 443.143501 8.185741) (xy 443.216407 8.230882) (xy 443.293167 8.269104) (xy 443.373126 8.30008)
			(xy 443.455602 8.323547) (xy 443.539892 8.339303) (xy 443.625275 8.347215) (xy 443.711025 8.347215)
			(xy 443.796408 8.339303) (xy 443.880698 8.323547) (xy 443.963174 8.30008) (xy 444.043133 8.269104)
			(xy 444.119893 8.230882) (xy 444.192799 8.185741) (xy 444.261228 8.134065) (xy 444.324598 8.076296)
			(xy 444.382367 8.012926) (xy 444.434043 7.944497) (xy 444.479184 7.871591) (xy 444.517406 7.794831)
			(xy 444.548382 7.714872) (xy 444.571849 7.632396) (xy 444.587605 7.548106) (xy 444.595517 7.462723)
			(xy 444.596012 7.419848) (xy 444.595517 7.376973) (xy 444.587605 7.29159) (xy 444.571849 7.2073)
			(xy 444.548382 7.124824) (xy 444.517406 7.044865) (xy 444.479184 6.968105) (xy 444.434043 6.895199)
			(xy 444.382367 6.82677) (xy 444.324598 6.7634) (xy 444.261228 6.705631) (xy 444.192799 6.653955)
			(xy 444.119893 6.608814) (xy 444.043133 6.570592) (xy 443.963174 6.539616) (xy 443.880698 6.516149)
			(xy 443.796408 6.500393) (xy 443.711025 6.492481) (xy 443.625275 6.492481) (xy 443.539892 6.500393)
			(xy 443.455602 6.516149) (xy 443.373126 6.539616) (xy 443.293167 6.570592) (xy 443.216407 6.608814)
			(xy 443.143501 6.653955) (xy 443.075072 6.705631) (xy 443.011702 6.7634) (xy 442.953933 6.82677)
			(xy 442.902257 6.895199) (xy 442.857116 6.968105) (xy 442.818894 7.044865) (xy 442.787918 7.124824)
			(xy 442.764451 7.2073) (xy 442.748695 7.29159) (xy 442.740783 7.376973) (xy 438.245517 7.376973)
			(xy 438.237605 7.29159) (xy 438.221849 7.2073) (xy 438.198382 7.124824) (xy 438.167406 7.044865)
			(xy 438.129184 6.968105) (xy 438.084043 6.895199) (xy 438.032367 6.82677) (xy 437.974598 6.7634)
			(xy 437.911228 6.705631) (xy 437.842799 6.653955) (xy 437.769893 6.608814) (xy 437.693133 6.570592)
			(xy 437.613174 6.539616) (xy 437.530698 6.516149) (xy 437.446408 6.500393) (xy 437.361025 6.492481)
			(xy 437.275275 6.492481) (xy 437.189892 6.500393) (xy 437.105602 6.516149) (xy 437.023126 6.539616)
			(xy 436.943167 6.570592) (xy 436.866407 6.608814) (xy 436.793501 6.653955) (xy 436.725072 6.705631)
			(xy 436.661702 6.7634) (xy 436.603933 6.82677) (xy 436.552257 6.895199) (xy 436.507116 6.968105)
			(xy 436.468894 7.044865) (xy 436.437918 7.124824) (xy 436.414451 7.2073) (xy 436.398695 7.29159)
			(xy 436.390783 7.376973) (xy 393.856731 7.376973) (xy 393.848819 7.29159) (xy 393.833063 7.2073)
			(xy 393.809596 7.124824) (xy 393.77862 7.044865) (xy 393.740398 6.968105) (xy 393.695257 6.895199)
			(xy 393.643581 6.82677) (xy 393.585812 6.7634) (xy 393.522442 6.705631) (xy 393.454013 6.653955)
			(xy 393.381107 6.608814) (xy 393.304347 6.570592) (xy 393.224388 6.539616) (xy 393.141912 6.516149)
			(xy 393.057622 6.500393) (xy 392.972239 6.492481) (xy 392.886489 6.492481) (xy 392.801106 6.500393)
			(xy 392.716816 6.516149) (xy 392.63434 6.539616) (xy 392.554381 6.570592) (xy 392.477621 6.608814)
			(xy 392.404715 6.653955) (xy 392.336286 6.705631) (xy 392.272916 6.7634) (xy 392.215147 6.82677)
			(xy 392.163471 6.895199) (xy 392.11833 6.968105) (xy 392.080108 7.044865) (xy 392.049132 7.124824)
			(xy 392.025665 7.2073) (xy 392.009909 7.29159) (xy 392.001997 7.376973) (xy 387.506731 7.376973)
			(xy 387.498819 7.29159) (xy 387.483063 7.2073) (xy 387.459596 7.124824) (xy 387.42862 7.044865) (xy 387.390398 6.968105)
			(xy 387.345257 6.895199) (xy 387.293581 6.82677) (xy 387.235812 6.7634) (xy 387.172442 6.705631)
			(xy 387.104013 6.653955) (xy 387.031107 6.608814) (xy 386.954347 6.570592) (xy 386.874388 6.539616)
			(xy 386.791912 6.516149) (xy 386.707622 6.500393) (xy 386.622239 6.492481) (xy 386.536489 6.492481)
			(xy 386.451106 6.500393) (xy 386.366816 6.516149) (xy 386.28434 6.539616) (xy 386.204381 6.570592)
			(xy 386.127621 6.608814) (xy 386.054715 6.653955) (xy 385.986286 6.705631) (xy 385.922916 6.7634)
			(xy 385.865147 6.82677) (xy 385.813471 6.895199) (xy 385.76833 6.968105) (xy 385.730108 7.044865)
			(xy 385.699132 7.124824) (xy 385.675665 7.2073) (xy 385.659909 7.29159) (xy 385.651997 7.376973)
			(xy 365.24438 7.376973) (xy 365.24438 7.191756) (xy 365.243876 7.16222) (xy 365.235832 7.103698)
			(xy 365.219895 7.046816) (xy 365.19636 6.992634) (xy 365.165667 6.942161) (xy 365.128387 6.896338)
			(xy 365.085215 6.856018) (xy 365.036955 6.821952) (xy 364.984505 6.794775) (xy 364.928844 6.774993)
			(xy 364.871007 6.762974) (xy 364.812072 6.758943) (xy 364.753137 6.762974) (xy 364.6953 6.774993)
			(xy 364.639639 6.794775) (xy 364.587189 6.821952) (xy 364.538929 6.856018) (xy 364.495757 6.896338)
			(xy 364.458477 6.942161) (xy 364.427784 6.992634) (xy 364.404249 7.046816) (xy 364.388312 7.103698)
			(xy 364.380268 7.16222) (xy 364.379764 7.191756) (xy 363.21713 7.191756) (xy 363.273217 7.163828)
			(xy 363.346123 7.118687) (xy 363.414552 7.067011) (xy 363.477922 7.009242) (xy 363.535691 6.945872)
			(xy 363.587367 6.877443) (xy 363.632508 6.804537) (xy 363.67073 6.727777) (xy 363.701706 6.647818)
			(xy 363.725173 6.565342) (xy 363.740929 6.481052) (xy 363.748841 6.395669) (xy 363.749336 6.352794)
			(xy 363.748841 6.309919) (xy 368.244107 6.309919) (xy 368.244107 6.395669) (xy 368.252019 6.481052)
			(xy 368.267775 6.565342) (xy 368.291242 6.647818) (xy 368.322218 6.727777) (xy 368.36044 6.804537)
			(xy 368.405581 6.877443) (xy 368.457257 6.945872) (xy 368.515026 7.009242) (xy 368.578396 7.067011)
			(xy 368.646825 7.118687) (xy 368.719731 7.163828) (xy 368.796491 7.20205) (xy 368.87645 7.233026)
			(xy 368.958926 7.256493) (xy 369.043216 7.272249) (xy 369.128599 7.280161) (xy 369.214349 7.280161)
			(xy 369.299732 7.272249) (xy 369.384022 7.256493) (xy 369.466498 7.233026) (xy 369.546457 7.20205)
			(xy 369.623217 7.163828) (xy 369.696123 7.118687) (xy 369.764552 7.067011) (xy 369.827922 7.009242)
			(xy 369.885691 6.945872) (xy 369.937367 6.877443) (xy 369.982508 6.804537) (xy 370.02073 6.727777)
			(xy 370.051706 6.647818) (xy 370.075173 6.565342) (xy 370.090929 6.481052) (xy 370.098841 6.395669)
			(xy 370.099336 6.352794) (xy 370.098841 6.309919) (xy 370.090929 6.224536) (xy 370.075173 6.140246)
			(xy 370.051706 6.05777) (xy 370.02073 5.977811) (xy 369.982508 5.901051) (xy 369.937367 5.828145)
			(xy 369.885691 5.759716) (xy 369.827922 5.696346) (xy 369.764552 5.638577) (xy 369.696123 5.586901)
			(xy 369.623217 5.54176) (xy 369.546457 5.503538) (xy 369.466498 5.472562) (xy 369.384022 5.449095)
			(xy 369.299732 5.433339) (xy 369.214349 5.425427) (xy 369.128599 5.425427) (xy 369.043216 5.433339)
			(xy 368.958926 5.449095) (xy 368.87645 5.472562) (xy 368.796491 5.503538) (xy 368.719731 5.54176)
			(xy 368.646825 5.586901) (xy 368.578396 5.638577) (xy 368.515026 5.696346) (xy 368.457257 5.759716)
			(xy 368.405581 5.828145) (xy 368.36044 5.901051) (xy 368.322218 5.977811) (xy 368.291242 6.05777)
			(xy 368.267775 6.140246) (xy 368.252019 6.224536) (xy 368.244107 6.309919) (xy 363.748841 6.309919)
			(xy 363.740929 6.224536) (xy 363.725173 6.140246) (xy 363.701706 6.05777) (xy 363.67073 5.977811)
			(xy 363.632508 5.901051) (xy 363.587367 5.828145) (xy 363.535691 5.759716) (xy 363.477922 5.696346)
			(xy 363.414552 5.638577) (xy 363.346123 5.586901) (xy 363.273217 5.54176) (xy 363.196457 5.503538)
			(xy 363.116498 5.472562) (xy 363.034022 5.449095) (xy 362.949732 5.433339) (xy 362.864349 5.425427)
			(xy 362.778599 5.425427) (xy 362.693216 5.433339) (xy 362.608926 5.449095) (xy 362.52645 5.472562)
			(xy 362.446491 5.503538) (xy 362.369731 5.54176) (xy 362.296825 5.586901) (xy 362.228396 5.638577)
			(xy 362.165026 5.696346) (xy 362.107257 5.759716) (xy 362.055581 5.828145) (xy 362.01044 5.901051)
			(xy 361.972218 5.977811) (xy 361.941242 6.05777) (xy 361.917775 6.140246) (xy 361.902019 6.224536)
			(xy 361.894107 6.309919) (xy 319.360055 6.309919) (xy 319.352143 6.224536) (xy 319.336387 6.140246)
			(xy 319.31292 6.05777) (xy 319.281944 5.977811) (xy 319.243722 5.901051) (xy 319.198581 5.828145)
			(xy 319.146905 5.759716) (xy 319.089136 5.696346) (xy 319.025766 5.638577) (xy 318.957337 5.586901)
			(xy 318.884431 5.54176) (xy 318.807671 5.503538) (xy 318.727712 5.472562) (xy 318.645236 5.449095)
			(xy 318.560946 5.433339) (xy 318.475563 5.425427) (xy 318.389813 5.425427) (xy 318.30443 5.433339)
			(xy 318.22014 5.449095) (xy 318.137664 5.472562) (xy 318.057705 5.503538) (xy 317.980945 5.54176)
			(xy 317.908039 5.586901) (xy 317.83961 5.638577) (xy 317.77624 5.696346) (xy 317.718471 5.759716)
			(xy 317.666795 5.828145) (xy 317.621654 5.901051) (xy 317.583432 5.977811) (xy 317.552456 6.05777)
			(xy 317.528989 6.140246) (xy 317.513233 6.224536) (xy 317.505321 6.309919) (xy 313.010055 6.309919)
			(xy 313.002143 6.224536) (xy 312.986387 6.140246) (xy 312.96292 6.05777) (xy 312.931944 5.977811)
			(xy 312.893722 5.901051) (xy 312.848581 5.828145) (xy 312.796905 5.759716) (xy 312.739136 5.696346)
			(xy 312.675766 5.638577) (xy 312.607337 5.586901) (xy 312.534431 5.54176) (xy 312.457671 5.503538)
			(xy 312.377712 5.472562) (xy 312.295236 5.449095) (xy 312.210946 5.433339) (xy 312.125563 5.425427)
			(xy 312.039813 5.425427) (xy 311.95443 5.433339) (xy 311.87014 5.449095) (xy 311.787664 5.472562)
			(xy 311.707705 5.503538) (xy 311.630945 5.54176) (xy 311.558039 5.586901) (xy 311.48961 5.638577)
			(xy 311.42624 5.696346) (xy 311.368471 5.759716) (xy 311.316795 5.828145) (xy 311.271654 5.901051)
			(xy 311.233432 5.977811) (xy 311.202456 6.05777) (xy 311.178989 6.140246) (xy 311.163233 6.224536)
			(xy 311.155321 6.309919) (xy 304.348655 6.309919) (xy 304.340743 6.224536) (xy 304.324987 6.140246)
			(xy 304.30152 6.05777) (xy 304.270544 5.977811) (xy 304.232322 5.901051) (xy 304.187181 5.828145)
			(xy 304.135505 5.759716) (xy 304.077736 5.696346) (xy 304.014366 5.638577) (xy 303.945937 5.586901)
			(xy 303.873031 5.54176) (xy 303.796271 5.503538) (xy 303.716312 5.472562) (xy 303.633836 5.449095)
			(xy 303.549546 5.433339) (xy 303.464163 5.425427) (xy 303.378413 5.425427) (xy 303.29303 5.433339)
			(xy 303.20874 5.449095) (xy 303.126264 5.472562) (xy 303.046305 5.503538) (xy 302.969545 5.54176)
			(xy 302.896639 5.586901) (xy 302.82821 5.638577) (xy 302.76484 5.696346) (xy 302.707071 5.759716)
			(xy 302.655395 5.828145) (xy 302.610254 5.901051) (xy 302.572032 5.977811) (xy 302.541056 6.05777)
			(xy 302.517589 6.140246) (xy 302.501833 6.224536) (xy 302.493921 6.309919) (xy 297.998655 6.309919)
			(xy 297.990743 6.224536) (xy 297.974987 6.140246) (xy 297.95152 6.05777) (xy 297.920544 5.977811)
			(xy 297.882322 5.901051) (xy 297.837181 5.828145) (xy 297.785505 5.759716) (xy 297.727736 5.696346)
			(xy 297.664366 5.638577) (xy 297.595937 5.586901) (xy 297.523031 5.54176) (xy 297.446271 5.503538)
			(xy 297.366312 5.472562) (xy 297.283836 5.449095) (xy 297.199546 5.433339) (xy 297.114163 5.425427)
			(xy 297.028413 5.425427) (xy 296.94303 5.433339) (xy 296.85874 5.449095) (xy 296.776264 5.472562)
			(xy 296.696305 5.503538) (xy 296.619545 5.54176) (xy 296.546639 5.586901) (xy 296.47821 5.638577)
			(xy 296.41484 5.696346) (xy 296.357071 5.759716) (xy 296.305395 5.828145) (xy 296.260254 5.901051)
			(xy 296.222032 5.977811) (xy 296.191056 6.05777) (xy 296.167589 6.140246) (xy 296.151833 6.224536)
			(xy 296.143921 6.309919) (xy 216.865975 6.309919) (xy 216.858063 6.224536) (xy 216.842307 6.140246)
			(xy 216.81884 6.05777) (xy 216.787864 5.977811) (xy 216.749642 5.901051) (xy 216.704501 5.828145)
			(xy 216.652825 5.759716) (xy 216.595056 5.696346) (xy 216.531686 5.638577) (xy 216.463257 5.586901)
			(xy 216.390351 5.54176) (xy 216.313591 5.503538) (xy 216.233632 5.472562) (xy 216.151156 5.449095)
			(xy 216.066866 5.433339) (xy 215.981483 5.425427) (xy 215.895733 5.425427) (xy 215.81035 5.433339)
			(xy 215.72606 5.449095) (xy 215.643584 5.472562) (xy 215.563625 5.503538) (xy 215.486865 5.54176)
			(xy 215.413959 5.586901) (xy 215.34553 5.638577) (xy 215.28216 5.696346) (xy 215.224391 5.759716)
			(xy 215.172715 5.828145) (xy 215.127574 5.901051) (xy 215.089352 5.977811) (xy 215.058376 6.05777)
			(xy 215.034909 6.140246) (xy 215.019153 6.224536) (xy 215.011241 6.309919) (xy 210.515975 6.309919)
			(xy 210.508063 6.224536) (xy 210.492307 6.140246) (xy 210.46884 6.05777) (xy 210.437864 5.977811)
			(xy 210.399642 5.901051) (xy 210.354501 5.828145) (xy 210.302825 5.759716) (xy 210.245056 5.696346)
			(xy 210.181686 5.638577) (xy 210.113257 5.586901) (xy 210.040351 5.54176) (xy 209.963591 5.503538)
			(xy 209.883632 5.472562) (xy 209.801156 5.449095) (xy 209.716866 5.433339) (xy 209.631483 5.425427)
			(xy 209.545733 5.425427) (xy 209.46035 5.433339) (xy 209.37606 5.449095) (xy 209.293584 5.472562)
			(xy 209.213625 5.503538) (xy 209.136865 5.54176) (xy 209.063959 5.586901) (xy 208.99553 5.638577)
			(xy 208.93216 5.696346) (xy 208.874391 5.759716) (xy 208.822715 5.828145) (xy 208.777574 5.901051)
			(xy 208.739352 5.977811) (xy 208.708376 6.05777) (xy 208.684909 6.140246) (xy 208.669153 6.224536)
			(xy 208.661241 6.309919) (xy 185.514488 6.309919) (xy 185.514488 5.512054) (xy 185.514028 5.49994)
			(xy 185.506531 5.476899) (xy 185.492285 5.457301) (xy 185.472683 5.44306) (xy 185.44964 5.435569)
			(xy 185.437526 5.435092) (xy 184.825386 5.435092) (xy 184.811416 5.436362) (xy 184.772808 5.418836)
			(xy 184.766211 5.415555) (xy 184.755111 5.405876) (xy 184.750964 5.399786) (xy 184.733849 5.373922)
			(xy 184.69338 5.326925) (xy 184.64661 5.286195) (xy 184.594498 5.252569) (xy 184.538115 5.226736)
			(xy 184.478618 5.209227) (xy 184.41723 5.200402) (xy 184.38622 5.199888) (xy 184.357915 5.200353)
			(xy 184.301788 5.20774) (xy 184.247106 5.22239) (xy 184.194804 5.244052) (xy 184.145776 5.272355)
			(xy 184.100863 5.306816) (xy 184.060832 5.346845) (xy 184.026369 5.391756) (xy 183.998062 5.440782)
			(xy 183.976398 5.493083) (xy 183.961745 5.547764) (xy 183.954355 5.603891) (xy 183.953912 5.632196)
			(xy 182.791278 5.632196) (xy 182.847365 5.604268) (xy 182.920271 5.559127) (xy 182.9887 5.507451)
			(xy 183.05207 5.449682) (xy 183.109839 5.386312) (xy 183.161515 5.317883) (xy 183.206656 5.244977)
			(xy 183.244878 5.168217) (xy 183.275854 5.088258) (xy 183.299321 5.005782) (xy 183.315077 4.921492)
			(xy 183.322989 4.836109) (xy 183.323484 4.793234) (xy 183.322989 4.750359) (xy 187.818255 4.750359)
			(xy 187.818255 4.836109) (xy 187.826167 4.921492) (xy 187.841923 5.005782) (xy 187.86539 5.088258)
			(xy 187.896366 5.168217) (xy 187.934588 5.244977) (xy 187.979729 5.317883) (xy 188.031405 5.386312)
			(xy 188.089174 5.449682) (xy 188.152544 5.507451) (xy 188.220973 5.559127) (xy 188.293879 5.604268)
			(xy 188.370639 5.64249) (xy 188.450598 5.673466) (xy 188.533074 5.696933) (xy 188.617364 5.712689)
			(xy 188.702747 5.720601) (xy 188.788497 5.720601) (xy 188.87388 5.712689) (xy 188.95817 5.696933)
			(xy 189.040646 5.673466) (xy 189.120605 5.64249) (xy 189.197365 5.604268) (xy 189.270271 5.559127)
			(xy 189.3387 5.507451) (xy 189.40207 5.449682) (xy 189.459839 5.386312) (xy 189.511515 5.317883)
			(xy 189.556656 5.244977) (xy 189.594878 5.168217) (xy 189.625854 5.088258) (xy 189.649321 5.005782)
			(xy 189.665077 4.921492) (xy 189.672989 4.836109) (xy 189.673484 4.793234) (xy 189.672989 4.750359)
			(xy 189.665077 4.664976) (xy 189.649321 4.580686) (xy 189.625854 4.49821) (xy 189.594878 4.418251)
			(xy 189.556656 4.341491) (xy 189.511515 4.268585) (xy 189.459839 4.200156) (xy 189.40207 4.136786)
			(xy 189.3387 4.079017) (xy 189.270271 4.027341) (xy 189.197365 3.9822) (xy 189.120605 3.943978) (xy 189.040646 3.913002)
			(xy 188.95817 3.889535) (xy 188.87388 3.873779) (xy 188.788497 3.865867) (xy 188.702747 3.865867)
			(xy 188.617364 3.873779) (xy 188.533074 3.889535) (xy 188.450598 3.913002) (xy 188.370639 3.943978)
			(xy 188.293879 3.9822) (xy 188.220973 4.027341) (xy 188.152544 4.079017) (xy 188.089174 4.136786)
			(xy 188.031405 4.200156) (xy 187.979729 4.268585) (xy 187.934588 4.341491) (xy 187.896366 4.418251)
			(xy 187.86539 4.49821) (xy 187.841923 4.580686) (xy 187.826167 4.664976) (xy 187.818255 4.750359)
			(xy 183.322989 4.750359) (xy 183.315077 4.664976) (xy 183.299321 4.580686) (xy 183.275854 4.49821)
			(xy 183.244878 4.418251) (xy 183.206656 4.341491) (xy 183.161515 4.268585) (xy 183.109839 4.200156)
			(xy 183.05207 4.136786) (xy 182.9887 4.079017) (xy 182.920271 4.027341) (xy 182.847365 3.9822) (xy 182.770605 3.943978)
			(xy 182.690646 3.913002) (xy 182.60817 3.889535) (xy 182.52388 3.873779) (xy 182.438497 3.865867)
			(xy 182.352747 3.865867) (xy 182.267364 3.873779) (xy 182.183074 3.889535) (xy 182.100598 3.913002)
			(xy 182.020639 3.943978) (xy 181.943879 3.9822) (xy 181.870973 4.027341) (xy 181.802544 4.079017)
			(xy 181.739174 4.136786) (xy 181.681405 4.200156) (xy 181.629729 4.268585) (xy 181.584588 4.341491)
			(xy 181.546366 4.418251) (xy 181.51539 4.49821) (xy 181.491923 4.580686) (xy 181.476167 4.664976)
			(xy 181.468255 4.750359) (xy 102.190309 4.750359) (xy 102.182397 4.664976) (xy 102.166641 4.580686)
			(xy 102.143174 4.49821) (xy 102.112198 4.418251) (xy 102.073976 4.341491) (xy 102.028835 4.268585)
			(xy 101.977159 4.200156) (xy 101.91939 4.136786) (xy 101.85602 4.079017) (xy 101.787591 4.027341)
			(xy 101.714685 3.9822) (xy 101.637925 3.943978) (xy 101.557966 3.913002) (xy 101.47549 3.889535)
			(xy 101.3912 3.873779) (xy 101.305817 3.865867) (xy 101.220067 3.865867) (xy 101.134684 3.873779)
			(xy 101.050394 3.889535) (xy 100.967918 3.913002) (xy 100.887959 3.943978) (xy 100.811199 3.9822)
			(xy 100.738293 4.027341) (xy 100.669864 4.079017) (xy 100.606494 4.136786) (xy 100.548725 4.200156)
			(xy 100.497049 4.268585) (xy 100.451908 4.341491) (xy 100.413686 4.418251) (xy 100.38271 4.49821)
			(xy 100.359243 4.580686) (xy 100.343487 4.664976) (xy 100.335575 4.750359) (xy 95.840309 4.750359)
			(xy 95.832397 4.664976) (xy 95.816641 4.580686) (xy 95.793174 4.49821) (xy 95.762198 4.418251) (xy 95.723976 4.341491)
			(xy 95.678835 4.268585) (xy 95.627159 4.200156) (xy 95.56939 4.136786) (xy 95.50602 4.079017) (xy 95.437591 4.027341)
			(xy 95.364685 3.9822) (xy 95.287925 3.943978) (xy 95.207966 3.913002) (xy 95.12549 3.889535) (xy 95.0412 3.873779)
			(xy 94.955817 3.865867) (xy 94.870067 3.865867) (xy 94.784684 3.873779) (xy 94.700394 3.889535) (xy 94.617918 3.913002)
			(xy 94.537959 3.943978) (xy 94.461199 3.9822) (xy 94.388293 4.027341) (xy 94.319864 4.079017) (xy 94.256494 4.136786)
			(xy 94.198725 4.200156) (xy 94.147049 4.268585) (xy 94.101908 4.341491) (xy 94.063686 4.418251) (xy 94.03271 4.49821)
			(xy 94.009243 4.580686) (xy 93.993487 4.664976) (xy 93.985575 4.750359) (xy 0.509016 4.750359) (xy 0.509016 -7.78002)
			(xy 0.509537 -7.835789) (xy 0.517873 -7.947015) (xy 0.534497 -8.057308) (xy 0.559316 -8.166049) (xy 0.592193 -8.272632)
			(xy 0.632942 -8.37646) (xy 0.681336 -8.476953) (xy 0.737105 -8.573548) (xy 0.799937 -8.665705) (xy 0.86948 -8.752909)
			(xy 0.945345 -8.834672) (xy 1.027108 -8.910538) (xy 1.114312 -8.980081) (xy 1.206469 -9.042912) (xy 1.303064 -9.098682)
			(xy 1.403556 -9.147076) (xy 1.507384 -9.187826) (xy 1.613967 -9.220703) (xy 1.722708 -9.245523) (xy 1.833001 -9.262147)
			(xy 1.944227 -9.270482) (xy 1.999996 -9.271) (xy 9.10209 -9.271) (xy 9.15786 -9.270479) (xy 9.269087 -9.262144)
			(xy 9.37938 -9.245521) (xy 9.488123 -9.220702) (xy 9.594707 -9.187826) (xy 9.698536 -9.147077) (xy 9.79903 -9.098683)
			(xy 9.895626 -9.042915) (xy 9.987784 -8.980083) (xy 10.07499 -8.910541) (xy 10.156754 -8.834676)
			(xy 10.232621 -8.752912) (xy 10.302165 -8.665708) (xy 10.364999 -8.573551) (xy 10.420769 -8.476956)
			(xy 10.469165 -8.376463) (xy 10.509916 -8.272635) (xy 10.542794 -8.166052) (xy 10.567616 -8.05731)
			(xy 10.584241 -7.947017) (xy 10.592578 -7.83579) (xy 10.59307 -7.78002) (xy 10.59307 0.40005) (xy 10.593555 0.470432)
			(xy 10.601447 0.610976) (xy 10.617208 0.750856) (xy 10.640787 0.889632) (xy 10.67211 1.026868) (xy 10.711079 1.162131)
			(xy 10.757571 1.294997) (xy 10.811439 1.425046) (xy 10.872515 1.551871) (xy 10.940606 1.675072) (xy 11.015497 1.794261)
			(xy 11.096954 1.909063) (xy 11.184719 2.019118) (xy 11.278518 2.124078) (xy 11.378053 2.223614) (xy 11.483014 2.317412)
			(xy 11.593068 2.405178) (xy 11.707871 2.486634) (xy 11.82706 2.561525) (xy 11.950261 2.629616) (xy 12.077085 2.690692)
			(xy 12.207135 2.74456) (xy 12.340001 2.791052) (xy 12.475264 2.83002) (xy 12.6125 2.861343) (xy 12.751276 2.884922)
			(xy 12.891156 2.900683) (xy 13.0317 2.908575) (xy 13.102082 2.909062) (xy 81.701894 2.909062) (xy 81.772277 2.908568)
			(xy 81.912821 2.900676) (xy 82.052702 2.884916) (xy 82.191479 2.861337) (xy 82.328715 2.830015) (xy 82.46398 2.791046)
			(xy 82.596846 2.744555) (xy 82.726897 2.690688) (xy 82.853723 2.629613) (xy 82.976925 2.561522) (xy 83.096116 2.486632)
			(xy 83.210919 2.405176) (xy 83.320975 2.317411) (xy 83.425937 2.223613) (xy 83.439191 2.210359) (xy 93.985575 2.210359)
			(xy 93.985575 2.296109) (xy 93.993487 2.381492) (xy 94.009243 2.465782) (xy 94.03271 2.548258) (xy 94.063686 2.628217)
			(xy 94.101908 2.704977) (xy 94.147049 2.777883) (xy 94.198725 2.846312) (xy 94.256494 2.909682) (xy 94.319864 2.967451)
			(xy 94.388293 3.019127) (xy 94.461199 3.064268) (xy 94.537959 3.10249) (xy 94.617918 3.133466) (xy 94.700394 3.156933)
			(xy 94.784684 3.172689) (xy 94.870067 3.180601) (xy 94.955817 3.180601) (xy 95.0412 3.172689) (xy 95.12549 3.156933)
			(xy 95.207966 3.133466) (xy 95.287925 3.10249) (xy 95.308598 3.092196) (xy 98.842576 3.092196) (xy 98.842576 3.955796)
			(xy 98.84308 3.985332) (xy 98.851124 4.043854) (xy 98.867061 4.100736) (xy 98.890596 4.154918) (xy 98.921289 4.205391)
			(xy 98.958569 4.251214) (xy 99.001741 4.291534) (xy 99.050001 4.3256) (xy 99.102451 4.352777) (xy 99.158112 4.372559)
			(xy 99.215949 4.384578) (xy 99.274884 4.388609) (xy 99.333819 4.384578) (xy 99.391656 4.372559) (xy 99.447317 4.352777)
			(xy 99.499767 4.3256) (xy 99.548027 4.291534) (xy 99.591199 4.251214) (xy 99.628479 4.205391) (xy 99.659172 4.154918)
			(xy 99.682707 4.100736) (xy 99.698644 4.043854) (xy 99.706688 3.985332) (xy 99.707192 3.955796) (xy 99.707192 3.092196)
			(xy 99.706688 3.06266) (xy 99.698644 3.004138) (xy 99.682707 2.947256) (xy 99.659172 2.893074) (xy 99.628479 2.842601)
			(xy 99.591199 2.796778) (xy 99.548027 2.756458) (xy 99.499767 2.722392) (xy 99.447317 2.695215) (xy 99.391656 2.675433)
			(xy 99.333819 2.663414) (xy 99.274884 2.659383) (xy 99.215949 2.663414) (xy 99.158112 2.675433) (xy 99.102451 2.695215)
			(xy 99.050001 2.722392) (xy 99.001741 2.756458) (xy 98.958569 2.796778) (xy 98.921289 2.842601) (xy 98.890596 2.893074)
			(xy 98.867061 2.947256) (xy 98.851124 3.004138) (xy 98.84308 3.06266) (xy 98.842576 3.092196) (xy 95.308598 3.092196)
			(xy 95.364685 3.064268) (xy 95.437591 3.019127) (xy 95.50602 2.967451) (xy 95.56939 2.909682) (xy 95.627159 2.846312)
			(xy 95.678835 2.777883) (xy 95.723976 2.704977) (xy 95.762198 2.628217) (xy 95.793174 2.548258) (xy 95.816641 2.465782)
			(xy 95.832397 2.381492) (xy 95.840309 2.296109) (xy 95.840804 2.253234) (xy 95.840309 2.210359) (xy 100.335575 2.210359)
			(xy 100.335575 2.296109) (xy 100.343487 2.381492) (xy 100.359243 2.465782) (xy 100.38271 2.548258)
			(xy 100.413686 2.628217) (xy 100.451908 2.704977) (xy 100.497049 2.777883) (xy 100.548725 2.846312)
			(xy 100.606494 2.909682) (xy 100.669864 2.967451) (xy 100.738293 3.019127) (xy 100.811199 3.064268)
			(xy 100.887959 3.10249) (xy 100.967918 3.133466) (xy 101.050394 3.156933) (xy 101.134684 3.172689)
			(xy 101.220067 3.180601) (xy 101.305817 3.180601) (xy 101.3912 3.172689) (xy 101.47549 3.156933)
			(xy 101.557966 3.133466) (xy 101.637925 3.10249) (xy 101.714685 3.064268) (xy 101.787591 3.019127)
			(xy 101.85602 2.967451) (xy 101.91939 2.909682) (xy 101.977159 2.846312) (xy 102.028835 2.777883)
			(xy 102.073976 2.704977) (xy 102.112198 2.628217) (xy 102.143174 2.548258) (xy 102.166641 2.465782)
			(xy 102.182397 2.381492) (xy 102.190309 2.296109) (xy 102.190804 2.253234) (xy 102.190309 2.210359)
			(xy 181.468255 2.210359) (xy 181.468255 2.296109) (xy 181.476167 2.381492) (xy 181.491923 2.465782)
			(xy 181.51539 2.548258) (xy 181.546366 2.628217) (xy 181.584588 2.704977) (xy 181.629729 2.777883)
			(xy 181.681405 2.846312) (xy 181.739174 2.909682) (xy 181.802544 2.967451) (xy 181.870973 3.019127)
			(xy 181.943879 3.064268) (xy 182.020639 3.10249) (xy 182.100598 3.133466) (xy 182.183074 3.156933)
			(xy 182.267364 3.172689) (xy 182.352747 3.180601) (xy 182.438497 3.180601) (xy 182.52388 3.172689)
			(xy 182.60817 3.156933) (xy 182.690646 3.133466) (xy 182.770605 3.10249) (xy 182.791278 3.092196)
			(xy 183.953912 3.092196) (xy 183.953912 3.955796) (xy 183.954416 3.985332) (xy 183.96246 4.043854)
			(xy 183.978397 4.100736) (xy 184.001932 4.154918) (xy 184.032625 4.205391) (xy 184.069905 4.251214)
			(xy 184.113077 4.291534) (xy 184.161337 4.3256) (xy 184.213787 4.352777) (xy 184.269448 4.372559)
			(xy 184.327285 4.384578) (xy 184.38622 4.388609) (xy 184.445155 4.384578) (xy 184.502992 4.372559)
			(xy 184.558653 4.352777) (xy 184.611103 4.3256) (xy 184.659363 4.291534) (xy 184.702535 4.251214)
			(xy 184.739815 4.205391) (xy 184.770508 4.154918) (xy 184.794043 4.100736) (xy 184.80998 4.043854)
			(xy 184.818024 3.985332) (xy 184.818528 3.955796) (xy 184.818528 3.769919) (xy 208.661241 3.769919)
			(xy 208.661241 3.855669) (xy 208.669153 3.941052) (xy 208.684909 4.025342) (xy 208.708376 4.107818)
			(xy 208.739352 4.187777) (xy 208.777574 4.264537) (xy 208.822715 4.337443) (xy 208.874391 4.405872)
			(xy 208.93216 4.469242) (xy 208.99553 4.527011) (xy 209.063959 4.578687) (xy 209.136865 4.623828)
			(xy 209.213625 4.66205) (xy 209.293584 4.693026) (xy 209.37606 4.716493) (xy 209.46035 4.732249)
			(xy 209.545733 4.740161) (xy 209.631483 4.740161) (xy 209.716866 4.732249) (xy 209.801156 4.716493)
			(xy 209.883632 4.693026) (xy 209.963591 4.66205) (xy 210.040351 4.623828) (xy 210.113257 4.578687)
			(xy 210.168864 4.536694) (xy 212.819996 4.536694) (xy 212.819996 5.633974) (xy 212.820529 5.646058)
			(xy 212.827973 5.66905) (xy 212.842144 5.688627) (xy 212.861661 5.70288) (xy 212.884622 5.71042)
			(xy 212.896704 5.710936) (xy 213.508844 5.710936) (xy 213.512908 5.710682) (xy 213.518925 5.710617)
			(xy 213.530731 5.712918) (xy 213.536276 5.715254) (xy 213.562946 5.727192) (xy 213.56961 5.730449)
			(xy 213.580841 5.74013) (xy 213.585044 5.746242) (xy 213.60215 5.772247) (xy 213.642596 5.819558)
			(xy 213.689408 5.86058) (xy 213.741619 5.894465) (xy 213.798149 5.920513) (xy 213.85783 5.938186)
			(xy 213.919429 5.947119) (xy 213.95055 5.947664) (xy 213.978862 5.947246) (xy 214.035 5.939852) (xy 214.089695 5.925197)
			(xy 214.142009 5.903532) (xy 214.19105 5.875226) (xy 214.235979 5.840763) (xy 214.276027 5.800734)
			(xy 214.310511 5.755822) (xy 214.33884 5.706794) (xy 214.360531 5.65449) (xy 214.375212 5.599803)
			(xy 214.382633 5.543668) (xy 214.383112 5.515356) (xy 214.383112 4.651756) (xy 214.382706 4.623439)
			(xy 214.375306 4.567289) (xy 214.360638 4.512587) (xy 214.338953 4.460268) (xy 214.310623 4.411228)
			(xy 214.276132 4.366307) (xy 214.236072 4.326274) (xy 214.191127 4.291814) (xy 214.142068 4.263517)
			(xy 214.089734 4.241868) (xy 214.035022 4.227237) (xy 213.978868 4.219875) (xy 213.95055 4.219448)
			(xy 213.919177 4.220047) (xy 213.857087 4.229101) (xy 213.796955 4.247025) (xy 213.740042 4.273445)
			(xy 213.687541 4.307806) (xy 213.640552 4.349389) (xy 213.600059 4.39732) (xy 213.583012 4.423664)
			(xy 213.578952 4.429808) (xy 213.56798 4.439619) (xy 213.561422 4.442968) (xy 213.52256 4.461002)
			(xy 213.508844 4.459732) (xy 212.896704 4.459732) (xy 212.884592 4.46012) (xy 212.861559 4.467622)
			(xy 212.841983 4.48189) (xy 212.82779 4.50152) (xy 212.820375 4.524581) (xy 212.819996 4.536694)
			(xy 210.168864 4.536694) (xy 210.181686 4.527011) (xy 210.245056 4.469242) (xy 210.302825 4.405872)
			(xy 210.354501 4.337443) (xy 210.399642 4.264537) (xy 210.437864 4.187777) (xy 210.46884 4.107818)
			(xy 210.492307 4.025342) (xy 210.508063 3.941052) (xy 210.515975 3.855669) (xy 210.51647 3.812794)
			(xy 210.515975 3.769919) (xy 215.011241 3.769919) (xy 215.011241 3.855669) (xy 215.019153 3.941052)
			(xy 215.034909 4.025342) (xy 215.058376 4.107818) (xy 215.089352 4.187777) (xy 215.127574 4.264537)
			(xy 215.172715 4.337443) (xy 215.224391 4.405872) (xy 215.28216 4.469242) (xy 215.34553 4.527011)
			(xy 215.413959 4.578687) (xy 215.486865 4.623828) (xy 215.563625 4.66205) (xy 215.643584 4.693026)
			(xy 215.72606 4.716493) (xy 215.81035 4.732249) (xy 215.895733 4.740161) (xy 215.981483 4.740161)
			(xy 216.066866 4.732249) (xy 216.151156 4.716493) (xy 216.233632 4.693026) (xy 216.313591 4.66205)
			(xy 216.390351 4.623828) (xy 216.463257 4.578687) (xy 216.531686 4.527011) (xy 216.595056 4.469242)
			(xy 216.652825 4.405872) (xy 216.704501 4.337443) (xy 216.749642 4.264537) (xy 216.787864 4.187777)
			(xy 216.81884 4.107818) (xy 216.842307 4.025342) (xy 216.858063 3.941052) (xy 216.865975 3.855669)
			(xy 216.86647 3.812794) (xy 216.865975 3.769919) (xy 296.143921 3.769919) (xy 296.143921 3.855669)
			(xy 296.151833 3.941052) (xy 296.167589 4.025342) (xy 296.191056 4.107818) (xy 296.222032 4.187777)
			(xy 296.260254 4.264537) (xy 296.305395 4.337443) (xy 296.357071 4.405872) (xy 296.41484 4.469242)
			(xy 296.47821 4.527011) (xy 296.546639 4.578687) (xy 296.619545 4.623828) (xy 296.696305 4.66205)
			(xy 296.776264 4.693026) (xy 296.85874 4.716493) (xy 296.94303 4.732249) (xy 297.028413 4.740161)
			(xy 297.114163 4.740161) (xy 297.199546 4.732249) (xy 297.283836 4.716493) (xy 297.366312 4.693026)
			(xy 297.446271 4.66205) (xy 297.466944 4.651756) (xy 298.629324 4.651756) (xy 298.629324 5.515356)
			(xy 298.629777 5.543673) (xy 298.637167 5.599822) (xy 298.651826 5.654526) (xy 298.673504 5.706846)
			(xy 298.701828 5.755888) (xy 298.736314 5.800811) (xy 298.776371 5.840846) (xy 298.821313 5.875307)
			(xy 298.870371 5.903604) (xy 298.922704 5.925252) (xy 298.977415 5.93988) (xy 299.033569 5.947239)
			(xy 299.061886 5.947664) (xy 299.093352 5.947125) (xy 299.15562 5.938002) (xy 299.215907 5.919946)
			(xy 299.272938 5.89334) (xy 299.325509 5.858745) (xy 299.372508 5.816894) (xy 299.412942 5.768669)
			(xy 299.429932 5.742178) (xy 299.433953 5.736121) (xy 299.444801 5.72645) (xy 299.451268 5.723128)
			(xy 299.489368 5.70484) (xy 299.501052 5.705856) (xy 300.113192 5.705856) (xy 300.125295 5.705378)
			(xy 300.148312 5.697887) (xy 300.167881 5.68364) (xy 300.182078 5.664035) (xy 300.189509 5.640998)
			(xy 300.1899 5.628894) (xy 300.1899 4.531614) (xy 300.189381 4.519529) (xy 300.181933 4.496536) (xy 300.167759 4.476959)
			(xy 300.148238 4.462707) (xy 300.125275 4.455167) (xy 300.113192 4.454652) (xy 299.501052 4.454652)
			(xy 299.487082 4.455922) (xy 299.448474 4.438396) (xy 299.441866 4.435135) (xy 299.430772 4.425442)
			(xy 299.42663 4.419346) (xy 299.409517 4.39348) (xy 299.369051 4.34648) (xy 299.322281 4.305748)
			(xy 299.270168 4.272121) (xy 299.213784 4.246288) (xy 299.154286 4.228781) (xy 299.092896 4.21996)
			(xy 299.061886 4.219448) (xy 299.033575 4.219887) (xy 298.977436 4.227277) (xy 298.922742 4.241929)
			(xy 298.870426 4.263591) (xy 298.821385 4.291894) (xy 298.776455 4.326354) (xy 298.736406 4.366382)
			(xy 298.701922 4.411293) (xy 298.673593 4.46032) (xy 298.651903 4.512623) (xy 298.637222 4.56731)
			(xy 298.629802 4.623445) (xy 298.629324 4.651756) (xy 297.466944 4.651756) (xy 297.523031 4.623828)
			(xy 297.595937 4.578687) (xy 297.664366 4.527011) (xy 297.727736 4.469242) (xy 297.785505 4.405872)
			(xy 297.837181 4.337443) (xy 297.882322 4.264537) (xy 297.920544 4.187777) (xy 297.95152 4.107818)
			(xy 297.974987 4.025342) (xy 297.990743 3.941052) (xy 297.998655 3.855669) (xy 297.99915 3.812794)
			(xy 297.998655 3.769919) (xy 302.493921 3.769919) (xy 302.493921 3.855669) (xy 302.501833 3.941052)
			(xy 302.517589 4.025342) (xy 302.541056 4.107818) (xy 302.572032 4.187777) (xy 302.610254 4.264537)
			(xy 302.655395 4.337443) (xy 302.707071 4.405872) (xy 302.76484 4.469242) (xy 302.82821 4.527011)
			(xy 302.896639 4.578687) (xy 302.969545 4.623828) (xy 303.046305 4.66205) (xy 303.126264 4.693026)
			(xy 303.20874 4.716493) (xy 303.29303 4.732249) (xy 303.378413 4.740161) (xy 303.464163 4.740161)
			(xy 303.549546 4.732249) (xy 303.633836 4.716493) (xy 303.716312 4.693026) (xy 303.796271 4.66205)
			(xy 303.873031 4.623828) (xy 303.945937 4.578687) (xy 304.014366 4.527011) (xy 304.077736 4.469242)
			(xy 304.135505 4.405872) (xy 304.187181 4.337443) (xy 304.232322 4.264537) (xy 304.270544 4.187777)
			(xy 304.30152 4.107818) (xy 304.324987 4.025342) (xy 304.340743 3.941052) (xy 304.348655 3.855669)
			(xy 304.34915 3.812794) (xy 304.348655 3.769919) (xy 311.155321 3.769919) (xy 311.155321 3.855669)
			(xy 311.163233 3.941052) (xy 311.178989 4.025342) (xy 311.202456 4.107818) (xy 311.233432 4.187777)
			(xy 311.271654 4.264537) (xy 311.316795 4.337443) (xy 311.368471 4.405872) (xy 311.42624 4.469242)
			(xy 311.48961 4.527011) (xy 311.558039 4.578687) (xy 311.630945 4.623828) (xy 311.707705 4.66205)
			(xy 311.787664 4.693026) (xy 311.87014 4.716493) (xy 311.95443 4.732249) (xy 312.039813 4.740161)
			(xy 312.125563 4.740161) (xy 312.210946 4.732249) (xy 312.295236 4.716493) (xy 312.377712 4.693026)
			(xy 312.457671 4.66205) (xy 312.534431 4.623828) (xy 312.607337 4.578687) (xy 312.662944 4.536694)
			(xy 315.314076 4.536694) (xy 315.314076 5.633974) (xy 315.31453 5.646066) (xy 315.321984 5.669072)
			(xy 315.336173 5.688655) (xy 315.355711 5.702905) (xy 315.378694 5.710431) (xy 315.390784 5.710936)
			(xy 316.002924 5.710936) (xy 316.006988 5.710682) (xy 316.013005 5.71059) (xy 316.024813 5.71291)
			(xy 316.030356 5.715254) (xy 316.057026 5.727192) (xy 316.063688 5.730455) (xy 316.07492 5.740132)
			(xy 316.079124 5.746242) (xy 316.096177 5.772284) (xy 316.136632 5.819594) (xy 316.183453 5.860613)
			(xy 316.235673 5.894495) (xy 316.292211 5.920537) (xy 316.3519 5.938202) (xy 316.413506 5.947124)
			(xy 316.44463 5.947664) (xy 316.472941 5.947228) (xy 316.529079 5.939836) (xy 316.583773 5.925183)
			(xy 316.636088 5.90352) (xy 316.685129 5.875216) (xy 316.730058 5.840756) (xy 316.770106 5.800728)
			(xy 316.80459 5.755817) (xy 316.83292 5.706791) (xy 316.854611 5.654487) (xy 316.869292 5.599801)
			(xy 316.876713 5.543667) (xy 316.877192 5.515356) (xy 316.877192 4.651756) (xy 316.876806 4.623438)
			(xy 316.869405 4.567287) (xy 316.854736 4.512583) (xy 316.83305 4.460263) (xy 316.804718 4.411222)
			(xy 316.770226 4.3663) (xy 316.730163 4.326267) (xy 316.685217 4.291807) (xy 316.636155 4.263511)
			(xy 316.583819 4.241863) (xy 316.529105 4.227234) (xy 316.472949 4.219874) (xy 316.44463 4.219448)
			(xy 316.413256 4.220032) (xy 316.351166 4.229088) (xy 316.291034 4.247015) (xy 316.234121 4.273438)
			(xy 316.18162 4.307801) (xy 316.134631 4.349386) (xy 316.094139 4.39732) (xy 316.077092 4.423664)
			(xy 316.073038 4.429812) (xy 316.062062 4.439621) (xy 316.055502 4.442968) (xy 316.01664 4.461002)
			(xy 316.002924 4.459732) (xy 315.390784 4.459732) (xy 315.378671 4.460103) (xy 315.355638 4.467611)
			(xy 315.336062 4.481883) (xy 315.321869 4.501516) (xy 315.314455 4.524579) (xy 315.314076 4.536694)
			(xy 312.662944 4.536694) (xy 312.675766 4.527011) (xy 312.739136 4.469242) (xy 312.796905 4.405872)
			(xy 312.848581 4.337443) (xy 312.893722 4.264537) (xy 312.931944 4.187777) (xy 312.96292 4.107818)
			(xy 312.986387 4.025342) (xy 313.002143 3.941052) (xy 313.010055 3.855669) (xy 313.01055 3.812794)
			(xy 313.010055 3.769919) (xy 317.505321 3.769919) (xy 317.505321 3.855669) (xy 317.513233 3.941052)
			(xy 317.528989 4.025342) (xy 317.552456 4.107818) (xy 317.583432 4.187777) (xy 317.621654 4.264537)
			(xy 317.666795 4.337443) (xy 317.718471 4.405872) (xy 317.77624 4.469242) (xy 317.83961 4.527011)
			(xy 317.908039 4.578687) (xy 317.980945 4.623828) (xy 318.057705 4.66205) (xy 318.137664 4.693026)
			(xy 318.22014 4.716493) (xy 318.30443 4.732249) (xy 318.389813 4.740161) (xy 318.475563 4.740161)
			(xy 318.560946 4.732249) (xy 318.645236 4.716493) (xy 318.727712 4.693026) (xy 318.807671 4.66205)
			(xy 318.884431 4.623828) (xy 318.957337 4.578687) (xy 319.025766 4.527011) (xy 319.089136 4.469242)
			(xy 319.146905 4.405872) (xy 319.198581 4.337443) (xy 319.243722 4.264537) (xy 319.281944 4.187777)
			(xy 319.31292 4.107818) (xy 319.336387 4.025342) (xy 319.352143 3.941052) (xy 319.360055 3.855669)
			(xy 319.36055 3.812794) (xy 319.360055 3.769919) (xy 361.894107 3.769919) (xy 361.894107 3.855669)
			(xy 361.902019 3.941052) (xy 361.917775 4.025342) (xy 361.941242 4.107818) (xy 361.972218 4.187777)
			(xy 362.01044 4.264537) (xy 362.055581 4.337443) (xy 362.107257 4.405872) (xy 362.165026 4.469242)
			(xy 362.228396 4.527011) (xy 362.296825 4.578687) (xy 362.369731 4.623828) (xy 362.446491 4.66205)
			(xy 362.52645 4.693026) (xy 362.608926 4.716493) (xy 362.693216 4.732249) (xy 362.778599 4.740161)
			(xy 362.864349 4.740161) (xy 362.949732 4.732249) (xy 363.034022 4.716493) (xy 363.116498 4.693026)
			(xy 363.196457 4.66205) (xy 363.21713 4.651756) (xy 364.379764 4.651756) (xy 364.379764 5.515356)
			(xy 364.380276 5.54366) (xy 364.387659 5.599784) (xy 364.402305 5.654464) (xy 364.423963 5.706764)
			(xy 364.452262 5.75579) (xy 364.486719 5.800703) (xy 364.526743 5.840733) (xy 364.57165 5.875197)
			(xy 364.620671 5.903505) (xy 364.672968 5.925172) (xy 364.727646 5.939827) (xy 364.783768 5.947219)
			(xy 364.812072 5.947664) (xy 364.843538 5.947114) (xy 364.905805 5.937993) (xy 364.966091 5.919939)
			(xy 365.023123 5.893335) (xy 365.075694 5.858742) (xy 365.122694 5.816892) (xy 365.163128 5.768669)
			(xy 365.180118 5.742178) (xy 365.184143 5.736124) (xy 365.194988 5.726451) (xy 365.201454 5.723128)
			(xy 365.239554 5.70484) (xy 365.251238 5.705856) (xy 365.863378 5.705856) (xy 365.8755 5.705421)
			(xy 365.898559 5.697934) (xy 365.918175 5.683687) (xy 365.932427 5.664074) (xy 365.939919 5.641016)
			(xy 365.94034 5.628894) (xy 365.94034 4.836973) (xy 385.651997 4.836973) (xy 385.651997 4.922723)
			(xy 385.659909 5.008106) (xy 385.675665 5.092396) (xy 385.699132 5.174872) (xy 385.730108 5.254831)
			(xy 385.76833 5.331591) (xy 385.813471 5.404497) (xy 385.865147 5.472926) (xy 385.922916 5.536296)
			(xy 385.986286 5.594065) (xy 386.054715 5.645741) (xy 386.127621 5.690882) (xy 386.204381 5.729104)
			(xy 386.28434 5.76008) (xy 386.366816 5.783547) (xy 386.451106 5.799303) (xy 386.536489 5.807215)
			(xy 386.622239 5.807215) (xy 386.707622 5.799303) (xy 386.791912 5.783547) (xy 386.874388 5.76008)
			(xy 386.954347 5.729104) (xy 387.031107 5.690882) (xy 387.104013 5.645741) (xy 387.15962 5.603748)
			(xy 389.810752 5.603748) (xy 389.810752 6.701028) (xy 389.811239 6.7131) (xy 389.818705 6.736061)
			(xy 389.832897 6.755595) (xy 389.852428 6.76979) (xy 389.875388 6.777259) (xy 389.88746 6.777736)
			(xy 390.503664 6.777736) (xy 390.509681 6.777657) (xy 390.521488 6.779968) (xy 390.527032 6.782308)
			(xy 390.553702 6.794246) (xy 390.560368 6.7975) (xy 390.571596 6.807184) (xy 390.5758 6.813296) (xy 390.592846 6.839353)
			(xy 390.633287 6.886699) (xy 390.680099 6.927757) (xy 390.732316 6.961676) (xy 390.788857 6.987757)
			(xy 390.848554 7.005458) (xy 390.910173 7.014416) (xy 390.941306 7.014972) (xy 390.969627 7.014504)
			(xy 391.025784 7.007111) (xy 391.080496 6.99245) (xy 391.132826 6.970774) (xy 391.18188 6.942453)
			(xy 391.226817 6.907972) (xy 391.266869 6.86792) (xy 391.301351 6.822983) (xy 391.329672 6.77393)
			(xy 391.351349 6.7216) (xy 391.36601 6.666888) (xy 391.373404 6.610731) (xy 391.373868 6.58241) (xy 391.373868 5.71881)
			(xy 391.373409 5.690488) (xy 391.366017 5.634328) (xy 391.351358 5.579614) (xy 391.329682 5.527281)
			(xy 391.301361 5.478225) (xy 391.266879 5.433286) (xy 391.226826 5.393231) (xy 391.181888 5.358748)
			(xy 391.132833 5.330425) (xy 391.080501 5.308747) (xy 391.025788 5.294086) (xy 390.969628 5.286692)
			(xy 390.941306 5.286248) (xy 390.909919 5.286808) (xy 390.847805 5.295881) (xy 390.787654 5.313837)
			(xy 390.730731 5.340299) (xy 390.678231 5.374712) (xy 390.631256 5.416352) (xy 390.590794 5.464345)
			(xy 390.573768 5.490718) (xy 390.569732 5.496879) (xy 390.558743 5.50668) (xy 390.552178 5.510022)
			(xy 390.513316 5.528056) (xy 390.4996 5.52704) (xy 389.88746 5.52704) (xy 389.87537 5.527379) (xy 389.852378 5.534864)
			(xy 389.832825 5.549087) (xy 389.818623 5.568657) (xy 389.811165 5.591658) (xy 389.810752 5.603748)
			(xy 387.15962 5.603748) (xy 387.172442 5.594065) (xy 387.235812 5.536296) (xy 387.293581 5.472926)
			(xy 387.345257 5.404497) (xy 387.390398 5.331591) (xy 387.42862 5.254831) (xy 387.459596 5.174872)
			(xy 387.483063 5.092396) (xy 387.498819 5.008106) (xy 387.506731 4.922723) (xy 387.507226 4.879848)
			(xy 387.506731 4.836973) (xy 392.001997 4.836973) (xy 392.001997 4.922723) (xy 392.009909 5.008106)
			(xy 392.025665 5.092396) (xy 392.049132 5.174872) (xy 392.080108 5.254831) (xy 392.11833 5.331591)
			(xy 392.163471 5.404497) (xy 392.215147 5.472926) (xy 392.272916 5.536296) (xy 392.336286 5.594065)
			(xy 392.404715 5.645741) (xy 392.477621 5.690882) (xy 392.554381 5.729104) (xy 392.63434 5.76008)
			(xy 392.716816 5.783547) (xy 392.801106 5.799303) (xy 392.886489 5.807215) (xy 392.972239 5.807215)
			(xy 393.057622 5.799303) (xy 393.141912 5.783547) (xy 393.224388 5.76008) (xy 393.304347 5.729104)
			(xy 393.381107 5.690882) (xy 393.454013 5.645741) (xy 393.522442 5.594065) (xy 393.585812 5.536296)
			(xy 393.643581 5.472926) (xy 393.695257 5.404497) (xy 393.740398 5.331591) (xy 393.77862 5.254831)
			(xy 393.809596 5.174872) (xy 393.833063 5.092396) (xy 393.848819 5.008106) (xy 393.856731 4.922723)
			(xy 393.857226 4.879848) (xy 393.856731 4.836973) (xy 436.390783 4.836973) (xy 436.390783 4.922723)
			(xy 436.398695 5.008106) (xy 436.414451 5.092396) (xy 436.437918 5.174872) (xy 436.468894 5.254831)
			(xy 436.507116 5.331591) (xy 436.552257 5.404497) (xy 436.603933 5.472926) (xy 436.661702 5.536296)
			(xy 436.725072 5.594065) (xy 436.793501 5.645741) (xy 436.866407 5.690882) (xy 436.943167 5.729104)
			(xy 437.023126 5.76008) (xy 437.105602 5.783547) (xy 437.189892 5.799303) (xy 437.275275 5.807215)
			(xy 437.361025 5.807215) (xy 437.446408 5.799303) (xy 437.530698 5.783547) (xy 437.613174 5.76008)
			(xy 437.693133 5.729104) (xy 437.713806 5.71881) (xy 438.87644 5.71881) (xy 438.87644 6.58241) (xy 438.876891 6.610721)
			(xy 438.88428 6.666859) (xy 438.898931 6.721553) (xy 438.920592 6.773867) (xy 438.948895 6.822908)
			(xy 438.983354 6.867838) (xy 439.02338 6.907887) (xy 439.06829 6.942371) (xy 439.117315 6.9707) (xy 439.169618 6.992391)
			(xy 439.224304 7.007073) (xy 439.280437 7.014493) (xy 439.308748 7.014972) (xy 439.340223 7.014436)
			(xy 439.402501 7.005263) (xy 439.462792 6.98716) (xy 439.519824 6.960511) (xy 439.57239 6.925878)
			(xy 439.619383 6.883991) (xy 439.659809 6.835737) (xy 439.676794 6.809232) (xy 439.680836 6.803191)
			(xy 439.691669 6.79351) (xy 439.69813 6.790182) (xy 439.73623 6.771894) (xy 439.747914 6.772656)
			(xy 440.360054 6.772656) (xy 440.372142 6.772153) (xy 440.395141 6.764709) (xy 440.414722 6.750532)
			(xy 440.428974 6.731005) (xy 440.436507 6.708034) (xy 440.437016 6.695948) (xy 440.437016 5.598668)
			(xy 440.436611 5.586559) (xy 440.429105 5.563533) (xy 440.41484 5.543962) (xy 440.395217 5.529768)
			(xy 440.372164 5.522345) (xy 440.360054 5.52196) (xy 439.747914 5.52196) (xy 439.733944 5.522976)
			(xy 439.695336 5.50545) (xy 439.688745 5.502158) (xy 439.677642 5.492486) (xy 439.673492 5.4864)
			(xy 439.656394 5.460515) (xy 439.615929 5.413493) (xy 439.569162 5.372734) (xy 439.517051 5.339074)
			(xy 439.460667 5.313204) (xy 439.401165 5.295654) (xy 439.339766 5.286785) (xy 439.308748 5.286248)
			(xy 439.280434 5.286781) (xy 439.224291 5.294168) (xy 439.169594 5.308824) (xy 439.117278 5.330496)
			(xy 439.06824 5.358814) (xy 439.023319 5.393293) (xy 438.983286 5.433341) (xy 438.948824 5.478275)
			(xy 438.920524 5.527323) (xy 438.898872 5.579647) (xy 438.884237 5.63435) (xy 438.87687 5.690496)
			(xy 438.87644 5.71881) (xy 437.713806 5.71881) (xy 437.769893 5.690882) (xy 437.842799 5.645741)
			(xy 437.911228 5.594065) (xy 437.974598 5.536296) (xy 438.032367 5.472926) (xy 438.084043 5.404497)
			(xy 438.129184 5.331591) (xy 438.167406 5.254831) (xy 438.198382 5.174872) (xy 438.221849 5.092396)
			(xy 438.237605 5.008106) (xy 438.245517 4.922723) (xy 438.246012 4.879848) (xy 438.245517 4.836973)
			(xy 442.740783 4.836973) (xy 442.740783 4.922723) (xy 442.748695 5.008106) (xy 442.764451 5.092396)
			(xy 442.787918 5.174872) (xy 442.818894 5.254831) (xy 442.857116 5.331591) (xy 442.902257 5.404497)
			(xy 442.953933 5.472926) (xy 443.011702 5.536296) (xy 443.075072 5.594065) (xy 443.143501 5.645741)
			(xy 443.216407 5.690882) (xy 443.293167 5.729104) (xy 443.373126 5.76008) (xy 443.455602 5.783547)
			(xy 443.539892 5.799303) (xy 443.625275 5.807215) (xy 443.711025 5.807215) (xy 443.796408 5.799303)
			(xy 443.880698 5.783547) (xy 443.963174 5.76008) (xy 444.043133 5.729104) (xy 444.119893 5.690882)
			(xy 444.192799 5.645741) (xy 444.261228 5.594065) (xy 444.324598 5.536296) (xy 444.382367 5.472926)
			(xy 444.434043 5.404497) (xy 444.479184 5.331591) (xy 444.517406 5.254831) (xy 444.548382 5.174872)
			(xy 444.571849 5.092396) (xy 444.587605 5.008106) (xy 444.595517 4.922723) (xy 444.596012 4.879848)
			(xy 444.595517 4.836973) (xy 444.587605 4.75159) (xy 444.571849 4.6673) (xy 444.548382 4.584824)
			(xy 444.517406 4.504865) (xy 444.479184 4.428105) (xy 444.434043 4.355199) (xy 444.382367 4.28677)
			(xy 444.324598 4.2234) (xy 444.261228 4.165631) (xy 444.192799 4.113955) (xy 444.119893 4.068814)
			(xy 444.043133 4.030592) (xy 443.963174 3.999616) (xy 443.880698 3.976149) (xy 443.796408 3.960393)
			(xy 443.711025 3.952481) (xy 443.625275 3.952481) (xy 443.539892 3.960393) (xy 443.455602 3.976149)
			(xy 443.373126 3.999616) (xy 443.293167 4.030592) (xy 443.216407 4.068814) (xy 443.143501 4.113955)
			(xy 443.075072 4.165631) (xy 443.011702 4.2234) (xy 442.953933 4.28677) (xy 442.902257 4.355199)
			(xy 442.857116 4.428105) (xy 442.818894 4.504865) (xy 442.787918 4.584824) (xy 442.764451 4.6673)
			(xy 442.748695 4.75159) (xy 442.740783 4.836973) (xy 438.245517 4.836973) (xy 438.237605 4.75159)
			(xy 438.221849 4.6673) (xy 438.198382 4.584824) (xy 438.167406 4.504865) (xy 438.129184 4.428105)
			(xy 438.084043 4.355199) (xy 438.032367 4.28677) (xy 437.974598 4.2234) (xy 437.911228 4.165631)
			(xy 437.842799 4.113955) (xy 437.769893 4.068814) (xy 437.693133 4.030592) (xy 437.613174 3.999616)
			(xy 437.530698 3.976149) (xy 437.446408 3.960393) (xy 437.361025 3.952481) (xy 437.275275 3.952481)
			(xy 437.189892 3.960393) (xy 437.105602 3.976149) (xy 437.023126 3.999616) (xy 436.943167 4.030592)
			(xy 436.866407 4.068814) (xy 436.793501 4.113955) (xy 436.725072 4.165631) (xy 436.661702 4.2234)
			(xy 436.603933 4.28677) (xy 436.552257 4.355199) (xy 436.507116 4.428105) (xy 436.468894 4.504865)
			(xy 436.437918 4.584824) (xy 436.414451 4.6673) (xy 436.398695 4.75159) (xy 436.390783 4.836973)
			(xy 393.856731 4.836973) (xy 393.848819 4.75159) (xy 393.833063 4.6673) (xy 393.809596 4.584824)
			(xy 393.77862 4.504865) (xy 393.740398 4.428105) (xy 393.695257 4.355199) (xy 393.643581 4.28677)
			(xy 393.585812 4.2234) (xy 393.522442 4.165631) (xy 393.454013 4.113955) (xy 393.381107 4.068814)
			(xy 393.304347 4.030592) (xy 393.224388 3.999616) (xy 393.141912 3.976149) (xy 393.057622 3.960393)
			(xy 392.972239 3.952481) (xy 392.886489 3.952481) (xy 392.801106 3.960393) (xy 392.716816 3.976149)
			(xy 392.63434 3.999616) (xy 392.554381 4.030592) (xy 392.477621 4.068814) (xy 392.404715 4.113955)
			(xy 392.336286 4.165631) (xy 392.272916 4.2234) (xy 392.215147 4.28677) (xy 392.163471 4.355199)
			(xy 392.11833 4.428105) (xy 392.080108 4.504865) (xy 392.049132 4.584824) (xy 392.025665 4.6673)
			(xy 392.009909 4.75159) (xy 392.001997 4.836973) (xy 387.506731 4.836973) (xy 387.498819 4.75159)
			(xy 387.483063 4.6673) (xy 387.459596 4.584824) (xy 387.42862 4.504865) (xy 387.390398 4.428105)
			(xy 387.345257 4.355199) (xy 387.293581 4.28677) (xy 387.235812 4.2234) (xy 387.172442 4.165631)
			(xy 387.104013 4.113955) (xy 387.031107 4.068814) (xy 386.954347 4.030592) (xy 386.874388 3.999616)
			(xy 386.791912 3.976149) (xy 386.707622 3.960393) (xy 386.622239 3.952481) (xy 386.536489 3.952481)
			(xy 386.451106 3.960393) (xy 386.366816 3.976149) (xy 386.28434 3.999616) (xy 386.204381 4.030592)
			(xy 386.127621 4.068814) (xy 386.054715 4.113955) (xy 385.986286 4.165631) (xy 385.922916 4.2234)
			(xy 385.865147 4.28677) (xy 385.813471 4.355199) (xy 385.76833 4.428105) (xy 385.730108 4.504865)
			(xy 385.699132 4.584824) (xy 385.675665 4.6673) (xy 385.659909 4.75159) (xy 385.651997 4.836973)
			(xy 365.94034 4.836973) (xy 365.94034 4.531614) (xy 365.939928 4.51949) (xy 365.932437 4.496428)
			(xy 365.918184 4.476811) (xy 365.898565 4.46256) (xy 365.875502 4.455071) (xy 365.863378 4.454652)
			(xy 365.251238 4.454652) (xy 365.237268 4.455922) (xy 365.19866 4.438396) (xy 365.19205 4.435139)
			(xy 365.180958 4.425443) (xy 365.176816 4.419346) (xy 365.159713 4.393473) (xy 365.119244 4.346474)
			(xy 365.072473 4.305742) (xy 365.020359 4.272116) (xy 364.963973 4.246284) (xy 364.904474 4.228779)
			(xy 364.843083 4.219959) (xy 364.812072 4.219448) (xy 364.783769 4.219928) (xy 364.727646 4.22732)
			(xy 364.672969 4.241973) (xy 364.620671 4.263637) (xy 364.571648 4.291941) (xy 364.526739 4.3264)
			(xy 364.486711 4.366427) (xy 364.452249 4.411335) (xy 364.423944 4.460357) (xy 364.402278 4.512654)
			(xy 364.387623 4.567331) (xy 364.380229 4.623453) (xy 364.379764 4.651756) (xy 363.21713 4.651756)
			(xy 363.273217 4.623828) (xy 363.346123 4.578687) (xy 363.414552 4.527011) (xy 363.477922 4.469242)
			(xy 363.535691 4.405872) (xy 363.587367 4.337443) (xy 363.632508 4.264537) (xy 363.67073 4.187777)
			(xy 363.701706 4.107818) (xy 363.725173 4.025342) (xy 363.740929 3.941052) (xy 363.748841 3.855669)
			(xy 363.749336 3.812794) (xy 363.748841 3.769919) (xy 368.244107 3.769919) (xy 368.244107 3.855669)
			(xy 368.252019 3.941052) (xy 368.267775 4.025342) (xy 368.291242 4.107818) (xy 368.322218 4.187777)
			(xy 368.36044 4.264537) (xy 368.405581 4.337443) (xy 368.457257 4.405872) (xy 368.515026 4.469242)
			(xy 368.578396 4.527011) (xy 368.646825 4.578687) (xy 368.719731 4.623828) (xy 368.796491 4.66205)
			(xy 368.87645 4.693026) (xy 368.958926 4.716493) (xy 369.043216 4.732249) (xy 369.128599 4.740161)
			(xy 369.214349 4.740161) (xy 369.299732 4.732249) (xy 369.384022 4.716493) (xy 369.466498 4.693026)
			(xy 369.546457 4.66205) (xy 369.623217 4.623828) (xy 369.696123 4.578687) (xy 369.764552 4.527011)
			(xy 369.827922 4.469242) (xy 369.885691 4.405872) (xy 369.937367 4.337443) (xy 369.982508 4.264537)
			(xy 370.02073 4.187777) (xy 370.051706 4.107818) (xy 370.075173 4.025342) (xy 370.090929 3.941052)
			(xy 370.098841 3.855669) (xy 370.099336 3.812794) (xy 370.098841 3.769919) (xy 370.090929 3.684536)
			(xy 370.075173 3.600246) (xy 370.051706 3.51777) (xy 370.02073 3.437811) (xy 369.982508 3.361051)
			(xy 369.937367 3.288145) (xy 369.885691 3.219716) (xy 369.827922 3.156346) (xy 369.764552 3.098577)
			(xy 369.696123 3.046901) (xy 369.623217 3.00176) (xy 369.546457 2.963538) (xy 369.466498 2.932562)
			(xy 369.384022 2.909095) (xy 369.299732 2.893339) (xy 369.214349 2.885427) (xy 369.128599 2.885427)
			(xy 369.043216 2.893339) (xy 368.958926 2.909095) (xy 368.87645 2.932562) (xy 368.796491 2.963538)
			(xy 368.719731 3.00176) (xy 368.646825 3.046901) (xy 368.578396 3.098577) (xy 368.515026 3.156346)
			(xy 368.457257 3.219716) (xy 368.405581 3.288145) (xy 368.36044 3.361051) (xy 368.322218 3.437811)
			(xy 368.291242 3.51777) (xy 368.267775 3.600246) (xy 368.252019 3.684536) (xy 368.244107 3.769919)
			(xy 363.748841 3.769919) (xy 363.740929 3.684536) (xy 363.725173 3.600246) (xy 363.701706 3.51777)
			(xy 363.67073 3.437811) (xy 363.632508 3.361051) (xy 363.587367 3.288145) (xy 363.535691 3.219716)
			(xy 363.477922 3.156346) (xy 363.414552 3.098577) (xy 363.346123 3.046901) (xy 363.273217 3.00176)
			(xy 363.196457 2.963538) (xy 363.116498 2.932562) (xy 363.034022 2.909095) (xy 362.949732 2.893339)
			(xy 362.864349 2.885427) (xy 362.778599 2.885427) (xy 362.693216 2.893339) (xy 362.608926 2.909095)
			(xy 362.52645 2.932562) (xy 362.446491 2.963538) (xy 362.369731 3.00176) (xy 362.296825 3.046901)
			(xy 362.228396 3.098577) (xy 362.165026 3.156346) (xy 362.107257 3.219716) (xy 362.055581 3.288145)
			(xy 362.01044 3.361051) (xy 361.972218 3.437811) (xy 361.941242 3.51777) (xy 361.917775 3.600246)
			(xy 361.902019 3.684536) (xy 361.894107 3.769919) (xy 319.360055 3.769919) (xy 319.352143 3.684536)
			(xy 319.336387 3.600246) (xy 319.31292 3.51777) (xy 319.281944 3.437811) (xy 319.243722 3.361051)
			(xy 319.198581 3.288145) (xy 319.146905 3.219716) (xy 319.089136 3.156346) (xy 319.025766 3.098577)
			(xy 318.957337 3.046901) (xy 318.884431 3.00176) (xy 318.807671 2.963538) (xy 318.727712 2.932562)
			(xy 318.645236 2.909095) (xy 318.560946 2.893339) (xy 318.475563 2.885427) (xy 318.389813 2.885427)
			(xy 318.30443 2.893339) (xy 318.22014 2.909095) (xy 318.137664 2.932562) (xy 318.057705 2.963538)
			(xy 317.980945 3.00176) (xy 317.908039 3.046901) (xy 317.83961 3.098577) (xy 317.77624 3.156346)
			(xy 317.718471 3.219716) (xy 317.666795 3.288145) (xy 317.621654 3.361051) (xy 317.583432 3.437811)
			(xy 317.552456 3.51777) (xy 317.528989 3.600246) (xy 317.513233 3.684536) (xy 317.505321 3.769919)
			(xy 313.010055 3.769919) (xy 313.002143 3.684536) (xy 312.986387 3.600246) (xy 312.96292 3.51777)
			(xy 312.931944 3.437811) (xy 312.893722 3.361051) (xy 312.848581 3.288145) (xy 312.796905 3.219716)
			(xy 312.739136 3.156346) (xy 312.675766 3.098577) (xy 312.607337 3.046901) (xy 312.534431 3.00176)
			(xy 312.457671 2.963538) (xy 312.377712 2.932562) (xy 312.295236 2.909095) (xy 312.210946 2.893339)
			(xy 312.125563 2.885427) (xy 312.039813 2.885427) (xy 311.95443 2.893339) (xy 311.87014 2.909095)
			(xy 311.787664 2.932562) (xy 311.707705 2.963538) (xy 311.630945 3.00176) (xy 311.558039 3.046901)
			(xy 311.48961 3.098577) (xy 311.42624 3.156346) (xy 311.368471 3.219716) (xy 311.316795 3.288145)
			(xy 311.271654 3.361051) (xy 311.233432 3.437811) (xy 311.202456 3.51777) (xy 311.178989 3.600246)
			(xy 311.163233 3.684536) (xy 311.155321 3.769919) (xy 304.348655 3.769919) (xy 304.340743 3.684536)
			(xy 304.324987 3.600246) (xy 304.30152 3.51777) (xy 304.270544 3.437811) (xy 304.232322 3.361051)
			(xy 304.187181 3.288145) (xy 304.135505 3.219716) (xy 304.077736 3.156346) (xy 304.014366 3.098577)
			(xy 303.945937 3.046901) (xy 303.873031 3.00176) (xy 303.796271 2.963538) (xy 303.716312 2.932562)
			(xy 303.633836 2.909095) (xy 303.549546 2.893339) (xy 303.464163 2.885427) (xy 303.378413 2.885427)
			(xy 303.29303 2.893339) (xy 303.20874 2.909095) (xy 303.126264 2.932562) (xy 303.046305 2.963538)
			(xy 302.969545 3.00176) (xy 302.896639 3.046901) (xy 302.82821 3.098577) (xy 302.76484 3.156346)
			(xy 302.707071 3.219716) (xy 302.655395 3.288145) (xy 302.610254 3.361051) (xy 302.572032 3.437811)
			(xy 302.541056 3.51777) (xy 302.517589 3.600246) (xy 302.501833 3.684536) (xy 302.493921 3.769919)
			(xy 297.998655 3.769919) (xy 297.990743 3.684536) (xy 297.974987 3.600246) (xy 297.95152 3.51777)
			(xy 297.920544 3.437811) (xy 297.882322 3.361051) (xy 297.837181 3.288145) (xy 297.785505 3.219716)
			(xy 297.727736 3.156346) (xy 297.664366 3.098577) (xy 297.595937 3.046901) (xy 297.523031 3.00176)
			(xy 297.446271 2.963538) (xy 297.366312 2.932562) (xy 297.283836 2.909095) (xy 297.199546 2.893339)
			(xy 297.114163 2.885427) (xy 297.028413 2.885427) (xy 296.94303 2.893339) (xy 296.85874 2.909095)
			(xy 296.776264 2.932562) (xy 296.696305 2.963538) (xy 296.619545 3.00176) (xy 296.546639 3.046901)
			(xy 296.47821 3.098577) (xy 296.41484 3.156346) (xy 296.357071 3.219716) (xy 296.305395 3.288145)
			(xy 296.260254 3.361051) (xy 296.222032 3.437811) (xy 296.191056 3.51777) (xy 296.167589 3.600246)
			(xy 296.151833 3.684536) (xy 296.143921 3.769919) (xy 216.865975 3.769919) (xy 216.858063 3.684536)
			(xy 216.842307 3.600246) (xy 216.81884 3.51777) (xy 216.787864 3.437811) (xy 216.749642 3.361051)
			(xy 216.704501 3.288145) (xy 216.652825 3.219716) (xy 216.595056 3.156346) (xy 216.531686 3.098577)
			(xy 216.463257 3.046901) (xy 216.390351 3.00176) (xy 216.313591 2.963538) (xy 216.233632 2.932562)
			(xy 216.151156 2.909095) (xy 216.066866 2.893339) (xy 215.981483 2.885427) (xy 215.895733 2.885427)
			(xy 215.81035 2.893339) (xy 215.72606 2.909095) (xy 215.643584 2.932562) (xy 215.563625 2.963538)
			(xy 215.486865 3.00176) (xy 215.413959 3.046901) (xy 215.34553 3.098577) (xy 215.28216 3.156346)
			(xy 215.224391 3.219716) (xy 215.172715 3.288145) (xy 215.127574 3.361051) (xy 215.089352 3.437811)
			(xy 215.058376 3.51777) (xy 215.034909 3.600246) (xy 215.019153 3.684536) (xy 215.011241 3.769919)
			(xy 210.515975 3.769919) (xy 210.508063 3.684536) (xy 210.492307 3.600246) (xy 210.46884 3.51777)
			(xy 210.437864 3.437811) (xy 210.399642 3.361051) (xy 210.354501 3.288145) (xy 210.302825 3.219716)
			(xy 210.245056 3.156346) (xy 210.181686 3.098577) (xy 210.113257 3.046901) (xy 210.040351 3.00176)
			(xy 209.963591 2.963538) (xy 209.883632 2.932562) (xy 209.801156 2.909095) (xy 209.716866 2.893339)
			(xy 209.631483 2.885427) (xy 209.545733 2.885427) (xy 209.46035 2.893339) (xy 209.37606 2.909095)
			(xy 209.293584 2.932562) (xy 209.213625 2.963538) (xy 209.136865 3.00176) (xy 209.063959 3.046901)
			(xy 208.99553 3.098577) (xy 208.93216 3.156346) (xy 208.874391 3.219716) (xy 208.822715 3.288145)
			(xy 208.777574 3.361051) (xy 208.739352 3.437811) (xy 208.708376 3.51777) (xy 208.684909 3.600246)
			(xy 208.669153 3.684536) (xy 208.661241 3.769919) (xy 184.818528 3.769919) (xy 184.818528 3.092196)
			(xy 184.818024 3.06266) (xy 184.80998 3.004138) (xy 184.794043 2.947256) (xy 184.770508 2.893074)
			(xy 184.739815 2.842601) (xy 184.702535 2.796778) (xy 184.659363 2.756458) (xy 184.611103 2.722392)
			(xy 184.558653 2.695215) (xy 184.502992 2.675433) (xy 184.445155 2.663414) (xy 184.38622 2.659383)
			(xy 184.327285 2.663414) (xy 184.269448 2.675433) (xy 184.213787 2.695215) (xy 184.161337 2.722392)
			(xy 184.113077 2.756458) (xy 184.069905 2.796778) (xy 184.032625 2.842601) (xy 184.001932 2.893074)
			(xy 183.978397 2.947256) (xy 183.96246 3.004138) (xy 183.954416 3.06266) (xy 183.953912 3.092196)
			(xy 182.791278 3.092196) (xy 182.847365 3.064268) (xy 182.920271 3.019127) (xy 182.9887 2.967451)
			(xy 183.05207 2.909682) (xy 183.109839 2.846312) (xy 183.161515 2.777883) (xy 183.206656 2.704977)
			(xy 183.244878 2.628217) (xy 183.275854 2.548258) (xy 183.299321 2.465782) (xy 183.315077 2.381492)
			(xy 183.322989 2.296109) (xy 183.323484 2.253234) (xy 183.322989 2.210359) (xy 187.818255 2.210359)
			(xy 187.818255 2.296109) (xy 187.826167 2.381492) (xy 187.841923 2.465782) (xy 187.86539 2.548258)
			(xy 187.896366 2.628217) (xy 187.934588 2.704977) (xy 187.979729 2.777883) (xy 188.031405 2.846312)
			(xy 188.089174 2.909682) (xy 188.152544 2.967451) (xy 188.220973 3.019127) (xy 188.293879 3.064268)
			(xy 188.370639 3.10249) (xy 188.450598 3.133466) (xy 188.533074 3.156933) (xy 188.617364 3.172689)
			(xy 188.702747 3.180601) (xy 188.788497 3.180601) (xy 188.87388 3.172689) (xy 188.95817 3.156933)
			(xy 189.040646 3.133466) (xy 189.120605 3.10249) (xy 189.197365 3.064268) (xy 189.270271 3.019127)
			(xy 189.3387 2.967451) (xy 189.40207 2.909682) (xy 189.459839 2.846312) (xy 189.511515 2.777883)
			(xy 189.556656 2.704977) (xy 189.594878 2.628217) (xy 189.625854 2.548258) (xy 189.649321 2.465782)
			(xy 189.665077 2.381492) (xy 189.672989 2.296109) (xy 189.673484 2.253234) (xy 189.672989 2.210359)
			(xy 189.665077 2.124976) (xy 189.649321 2.040686) (xy 189.625854 1.95821) (xy 189.594878 1.878251)
			(xy 189.556656 1.801491) (xy 189.511515 1.728585) (xy 189.459839 1.660156) (xy 189.40207 1.596786)
			(xy 189.3387 1.539017) (xy 189.270271 1.487341) (xy 189.197365 1.4422) (xy 189.120605 1.403978) (xy 189.040646 1.373002)
			(xy 188.95817 1.349535) (xy 188.87388 1.333779) (xy 188.788497 1.325867) (xy 188.702747 1.325867)
			(xy 188.617364 1.333779) (xy 188.533074 1.349535) (xy 188.450598 1.373002) (xy 188.370639 1.403978)
			(xy 188.293879 1.4422) (xy 188.220973 1.487341) (xy 188.152544 1.539017) (xy 188.089174 1.596786)
			(xy 188.031405 1.660156) (xy 187.979729 1.728585) (xy 187.934588 1.801491) (xy 187.896366 1.878251)
			(xy 187.86539 1.95821) (xy 187.841923 2.040686) (xy 187.826167 2.124976) (xy 187.818255 2.210359)
			(xy 183.322989 2.210359) (xy 183.315077 2.124976) (xy 183.299321 2.040686) (xy 183.275854 1.95821)
			(xy 183.244878 1.878251) (xy 183.206656 1.801491) (xy 183.161515 1.728585) (xy 183.109839 1.660156)
			(xy 183.05207 1.596786) (xy 182.9887 1.539017) (xy 182.920271 1.487341) (xy 182.847365 1.4422) (xy 182.770605 1.403978)
			(xy 182.690646 1.373002) (xy 182.60817 1.349535) (xy 182.52388 1.333779) (xy 182.438497 1.325867)
			(xy 182.352747 1.325867) (xy 182.267364 1.333779) (xy 182.183074 1.349535) (xy 182.100598 1.373002)
			(xy 182.020639 1.403978) (xy 181.943879 1.4422) (xy 181.870973 1.487341) (xy 181.802544 1.539017)
			(xy 181.739174 1.596786) (xy 181.681405 1.660156) (xy 181.629729 1.728585) (xy 181.584588 1.801491)
			(xy 181.546366 1.878251) (xy 181.51539 1.95821) (xy 181.491923 2.040686) (xy 181.476167 2.124976)
			(xy 181.468255 2.210359) (xy 102.190309 2.210359) (xy 102.182397 2.124976) (xy 102.166641 2.040686)
			(xy 102.143174 1.95821) (xy 102.112198 1.878251) (xy 102.073976 1.801491) (xy 102.028835 1.728585)
			(xy 101.977159 1.660156) (xy 101.91939 1.596786) (xy 101.85602 1.539017) (xy 101.787591 1.487341)
			(xy 101.714685 1.4422) (xy 101.637925 1.403978) (xy 101.557966 1.373002) (xy 101.47549 1.349535)
			(xy 101.3912 1.333779) (xy 101.305817 1.325867) (xy 101.220067 1.325867) (xy 101.134684 1.333779)
			(xy 101.050394 1.349535) (xy 100.967918 1.373002) (xy 100.887959 1.403978) (xy 100.811199 1.4422)
			(xy 100.738293 1.487341) (xy 100.669864 1.539017) (xy 100.606494 1.596786) (xy 100.548725 1.660156)
			(xy 100.497049 1.728585) (xy 100.451908 1.801491) (xy 100.413686 1.878251) (xy 100.38271 1.95821)
			(xy 100.359243 2.040686) (xy 100.343487 2.124976) (xy 100.335575 2.210359) (xy 95.840309 2.210359)
			(xy 95.832397 2.124976) (xy 95.816641 2.040686) (xy 95.793174 1.95821) (xy 95.762198 1.878251) (xy 95.723976 1.801491)
			(xy 95.678835 1.728585) (xy 95.627159 1.660156) (xy 95.56939 1.596786) (xy 95.50602 1.539017) (xy 95.437591 1.487341)
			(xy 95.364685 1.4422) (xy 95.287925 1.403978) (xy 95.207966 1.373002) (xy 95.12549 1.349535) (xy 95.0412 1.333779)
			(xy 94.955817 1.325867) (xy 94.870067 1.325867) (xy 94.784684 1.333779) (xy 94.700394 1.349535) (xy 94.617918 1.373002)
			(xy 94.537959 1.403978) (xy 94.461199 1.4422) (xy 94.388293 1.487341) (xy 94.319864 1.539017) (xy 94.256494 1.596786)
			(xy 94.198725 1.660156) (xy 94.147049 1.728585) (xy 94.101908 1.801491) (xy 94.063686 1.878251) (xy 94.03271 1.95821)
			(xy 94.009243 2.040686) (xy 93.993487 2.124976) (xy 93.985575 2.210359) (xy 83.439191 2.210359) (xy 83.525475 2.124078)
			(xy 83.619275 2.019118) (xy 83.707042 1.909064) (xy 83.788501 1.794262) (xy 83.863394 1.675073) (xy 83.931487 1.551873)
			(xy 83.992565 1.425048) (xy 84.046435 1.294999) (xy 84.069209 1.229919) (xy 208.661241 1.229919)
			(xy 208.661241 1.315669) (xy 208.669153 1.401052) (xy 208.684909 1.485342) (xy 208.708376 1.567818)
			(xy 208.739352 1.647777) (xy 208.777574 1.724537) (xy 208.822715 1.797443) (xy 208.874391 1.865872)
			(xy 208.93216 1.929242) (xy 208.99553 1.987011) (xy 209.063959 2.038687) (xy 209.136865 2.083828)
			(xy 209.213625 2.12205) (xy 209.293584 2.153026) (xy 209.37606 2.176493) (xy 209.46035 2.192249)
			(xy 209.545733 2.200161) (xy 209.631483 2.200161) (xy 209.716866 2.192249) (xy 209.801156 2.176493)
			(xy 209.883632 2.153026) (xy 209.963591 2.12205) (xy 209.984264 2.111756) (xy 213.517988 2.111756)
			(xy 213.517988 2.975356) (xy 213.518492 3.00491) (xy 213.526541 3.063466) (xy 213.542487 3.120381)
			(xy 213.566036 3.174595) (xy 213.596747 3.225098) (xy 213.634049 3.270948) (xy 213.677246 3.311291)
			(xy 213.725535 3.345377) (xy 213.778015 3.37257) (xy 213.83371 3.392364) (xy 213.891581 3.40439)
			(xy 213.95055 3.408424) (xy 214.009519 3.40439) (xy 214.06739 3.392364) (xy 214.123085 3.37257) (xy 214.175565 3.345377)
			(xy 214.223854 3.311291) (xy 214.267051 3.270948) (xy 214.304353 3.225098) (xy 214.335064 3.174595)
			(xy 214.358613 3.120381) (xy 214.374559 3.063466) (xy 214.382608 3.00491) (xy 214.383112 2.975356)
			(xy 214.383112 2.111756) (xy 214.382608 2.082202) (xy 214.374559 2.023646) (xy 214.358613 1.966731)
			(xy 214.335064 1.912517) (xy 214.304353 1.862014) (xy 214.267051 1.816164) (xy 214.223854 1.775821)
			(xy 214.175565 1.741735) (xy 214.123085 1.714542) (xy 214.06739 1.694748) (xy 214.009519 1.682722)
			(xy 213.95055 1.678689) (xy 213.891581 1.682722) (xy 213.83371 1.694748) (xy 213.778015 1.714542)
			(xy 213.725535 1.741735) (xy 213.677246 1.775821) (xy 213.634049 1.816164) (xy 213.596747 1.862014)
			(xy 213.566036 1.912517) (xy 213.542487 1.966731) (xy 213.526541 2.023646) (xy 213.518492 2.082202)
			(xy 213.517988 2.111756) (xy 209.984264 2.111756) (xy 210.040351 2.083828) (xy 210.113257 2.038687)
			(xy 210.181686 1.987011) (xy 210.245056 1.929242) (xy 210.302825 1.865872) (xy 210.354501 1.797443)
			(xy 210.399642 1.724537) (xy 210.437864 1.647777) (xy 210.46884 1.567818) (xy 210.492307 1.485342)
			(xy 210.508063 1.401052) (xy 210.515975 1.315669) (xy 210.51647 1.272794) (xy 210.515975 1.229919)
			(xy 215.011241 1.229919) (xy 215.011241 1.315669) (xy 215.019153 1.401052) (xy 215.034909 1.485342)
			(xy 215.058376 1.567818) (xy 215.089352 1.647777) (xy 215.127574 1.724537) (xy 215.172715 1.797443)
			(xy 215.224391 1.865872) (xy 215.28216 1.929242) (xy 215.34553 1.987011) (xy 215.413959 2.038687)
			(xy 215.486865 2.083828) (xy 215.563625 2.12205) (xy 215.643584 2.153026) (xy 215.72606 2.176493)
			(xy 215.81035 2.192249) (xy 215.895733 2.200161) (xy 215.981483 2.200161) (xy 216.066866 2.192249)
			(xy 216.151156 2.176493) (xy 216.233632 2.153026) (xy 216.313591 2.12205) (xy 216.390351 2.083828)
			(xy 216.463257 2.038687) (xy 216.531686 1.987011) (xy 216.595056 1.929242) (xy 216.652825 1.865872)
			(xy 216.704501 1.797443) (xy 216.749642 1.724537) (xy 216.787864 1.647777) (xy 216.81884 1.567818)
			(xy 216.842307 1.485342) (xy 216.858063 1.401052) (xy 216.865975 1.315669) (xy 216.86647 1.272794)
			(xy 216.865975 1.229919) (xy 296.143921 1.229919) (xy 296.143921 1.315669) (xy 296.151833 1.401052)
			(xy 296.167589 1.485342) (xy 296.191056 1.567818) (xy 296.222032 1.647777) (xy 296.260254 1.724537)
			(xy 296.305395 1.797443) (xy 296.357071 1.865872) (xy 296.41484 1.929242) (xy 296.47821 1.987011)
			(xy 296.546639 2.038687) (xy 296.619545 2.083828) (xy 296.696305 2.12205) (xy 296.776264 2.153026)
			(xy 296.85874 2.176493) (xy 296.94303 2.192249) (xy 297.028413 2.200161) (xy 297.114163 2.200161)
			(xy 297.199546 2.192249) (xy 297.283836 2.176493) (xy 297.366312 2.153026) (xy 297.446271 2.12205)
			(xy 297.466944 2.111756) (xy 298.629324 2.111756) (xy 298.629324 2.975356) (xy 298.629828 3.00491)
			(xy 298.637877 3.063466) (xy 298.653823 3.120381) (xy 298.677372 3.174595) (xy 298.708083 3.225098)
			(xy 298.745385 3.270948) (xy 298.788582 3.311291) (xy 298.836871 3.345377) (xy 298.889351 3.37257)
			(xy 298.945046 3.392364) (xy 299.002917 3.40439) (xy 299.061886 3.408424) (xy 299.120855 3.40439)
			(xy 299.178726 3.392364) (xy 299.234421 3.37257) (xy 299.286901 3.345377) (xy 299.33519 3.311291)
			(xy 299.378387 3.270948) (xy 299.415689 3.225098) (xy 299.4464 3.174595) (xy 299.469949 3.120381)
			(xy 299.485895 3.063466) (xy 299.493944 3.00491) (xy 299.494448 2.975356) (xy 299.494448 2.111756)
			(xy 299.493944 2.082202) (xy 299.485895 2.023646) (xy 299.469949 1.966731) (xy 299.4464 1.912517)
			(xy 299.415689 1.862014) (xy 299.378387 1.816164) (xy 299.33519 1.775821) (xy 299.286901 1.741735)
			(xy 299.234421 1.714542) (xy 299.178726 1.694748) (xy 299.120855 1.682722) (xy 299.061886 1.678689)
			(xy 299.002917 1.682722) (xy 298.945046 1.694748) (xy 298.889351 1.714542) (xy 298.836871 1.741735)
			(xy 298.788582 1.775821) (xy 298.745385 1.816164) (xy 298.708083 1.862014) (xy 298.677372 1.912517)
			(xy 298.653823 1.966731) (xy 298.637877 2.023646) (xy 298.629828 2.082202) (xy 298.629324 2.111756)
			(xy 297.466944 2.111756) (xy 297.523031 2.083828) (xy 297.595937 2.038687) (xy 297.664366 1.987011)
			(xy 297.727736 1.929242) (xy 297.785505 1.865872) (xy 297.837181 1.797443) (xy 297.882322 1.724537)
			(xy 297.920544 1.647777) (xy 297.95152 1.567818) (xy 297.974987 1.485342) (xy 297.990743 1.401052)
			(xy 297.998655 1.315669) (xy 297.99915 1.272794) (xy 297.998655 1.229919) (xy 302.493921 1.229919)
			(xy 302.493921 1.315669) (xy 302.501833 1.401052) (xy 302.517589 1.485342) (xy 302.541056 1.567818)
			(xy 302.572032 1.647777) (xy 302.610254 1.724537) (xy 302.655395 1.797443) (xy 302.707071 1.865872)
			(xy 302.76484 1.929242) (xy 302.82821 1.987011) (xy 302.896639 2.038687) (xy 302.969545 2.083828)
			(xy 303.046305 2.12205) (xy 303.126264 2.153026) (xy 303.20874 2.176493) (xy 303.29303 2.192249)
			(xy 303.378413 2.200161) (xy 303.464163 2.200161) (xy 303.549546 2.192249) (xy 303.633836 2.176493)
			(xy 303.716312 2.153026) (xy 303.796271 2.12205) (xy 303.873031 2.083828) (xy 303.945937 2.038687)
			(xy 304.014366 1.987011) (xy 304.077736 1.929242) (xy 304.135505 1.865872) (xy 304.187181 1.797443)
			(xy 304.232322 1.724537) (xy 304.270544 1.647777) (xy 304.30152 1.567818) (xy 304.324987 1.485342)
			(xy 304.340743 1.401052) (xy 304.348655 1.315669) (xy 304.34915 1.272794) (xy 304.348655 1.229919)
			(xy 311.155321 1.229919) (xy 311.155321 1.315669) (xy 311.163233 1.401052) (xy 311.178989 1.485342)
			(xy 311.202456 1.567818) (xy 311.233432 1.647777) (xy 311.271654 1.724537) (xy 311.316795 1.797443)
			(xy 311.368471 1.865872) (xy 311.42624 1.929242) (xy 311.48961 1.987011) (xy 311.558039 2.038687)
			(xy 311.630945 2.083828) (xy 311.707705 2.12205) (xy 311.787664 2.153026) (xy 311.87014 2.176493)
			(xy 311.95443 2.192249) (xy 312.039813 2.200161) (xy 312.125563 2.200161) (xy 312.210946 2.192249)
			(xy 312.295236 2.176493) (xy 312.377712 2.153026) (xy 312.457671 2.12205) (xy 312.534431 2.083828)
			(xy 312.607337 2.038687) (xy 312.675766 1.987011) (xy 312.739136 1.929242) (xy 312.796905 1.865872)
			(xy 312.848581 1.797443) (xy 312.893722 1.724537) (xy 312.931944 1.647777) (xy 312.96292 1.567818)
			(xy 312.986387 1.485342) (xy 313.002143 1.401052) (xy 313.010055 1.315669) (xy 313.01055 1.272794)
			(xy 313.010055 1.229919) (xy 317.505321 1.229919) (xy 317.505321 1.315669) (xy 317.513233 1.401052)
			(xy 317.528989 1.485342) (xy 317.552456 1.567818) (xy 317.583432 1.647777) (xy 317.621654 1.724537)
			(xy 317.666795 1.797443) (xy 317.718471 1.865872) (xy 317.77624 1.929242) (xy 317.83961 1.987011)
			(xy 317.908039 2.038687) (xy 317.980945 2.083828) (xy 318.057705 2.12205) (xy 318.137664 2.153026)
			(xy 318.22014 2.176493) (xy 318.30443 2.192249) (xy 318.389813 2.200161) (xy 318.475563 2.200161)
			(xy 318.560946 2.192249) (xy 318.645236 2.176493) (xy 318.727712 2.153026) (xy 318.807671 2.12205)
			(xy 318.884431 2.083828) (xy 318.957337 2.038687) (xy 319.025766 1.987011) (xy 319.089136 1.929242)
			(xy 319.146905 1.865872) (xy 319.198581 1.797443) (xy 319.243722 1.724537) (xy 319.281944 1.647777)
			(xy 319.31292 1.567818) (xy 319.336387 1.485342) (xy 319.352143 1.401052) (xy 319.360055 1.315669)
			(xy 319.36055 1.272794) (xy 319.360055 1.229919) (xy 361.894107 1.229919) (xy 361.894107 1.315669)
			(xy 361.902019 1.401052) (xy 361.917775 1.485342) (xy 361.941242 1.567818) (xy 361.972218 1.647777)
			(xy 362.01044 1.724537) (xy 362.055581 1.797443) (xy 362.107257 1.865872) (xy 362.165026 1.929242)
			(xy 362.228396 1.987011) (xy 362.296825 2.038687) (xy 362.369731 2.083828) (xy 362.446491 2.12205)
			(xy 362.52645 2.153026) (xy 362.608926 2.176493) (xy 362.693216 2.192249) (xy 362.778599 2.200161)
			(xy 362.864349 2.200161) (xy 362.949732 2.192249) (xy 363.034022 2.176493) (xy 363.116498 2.153026)
			(xy 363.196457 2.12205) (xy 363.273217 2.083828) (xy 363.346123 2.038687) (xy 363.414552 1.987011)
			(xy 363.477922 1.929242) (xy 363.535691 1.865872) (xy 363.587367 1.797443) (xy 363.632508 1.724537)
			(xy 363.67073 1.647777) (xy 363.701706 1.567818) (xy 363.725173 1.485342) (xy 363.740929 1.401052)
			(xy 363.748841 1.315669) (xy 363.749336 1.272794) (xy 363.748841 1.229919) (xy 368.244107 1.229919)
			(xy 368.244107 1.315669) (xy 368.252019 1.401052) (xy 368.267775 1.485342) (xy 368.291242 1.567818)
			(xy 368.322218 1.647777) (xy 368.36044 1.724537) (xy 368.405581 1.797443) (xy 368.457257 1.865872)
			(xy 368.515026 1.929242) (xy 368.578396 1.987011) (xy 368.646825 2.038687) (xy 368.719731 2.083828)
			(xy 368.796491 2.12205) (xy 368.87645 2.153026) (xy 368.958926 2.176493) (xy 369.043216 2.192249)
			(xy 369.128599 2.200161) (xy 369.214349 2.200161) (xy 369.299732 2.192249) (xy 369.384022 2.176493)
			(xy 369.466498 2.153026) (xy 369.546457 2.12205) (xy 369.623217 2.083828) (xy 369.696123 2.038687)
			(xy 369.764552 1.987011) (xy 369.827922 1.929242) (xy 369.885691 1.865872) (xy 369.937367 1.797443)
			(xy 369.982508 1.724537) (xy 370.02073 1.647777) (xy 370.051706 1.567818) (xy 370.075173 1.485342)
			(xy 370.090929 1.401052) (xy 370.098841 1.315669) (xy 370.099336 1.272794) (xy 370.098841 1.229919)
			(xy 370.090929 1.144536) (xy 370.075173 1.060246) (xy 370.051706 0.97777) (xy 370.02073 0.897811)
			(xy 369.982508 0.821051) (xy 369.937367 0.748145) (xy 369.885691 0.679716) (xy 369.827922 0.616346)
			(xy 369.764552 0.558577) (xy 369.696123 0.506901) (xy 369.623217 0.46176) (xy 369.546457 0.423538)
			(xy 369.466498 0.392562) (xy 369.384022 0.369095) (xy 369.299732 0.353339) (xy 369.214349 0.345427)
			(xy 369.128599 0.345427) (xy 369.043216 0.353339) (xy 368.958926 0.369095) (xy 368.87645 0.392562)
			(xy 368.796491 0.423538) (xy 368.719731 0.46176) (xy 368.646825 0.506901) (xy 368.578396 0.558577)
			(xy 368.515026 0.616346) (xy 368.457257 0.679716) (xy 368.405581 0.748145) (xy 368.36044 0.821051)
			(xy 368.322218 0.897811) (xy 368.291242 0.97777) (xy 368.267775 1.060246) (xy 368.252019 1.144536)
			(xy 368.244107 1.229919) (xy 363.748841 1.229919) (xy 363.740929 1.144536) (xy 363.725173 1.060246)
			(xy 363.701706 0.97777) (xy 363.67073 0.897811) (xy 363.632508 0.821051) (xy 363.587367 0.748145)
			(xy 363.535691 0.679716) (xy 363.477922 0.616346) (xy 363.414552 0.558577) (xy 363.346123 0.506901)
			(xy 363.273217 0.46176) (xy 363.196457 0.423538) (xy 363.116498 0.392562) (xy 363.034022 0.369095)
			(xy 362.949732 0.353339) (xy 362.864349 0.345427) (xy 362.778599 0.345427) (xy 362.693216 0.353339)
			(xy 362.608926 0.369095) (xy 362.52645 0.392562) (xy 362.446491 0.423538) (xy 362.369731 0.46176)
			(xy 362.296825 0.506901) (xy 362.228396 0.558577) (xy 362.165026 0.616346) (xy 362.107257 0.679716)
			(xy 362.055581 0.748145) (xy 362.01044 0.821051) (xy 361.972218 0.897811) (xy 361.941242 0.97777)
			(xy 361.917775 1.060246) (xy 361.902019 1.144536) (xy 361.894107 1.229919) (xy 319.360055 1.229919)
			(xy 319.352143 1.144536) (xy 319.336387 1.060246) (xy 319.31292 0.97777) (xy 319.281944 0.897811)
			(xy 319.243722 0.821051) (xy 319.198581 0.748145) (xy 319.146905 0.679716) (xy 319.089136 0.616346)
			(xy 319.025766 0.558577) (xy 318.957337 0.506901) (xy 318.884431 0.46176) (xy 318.807671 0.423538)
			(xy 318.727712 0.392562) (xy 318.645236 0.369095) (xy 318.560946 0.353339) (xy 318.475563 0.345427)
			(xy 318.389813 0.345427) (xy 318.30443 0.353339) (xy 318.22014 0.369095) (xy 318.137664 0.392562)
			(xy 318.057705 0.423538) (xy 317.980945 0.46176) (xy 317.908039 0.506901) (xy 317.83961 0.558577)
			(xy 317.77624 0.616346) (xy 317.718471 0.679716) (xy 317.666795 0.748145) (xy 317.621654 0.821051)
			(xy 317.583432 0.897811) (xy 317.552456 0.97777) (xy 317.528989 1.060246) (xy 317.513233 1.144536)
			(xy 317.505321 1.229919) (xy 313.010055 1.229919) (xy 313.002143 1.144536) (xy 312.986387 1.060246)
			(xy 312.96292 0.97777) (xy 312.931944 0.897811) (xy 312.893722 0.821051) (xy 312.848581 0.748145)
			(xy 312.796905 0.679716) (xy 312.739136 0.616346) (xy 312.675766 0.558577) (xy 312.607337 0.506901)
			(xy 312.534431 0.46176) (xy 312.457671 0.423538) (xy 312.377712 0.392562) (xy 312.295236 0.369095)
			(xy 312.210946 0.353339) (xy 312.125563 0.345427) (xy 312.039813 0.345427) (xy 311.95443 0.353339)
			(xy 311.87014 0.369095) (xy 311.787664 0.392562) (xy 311.707705 0.423538) (xy 311.630945 0.46176)
			(xy 311.558039 0.506901) (xy 311.48961 0.558577) (xy 311.42624 0.616346) (xy 311.368471 0.679716)
			(xy 311.316795 0.748145) (xy 311.271654 0.821051) (xy 311.233432 0.897811) (xy 311.202456 0.97777)
			(xy 311.178989 1.060246) (xy 311.163233 1.144536) (xy 311.155321 1.229919) (xy 304.348655 1.229919)
			(xy 304.340743 1.144536) (xy 304.324987 1.060246) (xy 304.30152 0.97777) (xy 304.270544 0.897811)
			(xy 304.232322 0.821051) (xy 304.187181 0.748145) (xy 304.135505 0.679716) (xy 304.077736 0.616346)
			(xy 304.014366 0.558577) (xy 303.945937 0.506901) (xy 303.873031 0.46176) (xy 303.796271 0.423538)
			(xy 303.716312 0.392562) (xy 303.633836 0.369095) (xy 303.549546 0.353339) (xy 303.464163 0.345427)
			(xy 303.378413 0.345427) (xy 303.29303 0.353339) (xy 303.20874 0.369095) (xy 303.126264 0.392562)
			(xy 303.046305 0.423538) (xy 302.969545 0.46176) (xy 302.896639 0.506901) (xy 302.82821 0.558577)
			(xy 302.76484 0.616346) (xy 302.707071 0.679716) (xy 302.655395 0.748145) (xy 302.610254 0.821051)
			(xy 302.572032 0.897811) (xy 302.541056 0.97777) (xy 302.517589 1.060246) (xy 302.501833 1.144536)
			(xy 302.493921 1.229919) (xy 297.998655 1.229919) (xy 297.990743 1.144536) (xy 297.974987 1.060246)
			(xy 297.95152 0.97777) (xy 297.920544 0.897811) (xy 297.882322 0.821051) (xy 297.837181 0.748145)
			(xy 297.785505 0.679716) (xy 297.727736 0.616346) (xy 297.664366 0.558577) (xy 297.595937 0.506901)
			(xy 297.523031 0.46176) (xy 297.446271 0.423538) (xy 297.366312 0.392562) (xy 297.283836 0.369095)
			(xy 297.199546 0.353339) (xy 297.114163 0.345427) (xy 297.028413 0.345427) (xy 296.94303 0.353339)
			(xy 296.85874 0.369095) (xy 296.776264 0.392562) (xy 296.696305 0.423538) (xy 296.619545 0.46176)
			(xy 296.546639 0.506901) (xy 296.47821 0.558577) (xy 296.41484 0.616346) (xy 296.357071 0.679716)
			(xy 296.305395 0.748145) (xy 296.260254 0.821051) (xy 296.222032 0.897811) (xy 296.191056 0.97777)
			(xy 296.167589 1.060246) (xy 296.151833 1.144536) (xy 296.143921 1.229919) (xy 216.865975 1.229919)
			(xy 216.858063 1.144536) (xy 216.842307 1.060246) (xy 216.81884 0.97777) (xy 216.787864 0.897811)
			(xy 216.749642 0.821051) (xy 216.704501 0.748145) (xy 216.652825 0.679716) (xy 216.595056 0.616346)
			(xy 216.531686 0.558577) (xy 216.463257 0.506901) (xy 216.390351 0.46176) (xy 216.313591 0.423538)
			(xy 216.233632 0.392562) (xy 216.151156 0.369095) (xy 216.066866 0.353339) (xy 215.981483 0.345427)
			(xy 215.895733 0.345427) (xy 215.81035 0.353339) (xy 215.72606 0.369095) (xy 215.643584 0.392562)
			(xy 215.563625 0.423538) (xy 215.486865 0.46176) (xy 215.413959 0.506901) (xy 215.34553 0.558577)
			(xy 215.28216 0.616346) (xy 215.224391 0.679716) (xy 215.172715 0.748145) (xy 215.127574 0.821051)
			(xy 215.089352 0.897811) (xy 215.058376 0.97777) (xy 215.034909 1.060246) (xy 215.019153 1.144536)
			(xy 215.011241 1.229919) (xy 210.515975 1.229919) (xy 210.508063 1.144536) (xy 210.492307 1.060246)
			(xy 210.46884 0.97777) (xy 210.437864 0.897811) (xy 210.399642 0.821051) (xy 210.354501 0.748145)
			(xy 210.302825 0.679716) (xy 210.245056 0.616346) (xy 210.181686 0.558577) (xy 210.113257 0.506901)
			(xy 210.040351 0.46176) (xy 209.963591 0.423538) (xy 209.883632 0.392562) (xy 209.801156 0.369095)
			(xy 209.716866 0.353339) (xy 209.631483 0.345427) (xy 209.545733 0.345427) (xy 209.46035 0.353339)
			(xy 209.37606 0.369095) (xy 209.293584 0.392562) (xy 209.213625 0.423538) (xy 209.136865 0.46176)
			(xy 209.063959 0.506901) (xy 208.99553 0.558577) (xy 208.93216 0.616346) (xy 208.874391 0.679716)
			(xy 208.822715 0.748145) (xy 208.777574 0.821051) (xy 208.739352 0.897811) (xy 208.708376 0.97777)
			(xy 208.684909 1.060246) (xy 208.669153 1.144536) (xy 208.661241 1.229919) (xy 84.069209 1.229919)
			(xy 84.092929 1.162133) (xy 84.131901 1.02687) (xy 84.163226 0.889634) (xy 84.186808 0.750857) (xy 84.202571 0.610977)
			(xy 84.210467 0.470433) (xy 84.210906 0.40005) (xy 84.210906 -1.310081) (xy 208.661241 -1.310081)
			(xy 208.661241 -1.224331) (xy 208.669153 -1.138948) (xy 208.684909 -1.054658) (xy 208.708376 -0.972182)
			(xy 208.739352 -0.892223) (xy 208.777574 -0.815463) (xy 208.822715 -0.742557) (xy 208.874391 -0.674128)
			(xy 208.93216 -0.610758) (xy 208.99553 -0.552989) (xy 209.063959 -0.501313) (xy 209.136865 -0.456172)
			(xy 209.213625 -0.41795) (xy 209.293584 -0.386974) (xy 209.37606 -0.363507) (xy 209.46035 -0.347751)
			(xy 209.545733 -0.339839) (xy 209.631483 -0.339839) (xy 209.716866 -0.347751) (xy 209.801156 -0.363507)
			(xy 209.883632 -0.386974) (xy 209.963591 -0.41795) (xy 210.040351 -0.456172) (xy 210.113257 -0.501313)
			(xy 210.1692 -0.54356) (xy 212.819996 -0.54356) (xy 212.819996 -0.543306) (xy 212.819996 0.553974)
			(xy 212.820529 0.566058) (xy 212.827973 0.58905) (xy 212.842144 0.608627) (xy 212.861661 0.62288)
			(xy 212.884622 0.63042) (xy 212.896704 0.630936) (xy 213.508844 0.630936) (xy 213.520918 0.630474)
			(xy 213.543882 0.623003) (xy 213.563416 0.608805) (xy 213.57761 0.589268) (xy 213.585076 0.566302)
			(xy 213.585552 0.554228) (xy 213.585552 0.553974) (xy 213.585552 -0.543306) (xy 213.585097 -0.555397)
			(xy 213.577638 -0.578399) (xy 213.563449 -0.597979) (xy 213.543912 -0.612229) (xy 213.520933 -0.61976)
			(xy 213.508844 -0.620268) (xy 212.896704 -0.620268) (xy 212.884617 -0.619884) (xy 212.861628 -0.612412)
			(xy 212.842074 -0.5982) (xy 212.827871 -0.57864) (xy 212.820411 -0.555647) (xy 212.819996 -0.54356)
			(xy 210.1692 -0.54356) (xy 210.181686 -0.552989) (xy 210.245056 -0.610758) (xy 210.302825 -0.674128)
			(xy 210.354501 -0.742557) (xy 210.399642 -0.815463) (xy 210.437864 -0.892223) (xy 210.46884 -0.972182)
			(xy 210.492307 -1.054658) (xy 210.508063 -1.138948) (xy 210.515975 -1.224331) (xy 210.51647 -1.267206)
			(xy 210.515975 -1.310081) (xy 215.011241 -1.310081) (xy 215.011241 -1.224331) (xy 215.019153 -1.138948)
			(xy 215.034909 -1.054658) (xy 215.058376 -0.972182) (xy 215.089352 -0.892223) (xy 215.127574 -0.815463)
			(xy 215.172715 -0.742557) (xy 215.224391 -0.674128) (xy 215.28216 -0.610758) (xy 215.34553 -0.552989)
			(xy 215.413959 -0.501313) (xy 215.486865 -0.456172) (xy 215.563625 -0.41795) (xy 215.643584 -0.386974)
			(xy 215.72606 -0.363507) (xy 215.81035 -0.347751) (xy 215.895733 -0.339839) (xy 215.981483 -0.339839)
			(xy 216.066866 -0.347751) (xy 216.151156 -0.363507) (xy 216.233632 -0.386974) (xy 216.313591 -0.41795)
			(xy 216.390351 -0.456172) (xy 216.463257 -0.501313) (xy 216.531686 -0.552989) (xy 216.595056 -0.610758)
			(xy 216.652825 -0.674128) (xy 216.704501 -0.742557) (xy 216.749642 -0.815463) (xy 216.787864 -0.892223)
			(xy 216.81884 -0.972182) (xy 216.842307 -1.054658) (xy 216.858063 -1.138948) (xy 216.865975 -1.224331)
			(xy 216.86647 -1.267206) (xy 216.865975 -1.310081) (xy 296.143921 -1.310081) (xy 296.143921 -1.224331)
			(xy 296.151833 -1.138948) (xy 296.167589 -1.054658) (xy 296.191056 -0.972182) (xy 296.222032 -0.892223)
			(xy 296.260254 -0.815463) (xy 296.305395 -0.742557) (xy 296.357071 -0.674128) (xy 296.41484 -0.610758)
			(xy 296.47821 -0.552989) (xy 296.546639 -0.501313) (xy 296.619545 -0.456172) (xy 296.696305 -0.41795)
			(xy 296.776264 -0.386974) (xy 296.85874 -0.363507) (xy 296.94303 -0.347751) (xy 297.028413 -0.339839)
			(xy 297.114163 -0.339839) (xy 297.199546 -0.347751) (xy 297.283836 -0.363507) (xy 297.366312 -0.386974)
			(xy 297.446271 -0.41795) (xy 297.523031 -0.456172) (xy 297.595937 -0.501313) (xy 297.658607 -0.54864)
			(xy 299.424344 -0.54864) (xy 299.424344 -0.548386) (xy 299.424344 0.548894) (xy 299.424813 0.560984)
			(xy 299.432268 0.583985) (xy 299.446454 0.603565) (xy 299.465988 0.617816) (xy 299.488964 0.625347)
			(xy 299.501052 0.625856) (xy 300.113192 0.625856) (xy 300.125261 0.62533) (xy 300.14822 0.617875)
			(xy 300.167753 0.603693) (xy 300.18195 0.58417) (xy 300.189421 0.561217) (xy 300.1899 0.549148) (xy 300.1899 0.548894)
			(xy 300.1899 -0.548386) (xy 300.189381 -0.560471) (xy 300.181933 -0.583464) (xy 300.167759 -0.603041)
			(xy 300.148238 -0.617293) (xy 300.125275 -0.624833) (xy 300.113192 -0.625348) (xy 299.501052 -0.625348)
			(xy 299.488979 -0.624877) (xy 299.466017 -0.617407) (xy 299.446484 -0.60321) (xy 299.43229 -0.583676)
			(xy 299.424821 -0.560713) (xy 299.424344 -0.54864) (xy 297.658607 -0.54864) (xy 297.664366 -0.552989)
			(xy 297.727736 -0.610758) (xy 297.785505 -0.674128) (xy 297.837181 -0.742557) (xy 297.882322 -0.815463)
			(xy 297.920544 -0.892223) (xy 297.95152 -0.972182) (xy 297.974987 -1.054658) (xy 297.990743 -1.138948)
			(xy 297.998655 -1.224331) (xy 297.99915 -1.267206) (xy 297.998655 -1.310081) (xy 302.493921 -1.310081)
			(xy 302.493921 -1.224331) (xy 302.501833 -1.138948) (xy 302.517589 -1.054658) (xy 302.541056 -0.972182)
			(xy 302.572032 -0.892223) (xy 302.610254 -0.815463) (xy 302.655395 -0.742557) (xy 302.707071 -0.674128)
			(xy 302.76484 -0.610758) (xy 302.82821 -0.552989) (xy 302.896639 -0.501313) (xy 302.969545 -0.456172)
			(xy 303.046305 -0.41795) (xy 303.126264 -0.386974) (xy 303.20874 -0.363507) (xy 303.29303 -0.347751)
			(xy 303.378413 -0.339839) (xy 303.464163 -0.339839) (xy 303.549546 -0.347751) (xy 303.633836 -0.363507)
			(xy 303.716312 -0.386974) (xy 303.796271 -0.41795) (xy 303.873031 -0.456172) (xy 303.945937 -0.501313)
			(xy 304.014366 -0.552989) (xy 304.077736 -0.610758) (xy 304.135505 -0.674128) (xy 304.187181 -0.742557)
			(xy 304.232322 -0.815463) (xy 304.270544 -0.892223) (xy 304.30152 -0.972182) (xy 304.324987 -1.054658)
			(xy 304.340743 -1.138948) (xy 304.348655 -1.224331) (xy 304.34915 -1.267206) (xy 304.348655 -1.310081)
			(xy 311.155321 -1.310081) (xy 311.155321 -1.224331) (xy 311.163233 -1.138948) (xy 311.178989 -1.054658)
			(xy 311.202456 -0.972182) (xy 311.233432 -0.892223) (xy 311.271654 -0.815463) (xy 311.316795 -0.742557)
			(xy 311.368471 -0.674128) (xy 311.42624 -0.610758) (xy 311.48961 -0.552989) (xy 311.558039 -0.501313)
			(xy 311.630945 -0.456172) (xy 311.707705 -0.41795) (xy 311.787664 -0.386974) (xy 311.87014 -0.363507)
			(xy 311.95443 -0.347751) (xy 312.039813 -0.339839) (xy 312.125563 -0.339839) (xy 312.210946 -0.347751)
			(xy 312.295236 -0.363507) (xy 312.377712 -0.386974) (xy 312.457671 -0.41795) (xy 312.534431 -0.456172)
			(xy 312.607337 -0.501313) (xy 312.662944 -0.543306) (xy 315.314076 -0.543306) (xy 315.314076 0.553974)
			(xy 315.31453 0.566066) (xy 315.321984 0.589072) (xy 315.336173 0.608655) (xy 315.355711 0.622905)
			(xy 315.378694 0.630431) (xy 315.390784 0.630936) (xy 316.002924 0.630936) (xy 316.006988 0.630682)
			(xy 316.013005 0.63059) (xy 316.024813 0.63291) (xy 316.030356 0.635254) (xy 316.057026 0.647192)
			(xy 316.063688 0.650455) (xy 316.07492 0.660132) (xy 316.079124 0.666242) (xy 316.096177 0.692284)
			(xy 316.136632 0.739594) (xy 316.183453 0.780613) (xy 316.235673 0.814495) (xy 316.292211 0.840537)
			(xy 316.3519 0.858202) (xy 316.413506 0.867124) (xy 316.44463 0.867664) (xy 316.472941 0.867228)
			(xy 316.529079 0.859836) (xy 316.583773 0.845183) (xy 316.636088 0.82352) (xy 316.685129 0.795216)
			(xy 316.730058 0.760756) (xy 316.770106 0.720728) (xy 316.80459 0.675817) (xy 316.83292 0.626791)
			(xy 316.854611 0.574487) (xy 316.869292 0.519801) (xy 316.876713 0.463667) (xy 316.877192 0.435356)
			(xy 316.877192 -0.428244) (xy 316.876806 -0.456562) (xy 316.869405 -0.512713) (xy 316.854736 -0.567417)
			(xy 316.83305 -0.619737) (xy 316.804718 -0.668778) (xy 316.770226 -0.7137) (xy 316.730163 -0.753733)
			(xy 316.685217 -0.788193) (xy 316.636155 -0.816489) (xy 316.583819 -0.838137) (xy 316.529105 -0.852766)
			(xy 316.472949 -0.860126) (xy 316.44463 -0.860552) (xy 316.413256 -0.859968) (xy 316.351166 -0.850912)
			(xy 316.291034 -0.832985) (xy 316.234121 -0.806562) (xy 316.18162 -0.772199) (xy 316.134631 -0.730614)
			(xy 316.094139 -0.68268) (xy 316.077092 -0.656336) (xy 316.073038 -0.650188) (xy 316.062062 -0.640379)
			(xy 316.055502 -0.637032) (xy 316.01664 -0.618998) (xy 316.002924 -0.620268) (xy 315.390784 -0.620268)
			(xy 315.378671 -0.619897) (xy 315.355638 -0.612389) (xy 315.336062 -0.598117) (xy 315.321869 -0.578484)
			(xy 315.314455 -0.555421) (xy 315.314076 -0.543306) (xy 312.662944 -0.543306) (xy 312.675766 -0.552989)
			(xy 312.739136 -0.610758) (xy 312.796905 -0.674128) (xy 312.848581 -0.742557) (xy 312.893722 -0.815463)
			(xy 312.931944 -0.892223) (xy 312.96292 -0.972182) (xy 312.986387 -1.054658) (xy 313.002143 -1.138948)
			(xy 313.010055 -1.224331) (xy 313.01055 -1.267206) (xy 313.010055 -1.310081) (xy 317.505321 -1.310081)
			(xy 317.505321 -1.224331) (xy 317.513233 -1.138948) (xy 317.528989 -1.054658) (xy 317.552456 -0.972182)
			(xy 317.583432 -0.892223) (xy 317.621654 -0.815463) (xy 317.666795 -0.742557) (xy 317.718471 -0.674128)
			(xy 317.77624 -0.610758) (xy 317.83961 -0.552989) (xy 317.908039 -0.501313) (xy 317.980945 -0.456172)
			(xy 318.057705 -0.41795) (xy 318.137664 -0.386974) (xy 318.22014 -0.363507) (xy 318.30443 -0.347751)
			(xy 318.389813 -0.339839) (xy 318.475563 -0.339839) (xy 318.560946 -0.347751) (xy 318.645236 -0.363507)
			(xy 318.727712 -0.386974) (xy 318.807671 -0.41795) (xy 318.884431 -0.456172) (xy 318.957337 -0.501313)
			(xy 319.025766 -0.552989) (xy 319.089136 -0.610758) (xy 319.146905 -0.674128) (xy 319.198581 -0.742557)
			(xy 319.243722 -0.815463) (xy 319.281944 -0.892223) (xy 319.31292 -0.972182) (xy 319.336387 -1.054658)
			(xy 319.352143 -1.138948) (xy 319.360055 -1.224331) (xy 319.36055 -1.267206) (xy 319.360055 -1.310081)
			(xy 361.894107 -1.310081) (xy 361.894107 -1.224331) (xy 361.902019 -1.138948) (xy 361.917775 -1.054658)
			(xy 361.941242 -0.972182) (xy 361.972218 -0.892223) (xy 362.01044 -0.815463) (xy 362.055581 -0.742557)
			(xy 362.107257 -0.674128) (xy 362.165026 -0.610758) (xy 362.228396 -0.552989) (xy 362.296825 -0.501313)
			(xy 362.369731 -0.456172) (xy 362.446491 -0.41795) (xy 362.52645 -0.386974) (xy 362.608926 -0.363507)
			(xy 362.693216 -0.347751) (xy 362.778599 -0.339839) (xy 362.864349 -0.339839) (xy 362.949732 -0.347751)
			(xy 363.034022 -0.363507) (xy 363.116498 -0.386974) (xy 363.196457 -0.41795) (xy 363.21713 -0.428244)
			(xy 364.379764 -0.428244) (xy 364.379764 0.435356) (xy 364.380276 0.46366) (xy 364.387659 0.519784)
			(xy 364.402305 0.574464) (xy 364.423963 0.626764) (xy 364.452262 0.67579) (xy 364.486719 0.720703)
			(xy 364.526743 0.760733) (xy 364.57165 0.795197) (xy 364.620671 0.823505) (xy 364.672968 0.845172)
			(xy 364.727646 0.859827) (xy 364.783768 0.867219) (xy 364.812072 0.867664) (xy 364.843538 0.867114)
			(xy 364.905805 0.857993) (xy 364.966091 0.839939) (xy 365.023123 0.813335) (xy 365.075694 0.778742)
			(xy 365.122694 0.736892) (xy 365.163128 0.688669) (xy 365.180118 0.662178) (xy 365.184143 0.656124)
			(xy 365.194988 0.646451) (xy 365.201454 0.643128) (xy 365.239554 0.62484) (xy 365.251238 0.625856)
			(xy 365.863378 0.625856) (xy 365.8755 0.625421) (xy 365.898559 0.617934) (xy 365.918175 0.603687)
			(xy 365.932427 0.584074) (xy 365.939919 0.561016) (xy 365.94034 0.548894) (xy 365.94034 -0.548386)
			(xy 365.939928 -0.56051) (xy 365.932437 -0.583572) (xy 365.918184 -0.603189) (xy 365.898565 -0.61744)
			(xy 365.875502 -0.624929) (xy 365.863378 -0.625348) (xy 365.251238 -0.625348) (xy 365.237268 -0.624078)
			(xy 365.19866 -0.641604) (xy 365.19205 -0.644861) (xy 365.180958 -0.654557) (xy 365.176816 -0.660654)
			(xy 365.159713 -0.686527) (xy 365.119244 -0.733526) (xy 365.072473 -0.774258) (xy 365.020359 -0.807884)
			(xy 364.963973 -0.833716) (xy 364.904474 -0.851221) (xy 364.843083 -0.860041) (xy 364.812072 -0.860552)
			(xy 364.783769 -0.860072) (xy 364.727646 -0.85268) (xy 364.672969 -0.838027) (xy 364.620671 -0.816363)
			(xy 364.571648 -0.788059) (xy 364.526739 -0.7536) (xy 364.486711 -0.713573) (xy 364.452249 -0.668665)
			(xy 364.423944 -0.619643) (xy 364.402278 -0.567346) (xy 364.387623 -0.512669) (xy 364.380229 -0.456547)
			(xy 364.379764 -0.428244) (xy 363.21713 -0.428244) (xy 363.273217 -0.456172) (xy 363.346123 -0.501313)
			(xy 363.414552 -0.552989) (xy 363.477922 -0.610758) (xy 363.535691 -0.674128) (xy 363.587367 -0.742557)
			(xy 363.632508 -0.815463) (xy 363.67073 -0.892223) (xy 363.701706 -0.972182) (xy 363.725173 -1.054658)
			(xy 363.740929 -1.138948) (xy 363.748841 -1.224331) (xy 363.749336 -1.267206) (xy 363.748841 -1.310081)
			(xy 368.244107 -1.310081) (xy 368.244107 -1.224331) (xy 368.252019 -1.138948) (xy 368.267775 -1.054658)
			(xy 368.291242 -0.972182) (xy 368.322218 -0.892223) (xy 368.36044 -0.815463) (xy 368.405581 -0.742557)
			(xy 368.457257 -0.674128) (xy 368.515026 -0.610758) (xy 368.578396 -0.552989) (xy 368.646825 -0.501313)
			(xy 368.719731 -0.456172) (xy 368.796491 -0.41795) (xy 368.87645 -0.386974) (xy 368.958926 -0.363507)
			(xy 369.043216 -0.347751) (xy 369.128599 -0.339839) (xy 369.214349 -0.339839) (xy 369.299732 -0.347751)
			(xy 369.384022 -0.363507) (xy 369.466498 -0.386974) (xy 369.546457 -0.41795) (xy 369.623217 -0.456172)
			(xy 369.696123 -0.501313) (xy 369.764552 -0.552989) (xy 369.827922 -0.610758) (xy 369.885691 -0.674128)
			(xy 369.937367 -0.742557) (xy 369.982508 -0.815463) (xy 370.02073 -0.892223) (xy 370.051706 -0.972182)
			(xy 370.075173 -1.054658) (xy 370.090929 -1.138948) (xy 370.098841 -1.224331) (xy 370.099336 -1.267206)
			(xy 370.098841 -1.310081) (xy 370.090929 -1.395464) (xy 370.075173 -1.479754) (xy 370.051706 -1.56223)
			(xy 370.02073 -1.642189) (xy 369.982508 -1.718949) (xy 369.937367 -1.791855) (xy 369.885691 -1.860284)
			(xy 369.827922 -1.923654) (xy 369.764552 -1.981423) (xy 369.696123 -2.033099) (xy 369.623217 -2.07824)
			(xy 369.546457 -2.116462) (xy 369.466498 -2.147438) (xy 369.384022 -2.170905) (xy 369.299732 -2.186661)
			(xy 369.214349 -2.194573) (xy 369.128599 -2.194573) (xy 369.043216 -2.186661) (xy 368.958926 -2.170905)
			(xy 368.87645 -2.147438) (xy 368.796491 -2.116462) (xy 368.719731 -2.07824) (xy 368.646825 -2.033099)
			(xy 368.578396 -1.981423) (xy 368.515026 -1.923654) (xy 368.457257 -1.860284) (xy 368.405581 -1.791855)
			(xy 368.36044 -1.718949) (xy 368.322218 -1.642189) (xy 368.291242 -1.56223) (xy 368.267775 -1.479754)
			(xy 368.252019 -1.395464) (xy 368.244107 -1.310081) (xy 363.748841 -1.310081) (xy 363.740929 -1.395464)
			(xy 363.725173 -1.479754) (xy 363.701706 -1.56223) (xy 363.67073 -1.642189) (xy 363.632508 -1.718949)
			(xy 363.587367 -1.791855) (xy 363.535691 -1.860284) (xy 363.477922 -1.923654) (xy 363.414552 -1.981423)
			(xy 363.346123 -2.033099) (xy 363.273217 -2.07824) (xy 363.196457 -2.116462) (xy 363.116498 -2.147438)
			(xy 363.034022 -2.170905) (xy 362.949732 -2.186661) (xy 362.864349 -2.194573) (xy 362.778599 -2.194573)
			(xy 362.693216 -2.186661) (xy 362.608926 -2.170905) (xy 362.52645 -2.147438) (xy 362.446491 -2.116462)
			(xy 362.369731 -2.07824) (xy 362.296825 -2.033099) (xy 362.228396 -1.981423) (xy 362.165026 -1.923654)
			(xy 362.107257 -1.860284) (xy 362.055581 -1.791855) (xy 362.01044 -1.718949) (xy 361.972218 -1.642189)
			(xy 361.941242 -1.56223) (xy 361.917775 -1.479754) (xy 361.902019 -1.395464) (xy 361.894107 -1.310081)
			(xy 319.360055 -1.310081) (xy 319.352143 -1.395464) (xy 319.336387 -1.479754) (xy 319.31292 -1.56223)
			(xy 319.281944 -1.642189) (xy 319.243722 -1.718949) (xy 319.198581 -1.791855) (xy 319.146905 -1.860284)
			(xy 319.089136 -1.923654) (xy 319.025766 -1.981423) (xy 318.957337 -2.033099) (xy 318.884431 -2.07824)
			(xy 318.807671 -2.116462) (xy 318.727712 -2.147438) (xy 318.645236 -2.170905) (xy 318.560946 -2.186661)
			(xy 318.475563 -2.194573) (xy 318.389813 -2.194573) (xy 318.30443 -2.186661) (xy 318.22014 -2.170905)
			(xy 318.137664 -2.147438) (xy 318.057705 -2.116462) (xy 317.980945 -2.07824) (xy 317.908039 -2.033099)
			(xy 317.83961 -1.981423) (xy 317.77624 -1.923654) (xy 317.718471 -1.860284) (xy 317.666795 -1.791855)
			(xy 317.621654 -1.718949) (xy 317.583432 -1.642189) (xy 317.552456 -1.56223) (xy 317.528989 -1.479754)
			(xy 317.513233 -1.395464) (xy 317.505321 -1.310081) (xy 313.010055 -1.310081) (xy 313.002143 -1.395464)
			(xy 312.986387 -1.479754) (xy 312.96292 -1.56223) (xy 312.931944 -1.642189) (xy 312.893722 -1.718949)
			(xy 312.848581 -1.791855) (xy 312.796905 -1.860284) (xy 312.739136 -1.923654) (xy 312.675766 -1.981423)
			(xy 312.607337 -2.033099) (xy 312.534431 -2.07824) (xy 312.457671 -2.116462) (xy 312.377712 -2.147438)
			(xy 312.295236 -2.170905) (xy 312.210946 -2.186661) (xy 312.125563 -2.194573) (xy 312.039813 -2.194573)
			(xy 311.95443 -2.186661) (xy 311.87014 -2.170905) (xy 311.787664 -2.147438) (xy 311.707705 -2.116462)
			(xy 311.630945 -2.07824) (xy 311.558039 -2.033099) (xy 311.48961 -1.981423) (xy 311.42624 -1.923654)
			(xy 311.368471 -1.860284) (xy 311.316795 -1.791855) (xy 311.271654 -1.718949) (xy 311.233432 -1.642189)
			(xy 311.202456 -1.56223) (xy 311.178989 -1.479754) (xy 311.163233 -1.395464) (xy 311.155321 -1.310081)
			(xy 304.348655 -1.310081) (xy 304.340743 -1.395464) (xy 304.324987 -1.479754) (xy 304.30152 -1.56223)
			(xy 304.270544 -1.642189) (xy 304.232322 -1.718949) (xy 304.187181 -1.791855) (xy 304.135505 -1.860284)
			(xy 304.077736 -1.923654) (xy 304.014366 -1.981423) (xy 303.945937 -2.033099) (xy 303.873031 -2.07824)
			(xy 303.796271 -2.116462) (xy 303.716312 -2.147438) (xy 303.633836 -2.170905) (xy 303.549546 -2.186661)
			(xy 303.464163 -2.194573) (xy 303.378413 -2.194573) (xy 303.29303 -2.186661) (xy 303.20874 -2.170905)
			(xy 303.126264 -2.147438) (xy 303.046305 -2.116462) (xy 302.969545 -2.07824) (xy 302.896639 -2.033099)
			(xy 302.82821 -1.981423) (xy 302.76484 -1.923654) (xy 302.707071 -1.860284) (xy 302.655395 -1.791855)
			(xy 302.610254 -1.718949) (xy 302.572032 -1.642189) (xy 302.541056 -1.56223) (xy 302.517589 -1.479754)
			(xy 302.501833 -1.395464) (xy 302.493921 -1.310081) (xy 297.998655 -1.310081) (xy 297.990743 -1.395464)
			(xy 297.974987 -1.479754) (xy 297.95152 -1.56223) (xy 297.920544 -1.642189) (xy 297.882322 -1.718949)
			(xy 297.837181 -1.791855) (xy 297.785505 -1.860284) (xy 297.727736 -1.923654) (xy 297.664366 -1.981423)
			(xy 297.595937 -2.033099) (xy 297.523031 -2.07824) (xy 297.446271 -2.116462) (xy 297.366312 -2.147438)
			(xy 297.283836 -2.170905) (xy 297.199546 -2.186661) (xy 297.114163 -2.194573) (xy 297.028413 -2.194573)
			(xy 296.94303 -2.186661) (xy 296.85874 -2.170905) (xy 296.776264 -2.147438) (xy 296.696305 -2.116462)
			(xy 296.619545 -2.07824) (xy 296.546639 -2.033099) (xy 296.47821 -1.981423) (xy 296.41484 -1.923654)
			(xy 296.357071 -1.860284) (xy 296.305395 -1.791855) (xy 296.260254 -1.718949) (xy 296.222032 -1.642189)
			(xy 296.191056 -1.56223) (xy 296.167589 -1.479754) (xy 296.151833 -1.395464) (xy 296.143921 -1.310081)
			(xy 216.865975 -1.310081) (xy 216.858063 -1.395464) (xy 216.842307 -1.479754) (xy 216.81884 -1.56223)
			(xy 216.787864 -1.642189) (xy 216.749642 -1.718949) (xy 216.704501 -1.791855) (xy 216.652825 -1.860284)
			(xy 216.595056 -1.923654) (xy 216.531686 -1.981423) (xy 216.463257 -2.033099) (xy 216.390351 -2.07824)
			(xy 216.313591 -2.116462) (xy 216.233632 -2.147438) (xy 216.151156 -2.170905) (xy 216.066866 -2.186661)
			(xy 215.981483 -2.194573) (xy 215.895733 -2.194573) (xy 215.81035 -2.186661) (xy 215.72606 -2.170905)
			(xy 215.643584 -2.147438) (xy 215.563625 -2.116462) (xy 215.486865 -2.07824) (xy 215.413959 -2.033099)
			(xy 215.34553 -1.981423) (xy 215.28216 -1.923654) (xy 215.224391 -1.860284) (xy 215.172715 -1.791855)
			(xy 215.127574 -1.718949) (xy 215.089352 -1.642189) (xy 215.058376 -1.56223) (xy 215.034909 -1.479754)
			(xy 215.019153 -1.395464) (xy 215.011241 -1.310081) (xy 210.515975 -1.310081) (xy 210.508063 -1.395464)
			(xy 210.492307 -1.479754) (xy 210.46884 -1.56223) (xy 210.437864 -1.642189) (xy 210.399642 -1.718949)
			(xy 210.354501 -1.791855) (xy 210.302825 -1.860284) (xy 210.245056 -1.923654) (xy 210.181686 -1.981423)
			(xy 210.113257 -2.033099) (xy 210.040351 -2.07824) (xy 209.963591 -2.116462) (xy 209.883632 -2.147438)
			(xy 209.801156 -2.170905) (xy 209.716866 -2.186661) (xy 209.631483 -2.194573) (xy 209.545733 -2.194573)
			(xy 209.46035 -2.186661) (xy 209.37606 -2.170905) (xy 209.293584 -2.147438) (xy 209.213625 -2.116462)
			(xy 209.136865 -2.07824) (xy 209.063959 -2.033099) (xy 208.99553 -1.981423) (xy 208.93216 -1.923654)
			(xy 208.874391 -1.860284) (xy 208.822715 -1.791855) (xy 208.777574 -1.718949) (xy 208.739352 -1.642189)
			(xy 208.708376 -1.56223) (xy 208.684909 -1.479754) (xy 208.669153 -1.395464) (xy 208.661241 -1.310081)
			(xy 84.210906 -1.310081) (xy 84.210906 -7.78002) (xy 84.211428 -7.835789) (xy 84.219765 -7.947014)
			(xy 84.23639 -8.057306) (xy 84.26121 -8.166046) (xy 84.294088 -8.272628) (xy 84.334838 -8.376455)
			(xy 84.383233 -8.476947) (xy 84.439002 -8.573541) (xy 84.501834 -8.665697) (xy 84.571376 -8.7529)
			(xy 84.647241 -8.834663) (xy 84.729004 -8.910527) (xy 84.816208 -8.98007) (xy 84.908364 -9.042901)
			(xy 85.004959 -9.09867) (xy 85.10545 -9.147065) (xy 85.209277 -9.187814) (xy 85.315859 -9.220691)
			(xy 85.4246 -9.245511) (xy 85.534892 -9.262136) (xy 85.646117 -9.270472) (xy 85.701886 -9.271) (xy 122.102118 -9.271)
			(xy 122.157887 -9.270478) (xy 122.269113 -9.262141) (xy 122.379404 -9.245517) (xy 122.488145 -9.220696)
			(xy 122.594728 -9.187819) (xy 122.698555 -9.147069) (xy 122.799047 -9.098674) (xy 122.895641 -9.042905)
			(xy 122.987798 -8.980073) (xy 123.075001 -8.910531) (xy 123.156764 -8.834666) (xy 123.232629 -8.752903)
			(xy 123.302172 -8.665699) (xy 123.365004 -8.573543) (xy 123.420773 -8.476948) (xy 123.469168 -8.376457)
			(xy 123.509918 -8.27263) (xy 123.542796 -8.166047) (xy 123.567616 -8.057306) (xy 123.584241 -7.947015)
			(xy 123.592578 -7.835789) (xy 123.593098 -7.78002) (xy 123.593098 -4.879848) (xy 123.593581 -4.809465)
			(xy 123.601472 -4.66892) (xy 123.61723 -4.529038) (xy 123.640807 -4.39026) (xy 123.672128 -4.253022)
			(xy 123.711095 -4.117757) (xy 123.757586 -3.984889) (xy 123.811453 -3.854837) (xy 123.872528 -3.72801)
			(xy 123.940618 -3.604807) (xy 124.015509 -3.485616) (xy 124.096965 -3.370811) (xy 124.184731 -3.260755)
			(xy 124.278529 -3.155793) (xy 124.378065 -3.056255) (xy 124.483026 -2.962455) (xy 124.593081 -2.874688)
			(xy 124.707884 -2.79323) (xy 124.827074 -2.718337) (xy 124.950276 -2.650245) (xy 125.077102 -2.589169)
			(xy 125.207153 -2.535299) (xy 125.340021 -2.488807) (xy 125.475285 -2.449838) (xy 125.612523 -2.418514)
			(xy 125.7513 -2.394935) (xy 125.891182 -2.379175) (xy 126.031727 -2.371282) (xy 126.10211 -2.370836)
			(xy 194.701922 -2.370836) (xy 194.772304 -2.371321) (xy 194.912845 -2.379215) (xy 195.052723 -2.394977)
			(xy 195.191497 -2.418557) (xy 195.328731 -2.449881) (xy 195.463992 -2.488851) (xy 195.596856 -2.535344)
			(xy 195.726904 -2.589213) (xy 195.853726 -2.650289) (xy 195.976925 -2.71838) (xy 196.096111 -2.793273)
			(xy 196.210911 -2.87473) (xy 196.320963 -2.962495) (xy 196.425921 -3.056294) (xy 196.525454 -3.15583)
			(xy 196.61925 -3.26079) (xy 196.707012 -3.370845) (xy 196.788466 -3.485647) (xy 196.863355 -3.604836)
			(xy 196.931443 -3.728036) (xy 196.990215 -3.850081) (xy 208.661241 -3.850081) (xy 208.661241 -3.764331)
			(xy 208.669153 -3.678948) (xy 208.684909 -3.594658) (xy 208.708376 -3.512182) (xy 208.739352 -3.432223)
			(xy 208.777574 -3.355463) (xy 208.822715 -3.282557) (xy 208.874391 -3.214128) (xy 208.93216 -3.150758)
			(xy 208.99553 -3.092989) (xy 209.063959 -3.041313) (xy 209.136865 -2.996172) (xy 209.213625 -2.95795)
			(xy 209.293584 -2.926974) (xy 209.37606 -2.903507) (xy 209.46035 -2.887751) (xy 209.545733 -2.879839)
			(xy 209.631483 -2.879839) (xy 209.716866 -2.887751) (xy 209.801156 -2.903507) (xy 209.883632 -2.926974)
			(xy 209.963591 -2.95795) (xy 209.984264 -2.968244) (xy 213.517988 -2.968244) (xy 213.517988 -2.104644)
			(xy 213.518492 -2.07509) (xy 213.526541 -2.016534) (xy 213.542487 -1.959619) (xy 213.566036 -1.905405)
			(xy 213.596747 -1.854902) (xy 213.634049 -1.809052) (xy 213.677246 -1.768709) (xy 213.725535 -1.734623)
			(xy 213.778015 -1.70743) (xy 213.83371 -1.687636) (xy 213.891581 -1.67561) (xy 213.95055 -1.671577)
			(xy 214.009519 -1.67561) (xy 214.06739 -1.687636) (xy 214.123085 -1.70743) (xy 214.175565 -1.734623)
			(xy 214.223854 -1.768709) (xy 214.267051 -1.809052) (xy 214.304353 -1.854902) (xy 214.335064 -1.905405)
			(xy 214.358613 -1.959619) (xy 214.374559 -2.016534) (xy 214.382608 -2.07509) (xy 214.383112 -2.104644)
			(xy 214.383112 -2.968244) (xy 214.382608 -2.997798) (xy 214.374559 -3.056354) (xy 214.358613 -3.113269)
			(xy 214.335064 -3.167483) (xy 214.304353 -3.217986) (xy 214.267051 -3.263836) (xy 214.223854 -3.304179)
			(xy 214.175565 -3.338265) (xy 214.123085 -3.365458) (xy 214.06739 -3.385252) (xy 214.009519 -3.397278)
			(xy 213.95055 -3.401312) (xy 213.891581 -3.397278) (xy 213.83371 -3.385252) (xy 213.778015 -3.365458)
			(xy 213.725535 -3.338265) (xy 213.677246 -3.304179) (xy 213.634049 -3.263836) (xy 213.596747 -3.217986)
			(xy 213.566036 -3.167483) (xy 213.542487 -3.113269) (xy 213.526541 -3.056354) (xy 213.518492 -2.997798)
			(xy 213.517988 -2.968244) (xy 209.984264 -2.968244) (xy 210.040351 -2.996172) (xy 210.113257 -3.041313)
			(xy 210.181686 -3.092989) (xy 210.245056 -3.150758) (xy 210.302825 -3.214128) (xy 210.354501 -3.282557)
			(xy 210.399642 -3.355463) (xy 210.437864 -3.432223) (xy 210.46884 -3.512182) (xy 210.492307 -3.594658)
			(xy 210.508063 -3.678948) (xy 210.515975 -3.764331) (xy 210.51647 -3.807206) (xy 210.515975 -3.850081)
			(xy 215.011241 -3.850081) (xy 215.011241 -3.764331) (xy 215.019153 -3.678948) (xy 215.034909 -3.594658)
			(xy 215.058376 -3.512182) (xy 215.089352 -3.432223) (xy 215.127574 -3.355463) (xy 215.172715 -3.282557)
			(xy 215.224391 -3.214128) (xy 215.28216 -3.150758) (xy 215.34553 -3.092989) (xy 215.413959 -3.041313)
			(xy 215.486865 -2.996172) (xy 215.563625 -2.95795) (xy 215.643584 -2.926974) (xy 215.72606 -2.903507)
			(xy 215.81035 -2.887751) (xy 215.895733 -2.879839) (xy 215.981483 -2.879839) (xy 216.066866 -2.887751)
			(xy 216.151156 -2.903507) (xy 216.233632 -2.926974) (xy 216.313591 -2.95795) (xy 216.390351 -2.996172)
			(xy 216.463257 -3.041313) (xy 216.531686 -3.092989) (xy 216.595056 -3.150758) (xy 216.652825 -3.214128)
			(xy 216.704501 -3.282557) (xy 216.749642 -3.355463) (xy 216.787864 -3.432223) (xy 216.81884 -3.512182)
			(xy 216.842307 -3.594658) (xy 216.858063 -3.678948) (xy 216.865975 -3.764331) (xy 216.86647 -3.807206)
			(xy 216.865975 -3.850081) (xy 296.143921 -3.850081) (xy 296.143921 -3.764331) (xy 296.151833 -3.678948)
			(xy 296.167589 -3.594658) (xy 296.191056 -3.512182) (xy 296.222032 -3.432223) (xy 296.260254 -3.355463)
			(xy 296.305395 -3.282557) (xy 296.357071 -3.214128) (xy 296.41484 -3.150758) (xy 296.47821 -3.092989)
			(xy 296.546639 -3.041313) (xy 296.619545 -2.996172) (xy 296.696305 -2.95795) (xy 296.776264 -2.926974)
			(xy 296.85874 -2.903507) (xy 296.94303 -2.887751) (xy 297.028413 -2.879839) (xy 297.114163 -2.879839)
			(xy 297.199546 -2.887751) (xy 297.283836 -2.903507) (xy 297.366312 -2.926974) (xy 297.446271 -2.95795)
			(xy 297.466944 -2.968244) (xy 298.629324 -2.968244) (xy 298.629324 -2.104644) (xy 298.629828 -2.07509)
			(xy 298.637877 -2.016534) (xy 298.653823 -1.959619) (xy 298.677372 -1.905405) (xy 298.708083 -1.854902)
			(xy 298.745385 -1.809052) (xy 298.788582 -1.768709) (xy 298.836871 -1.734623) (xy 298.889351 -1.70743)
			(xy 298.945046 -1.687636) (xy 299.002917 -1.67561) (xy 299.061886 -1.671577) (xy 299.120855 -1.67561)
			(xy 299.178726 -1.687636) (xy 299.234421 -1.70743) (xy 299.286901 -1.734623) (xy 299.33519 -1.768709)
			(xy 299.378387 -1.809052) (xy 299.415689 -1.854902) (xy 299.4464 -1.905405) (xy 299.469949 -1.959619)
			(xy 299.485895 -2.016534) (xy 299.493944 -2.07509) (xy 299.494448 -2.104644) (xy 299.494448 -2.968244)
			(xy 299.493944 -2.997798) (xy 299.485895 -3.056354) (xy 299.469949 -3.113269) (xy 299.4464 -3.167483)
			(xy 299.415689 -3.217986) (xy 299.378387 -3.263836) (xy 299.33519 -3.304179) (xy 299.286901 -3.338265)
			(xy 299.234421 -3.365458) (xy 299.178726 -3.385252) (xy 299.120855 -3.397278) (xy 299.061886 -3.401312)
			(xy 299.002917 -3.397278) (xy 298.945046 -3.385252) (xy 298.889351 -3.365458) (xy 298.836871 -3.338265)
			(xy 298.788582 -3.304179) (xy 298.745385 -3.263836) (xy 298.708083 -3.217986) (xy 298.677372 -3.167483)
			(xy 298.653823 -3.113269) (xy 298.637877 -3.056354) (xy 298.629828 -2.997798) (xy 298.629324 -2.968244)
			(xy 297.466944 -2.968244) (xy 297.523031 -2.996172) (xy 297.595937 -3.041313) (xy 297.664366 -3.092989)
			(xy 297.727736 -3.150758) (xy 297.785505 -3.214128) (xy 297.837181 -3.282557) (xy 297.882322 -3.355463)
			(xy 297.920544 -3.432223) (xy 297.95152 -3.512182) (xy 297.974987 -3.594658) (xy 297.990743 -3.678948)
			(xy 297.998655 -3.764331) (xy 297.99915 -3.807206) (xy 297.998655 -3.850081) (xy 302.493921 -3.850081)
			(xy 302.493921 -3.764331) (xy 302.501833 -3.678948) (xy 302.517589 -3.594658) (xy 302.541056 -3.512182)
			(xy 302.572032 -3.432223) (xy 302.610254 -3.355463) (xy 302.655395 -3.282557) (xy 302.707071 -3.214128)
			(xy 302.76484 -3.150758) (xy 302.82821 -3.092989) (xy 302.896639 -3.041313) (xy 302.969545 -2.996172)
			(xy 303.046305 -2.95795) (xy 303.126264 -2.926974) (xy 303.20874 -2.903507) (xy 303.29303 -2.887751)
			(xy 303.378413 -2.879839) (xy 303.464163 -2.879839) (xy 303.549546 -2.887751) (xy 303.633836 -2.903507)
			(xy 303.716312 -2.926974) (xy 303.796271 -2.95795) (xy 303.873031 -2.996172) (xy 303.945937 -3.041313)
			(xy 304.014366 -3.092989) (xy 304.077736 -3.150758) (xy 304.135505 -3.214128) (xy 304.187181 -3.282557)
			(xy 304.232322 -3.355463) (xy 304.270544 -3.432223) (xy 304.30152 -3.512182) (xy 304.324987 -3.594658)
			(xy 304.340743 -3.678948) (xy 304.348655 -3.764331) (xy 304.34915 -3.807206) (xy 304.348655 -3.850081)
			(xy 311.155321 -3.850081) (xy 311.155321 -3.764331) (xy 311.163233 -3.678948) (xy 311.178989 -3.594658)
			(xy 311.202456 -3.512182) (xy 311.233432 -3.432223) (xy 311.271654 -3.355463) (xy 311.316795 -3.282557)
			(xy 311.368471 -3.214128) (xy 311.42624 -3.150758) (xy 311.48961 -3.092989) (xy 311.558039 -3.041313)
			(xy 311.630945 -2.996172) (xy 311.707705 -2.95795) (xy 311.787664 -2.926974) (xy 311.87014 -2.903507)
			(xy 311.95443 -2.887751) (xy 312.039813 -2.879839) (xy 312.125563 -2.879839) (xy 312.210946 -2.887751)
			(xy 312.295236 -2.903507) (xy 312.377712 -2.926974) (xy 312.457671 -2.95795) (xy 312.478344 -2.968244)
			(xy 316.012068 -2.968244) (xy 316.012068 -2.104644) (xy 316.012572 -2.07509) (xy 316.020621 -2.016534)
			(xy 316.036567 -1.959619) (xy 316.060116 -1.905405) (xy 316.090827 -1.854902) (xy 316.128129 -1.809052)
			(xy 316.171326 -1.768709) (xy 316.219615 -1.734623) (xy 316.272095 -1.70743) (xy 316.32779 -1.687636)
			(xy 316.385661 -1.67561) (xy 316.44463 -1.671577) (xy 316.503599 -1.67561) (xy 316.56147 -1.687636)
			(xy 316.617165 -1.70743) (xy 316.669645 -1.734623) (xy 316.717934 -1.768709) (xy 316.761131 -1.809052)
			(xy 316.798433 -1.854902) (xy 316.829144 -1.905405) (xy 316.852693 -1.959619) (xy 316.868639 -2.016534)
			(xy 316.876688 -2.07509) (xy 316.877192 -2.104644) (xy 316.877192 -2.968244) (xy 316.876688 -2.997798)
			(xy 316.868639 -3.056354) (xy 316.852693 -3.113269) (xy 316.829144 -3.167483) (xy 316.798433 -3.217986)
			(xy 316.761131 -3.263836) (xy 316.717934 -3.304179) (xy 316.669645 -3.338265) (xy 316.617165 -3.365458)
			(xy 316.56147 -3.385252) (xy 316.503599 -3.397278) (xy 316.44463 -3.401312) (xy 316.385661 -3.397278)
			(xy 316.32779 -3.385252) (xy 316.272095 -3.365458) (xy 316.219615 -3.338265) (xy 316.171326 -3.304179)
			(xy 316.128129 -3.263836) (xy 316.090827 -3.217986) (xy 316.060116 -3.167483) (xy 316.036567 -3.113269)
			(xy 316.020621 -3.056354) (xy 316.012572 -2.997798) (xy 316.012068 -2.968244) (xy 312.478344 -2.968244)
			(xy 312.534431 -2.996172) (xy 312.607337 -3.041313) (xy 312.675766 -3.092989) (xy 312.739136 -3.150758)
			(xy 312.796905 -3.214128) (xy 312.848581 -3.282557) (xy 312.893722 -3.355463) (xy 312.931944 -3.432223)
			(xy 312.96292 -3.512182) (xy 312.986387 -3.594658) (xy 313.002143 -3.678948) (xy 313.010055 -3.764331)
			(xy 313.01055 -3.807206) (xy 313.010055 -3.850081) (xy 317.505321 -3.850081) (xy 317.505321 -3.764331)
			(xy 317.513233 -3.678948) (xy 317.528989 -3.594658) (xy 317.552456 -3.512182) (xy 317.583432 -3.432223)
			(xy 317.621654 -3.355463) (xy 317.666795 -3.282557) (xy 317.718471 -3.214128) (xy 317.77624 -3.150758)
			(xy 317.83961 -3.092989) (xy 317.908039 -3.041313) (xy 317.980945 -2.996172) (xy 318.057705 -2.95795)
			(xy 318.137664 -2.926974) (xy 318.22014 -2.903507) (xy 318.30443 -2.887751) (xy 318.389813 -2.879839)
			(xy 318.475563 -2.879839) (xy 318.560946 -2.887751) (xy 318.645236 -2.903507) (xy 318.727712 -2.926974)
			(xy 318.807671 -2.95795) (xy 318.884431 -2.996172) (xy 318.957337 -3.041313) (xy 319.025766 -3.092989)
			(xy 319.089136 -3.150758) (xy 319.146905 -3.214128) (xy 319.198581 -3.282557) (xy 319.243722 -3.355463)
			(xy 319.281944 -3.432223) (xy 319.31292 -3.512182) (xy 319.336387 -3.594658) (xy 319.352143 -3.678948)
			(xy 319.360055 -3.764331) (xy 319.36055 -3.807206) (xy 319.360055 -3.850081) (xy 361.894107 -3.850081)
			(xy 361.894107 -3.764331) (xy 361.902019 -3.678948) (xy 361.917775 -3.594658) (xy 361.941242 -3.512182)
			(xy 361.972218 -3.432223) (xy 362.01044 -3.355463) (xy 362.055581 -3.282557) (xy 362.107257 -3.214128)
			(xy 362.165026 -3.150758) (xy 362.228396 -3.092989) (xy 362.296825 -3.041313) (xy 362.369731 -2.996172)
			(xy 362.446491 -2.95795) (xy 362.52645 -2.926974) (xy 362.608926 -2.903507) (xy 362.693216 -2.887751)
			(xy 362.778599 -2.879839) (xy 362.864349 -2.879839) (xy 362.949732 -2.887751) (xy 363.034022 -2.903507)
			(xy 363.116498 -2.926974) (xy 363.196457 -2.95795) (xy 363.21713 -2.968244) (xy 364.379764 -2.968244)
			(xy 364.379764 -2.104644) (xy 364.380268 -2.075108) (xy 364.388312 -2.016586) (xy 364.404249 -1.959704)
			(xy 364.427784 -1.905522) (xy 364.458477 -1.855049) (xy 364.495757 -1.809226) (xy 364.538929 -1.768906)
			(xy 364.587189 -1.73484) (xy 364.639639 -1.707663) (xy 364.6953 -1.687881) (xy 364.753137 -1.675862)
			(xy 364.812072 -1.671831) (xy 364.871007 -1.675862) (xy 364.928844 -1.687881) (xy 364.984505 -1.707663)
			(xy 365.036955 -1.73484) (xy 365.085215 -1.768906) (xy 365.128387 -1.809226) (xy 365.165667 -1.855049)
			(xy 365.19636 -1.905522) (xy 365.219895 -1.959704) (xy 365.235832 -2.016586) (xy 365.243876 -2.075108)
			(xy 365.24438 -2.104644) (xy 365.24438 -2.968244) (xy 365.243876 -2.99778) (xy 365.235832 -3.056302)
			(xy 365.219895 -3.113184) (xy 365.19636 -3.167366) (xy 365.165667 -3.217839) (xy 365.128387 -3.263662)
			(xy 365.085215 -3.303982) (xy 365.036955 -3.338048) (xy 364.984505 -3.365225) (xy 364.928844 -3.385007)
			(xy 364.871007 -3.397026) (xy 364.812072 -3.401057) (xy 364.753137 -3.397026) (xy 364.6953 -3.385007)
			(xy 364.639639 -3.365225) (xy 364.587189 -3.338048) (xy 364.538929 -3.303982) (xy 364.495757 -3.263662)
			(xy 364.458477 -3.217839) (xy 364.427784 -3.167366) (xy 364.404249 -3.113184) (xy 364.388312 -3.056302)
			(xy 364.380268 -2.99778) (xy 364.379764 -2.968244) (xy 363.21713 -2.968244) (xy 363.273217 -2.996172)
			(xy 363.346123 -3.041313) (xy 363.414552 -3.092989) (xy 363.477922 -3.150758) (xy 363.535691 -3.214128)
			(xy 363.587367 -3.282557) (xy 363.632508 -3.355463) (xy 363.67073 -3.432223) (xy 363.701706 -3.512182)
			(xy 363.725173 -3.594658) (xy 363.740929 -3.678948) (xy 363.748841 -3.764331) (xy 363.749336 -3.807206)
			(xy 363.748841 -3.850081) (xy 368.244107 -3.850081) (xy 368.244107 -3.764331) (xy 368.252019 -3.678948)
			(xy 368.267775 -3.594658) (xy 368.291242 -3.512182) (xy 368.322218 -3.432223) (xy 368.36044 -3.355463)
			(xy 368.405581 -3.282557) (xy 368.457257 -3.214128) (xy 368.515026 -3.150758) (xy 368.578396 -3.092989)
			(xy 368.646825 -3.041313) (xy 368.719731 -2.996172) (xy 368.796491 -2.95795) (xy 368.87645 -2.926974)
			(xy 368.958926 -2.903507) (xy 369.043216 -2.887751) (xy 369.128599 -2.879839) (xy 369.214349 -2.879839)
			(xy 369.299732 -2.887751) (xy 369.384022 -2.903507) (xy 369.466498 -2.926974) (xy 369.546457 -2.95795)
			(xy 369.623217 -2.996172) (xy 369.696123 -3.041313) (xy 369.764552 -3.092989) (xy 369.827922 -3.150758)
			(xy 369.885691 -3.214128) (xy 369.937367 -3.282557) (xy 369.982508 -3.355463) (xy 370.02073 -3.432223)
			(xy 370.051706 -3.512182) (xy 370.075173 -3.594658) (xy 370.090929 -3.678948) (xy 370.098841 -3.764331)
			(xy 370.099336 -3.807206) (xy 370.098841 -3.850081) (xy 370.090929 -3.935464) (xy 370.075173 -4.019754)
			(xy 370.051706 -4.10223) (xy 370.02073 -4.182189) (xy 369.982508 -4.258949) (xy 369.937367 -4.331855)
			(xy 369.885691 -4.400284) (xy 369.827922 -4.463654) (xy 369.764552 -4.521423) (xy 369.696123 -4.573099)
			(xy 369.623217 -4.61824) (xy 369.546457 -4.656462) (xy 369.466498 -4.687438) (xy 369.384022 -4.710905)
			(xy 369.299732 -4.726661) (xy 369.214349 -4.734573) (xy 369.128599 -4.734573) (xy 369.043216 -4.726661)
			(xy 368.958926 -4.710905) (xy 368.87645 -4.687438) (xy 368.796491 -4.656462) (xy 368.719731 -4.61824)
			(xy 368.646825 -4.573099) (xy 368.578396 -4.521423) (xy 368.515026 -4.463654) (xy 368.457257 -4.400284)
			(xy 368.405581 -4.331855) (xy 368.36044 -4.258949) (xy 368.322218 -4.182189) (xy 368.291242 -4.10223)
			(xy 368.267775 -4.019754) (xy 368.252019 -3.935464) (xy 368.244107 -3.850081) (xy 363.748841 -3.850081)
			(xy 363.740929 -3.935464) (xy 363.725173 -4.019754) (xy 363.701706 -4.10223) (xy 363.67073 -4.182189)
			(xy 363.632508 -4.258949) (xy 363.587367 -4.331855) (xy 363.535691 -4.400284) (xy 363.477922 -4.463654)
			(xy 363.414552 -4.521423) (xy 363.346123 -4.573099) (xy 363.273217 -4.61824) (xy 363.196457 -4.656462)
			(xy 363.116498 -4.687438) (xy 363.034022 -4.710905) (xy 362.949732 -4.726661) (xy 362.864349 -4.734573)
			(xy 362.778599 -4.734573) (xy 362.693216 -4.726661) (xy 362.608926 -4.710905) (xy 362.52645 -4.687438)
			(xy 362.446491 -4.656462) (xy 362.369731 -4.61824) (xy 362.296825 -4.573099) (xy 362.228396 -4.521423)
			(xy 362.165026 -4.463654) (xy 362.107257 -4.400284) (xy 362.055581 -4.331855) (xy 362.01044 -4.258949)
			(xy 361.972218 -4.182189) (xy 361.941242 -4.10223) (xy 361.917775 -4.019754) (xy 361.902019 -3.935464)
			(xy 361.894107 -3.850081) (xy 319.360055 -3.850081) (xy 319.352143 -3.935464) (xy 319.336387 -4.019754)
			(xy 319.31292 -4.10223) (xy 319.281944 -4.182189) (xy 319.243722 -4.258949) (xy 319.198581 -4.331855)
			(xy 319.146905 -4.400284) (xy 319.089136 -4.463654) (xy 319.025766 -4.521423) (xy 318.957337 -4.573099)
			(xy 318.884431 -4.61824) (xy 318.807671 -4.656462) (xy 318.727712 -4.687438) (xy 318.645236 -4.710905)
			(xy 318.560946 -4.726661) (xy 318.475563 -4.734573) (xy 318.389813 -4.734573) (xy 318.30443 -4.726661)
			(xy 318.22014 -4.710905) (xy 318.137664 -4.687438) (xy 318.057705 -4.656462) (xy 317.980945 -4.61824)
			(xy 317.908039 -4.573099) (xy 317.83961 -4.521423) (xy 317.77624 -4.463654) (xy 317.718471 -4.400284)
			(xy 317.666795 -4.331855) (xy 317.621654 -4.258949) (xy 317.583432 -4.182189) (xy 317.552456 -4.10223)
			(xy 317.528989 -4.019754) (xy 317.513233 -3.935464) (xy 317.505321 -3.850081) (xy 313.010055 -3.850081)
			(xy 313.002143 -3.935464) (xy 312.986387 -4.019754) (xy 312.96292 -4.10223) (xy 312.931944 -4.182189)
			(xy 312.893722 -4.258949) (xy 312.848581 -4.331855) (xy 312.796905 -4.400284) (xy 312.739136 -4.463654)
			(xy 312.675766 -4.521423) (xy 312.607337 -4.573099) (xy 312.534431 -4.61824) (xy 312.457671 -4.656462)
			(xy 312.377712 -4.687438) (xy 312.295236 -4.710905) (xy 312.210946 -4.726661) (xy 312.125563 -4.734573)
			(xy 312.039813 -4.734573) (xy 311.95443 -4.726661) (xy 311.87014 -4.710905) (xy 311.787664 -4.687438)
			(xy 311.707705 -4.656462) (xy 311.630945 -4.61824) (xy 311.558039 -4.573099) (xy 311.48961 -4.521423)
			(xy 311.42624 -4.463654) (xy 311.368471 -4.400284) (xy 311.316795 -4.331855) (xy 311.271654 -4.258949)
			(xy 311.233432 -4.182189) (xy 311.202456 -4.10223) (xy 311.178989 -4.019754) (xy 311.163233 -3.935464)
			(xy 311.155321 -3.850081) (xy 304.348655 -3.850081) (xy 304.340743 -3.935464) (xy 304.324987 -4.019754)
			(xy 304.30152 -4.10223) (xy 304.270544 -4.182189) (xy 304.232322 -4.258949) (xy 304.187181 -4.331855)
			(xy 304.135505 -4.400284) (xy 304.077736 -4.463654) (xy 304.014366 -4.521423) (xy 303.945937 -4.573099)
			(xy 303.873031 -4.61824) (xy 303.796271 -4.656462) (xy 303.716312 -4.687438) (xy 303.633836 -4.710905)
			(xy 303.549546 -4.726661) (xy 303.464163 -4.734573) (xy 303.378413 -4.734573) (xy 303.29303 -4.726661)
			(xy 303.20874 -4.710905) (xy 303.126264 -4.687438) (xy 303.046305 -4.656462) (xy 302.969545 -4.61824)
			(xy 302.896639 -4.573099) (xy 302.82821 -4.521423) (xy 302.76484 -4.463654) (xy 302.707071 -4.400284)
			(xy 302.655395 -4.331855) (xy 302.610254 -4.258949) (xy 302.572032 -4.182189) (xy 302.541056 -4.10223)
			(xy 302.517589 -4.019754) (xy 302.501833 -3.935464) (xy 302.493921 -3.850081) (xy 297.998655 -3.850081)
			(xy 297.990743 -3.935464) (xy 297.974987 -4.019754) (xy 297.95152 -4.10223) (xy 297.920544 -4.182189)
			(xy 297.882322 -4.258949) (xy 297.837181 -4.331855) (xy 297.785505 -4.400284) (xy 297.727736 -4.463654)
			(xy 297.664366 -4.521423) (xy 297.595937 -4.573099) (xy 297.523031 -4.61824) (xy 297.446271 -4.656462)
			(xy 297.366312 -4.687438) (xy 297.283836 -4.710905) (xy 297.199546 -4.726661) (xy 297.114163 -4.734573)
			(xy 297.028413 -4.734573) (xy 296.94303 -4.726661) (xy 296.85874 -4.710905) (xy 296.776264 -4.687438)
			(xy 296.696305 -4.656462) (xy 296.619545 -4.61824) (xy 296.546639 -4.573099) (xy 296.47821 -4.521423)
			(xy 296.41484 -4.463654) (xy 296.357071 -4.400284) (xy 296.305395 -4.331855) (xy 296.260254 -4.258949)
			(xy 296.222032 -4.182189) (xy 296.191056 -4.10223) (xy 296.167589 -4.019754) (xy 296.151833 -3.935464)
			(xy 296.143921 -3.850081) (xy 216.865975 -3.850081) (xy 216.858063 -3.935464) (xy 216.842307 -4.019754)
			(xy 216.81884 -4.10223) (xy 216.787864 -4.182189) (xy 216.749642 -4.258949) (xy 216.704501 -4.331855)
			(xy 216.652825 -4.400284) (xy 216.595056 -4.463654) (xy 216.531686 -4.521423) (xy 216.463257 -4.573099)
			(xy 216.390351 -4.61824) (xy 216.313591 -4.656462) (xy 216.233632 -4.687438) (xy 216.151156 -4.710905)
			(xy 216.066866 -4.726661) (xy 215.981483 -4.734573) (xy 215.895733 -4.734573) (xy 215.81035 -4.726661)
			(xy 215.72606 -4.710905) (xy 215.643584 -4.687438) (xy 215.563625 -4.656462) (xy 215.486865 -4.61824)
			(xy 215.413959 -4.573099) (xy 215.34553 -4.521423) (xy 215.28216 -4.463654) (xy 215.224391 -4.400284)
			(xy 215.172715 -4.331855) (xy 215.127574 -4.258949) (xy 215.089352 -4.182189) (xy 215.058376 -4.10223)
			(xy 215.034909 -4.019754) (xy 215.019153 -3.935464) (xy 215.011241 -3.850081) (xy 210.515975 -3.850081)
			(xy 210.508063 -3.935464) (xy 210.492307 -4.019754) (xy 210.46884 -4.10223) (xy 210.437864 -4.182189)
			(xy 210.399642 -4.258949) (xy 210.354501 -4.331855) (xy 210.302825 -4.400284) (xy 210.245056 -4.463654)
			(xy 210.181686 -4.521423) (xy 210.113257 -4.573099) (xy 210.040351 -4.61824) (xy 209.963591 -4.656462)
			(xy 209.883632 -4.687438) (xy 209.801156 -4.710905) (xy 209.716866 -4.726661) (xy 209.631483 -4.734573)
			(xy 209.545733 -4.734573) (xy 209.46035 -4.726661) (xy 209.37606 -4.710905) (xy 209.293584 -4.687438)
			(xy 209.213625 -4.656462) (xy 209.136865 -4.61824) (xy 209.063959 -4.573099) (xy 208.99553 -4.521423)
			(xy 208.93216 -4.463654) (xy 208.874391 -4.400284) (xy 208.822715 -4.331855) (xy 208.777574 -4.258949)
			(xy 208.739352 -4.182189) (xy 208.708376 -4.10223) (xy 208.684909 -4.019754) (xy 208.669153 -3.935464)
			(xy 208.661241 -3.850081) (xy 196.990215 -3.850081) (xy 196.992516 -3.85486) (xy 197.046381 -3.984909)
			(xy 197.09287 -4.117774) (xy 197.131836 -4.253037) (xy 197.163157 -4.390271) (xy 197.186733 -4.529046)
			(xy 197.202491 -4.668924) (xy 197.210381 -4.809466) (xy 197.210934 -4.879848) (xy 197.210934 -6.390081)
			(xy 208.661241 -6.390081) (xy 208.661241 -6.304331) (xy 208.669153 -6.218948) (xy 208.684909 -6.134658)
			(xy 208.708376 -6.052182) (xy 208.739352 -5.972223) (xy 208.777574 -5.895463) (xy 208.822715 -5.822557)
			(xy 208.874391 -5.754128) (xy 208.93216 -5.690758) (xy 208.99553 -5.632989) (xy 209.063959 -5.581313)
			(xy 209.136865 -5.536172) (xy 209.213625 -5.49795) (xy 209.293584 -5.466974) (xy 209.37606 -5.443507)
			(xy 209.46035 -5.427751) (xy 209.545733 -5.419839) (xy 209.631483 -5.419839) (xy 209.716866 -5.427751)
			(xy 209.801156 -5.443507) (xy 209.883632 -5.466974) (xy 209.963591 -5.49795) (xy 210.040351 -5.536172)
			(xy 210.113257 -5.581313) (xy 210.168864 -5.623306) (xy 212.819996 -5.623306) (xy 212.819996 -4.526026)
			(xy 212.820529 -4.513942) (xy 212.827973 -4.49095) (xy 212.842144 -4.471373) (xy 212.861661 -4.45712)
			(xy 212.884622 -4.44958) (xy 212.896704 -4.449064) (xy 213.508844 -4.449064) (xy 213.512908 -4.449318)
			(xy 213.518925 -4.449383) (xy 213.530731 -4.447082) (xy 213.536276 -4.444746) (xy 213.562946 -4.432808)
			(xy 213.56961 -4.429551) (xy 213.580841 -4.41987) (xy 213.585044 -4.413758) (xy 213.60215 -4.387753)
			(xy 213.642596 -4.340442) (xy 213.689408 -4.29942) (xy 213.741619 -4.265535) (xy 213.798149 -4.239487)
			(xy 213.85783 -4.221814) (xy 213.919429 -4.212881) (xy 213.95055 -4.212336) (xy 213.978862 -4.212754)
			(xy 214.035 -4.220148) (xy 214.089695 -4.234803) (xy 214.142009 -4.256468) (xy 214.19105 -4.284774)
			(xy 214.235979 -4.319237) (xy 214.276027 -4.359266) (xy 214.310511 -4.404178) (xy 214.33884 -4.453206)
			(xy 214.360531 -4.50551) (xy 214.375212 -4.560197) (xy 214.382633 -4.616332) (xy 214.383112 -4.644644)
			(xy 214.383112 -5.508244) (xy 214.382706 -5.536561) (xy 214.375306 -5.592711) (xy 214.360638 -5.647413)
			(xy 214.338953 -5.699732) (xy 214.310623 -5.748772) (xy 214.276132 -5.793693) (xy 214.236072 -5.833726)
			(xy 214.191127 -5.868186) (xy 214.142068 -5.896483) (xy 214.089734 -5.918132) (xy 214.035022 -5.932763)
			(xy 213.978868 -5.940125) (xy 213.95055 -5.940552) (xy 213.919177 -5.939953) (xy 213.857087 -5.930899)
			(xy 213.796955 -5.912975) (xy 213.740042 -5.886555) (xy 213.687541 -5.852194) (xy 213.640552 -5.810611)
			(xy 213.600059 -5.76268) (xy 213.583012 -5.736336) (xy 213.578952 -5.730192) (xy 213.56798 -5.720381)
			(xy 213.561422 -5.717032) (xy 213.52256 -5.698998) (xy 213.508844 -5.700268) (xy 212.896704 -5.700268)
			(xy 212.884592 -5.69988) (xy 212.861559 -5.692378) (xy 212.841983 -5.67811) (xy 212.82779 -5.65848)
			(xy 212.820375 -5.635419) (xy 212.819996 -5.623306) (xy 210.168864 -5.623306) (xy 210.181686 -5.632989)
			(xy 210.245056 -5.690758) (xy 210.302825 -5.754128) (xy 210.354501 -5.822557) (xy 210.399642 -5.895463)
			(xy 210.437864 -5.972223) (xy 210.46884 -6.052182) (xy 210.492307 -6.134658) (xy 210.508063 -6.218948)
			(xy 210.515975 -6.304331) (xy 210.51647 -6.347206) (xy 210.515975 -6.390081) (xy 215.011241 -6.390081)
			(xy 215.011241 -6.304331) (xy 215.019153 -6.218948) (xy 215.034909 -6.134658) (xy 215.058376 -6.052182)
			(xy 215.089352 -5.972223) (xy 215.127574 -5.895463) (xy 215.172715 -5.822557) (xy 215.224391 -5.754128)
			(xy 215.28216 -5.690758) (xy 215.34553 -5.632989) (xy 215.413959 -5.581313) (xy 215.486865 -5.536172)
			(xy 215.563625 -5.49795) (xy 215.643584 -5.466974) (xy 215.72606 -5.443507) (xy 215.81035 -5.427751)
			(xy 215.895733 -5.419839) (xy 215.981483 -5.419839) (xy 216.066866 -5.427751) (xy 216.151156 -5.443507)
			(xy 216.233632 -5.466974) (xy 216.313591 -5.49795) (xy 216.390351 -5.536172) (xy 216.463257 -5.581313)
			(xy 216.531686 -5.632989) (xy 216.595056 -5.690758) (xy 216.652825 -5.754128) (xy 216.704501 -5.822557)
			(xy 216.749642 -5.895463) (xy 216.787864 -5.972223) (xy 216.81884 -6.052182) (xy 216.842307 -6.134658)
			(xy 216.858063 -6.218948) (xy 216.865975 -6.304331) (xy 216.86647 -6.347206) (xy 216.865975 -6.390081)
			(xy 296.143921 -6.390081) (xy 296.143921 -6.304331) (xy 296.151833 -6.218948) (xy 296.167589 -6.134658)
			(xy 296.191056 -6.052182) (xy 296.222032 -5.972223) (xy 296.260254 -5.895463) (xy 296.305395 -5.822557)
			(xy 296.357071 -5.754128) (xy 296.41484 -5.690758) (xy 296.47821 -5.632989) (xy 296.546639 -5.581313)
			(xy 296.619545 -5.536172) (xy 296.696305 -5.49795) (xy 296.776264 -5.466974) (xy 296.85874 -5.443507)
			(xy 296.94303 -5.427751) (xy 297.028413 -5.419839) (xy 297.114163 -5.419839) (xy 297.199546 -5.427751)
			(xy 297.283836 -5.443507) (xy 297.366312 -5.466974) (xy 297.446271 -5.49795) (xy 297.466944 -5.508244)
			(xy 298.629324 -5.508244) (xy 298.629324 -4.644644) (xy 298.629777 -4.616327) (xy 298.637167 -4.560178)
			(xy 298.651826 -4.505474) (xy 298.673504 -4.453154) (xy 298.701828 -4.404112) (xy 298.736314 -4.359189)
			(xy 298.776371 -4.319154) (xy 298.821313 -4.284693) (xy 298.870371 -4.256396) (xy 298.922704 -4.234748)
			(xy 298.977415 -4.22012) (xy 299.033569 -4.212761) (xy 299.061886 -4.212336) (xy 299.093352 -4.212875)
			(xy 299.15562 -4.221998) (xy 299.215907 -4.240054) (xy 299.272938 -4.26666) (xy 299.325509 -4.301255)
			(xy 299.372508 -4.343106) (xy 299.412942 -4.391331) (xy 299.429932 -4.417822) (xy 299.433953 -4.423879)
			(xy 299.444801 -4.43355) (xy 299.451268 -4.436872) (xy 299.489368 -4.45516) (xy 299.501052 -4.454144)
			(xy 300.113192 -4.454144) (xy 300.125295 -4.454622) (xy 300.148312 -4.462113) (xy 300.167881 -4.47636)
			(xy 300.182078 -4.495965) (xy 300.189509 -4.519002) (xy 300.1899 -4.531106) (xy 300.1899 -5.628386)
			(xy 300.189381 -5.640471) (xy 300.181933 -5.663464) (xy 300.167759 -5.683041) (xy 300.148238 -5.697293)
			(xy 300.125275 -5.704833) (xy 300.113192 -5.705348) (xy 299.501052 -5.705348) (xy 299.487082 -5.704078)
			(xy 299.448474 -5.721604) (xy 299.441866 -5.724865) (xy 299.430772 -5.734558) (xy 299.42663 -5.740654)
			(xy 299.409517 -5.76652) (xy 299.369051 -5.81352) (xy 299.322281 -5.854252) (xy 299.270168 -5.887879)
			(xy 299.213784 -5.913712) (xy 299.154286 -5.931219) (xy 299.092896 -5.94004) (xy 299.061886 -5.940552)
			(xy 299.033575 -5.940113) (xy 298.977436 -5.932723) (xy 298.922742 -5.918071) (xy 298.870426 -5.896409)
			(xy 298.821385 -5.868106) (xy 298.776455 -5.833646) (xy 298.736406 -5.793618) (xy 298.701922 -5.748707)
			(xy 298.673593 -5.69968) (xy 298.651903 -5.647377) (xy 298.637222 -5.59269) (xy 298.629802 -5.536555)
			(xy 298.629324 -5.508244) (xy 297.466944 -5.508244) (xy 297.523031 -5.536172) (xy 297.595937 -5.581313)
			(xy 297.664366 -5.632989) (xy 297.727736 -5.690758) (xy 297.785505 -5.754128) (xy 297.837181 -5.822557)
			(xy 297.882322 -5.895463) (xy 297.920544 -5.972223) (xy 297.95152 -6.052182) (xy 297.974987 -6.134658)
			(xy 297.990743 -6.218948) (xy 297.998655 -6.304331) (xy 297.99915 -6.347206) (xy 297.998655 -6.390081)
			(xy 302.493921 -6.390081) (xy 302.493921 -6.304331) (xy 302.501833 -6.218948) (xy 302.517589 -6.134658)
			(xy 302.541056 -6.052182) (xy 302.572032 -5.972223) (xy 302.610254 -5.895463) (xy 302.655395 -5.822557)
			(xy 302.707071 -5.754128) (xy 302.76484 -5.690758) (xy 302.82821 -5.632989) (xy 302.896639 -5.581313)
			(xy 302.969545 -5.536172) (xy 303.046305 -5.49795) (xy 303.126264 -5.466974) (xy 303.20874 -5.443507)
			(xy 303.29303 -5.427751) (xy 303.378413 -5.419839) (xy 303.464163 -5.419839) (xy 303.549546 -5.427751)
			(xy 303.633836 -5.443507) (xy 303.716312 -5.466974) (xy 303.796271 -5.49795) (xy 303.873031 -5.536172)
			(xy 303.945937 -5.581313) (xy 304.014366 -5.632989) (xy 304.077736 -5.690758) (xy 304.135505 -5.754128)
			(xy 304.187181 -5.822557) (xy 304.232322 -5.895463) (xy 304.270544 -5.972223) (xy 304.30152 -6.052182)
			(xy 304.324987 -6.134658) (xy 304.340743 -6.218948) (xy 304.348655 -6.304331) (xy 304.34915 -6.347206)
			(xy 304.348655 -6.390081) (xy 311.155321 -6.390081) (xy 311.155321 -6.304331) (xy 311.163233 -6.218948)
			(xy 311.178989 -6.134658) (xy 311.202456 -6.052182) (xy 311.233432 -5.972223) (xy 311.271654 -5.895463)
			(xy 311.316795 -5.822557) (xy 311.368471 -5.754128) (xy 311.42624 -5.690758) (xy 311.48961 -5.632989)
			(xy 311.558039 -5.581313) (xy 311.630945 -5.536172) (xy 311.707705 -5.49795) (xy 311.787664 -5.466974)
			(xy 311.87014 -5.443507) (xy 311.95443 -5.427751) (xy 312.039813 -5.419839) (xy 312.125563 -5.419839)
			(xy 312.210946 -5.427751) (xy 312.295236 -5.443507) (xy 312.377712 -5.466974) (xy 312.457671 -5.49795)
			(xy 312.534431 -5.536172) (xy 312.607337 -5.581313) (xy 312.66328 -5.62356) (xy 315.314076 -5.62356)
			(xy 315.314076 -5.623306) (xy 315.314076 -4.526026) (xy 315.31453 -4.513934) (xy 315.321984 -4.490928)
			(xy 315.336173 -4.471345) (xy 315.355711 -4.457095) (xy 315.378694 -4.449569) (xy 315.390784 -4.449064)
			(xy 316.002924 -4.449064) (xy 316.014997 -4.449544) (xy 316.03796 -4.457009) (xy 316.057494 -4.471203)
			(xy 316.071689 -4.490736) (xy 316.079156 -4.513699) (xy 316.079632 -4.525772) (xy 316.079632 -4.526026)
			(xy 316.079632 -5.623306) (xy 316.079197 -5.635399) (xy 316.071735 -5.658404) (xy 316.057541 -5.677986)
			(xy 316.037999 -5.692236) (xy 316.015015 -5.699762) (xy 316.002924 -5.700268) (xy 315.390784 -5.700268)
			(xy 315.378696 -5.6999) (xy 315.355706 -5.692424) (xy 315.336153 -5.678207) (xy 315.321951 -5.658643)
			(xy 315.314491 -5.635648) (xy 315.314076 -5.62356) (xy 312.66328 -5.62356) (xy 312.675766 -5.632989)
			(xy 312.739136 -5.690758) (xy 312.796905 -5.754128) (xy 312.848581 -5.822557) (xy 312.893722 -5.895463)
			(xy 312.931944 -5.972223) (xy 312.96292 -6.052182) (xy 312.986387 -6.134658) (xy 313.002143 -6.218948)
			(xy 313.010055 -6.304331) (xy 313.01055 -6.347206) (xy 313.010055 -6.390081) (xy 317.505321 -6.390081)
			(xy 317.505321 -6.304331) (xy 317.513233 -6.218948) (xy 317.528989 -6.134658) (xy 317.552456 -6.052182)
			(xy 317.583432 -5.972223) (xy 317.621654 -5.895463) (xy 317.666795 -5.822557) (xy 317.718471 -5.754128)
			(xy 317.77624 -5.690758) (xy 317.83961 -5.632989) (xy 317.908039 -5.581313) (xy 317.980945 -5.536172)
			(xy 318.057705 -5.49795) (xy 318.137664 -5.466974) (xy 318.22014 -5.443507) (xy 318.30443 -5.427751)
			(xy 318.389813 -5.419839) (xy 318.475563 -5.419839) (xy 318.560946 -5.427751) (xy 318.645236 -5.443507)
			(xy 318.727712 -5.466974) (xy 318.807671 -5.49795) (xy 318.884431 -5.536172) (xy 318.957337 -5.581313)
			(xy 319.025766 -5.632989) (xy 319.089136 -5.690758) (xy 319.146905 -5.754128) (xy 319.198581 -5.822557)
			(xy 319.243722 -5.895463) (xy 319.281944 -5.972223) (xy 319.31292 -6.052182) (xy 319.336387 -6.134658)
			(xy 319.352143 -6.218948) (xy 319.360055 -6.304331) (xy 319.36055 -6.347206) (xy 319.360055 -6.390081)
			(xy 361.894107 -6.390081) (xy 361.894107 -6.304331) (xy 361.902019 -6.218948) (xy 361.917775 -6.134658)
			(xy 361.941242 -6.052182) (xy 361.972218 -5.972223) (xy 362.01044 -5.895463) (xy 362.055581 -5.822557)
			(xy 362.107257 -5.754128) (xy 362.165026 -5.690758) (xy 362.228396 -5.632989) (xy 362.296825 -5.581313)
			(xy 362.369731 -5.536172) (xy 362.446491 -5.49795) (xy 362.52645 -5.466974) (xy 362.608926 -5.443507)
			(xy 362.693216 -5.427751) (xy 362.778599 -5.419839) (xy 362.864349 -5.419839) (xy 362.949732 -5.427751)
			(xy 363.034022 -5.443507) (xy 363.116498 -5.466974) (xy 363.196457 -5.49795) (xy 363.273217 -5.536172)
			(xy 363.346123 -5.581313) (xy 363.408457 -5.628386) (xy 365.174276 -5.628386) (xy 365.174276 -4.531106)
			(xy 365.174666 -4.51898) (xy 365.182161 -4.495915) (xy 365.196419 -4.476296) (xy 365.216043 -4.462046)
			(xy 365.239112 -4.454561) (xy 365.251238 -4.454144) (xy 365.863378 -4.454144) (xy 365.8755 -4.454579)
			(xy 365.898559 -4.462066) (xy 365.918175 -4.476313) (xy 365.932427 -4.495926) (xy 365.939919 -4.518984)
			(xy 365.94034 -4.531106) (xy 365.94034 -5.628386) (xy 365.939928 -5.64051) (xy 365.932437 -5.663572)
			(xy 365.918184 -5.683189) (xy 365.898565 -5.69744) (xy 365.875502 -5.704929) (xy 365.863378 -5.705348)
			(xy 365.251238 -5.705348) (xy 365.239116 -5.704908) (xy 365.216056 -5.697424) (xy 365.196439 -5.683178)
			(xy 365.182187 -5.663566) (xy 365.174696 -5.640508) (xy 365.174276 -5.628386) (xy 363.408457 -5.628386)
			(xy 363.414552 -5.632989) (xy 363.477922 -5.690758) (xy 363.535691 -5.754128) (xy 363.587367 -5.822557)
			(xy 363.632508 -5.895463) (xy 363.67073 -5.972223) (xy 363.701706 -6.052182) (xy 363.725173 -6.134658)
			(xy 363.740929 -6.218948) (xy 363.748841 -6.304331) (xy 363.749336 -6.347206) (xy 363.748841 -6.390081)
			(xy 368.244107 -6.390081) (xy 368.244107 -6.304331) (xy 368.252019 -6.218948) (xy 368.267775 -6.134658)
			(xy 368.291242 -6.052182) (xy 368.322218 -5.972223) (xy 368.36044 -5.895463) (xy 368.405581 -5.822557)
			(xy 368.457257 -5.754128) (xy 368.515026 -5.690758) (xy 368.578396 -5.632989) (xy 368.646825 -5.581313)
			(xy 368.719731 -5.536172) (xy 368.796491 -5.49795) (xy 368.87645 -5.466974) (xy 368.958926 -5.443507)
			(xy 369.043216 -5.427751) (xy 369.128599 -5.419839) (xy 369.214349 -5.419839) (xy 369.299732 -5.427751)
			(xy 369.384022 -5.443507) (xy 369.466498 -5.466974) (xy 369.546457 -5.49795) (xy 369.623217 -5.536172)
			(xy 369.696123 -5.581313) (xy 369.764552 -5.632989) (xy 369.827922 -5.690758) (xy 369.885691 -5.754128)
			(xy 369.937367 -5.822557) (xy 369.982508 -5.895463) (xy 370.02073 -5.972223) (xy 370.051706 -6.052182)
			(xy 370.075173 -6.134658) (xy 370.090929 -6.218948) (xy 370.098841 -6.304331) (xy 370.099336 -6.347206)
			(xy 370.098841 -6.390081) (xy 370.090929 -6.475464) (xy 370.075173 -6.559754) (xy 370.051706 -6.64223)
			(xy 370.02073 -6.722189) (xy 369.982508 -6.798949) (xy 369.937367 -6.871855) (xy 369.885691 -6.940284)
			(xy 369.827922 -7.003654) (xy 369.764552 -7.061423) (xy 369.696123 -7.113099) (xy 369.623217 -7.15824)
			(xy 369.546457 -7.196462) (xy 369.466498 -7.227438) (xy 369.384022 -7.250905) (xy 369.299732 -7.266661)
			(xy 369.214349 -7.274573) (xy 369.128599 -7.274573) (xy 369.043216 -7.266661) (xy 368.958926 -7.250905)
			(xy 368.87645 -7.227438) (xy 368.796491 -7.196462) (xy 368.719731 -7.15824) (xy 368.646825 -7.113099)
			(xy 368.578396 -7.061423) (xy 368.515026 -7.003654) (xy 368.457257 -6.940284) (xy 368.405581 -6.871855)
			(xy 368.36044 -6.798949) (xy 368.322218 -6.722189) (xy 368.291242 -6.64223) (xy 368.267775 -6.559754)
			(xy 368.252019 -6.475464) (xy 368.244107 -6.390081) (xy 363.748841 -6.390081) (xy 363.740929 -6.475464)
			(xy 363.725173 -6.559754) (xy 363.701706 -6.64223) (xy 363.67073 -6.722189) (xy 363.632508 -6.798949)
			(xy 363.587367 -6.871855) (xy 363.535691 -6.940284) (xy 363.477922 -7.003654) (xy 363.414552 -7.061423)
			(xy 363.346123 -7.113099) (xy 363.273217 -7.15824) (xy 363.196457 -7.196462) (xy 363.116498 -7.227438)
			(xy 363.034022 -7.250905) (xy 362.949732 -7.266661) (xy 362.864349 -7.274573) (xy 362.778599 -7.274573)
			(xy 362.693216 -7.266661) (xy 362.608926 -7.250905) (xy 362.52645 -7.227438) (xy 362.446491 -7.196462)
			(xy 362.369731 -7.15824) (xy 362.296825 -7.113099) (xy 362.228396 -7.061423) (xy 362.165026 -7.003654)
			(xy 362.107257 -6.940284) (xy 362.055581 -6.871855) (xy 362.01044 -6.798949) (xy 361.972218 -6.722189)
			(xy 361.941242 -6.64223) (xy 361.917775 -6.559754) (xy 361.902019 -6.475464) (xy 361.894107 -6.390081)
			(xy 319.360055 -6.390081) (xy 319.352143 -6.475464) (xy 319.336387 -6.559754) (xy 319.31292 -6.64223)
			(xy 319.281944 -6.722189) (xy 319.243722 -6.798949) (xy 319.198581 -6.871855) (xy 319.146905 -6.940284)
			(xy 319.089136 -7.003654) (xy 319.025766 -7.061423) (xy 318.957337 -7.113099) (xy 318.884431 -7.15824)
			(xy 318.807671 -7.196462) (xy 318.727712 -7.227438) (xy 318.645236 -7.250905) (xy 318.560946 -7.266661)
			(xy 318.475563 -7.274573) (xy 318.389813 -7.274573) (xy 318.30443 -7.266661) (xy 318.22014 -7.250905)
			(xy 318.137664 -7.227438) (xy 318.057705 -7.196462) (xy 317.980945 -7.15824) (xy 317.908039 -7.113099)
			(xy 317.83961 -7.061423) (xy 317.77624 -7.003654) (xy 317.718471 -6.940284) (xy 317.666795 -6.871855)
			(xy 317.621654 -6.798949) (xy 317.583432 -6.722189) (xy 317.552456 -6.64223) (xy 317.528989 -6.559754)
			(xy 317.513233 -6.475464) (xy 317.505321 -6.390081) (xy 313.010055 -6.390081) (xy 313.002143 -6.475464)
			(xy 312.986387 -6.559754) (xy 312.96292 -6.64223) (xy 312.931944 -6.722189) (xy 312.893722 -6.798949)
			(xy 312.848581 -6.871855) (xy 312.796905 -6.940284) (xy 312.739136 -7.003654) (xy 312.675766 -7.061423)
			(xy 312.607337 -7.113099) (xy 312.534431 -7.15824) (xy 312.457671 -7.196462) (xy 312.377712 -7.227438)
			(xy 312.295236 -7.250905) (xy 312.210946 -7.266661) (xy 312.125563 -7.274573) (xy 312.039813 -7.274573)
			(xy 311.95443 -7.266661) (xy 311.87014 -7.250905) (xy 311.787664 -7.227438) (xy 311.707705 -7.196462)
			(xy 311.630945 -7.15824) (xy 311.558039 -7.113099) (xy 311.48961 -7.061423) (xy 311.42624 -7.003654)
			(xy 311.368471 -6.940284) (xy 311.316795 -6.871855) (xy 311.271654 -6.798949) (xy 311.233432 -6.722189)
			(xy 311.202456 -6.64223) (xy 311.178989 -6.559754) (xy 311.163233 -6.475464) (xy 311.155321 -6.390081)
			(xy 304.348655 -6.390081) (xy 304.340743 -6.475464) (xy 304.324987 -6.559754) (xy 304.30152 -6.64223)
			(xy 304.270544 -6.722189) (xy 304.232322 -6.798949) (xy 304.187181 -6.871855) (xy 304.135505 -6.940284)
			(xy 304.077736 -7.003654) (xy 304.014366 -7.061423) (xy 303.945937 -7.113099) (xy 303.873031 -7.15824)
			(xy 303.796271 -7.196462) (xy 303.716312 -7.227438) (xy 303.633836 -7.250905) (xy 303.549546 -7.266661)
			(xy 303.464163 -7.274573) (xy 303.378413 -7.274573) (xy 303.29303 -7.266661) (xy 303.20874 -7.250905)
			(xy 303.126264 -7.227438) (xy 303.046305 -7.196462) (xy 302.969545 -7.15824) (xy 302.896639 -7.113099)
			(xy 302.82821 -7.061423) (xy 302.76484 -7.003654) (xy 302.707071 -6.940284) (xy 302.655395 -6.871855)
			(xy 302.610254 -6.798949) (xy 302.572032 -6.722189) (xy 302.541056 -6.64223) (xy 302.517589 -6.559754)
			(xy 302.501833 -6.475464) (xy 302.493921 -6.390081) (xy 297.998655 -6.390081) (xy 297.990743 -6.475464)
			(xy 297.974987 -6.559754) (xy 297.95152 -6.64223) (xy 297.920544 -6.722189) (xy 297.882322 -6.798949)
			(xy 297.837181 -6.871855) (xy 297.785505 -6.940284) (xy 297.727736 -7.003654) (xy 297.664366 -7.061423)
			(xy 297.595937 -7.113099) (xy 297.523031 -7.15824) (xy 297.446271 -7.196462) (xy 297.366312 -7.227438)
			(xy 297.283836 -7.250905) (xy 297.199546 -7.266661) (xy 297.114163 -7.274573) (xy 297.028413 -7.274573)
			(xy 296.94303 -7.266661) (xy 296.85874 -7.250905) (xy 296.776264 -7.227438) (xy 296.696305 -7.196462)
			(xy 296.619545 -7.15824) (xy 296.546639 -7.113099) (xy 296.47821 -7.061423) (xy 296.41484 -7.003654)
			(xy 296.357071 -6.940284) (xy 296.305395 -6.871855) (xy 296.260254 -6.798949) (xy 296.222032 -6.722189)
			(xy 296.191056 -6.64223) (xy 296.167589 -6.559754) (xy 296.151833 -6.475464) (xy 296.143921 -6.390081)
			(xy 216.865975 -6.390081) (xy 216.858063 -6.475464) (xy 216.842307 -6.559754) (xy 216.81884 -6.64223)
			(xy 216.787864 -6.722189) (xy 216.749642 -6.798949) (xy 216.704501 -6.871855) (xy 216.652825 -6.940284)
			(xy 216.595056 -7.003654) (xy 216.531686 -7.061423) (xy 216.463257 -7.113099) (xy 216.390351 -7.15824)
			(xy 216.313591 -7.196462) (xy 216.233632 -7.227438) (xy 216.151156 -7.250905) (xy 216.066866 -7.266661)
			(xy 215.981483 -7.274573) (xy 215.895733 -7.274573) (xy 215.81035 -7.266661) (xy 215.72606 -7.250905)
			(xy 215.643584 -7.227438) (xy 215.563625 -7.196462) (xy 215.486865 -7.15824) (xy 215.413959 -7.113099)
			(xy 215.34553 -7.061423) (xy 215.28216 -7.003654) (xy 215.224391 -6.940284) (xy 215.172715 -6.871855)
			(xy 215.127574 -6.798949) (xy 215.089352 -6.722189) (xy 215.058376 -6.64223) (xy 215.034909 -6.559754)
			(xy 215.019153 -6.475464) (xy 215.011241 -6.390081) (xy 210.515975 -6.390081) (xy 210.508063 -6.475464)
			(xy 210.492307 -6.559754) (xy 210.46884 -6.64223) (xy 210.437864 -6.722189) (xy 210.399642 -6.798949)
			(xy 210.354501 -6.871855) (xy 210.302825 -6.940284) (xy 210.245056 -7.003654) (xy 210.181686 -7.061423)
			(xy 210.113257 -7.113099) (xy 210.040351 -7.15824) (xy 209.963591 -7.196462) (xy 209.883632 -7.227438)
			(xy 209.801156 -7.250905) (xy 209.716866 -7.266661) (xy 209.631483 -7.274573) (xy 209.545733 -7.274573)
			(xy 209.46035 -7.266661) (xy 209.37606 -7.250905) (xy 209.293584 -7.227438) (xy 209.213625 -7.196462)
			(xy 209.136865 -7.15824) (xy 209.063959 -7.113099) (xy 208.99553 -7.061423) (xy 208.93216 -7.003654)
			(xy 208.874391 -6.940284) (xy 208.822715 -6.871855) (xy 208.777574 -6.798949) (xy 208.739352 -6.722189)
			(xy 208.708376 -6.64223) (xy 208.684909 -6.559754) (xy 208.669153 -6.475464) (xy 208.661241 -6.390081)
			(xy 197.210934 -6.390081) (xy 197.210934 -7.78002) (xy 197.211456 -7.835788) (xy 197.219793 -7.947013)
			(xy 197.236418 -8.057304) (xy 197.261239 -8.166044) (xy 197.294116 -8.272625) (xy 197.334866 -8.376451)
			(xy 197.383261 -8.476941) (xy 197.439031 -8.573534) (xy 197.501863 -8.66569) (xy 197.571406 -8.752892)
			(xy 197.647271 -8.834653) (xy 197.729034 -8.910516) (xy 197.816238 -8.980057) (xy 197.908394 -9.042887)
			(xy 198.004989 -9.098654) (xy 198.10548 -9.147047) (xy 198.209307 -9.187795) (xy 198.315889 -9.22067)
			(xy 198.42463 -9.245488) (xy 198.534921 -9.262111) (xy 198.646146 -9.270445) (xy 198.701914 -9.271)
			(xy 223.300036 -9.271) (xy 223.370417 -9.271495) (xy 223.510959 -9.279389) (xy 223.650836 -9.295152)
			(xy 223.78961 -9.318732) (xy 223.926844 -9.350057) (xy 224.062105 -9.389027) (xy 224.194968 -9.435519)
			(xy 224.325015 -9.489388) (xy 224.451838 -9.550465) (xy 224.575036 -9.618556) (xy 224.694222 -9.693447)
			(xy 224.809022 -9.774904) (xy 224.919074 -9.862669) (xy 225.024032 -9.956467) (xy 225.123566 -10.056003)
			(xy 225.217361 -10.160962) (xy 225.305125 -10.271016) (xy 225.386579 -10.385818) (xy 225.461469 -10.505006)
			(xy 225.529557 -10.628205) (xy 225.590631 -10.755029) (xy 225.644498 -10.885077) (xy 225.690988 -11.017941)
			(xy 225.729955 -11.153203) (xy 225.761277 -11.290437) (xy 225.784855 -11.429211) (xy 225.800615 -11.569089)
			(xy 225.808507 -11.709631) (xy 225.809048 -11.780012) (xy 225.809048 -33.120076) (xy 225.809549 -33.152224)
			(xy 225.817939 -33.21597) (xy 225.834578 -33.278076) (xy 225.859182 -33.337478) (xy 225.891329 -33.39316)
			(xy 225.93047 -33.44417) (xy 225.975934 -33.489634) (xy 226.026945 -33.528774) (xy 226.082627 -33.560921)
			(xy 226.14203 -33.585524) (xy 226.204136 -33.602162) (xy 226.267882 -33.610551) (xy 226.30003 -33.611058)
		)
		(stroke
			(width 0)
			(type solid)
		)
		(fill yes)
		(layer "In1.Cu")
		(net "DELTA_L_GND_1")
	)
)
